# ODB++ job Barreleye-G2-SXM2-RISER-EVT-HW-GBR.tgz
### matrix/matrix

STEP {
    COL=1
    NAME=DRC
}


LAYER {
    ROW=1
    CONTEXT=BOARD
    TYPE=DRILL
    NAME=DRILLO
    POLARITY=POSITIVE
    ORIENTATION=NOT_DEFINED
    START_NAME=
    END_NAME=
    OLD_NAME=DRILL
}

LAYER {
    ROW=2
    CONTEXT=BOARD
    TYPE=DRILL
    NAME=BD-12-4
    POLARITY=POSITIVE
    ORIENTATION=NOT_DEFINED
    START_NAME=L4
    END_NAME=LS
    OLD_NAME=BACKDRILL_GND4_BOTTOM
}

LAYER {
    ROW=3
    CONTEXT=BOARD
    TYPE=DRILL
    NAME=BD-12-6
    POLARITY=POSITIVE
    ORIENTATION=NOT_DEFINED
    START_NAME=L6
    END_NAME=LS
    OLD_NAME=BACKDRILL_GND6_BOTTOM
}

LAYER {
    ROW=4
    CONTEXT=BOARD
    TYPE=DRILL
    NAME=BD-1-4
    POLARITY=POSITIVE
    ORIENTATION=NOT_DEFINED
    START_NAME=LC
    END_NAME=L4
    OLD_NAME=BACKDRILL_TOP_GND4
}

LAYER {
    ROW=5
    CONTEXT=BOARD
    TYPE=DRILL
    NAME=BD-1-9
    POLARITY=POSITIVE
    ORIENTATION=NOT_DEFINED
    START_NAME=LC
    END_NAME=L9
    OLD_NAME=BACKDRILL_TOP_GND9
}

LAYER {
    ROW=6
    CONTEXT=BOARD
    TYPE=SILK_SCREEN
    NAME=LEGC
    POLARITY=POSITIVE
    ORIENTATION=NOT_DEFINED
    START_NAME=
    END_NAME=
    OLD_NAME=LEG
}

LAYER {
    ROW=7
    CONTEXT=BOARD
    TYPE=SOLDER_PASTE
    NAME=C-PASTE
    POLARITY=POSITIVE
    ORIENTATION=NOT_DEFINED
    START_NAME=
    END_NAME=
    OLD_NAME=SPT
}

LAYER {
    ROW=8
    CONTEXT=BOARD
    TYPE=SOLDER_MASK
    NAME=SMC
    POLARITY=POSITIVE
    ORIENTATION=NOT_DEFINED
    START_NAME=
    END_NAME=
    OLD_NAME=SMT
}

LAYER {
    ROW=9
    CONTEXT=BOARD
    TYPE=SIGNAL
    NAME=LC
    POLARITY=POSITIVE
    ORIENTATION=NOT_DEFINED
    START_NAME=
    END_NAME=
    OLD_NAME=TOP
}

LAYER {
    ROW=10
    CONTEXT=BOARD
    TYPE=POWER_GROUND
    NAME=L2
    POLARITY=NEGATIVE
    ORIENTATION=NOT_DEFINED
    START_NAME=
    END_NAME=
    OLD_NAME=GND2
}

LAYER {
    ROW=11
    CONTEXT=BOARD
    TYPE=SIGNAL
    NAME=L3
    POLARITY=POSITIVE
    ORIENTATION=NOT_DEFINED
    START_NAME=
    END_NAME=
    OLD_NAME=SIG3
}

LAYER {
    ROW=12
    CONTEXT=BOARD
    TYPE=POWER_GROUND
    NAME=L4
    POLARITY=NEGATIVE
    ORIENTATION=NOT_DEFINED
    START_NAME=
    END_NAME=
    OLD_NAME=GND4
}

LAYER {
    ROW=13
    CONTEXT=BOARD
    TYPE=SIGNAL
    NAME=L5
    POLARITY=POSITIVE
    ORIENTATION=NOT_DEFINED
    START_NAME=
    END_NAME=
    OLD_NAME=SIG5
}

LAYER {
    ROW=14
    CONTEXT=BOARD
    TYPE=POWER_GROUND
    NAME=L6
    POLARITY=NEGATIVE
    ORIENTATION=NOT_DEFINED
    START_NAME=
    END_NAME=
    OLD_NAME=GND6
}

LAYER {
    ROW=15
    CONTEXT=BOARD
    TYPE=POWER_GROUND
    NAME=L7
    POLARITY=NEGATIVE
    ORIENTATION=NOT_DEFINED
    START_NAME=
    END_NAME=
    OLD_NAME=PWR7
}

LAYER {
    ROW=16
    CONTEXT=BOARD
    TYPE=POWER_GROUND
    NAME=L8
    POLARITY=NEGATIVE
    ORIENTATION=NOT_DEFINED
    START_NAME=
    END_NAME=
    OLD_NAME=PWR8
}

LAYER {
    ROW=17
    CONTEXT=BOARD
    TYPE=POWER_GROUND
    NAME=L9
    POLARITY=NEGATIVE
    ORIENTATION=NOT_DEFINED
    START_NAME=
    END_NAME=
    OLD_NAME=GND9
}

LAYER {
    ROW=18
    CONTEXT=BOARD
    TYPE=SIGNAL
    NAME=L10
    POLARITY=POSITIVE
    ORIENTATION=NOT_DEFINED
    START_NAME=
    END_NAME=
    OLD_NAME=SIG10
}

LAYER {
    ROW=19
    CONTEXT=BOARD
    TYPE=POWER_GROUND
    NAME=L11
    POLARITY=NEGATIVE
    ORIENTATION=NOT_DEFINED
    START_NAME=
    END_NAME=
    OLD_NAME=GND11
}

LAYER {
    ROW=20
    CONTEXT=BOARD
    TYPE=SIGNAL
    NAME=LS
    POLARITY=POSITIVE
    ORIENTATION=NOT_DEFINED
    START_NAME=
    END_NAME=
    OLD_NAME=BOTTOM
}

LAYER {
    ROW=21
    CONTEXT=BOARD
    TYPE=SOLDER_MASK
    NAME=SMS
    POLARITY=POSITIVE
    ORIENTATION=NOT_DEFINED
    START_NAME=
    END_NAME=
    OLD_NAME=SMB
}

LAYER {
    ROW=22
    CONTEXT=BOARD
    TYPE=SOLDER_PASTE
    NAME=S-PASTE
    POLARITY=POSITIVE
    ORIENTATION=NOT_DEFINED
    START_NAME=
    END_NAME=
    OLD_NAME=SPB
}

LAYER {
    ROW=23
    CONTEXT=BOARD
    TYPE=SILK_SCREEN
    NAME=LEGS
    POLARITY=POSITIVE
    ORIENTATION=NOT_DEFINED
    START_NAME=
    END_NAME=
    OLD_NAME=SSB
}

LAYER {
    ROW=24
    CONTEXT=BOARD
    TYPE=ROUT
    NAME=ROUT
    POLARITY=POSITIVE
    ORIENTATION=NOT_DEFINED
    START_NAME=
    END_NAME=
    OLD_NAME=
}

LAYER {
    ROW=25
    CONTEXT=MISC
    TYPE=DOCUMENT
    NAME=PM
    POLARITY=POSITIVE
    ORIENTATION=NOT_DEFINED
    START_NAME=
    END_NAME=
    OLD_NAME=RISER-DRL
}

LAYER {
    ROW=26
    CONTEXT=MISC
    TYPE=DOCUMENT
    NAME=PM-12-4
    POLARITY=POSITIVE
    ORIENTATION=NOT_DEFINED
    START_NAME=
    END_NAME=
    OLD_NAME=RISER-BD-B-L4
}

LAYER {
    ROW=27
    CONTEXT=MISC
    TYPE=DOCUMENT
    NAME=PM-12-6
    POLARITY=POSITIVE
    ORIENTATION=NOT_DEFINED
    START_NAME=
    END_NAME=
    OLD_NAME=RISER-BD-B-L6
}

LAYER {
    ROW=28
    CONTEXT=MISC
    TYPE=DOCUMENT
    NAME=PM-1-4
    POLARITY=POSITIVE
    ORIENTATION=NOT_DEFINED
    START_NAME=
    END_NAME=
    OLD_NAME=RISER-BD-T-L4
}

LAYER {
    ROW=29
    CONTEXT=MISC
    TYPE=DOCUMENT
    NAME=PM-1-9
    POLARITY=POSITIVE
    ORIENTATION=NOT_DEFINED
    START_NAME=
    END_NAME=
    OLD_NAME=RISER-BD-T-L9
}

LAYER {
    ROW=30
    CONTEXT=MISC
    TYPE=DOCUMENT
    NAME=PANEL_ASSY
    POLARITY=POSITIVE
    ORIENTATION=NOT_DEFINED
    START_NAME=
    END_NAME=
    OLD_NAME=
}

LAYER {
    ROW=31
    CONTEXT=MISC
    TYPE=DOCUMENT
    NAME=ASSY_REF_TOP
    POLARITY=POSITIVE
    ORIENTATION=NOT_DEFINED
    START_NAME=
    END_NAME=
    OLD_NAME=
}

LAYER {
    ROW=32
    CONTEXT=MISC
    TYPE=DOCUMENT
    NAME=ASSY_REF_BOT
    POLARITY=POSITIVE
    ORIENTATION=NOT_DEFINED
    START_NAME=
    END_NAME=
    OLD_NAME=
}

LAYER {
    ROW=33
    CONTEXT=MISC
    TYPE=SIGNAL
    NAME=LC+++
    POLARITY=POSITIVE
    ORIENTATION=NOT_DEFINED
    START_NAME=
    END_NAME=
    OLD_NAME=
}

LAYER {
    ROW=34
    CONTEXT=MISC
    TYPE=SIGNAL
    NAME=LC-DUMMY
    POLARITY=POSITIVE
    ORIENTATION=NOT_DEFINED
    START_NAME=
    END_NAME=
    OLD_NAME=
}

LAYER {
    ROW=35
    CONTEXT=MISC
    TYPE=SIGNAL
    NAME=L3-DUMMY
    POLARITY=POSITIVE
    ORIENTATION=NOT_DEFINED
    START_NAME=
    END_NAME=
    OLD_NAME=
}

LAYER {
    ROW=36
    CONTEXT=MISC
    TYPE=SIGNAL
    NAME=L5-DUMMY
    POLARITY=POSITIVE
    ORIENTATION=NOT_DEFINED
    START_NAME=
    END_NAME=
    OLD_NAME=
}

LAYER {
    ROW=37
    CONTEXT=MISC
    TYPE=SIGNAL
    NAME=L10-DUMMY
    POLARITY=POSITIVE
    ORIENTATION=NOT_DEFINED
    START_NAME=
    END_NAME=
    OLD_NAME=
}

LAYER {
    ROW=38
    CONTEXT=MISC
    TYPE=SIGNAL
    NAME=LS-DUMMY
    POLARITY=POSITIVE
    ORIENTATION=NOT_DEFINED
    START_NAME=
    END_NAME=
    OLD_NAME=
}

### misc/info
JOB_NAME=669gb-015a-org
ODB_VERSION_MAJOR=6
ODB_VERSION_MINOR=3
CREATION_DATE=20171027.105354
SAVE_DATE=20171103.173124
SAVE_APP=Genesis 09.02c2
SAVE_USER=

### misc/attrlist
.comment = 
.customer = 
.global_camtek_aoiset = 
.technology = 
.primary_side = top
.design_origin_x = 0
.design_origin_y = 0
.board_thickness = 0.061800
datecode = 2000
dtool_version = 000
rtool_version = 000
itool_version = 000
otool_version = 000
mtool_version = 000
stool_version = 000
tool_version = 000
datecode-year = 01
datecode-week = 01
datecode-day = 000
datecode-serial = -01
serial_num = 00
gce = 669gb015a
ver = -
nver = 
njob = 
old = 
ver_9_13 = -00
ver_166_11_13 = -00
ver_166_6_9 = -00
eie_serial = 000
uvw_add_6mil = no
lot_code = 000
barcode = gce
675xd = 000000
675xdf = 000
675xds = 0000
675d = 00000
675ll = 0000-00
675llm = 0000
675lls = -00
wsr = yyww-88-11
gdc = 00
gdcs = 08
ndc = 0000
ddsl = 0321
end = 000
last6 = -00
vw = std
dscp = 88-11
e8 = e82152
today = 
dn = dn
week-day = 000
sver_9_13 = 
sver_166_11_13 = 
wk = 4
ds = 88
cp = 22
sjob = 
cjob = 
ss8388 = 8888
ch = china
lot = 000
n4 = 
serial_sm = 01
v0a = gx d-v0a
v0a2 = gx d-v0a-2
v0ads = gx ds-v0a
h = gx h
94 = 94v-0
dar = dar
ul_mark = gx b-v0
datecode_type = yyww
datecode-dot = .
datecodetype = yyww
filmtype = s
week_type = even

### steps/drc/stephdr
X_DATUM=0
Y_DATUM=0
X_ORIGIN=0
Y_ORIGIN=0

TOP_ACTIVE=0
BOTTOM_ACTIVE=0
RIGHT_ACTIVE=0
LEFT_ACTIVE=0
ONLINE_DRC_NAME=
ONLINE_DRC_MODE=DISABLED
ONLINE_DRC_STAT=RED
ONLINE_DRC_TIME=0
ONLINE_DRC_BEEP_VOL=2
ONLINE_DRC_BEEP_TONE=500
ONLINE_NET_MODE=DISABLED
ONLINE_NET_STAT=RED
ONLINE_NET_TIME=0
ONLINE_NET_BEEP_VOL=2
ONLINE_NET_BEEP_TONE=1000

### steps/drc/attrlist
.out_drill_full = no
.out_drill_optional = no
.out_rout_optional = no
.array_with_rotation = no
.flipped_out_of_date = no
.sr_pcb = no
.comment = 
.out_name = 
.assembly_proc_top = 
.assembly_proc_bottom = 
.all_eda_layers = 
.flipped_of = 
.pnl_scheme = 
.pnl_pcb = 
.pnl_class = 
.pnl_place = 
.source_name = 
.rotated_of = 
.transform_data = 
.released_from = 
.merge_processes = 
.neutralization_info = 
.design_center = 
.neutralization_ss_layers = 
.fs_direction_top = left2right
.fs_direction_bottom = right2left
.smt_direction_top = left2right
.smt_direction_bottom = right2left
.viacap_layer = none
.etm_tester = mania
.etm_pin_style = regular
.etm_repear_fmt = none
.se_coupon = none
.se_coupon_mode = start_end
.se_coupon_split_num = 1
.out_drill_order = 0
.out_rout_order = 0
.entity_version = 29876
.se_coupon_order = 1
.etm_adapter_h = 3750.000000
.rotation_angle = 0.000000

### steps/drc/layers/bd-1-4/attrlist
.out_mirror = no
.lpol_done = no
.cu_base = no
.etm_mirror = no
.comment = 
.flipped_of = 
.inp_file = 
.eda_layers = 
.action_mask_layer = 
.nec_n1_draw_num = 
.nec_n1_rev = 
.nec_n2_draw_num = 
.nec_n2_rev = 
.nec_n3_target_lyr = 
.nec_n3_edit_level = 
.nec_n3_lyr_type = 
.nec_n3_prod_rev = 
.nec_n3_pol = 
.nec_cbnk_blank_name = 
.numbered_layer = 
.layer_class = 
.se_coupon_method = none
.se_coupon_direct = 0
.se_coupon_dist_type = spacing
.action_mask_layer_type = exclude
.out_angle = 0.0
.cdr_mirror = unset
.cdr_drill_type = unset
.out_polarity = positive
.etm_rotate = 0
.layer_hdi_type = core
.drill_layer_direction = top2bottom
.se_coupon_min_hits = 0
.se_coupon_dist = 0.000000
.se_coupon_min_size = 0.000000
.se_coupon_max_size = 0.000000
.se_coupon_slot_length = 0.000000
.se_coupon_slot_angle = 0.000000
.out_x_scale = 1.000000
.out_y_scale = 1.000000
.out_comp = 0.000000
.et_adjacency = 20.000000
.depth = 0.000000
.inp_x_scale = 1.000000
.inp_y_scale = 1.000000
.etm_thickness = 20.000000
.etm_prim_sink_h = 0.000000
.etm_sec_sink_h = 0.000000
.etm_prim_sink_r = 0.000000
.etm_sec_sink_r = 0.000000
.etm_prim_sink_s = 0.000000
.etm_sec_sink_s = 0.000000
.etm_shift_x = 0.000000
.etm_shift_y = 0.000000
.etm_step_x = 0.000000
.etm_step_y = 0.000000
.etm_height = 20.000000
.layer_dielectric = 0.000100
.copper_weight = 1.000000
film_version = 000
stretchx = 100.0000
stretchy = 100.0000
projectx = 
projecty = 
normal_distancex = 
normal_distancey = 
distancex = 
distancey = 
out_strchx = 
out_strchy = 
in_strchx = 
in_strchy = 
smc_strchx = 
smc_strchy = 
sms_strchx = 
sms_strchy = 
legc_strchx = 
legc_strchy = 
legs_strchx = 
legs_strchy = 
copper_area = 
plot_user = 000000
plot_version = 00000000
gce_version = 
save_code = 
film_bar_code = 
sht_normal_distancex = 
sht_normal_distancey = 
sht_stretchx = 100.0000
sht_stretchy = 100.0000
pcb_serial = 00
work_serial = 00
stackx = 0
stacky = 0
out_projectx = 
out_projecty = 
number = 0000000
out_project3x = 
out_project3y = 
scpad_stretchx = 100.0000
scpad_stretchy = 100.0000
pcs_x = 
pcs_y = 
array_x = 
array_y = 
layer_lock = lock

### steps/drc/layers/bd-1-9/attrlist
.out_mirror = no
.lpol_done = no
.cu_base = no
.etm_mirror = no
.comment = 
.flipped_of = 
.inp_file = 
.eda_layers = 
.action_mask_layer = 
.nec_n1_draw_num = 
.nec_n1_rev = 
.nec_n2_draw_num = 
.nec_n2_rev = 
.nec_n3_target_lyr = 
.nec_n3_edit_level = 
.nec_n3_lyr_type = 
.nec_n3_prod_rev = 
.nec_n3_pol = 
.nec_cbnk_blank_name = 
.numbered_layer = 
.layer_class = 
.se_coupon_method = none
.se_coupon_direct = 0
.se_coupon_dist_type = spacing
.action_mask_layer_type = exclude
.out_angle = 0.0
.cdr_mirror = unset
.cdr_drill_type = unset
.out_polarity = positive
.etm_rotate = 0
.layer_hdi_type = core
.drill_layer_direction = top2bottom
.se_coupon_min_hits = 0
.se_coupon_dist = 0.000000
.se_coupon_min_size = 0.000000
.se_coupon_max_size = 0.000000
.se_coupon_slot_length = 0.000000
.se_coupon_slot_angle = 0.000000
.out_x_scale = 1.000000
.out_y_scale = 1.000000
.out_comp = 0.000000
.et_adjacency = 20.000000
.depth = 0.000000
.inp_x_scale = 1.000000
.inp_y_scale = 1.000000
.etm_thickness = 20.000000
.etm_prim_sink_h = 0.000000
.etm_sec_sink_h = 0.000000
.etm_prim_sink_r = 0.000000
.etm_sec_sink_r = 0.000000
.etm_prim_sink_s = 0.000000
.etm_sec_sink_s = 0.000000
.etm_shift_x = 0.000000
.etm_shift_y = 0.000000
.etm_step_x = 0.000000
.etm_step_y = 0.000000
.etm_height = 20.000000
.layer_dielectric = 0.000100
.copper_weight = 1.000000
film_version = 000
stretchx = 100.0000
stretchy = 100.0000
projectx = 
projecty = 
normal_distancex = 
normal_distancey = 
distancex = 
distancey = 
out_strchx = 
out_strchy = 
in_strchx = 
in_strchy = 
smc_strchx = 
smc_strchy = 
sms_strchx = 
sms_strchy = 
legc_strchx = 
legc_strchy = 
legs_strchx = 
legs_strchy = 
copper_area = 
plot_user = 000000
plot_version = 00000000
gce_version = 
save_code = 
film_bar_code = 
sht_normal_distancex = 
sht_normal_distancey = 
sht_stretchx = 100.0000
sht_stretchy = 100.0000
pcb_serial = 00
work_serial = 00
stackx = 0
stacky = 0
out_projectx = 
out_projecty = 
number = 0000000
out_project3x = 
out_project3y = 
scpad_stretchx = 100.0000
scpad_stretchy = 100.0000
pcs_x = 
pcs_y = 
array_x = 
array_y = 
layer_lock = lock

### steps/drc/layers/bd-12-4/attrlist
.out_mirror = no
.lpol_done = no
.cu_base = no
.etm_mirror = no
.comment = 
.flipped_of = 
.inp_file = 
.eda_layers = 
.action_mask_layer = 
.nec_n1_draw_num = 
.nec_n1_rev = 
.nec_n2_draw_num = 
.nec_n2_rev = 
.nec_n3_target_lyr = 
.nec_n3_edit_level = 
.nec_n3_lyr_type = 
.nec_n3_prod_rev = 
.nec_n3_pol = 
.nec_cbnk_blank_name = 
.numbered_layer = 
.layer_class = 
.se_coupon_method = none
.se_coupon_direct = 0
.se_coupon_dist_type = spacing
.action_mask_layer_type = exclude
.out_angle = 0.0
.cdr_mirror = unset
.cdr_drill_type = unset
.out_polarity = positive
.etm_rotate = 0
.layer_hdi_type = core
.drill_layer_direction = top2bottom
.se_coupon_min_hits = 0
.se_coupon_dist = 0.000000
.se_coupon_min_size = 0.000000
.se_coupon_max_size = 0.000000
.se_coupon_slot_length = 0.000000
.se_coupon_slot_angle = 0.000000
.out_x_scale = 1.000000
.out_y_scale = 1.000000
.out_comp = 0.000000
.et_adjacency = 20.000000
.depth = 0.000000
.inp_x_scale = 1.000000
.inp_y_scale = 1.000000
.etm_thickness = 20.000000
.etm_prim_sink_h = 0.000000
.etm_sec_sink_h = 0.000000
.etm_prim_sink_r = 0.000000
.etm_sec_sink_r = 0.000000
.etm_prim_sink_s = 0.000000
.etm_sec_sink_s = 0.000000
.etm_shift_x = 0.000000
.etm_shift_y = 0.000000
.etm_step_x = 0.000000
.etm_step_y = 0.000000
.etm_height = 20.000000
.layer_dielectric = 0.000100
.copper_weight = 1.000000
film_version = 000
stretchx = 100.0000
stretchy = 100.0000
projectx = 
projecty = 
normal_distancex = 
normal_distancey = 
distancex = 
distancey = 
out_strchx = 
out_strchy = 
in_strchx = 
in_strchy = 
smc_strchx = 
smc_strchy = 
sms_strchx = 
sms_strchy = 
legc_strchx = 
legc_strchy = 
legs_strchx = 
legs_strchy = 
copper_area = 
plot_user = 000000
plot_version = 00000000
gce_version = 
save_code = 
film_bar_code = 
sht_normal_distancex = 
sht_normal_distancey = 
sht_stretchx = 100.0000
sht_stretchy = 100.0000
pcb_serial = 00
work_serial = 00
stackx = 0
stacky = 0
out_projectx = 
out_projecty = 
number = 0000000
out_project3x = 
out_project3y = 
scpad_stretchx = 100.0000
scpad_stretchy = 100.0000
pcs_x = 
pcs_y = 
array_x = 
array_y = 
layer_lock = lock

### steps/drc/layers/bd-12-6/attrlist
.out_mirror = no
.lpol_done = no
.cu_base = no
.etm_mirror = no
.comment = 
.flipped_of = 
.inp_file = 
.eda_layers = 
.action_mask_layer = 
.nec_n1_draw_num = 
.nec_n1_rev = 
.nec_n2_draw_num = 
.nec_n2_rev = 
.nec_n3_target_lyr = 
.nec_n3_edit_level = 
.nec_n3_lyr_type = 
.nec_n3_prod_rev = 
.nec_n3_pol = 
.nec_cbnk_blank_name = 
.numbered_layer = 
.layer_class = 
.se_coupon_method = none
.se_coupon_direct = 0
.se_coupon_dist_type = spacing
.action_mask_layer_type = exclude
.out_angle = 0.0
.cdr_mirror = unset
.cdr_drill_type = unset
.out_polarity = positive
.etm_rotate = 0
.layer_hdi_type = core
.drill_layer_direction = top2bottom
.se_coupon_min_hits = 0
.se_coupon_dist = 0.000000
.se_coupon_min_size = 0.000000
.se_coupon_max_size = 0.000000
.se_coupon_slot_length = 0.000000
.se_coupon_slot_angle = 0.000000
.out_x_scale = 1.000000
.out_y_scale = 1.000000
.out_comp = 0.000000
.et_adjacency = 20.000000
.depth = 0.000000
.inp_x_scale = 1.000000
.inp_y_scale = 1.000000
.etm_thickness = 20.000000
.etm_prim_sink_h = 0.000000
.etm_sec_sink_h = 0.000000
.etm_prim_sink_r = 0.000000
.etm_sec_sink_r = 0.000000
.etm_prim_sink_s = 0.000000
.etm_sec_sink_s = 0.000000
.etm_shift_x = 0.000000
.etm_shift_y = 0.000000
.etm_step_x = 0.000000
.etm_step_y = 0.000000
.etm_height = 20.000000
.layer_dielectric = 0.000100
.copper_weight = 1.000000
film_version = 000
stretchx = 100.0000
stretchy = 100.0000
projectx = 
projecty = 
normal_distancex = 
normal_distancey = 
distancex = 
distancey = 
out_strchx = 
out_strchy = 
in_strchx = 
in_strchy = 
smc_strchx = 
smc_strchy = 
sms_strchx = 
sms_strchy = 
legc_strchx = 
legc_strchy = 
legs_strchx = 
legs_strchy = 
copper_area = 
plot_user = 000000
plot_version = 00000000
gce_version = 
save_code = 
film_bar_code = 
sht_normal_distancex = 
sht_normal_distancey = 
sht_stretchx = 100.0000
sht_stretchy = 100.0000
pcb_serial = 00
work_serial = 00
stackx = 0
stacky = 0
out_projectx = 
out_projecty = 
number = 0000000
out_project3x = 
out_project3y = 
scpad_stretchx = 100.0000
scpad_stretchy = 100.0000
pcs_x = 
pcs_y = 
array_x = 
array_y = 
layer_lock = lock

### steps/drc/layers/c-paste/attrlist
.out_mirror = no
.lpol_done = no
.cu_base = no
.etm_mirror = no
.comment = 
.flipped_of = 
.inp_file = 
.eda_layers = "VIA CLASS:PASTEMASK_TOP"&"PIN:PASTEMASK_TOP"&"PACKAGE GEOMETRY:PASTEMASK_TOP"&"DRAWING FORMAT:PASTE_TOP"&"DRAWING FORMAT:PASTE_TOP_TL"&"DRAWING FORMAT:ALL_LAYERS_TL"
.action_mask_layer = 
.nec_n1_draw_num = 
.nec_n1_rev = 
.nec_n2_draw_num = 
.nec_n2_rev = 
.nec_n3_target_lyr = 
.nec_n3_edit_level = 
.nec_n3_lyr_type = 
.nec_n3_prod_rev = 
.nec_n3_pol = 
.nec_cbnk_blank_name = 
.numbered_layer = 
.layer_class = 
.se_coupon_method = none
.se_coupon_direct = 0
.se_coupon_dist_type = spacing
.action_mask_layer_type = exclude
.out_angle = 0.0
.cdr_mirror = unset
.cdr_drill_type = unset
.out_polarity = positive
.etm_rotate = 0
.layer_hdi_type = core
.drill_layer_direction = top2bottom
.se_coupon_min_hits = 0
.se_coupon_dist = 0.000000
.se_coupon_min_size = 0.000000
.se_coupon_max_size = 0.000000
.se_coupon_slot_length = 0.000000
.se_coupon_slot_angle = 0.000000
.out_x_scale = 1.000000
.out_y_scale = 1.000000
.out_comp = 0.000000
.et_adjacency = 20.000000
.depth = 0.000000
.inp_x_scale = 1.000000
.inp_y_scale = 1.000000
.etm_thickness = 20.000000
.etm_prim_sink_h = 0.000000
.etm_sec_sink_h = 0.000000
.etm_prim_sink_r = 0.000000
.etm_sec_sink_r = 0.000000
.etm_prim_sink_s = 0.000000
.etm_sec_sink_s = 0.000000
.etm_shift_x = 0.000000
.etm_shift_y = 0.000000
.etm_step_x = 0.000000
.etm_step_y = 0.000000
.etm_height = 20.000000
.layer_dielectric = 0.000000
.copper_weight = 1.000000
film_version = 000
stretchx = 100.0000
stretchy = 100.0000
projectx = 
projecty = 
normal_distancex = 
normal_distancey = 
distancex = 
distancey = 
out_strchx = 
out_strchy = 
in_strchx = 
in_strchy = 
smc_strchx = 
smc_strchy = 
sms_strchx = 
sms_strchy = 
legc_strchx = 
legc_strchy = 
legs_strchx = 
legs_strchy = 
copper_area = 
plot_user = 000000
plot_version = 00000000
gce_version = 
save_code = 
film_bar_code = 
sht_normal_distancex = 
sht_normal_distancey = 
sht_stretchx = 100.0000
sht_stretchy = 100.0000
pcb_serial = 00
work_serial = 00
stackx = 0
stacky = 0
out_projectx = 
out_projecty = 
number = 0000000
out_project3x = 
out_project3y = 
scpad_stretchx = 100.0000
scpad_stretchy = 100.0000
pcs_x = 
pcs_y = 
array_x = 
array_y = 
layer_lock = lock

### steps/drc/layers/drillo/attrlist
.out_mirror = no
.lpol_done = no
.cu_base = no
.etm_mirror = no
.comment = 
.flipped_of = 
.inp_file = 
.eda_layers = 
.action_mask_layer = 
.nec_n1_draw_num = 
.nec_n1_rev = 
.nec_n2_draw_num = 
.nec_n2_rev = 
.nec_n3_target_lyr = 
.nec_n3_edit_level = 
.nec_n3_lyr_type = 
.nec_n3_prod_rev = 
.nec_n3_pol = 
.nec_cbnk_blank_name = 
.numbered_layer = 
.layer_class = 
.se_coupon_method = none
.se_coupon_direct = 0
.se_coupon_dist_type = spacing
.action_mask_layer_type = exclude
.out_angle = 0.0
.cdr_mirror = unset
.cdr_drill_type = unset
.out_polarity = positive
.etm_rotate = 0
.layer_hdi_type = core
.drill_layer_direction = top2bottom
.se_coupon_min_hits = 0
.se_coupon_dist = 0.000000
.se_coupon_min_size = 0.000000
.se_coupon_max_size = 0.000000
.se_coupon_slot_length = 0.000000
.se_coupon_slot_angle = 0.000000
.out_x_scale = 1.000000
.out_y_scale = 1.000000
.out_comp = 0.000000
.et_adjacency = 20.000000
.depth = 0.000000
.inp_x_scale = 1.000000
.inp_y_scale = 1.000000
.etm_thickness = 20.000000
.etm_prim_sink_h = 0.000000
.etm_sec_sink_h = 0.000000
.etm_prim_sink_r = 0.000000
.etm_sec_sink_r = 0.000000
.etm_prim_sink_s = 0.000000
.etm_sec_sink_s = 0.000000
.etm_shift_x = 0.000000
.etm_shift_y = 0.000000
.etm_step_x = 0.000000
.etm_step_y = 0.000000
.etm_height = 20.000000
.layer_dielectric = 0.000100
.copper_weight = 1.000000
film_version = 000
stretchx = 100.0000
stretchy = 100.0000
projectx = 
projecty = 
normal_distancex = 
normal_distancey = 
distancex = 
distancey = 
out_strchx = 
out_strchy = 
in_strchx = 
in_strchy = 
smc_strchx = 
smc_strchy = 
sms_strchx = 
sms_strchy = 
legc_strchx = 
legc_strchy = 
legs_strchx = 
legs_strchy = 
copper_area = 
plot_user = 000000
plot_version = 00000000
gce_version = 
save_code = 
film_bar_code = 
sht_normal_distancex = 
sht_normal_distancey = 
sht_stretchx = 100.0000
sht_stretchy = 100.0000
pcb_serial = 00
work_serial = 00
stackx = 0
stacky = 0
out_projectx = 
out_projecty = 
number = 0000000
out_project3x = 
out_project3y = 
scpad_stretchx = 100.0000
scpad_stretchy = 100.0000
pcs_x = 
pcs_y = 
array_x = 
array_y = 
layer_lock = lock

### steps/drc/layers/l10/attrlist
.out_mirror = no
.lpol_done = no
.cu_base = no
.etm_mirror = no
.comment = 
.flipped_of = 
.inp_file = 
.eda_layers = "VIA CLASS:SIG10"&"PIN:SIG10"&"ETCH:SIG10"&"DRAWING FORMAT:ETCH_L10_TL"&"DRAWING FORMAT:ETCH_ALL_LAYERS_TL"&"DRAWING FORMAT:ALL_LAYERS_TL"
.action_mask_layer = 
.nec_n1_draw_num = 
.nec_n1_rev = 
.nec_n2_draw_num = 
.nec_n2_rev = 
.nec_n3_target_lyr = 
.nec_n3_edit_level = 
.nec_n3_lyr_type = 
.nec_n3_prod_rev = 
.nec_n3_pol = 
.nec_cbnk_blank_name = 
.numbered_layer = 
.layer_class = 
.se_coupon_method = none
.se_coupon_direct = 0
.se_coupon_dist_type = spacing
.action_mask_layer_type = exclude
.out_angle = 0.0
.cdr_mirror = unset
.cdr_drill_type = unset
.out_polarity = positive
.etm_rotate = 0
.layer_hdi_type = core
.drill_layer_direction = top2bottom
.se_coupon_min_hits = 0
.se_coupon_dist = 0.000000
.se_coupon_min_size = 0.000000
.se_coupon_max_size = 0.000000
.se_coupon_slot_length = 0.000000
.se_coupon_slot_angle = 0.000000
.out_x_scale = 1.000000
.out_y_scale = 1.000000
.out_comp = 0.000000
.et_adjacency = 20.000000
.depth = 0.000000
.inp_x_scale = 1.000000
.inp_y_scale = 1.000000
.etm_thickness = 20.000000
.etm_prim_sink_h = 0.000000
.etm_sec_sink_h = 0.000000
.etm_prim_sink_r = 0.000000
.etm_sec_sink_r = 0.000000
.etm_prim_sink_s = 0.000000
.etm_sec_sink_s = 0.000000
.etm_shift_x = 0.000000
.etm_shift_y = 0.000000
.etm_step_x = 0.000000
.etm_step_y = 0.000000
.etm_height = 20.000000
.layer_dielectric = 0.003000
.copper_weight = 1.000000
film_version = 000
stretchx = 100.0000
stretchy = 100.0000
projectx = 
projecty = 
normal_distancex = 
normal_distancey = 
distancex = 
distancey = 
out_strchx = 
out_strchy = 
in_strchx = 
in_strchy = 
smc_strchx = 
smc_strchy = 
sms_strchx = 
sms_strchy = 
legc_strchx = 
legc_strchy = 
legs_strchx = 
legs_strchy = 
copper_area = 
plot_user = 000000
plot_version = 00000000
gce_version = 
save_code = 
film_bar_code = 
sht_normal_distancex = 
sht_normal_distancey = 
sht_stretchx = 100.0000
sht_stretchy = 100.0000
pcb_serial = 00
work_serial = 00
stackx = 0
stacky = 0
out_projectx = 
out_projecty = 
number = 0000000
out_project3x = 
out_project3y = 
scpad_stretchx = 100.0000
scpad_stretchy = 100.0000
pcs_x = 
pcs_y = 
array_x = 
array_y = 
layer_lock = lock

### steps/drc/layers/l11/attrlist
.out_mirror = no
.lpol_done = no
.cu_base = no
.etm_mirror = no
.comment = 
.flipped_of = 
.inp_file = 
.eda_layers = "ANTI ETCH:ALL"&"ANTI ETCH:GND11"&"VIA CLASS:GND11"&"PIN:GND11"&"ETCH:GND11"&"DRAWING FORMAT:ETCH_L11_TL"&"DRAWING FORMAT:ETCH_ALL_LAYERS_TL"&"DRAWING FORMAT:ALL_LAYERS_TL"
.action_mask_layer = 
.nec_n1_draw_num = 
.nec_n1_rev = 
.nec_n2_draw_num = 
.nec_n2_rev = 
.nec_n3_target_lyr = 
.nec_n3_edit_level = 
.nec_n3_lyr_type = 
.nec_n3_prod_rev = 
.nec_n3_pol = 
.nec_cbnk_blank_name = 
.numbered_layer = 
.layer_class = 
.se_coupon_method = none
.se_coupon_direct = 0
.se_coupon_dist_type = spacing
.action_mask_layer_type = exclude
.out_angle = 0.0
.cdr_mirror = unset
.cdr_drill_type = unset
.out_polarity = positive
.etm_rotate = 0
.layer_hdi_type = core
.drill_layer_direction = top2bottom
.se_coupon_min_hits = 0
.se_coupon_dist = 0.000000
.se_coupon_min_size = 0.000000
.se_coupon_max_size = 0.000000
.se_coupon_slot_length = 0.000000
.se_coupon_slot_angle = 0.000000
.out_x_scale = 1.000000
.out_y_scale = 1.000000
.out_comp = 0.000000
.et_adjacency = 20.000000
.depth = 0.000000
.inp_x_scale = 1.000000
.inp_y_scale = 1.000000
.etm_thickness = 20.000000
.etm_prim_sink_h = 0.000000
.etm_sec_sink_h = 0.000000
.etm_prim_sink_r = 0.000000
.etm_sec_sink_r = 0.000000
.etm_prim_sink_s = 0.000000
.etm_sec_sink_s = 0.000000
.etm_shift_x = 0.000000
.etm_shift_y = 0.000000
.etm_step_x = 0.000000
.etm_step_y = 0.000000
.etm_height = 20.000000
.layer_dielectric = 0.003600
.copper_weight = 1.000000
film_version = 000
stretchx = 100.0000
stretchy = 100.0000
projectx = 
projecty = 
normal_distancex = 
normal_distancey = 
distancex = 
distancey = 
out_strchx = 
out_strchy = 
in_strchx = 
in_strchy = 
smc_strchx = 
smc_strchy = 
sms_strchx = 
sms_strchy = 
legc_strchx = 
legc_strchy = 
legs_strchx = 
legs_strchy = 
copper_area = 
plot_user = 000000
plot_version = 00000000
gce_version = 
save_code = 
film_bar_code = 
sht_normal_distancex = 
sht_normal_distancey = 
sht_stretchx = 100.0000
sht_stretchy = 100.0000
pcb_serial = 00
work_serial = 00
stackx = 0
stacky = 0
out_projectx = 
out_projecty = 
number = 0000000
out_project3x = 
out_project3y = 
scpad_stretchx = 100.0000
scpad_stretchy = 100.0000
pcs_x = 
pcs_y = 
array_x = 
array_y = 
layer_lock = lock

### steps/drc/layers/l2/attrlist
.out_mirror = no
.lpol_done = no
.cu_base = no
.etm_mirror = no
.comment = 
.flipped_of = 
.inp_file = 
.eda_layers = "ANTI ETCH:ALL"&"ANTI ETCH:GND2"&"VIA CLASS:GND2"&"PIN:GND2"&"ETCH:GND2"&"DRAWING FORMAT:ETCH_L2_TL"&"DRAWING FORMAT:ETCH_ALL_LAYERS_TL"&"DRAWING FORMAT:ALL_LAYERS_TL"
.action_mask_layer = 
.nec_n1_draw_num = 
.nec_n1_rev = 
.nec_n2_draw_num = 
.nec_n2_rev = 
.nec_n3_target_lyr = 
.nec_n3_edit_level = 
.nec_n3_lyr_type = 
.nec_n3_prod_rev = 
.nec_n3_pol = 
.nec_cbnk_blank_name = 
.numbered_layer = 
.layer_class = 
.se_coupon_method = none
.se_coupon_direct = 0
.se_coupon_dist_type = spacing
.action_mask_layer_type = exclude
.out_angle = 0.0
.cdr_mirror = unset
.cdr_drill_type = unset
.out_polarity = positive
.etm_rotate = 0
.layer_hdi_type = core
.drill_layer_direction = top2bottom
.se_coupon_min_hits = 0
.se_coupon_dist = 0.000000
.se_coupon_min_size = 0.000000
.se_coupon_max_size = 0.000000
.se_coupon_slot_length = 0.000000
.se_coupon_slot_angle = 0.000000
.out_x_scale = 1.000000
.out_y_scale = 1.000000
.out_comp = 0.000000
.et_adjacency = 20.000000
.depth = 0.000000
.inp_x_scale = 1.000000
.inp_y_scale = 1.000000
.etm_thickness = 20.000000
.etm_prim_sink_h = 0.000000
.etm_sec_sink_h = 0.000000
.etm_prim_sink_r = 0.000000
.etm_sec_sink_r = 0.000000
.etm_prim_sink_s = 0.000000
.etm_sec_sink_s = 0.000000
.etm_shift_x = 0.000000
.etm_shift_y = 0.000000
.etm_step_x = 0.000000
.etm_step_y = 0.000000
.etm_height = 20.000000
.layer_dielectric = 0.003000
.copper_weight = 1.000000
film_version = 000
stretchx = 100.0000
stretchy = 100.0000
projectx = 
projecty = 
normal_distancex = 
normal_distancey = 
distancex = 
distancey = 
out_strchx = 
out_strchy = 
in_strchx = 
in_strchy = 
smc_strchx = 
smc_strchy = 
sms_strchx = 
sms_strchy = 
legc_strchx = 
legc_strchy = 
legs_strchx = 
legs_strchy = 
copper_area = 
plot_user = 000000
plot_version = 00000000
gce_version = 
save_code = 
film_bar_code = 
sht_normal_distancex = 
sht_normal_distancey = 
sht_stretchx = 100.0000
sht_stretchy = 100.0000
pcb_serial = 00
work_serial = 00
stackx = 0
stacky = 0
out_projectx = 
out_projecty = 
number = 0000000
out_project3x = 
out_project3y = 
scpad_stretchx = 100.0000
scpad_stretchy = 100.0000
pcs_x = 
pcs_y = 
array_x = 
array_y = 
layer_lock = lock

### steps/drc/layers/l3/attrlist
.out_mirror = no
.lpol_done = no
.cu_base = no
.etm_mirror = no
.comment = 
.flipped_of = 
.inp_file = 
.eda_layers = "VIA CLASS:SIG3"&"PIN:SIG3"&"ETCH:SIG3"&"DRAWING FORMAT:ETCH_L3_TL"&"DRAWING FORMAT:ETCH_ALL_LAYERS_TL"&"DRAWING FORMAT:ALL_LAYERS_TL"
.action_mask_layer = 
.nec_n1_draw_num = 
.nec_n1_rev = 
.nec_n2_draw_num = 
.nec_n2_rev = 
.nec_n3_target_lyr = 
.nec_n3_edit_level = 
.nec_n3_lyr_type = 
.nec_n3_prod_rev = 
.nec_n3_pol = 
.nec_cbnk_blank_name = 
.numbered_layer = 
.layer_class = 
.se_coupon_method = none
.se_coupon_direct = 0
.se_coupon_dist_type = spacing
.action_mask_layer_type = exclude
.out_angle = 0.0
.cdr_mirror = unset
.cdr_drill_type = unset
.out_polarity = positive
.etm_rotate = 0
.layer_hdi_type = core
.drill_layer_direction = top2bottom
.se_coupon_min_hits = 0
.se_coupon_dist = 0.000000
.se_coupon_min_size = 0.000000
.se_coupon_max_size = 0.000000
.se_coupon_slot_length = 0.000000
.se_coupon_slot_angle = 0.000000
.out_x_scale = 1.000000
.out_y_scale = 1.000000
.out_comp = 0.000000
.et_adjacency = 20.000000
.depth = 0.000000
.inp_x_scale = 1.000000
.inp_y_scale = 1.000000
.etm_thickness = 20.000000
.etm_prim_sink_h = 0.000000
.etm_sec_sink_h = 0.000000
.etm_prim_sink_r = 0.000000
.etm_sec_sink_r = 0.000000
.etm_prim_sink_s = 0.000000
.etm_sec_sink_s = 0.000000
.etm_shift_x = 0.000000
.etm_shift_y = 0.000000
.etm_step_x = 0.000000
.etm_step_y = 0.000000
.etm_height = 20.000000
.layer_dielectric = 0.004200
.copper_weight = 1.000000
film_version = 000
stretchx = 100.0000
stretchy = 100.0000
projectx = 
projecty = 
normal_distancex = 
normal_distancey = 
distancex = 
distancey = 
out_strchx = 
out_strchy = 
in_strchx = 
in_strchy = 
smc_strchx = 
smc_strchy = 
sms_strchx = 
sms_strchy = 
legc_strchx = 
legc_strchy = 
legs_strchx = 
legs_strchy = 
copper_area = 
plot_user = 000000
plot_version = 00000000
gce_version = 
save_code = 
film_bar_code = 
sht_normal_distancex = 
sht_normal_distancey = 
sht_stretchx = 100.0000
sht_stretchy = 100.0000
pcb_serial = 00
work_serial = 00
stackx = 0
stacky = 0
out_projectx = 
out_projecty = 
number = 0000000
out_project3x = 
out_project3y = 
scpad_stretchx = 100.0000
scpad_stretchy = 100.0000
pcs_x = 
pcs_y = 
array_x = 
array_y = 
layer_lock = lock

### steps/drc/layers/l4/attrlist
.out_mirror = no
.lpol_done = no
.cu_base = no
.etm_mirror = no
.comment = 
.flipped_of = 
.inp_file = 
.eda_layers = "ANTI ETCH:ALL"&"ANTI ETCH:GND4"&"VIA CLASS:GND4"&"PIN:GND4"&"ETCH:GND4"&"DRAWING FORMAT:ETCH_L4_TL"&"DRAWING FORMAT:ETCH_ALL_LAYERS_TL"&"DRAWING FORMAT:ALL_LAYERS_TL"
.action_mask_layer = 
.nec_n1_draw_num = 
.nec_n1_rev = 
.nec_n2_draw_num = 
.nec_n2_rev = 
.nec_n3_target_lyr = 
.nec_n3_edit_level = 
.nec_n3_lyr_type = 
.nec_n3_prod_rev = 
.nec_n3_pol = 
.nec_cbnk_blank_name = 
.numbered_layer = 
.layer_class = 
.se_coupon_method = none
.se_coupon_direct = 0
.se_coupon_dist_type = spacing
.action_mask_layer_type = exclude
.out_angle = 0.0
.cdr_mirror = unset
.cdr_drill_type = unset
.out_polarity = positive
.etm_rotate = 0
.layer_hdi_type = core
.drill_layer_direction = top2bottom
.se_coupon_min_hits = 0
.se_coupon_dist = 0.000000
.se_coupon_min_size = 0.000000
.se_coupon_max_size = 0.000000
.se_coupon_slot_length = 0.000000
.se_coupon_slot_angle = 0.000000
.out_x_scale = 1.000000
.out_y_scale = 1.000000
.out_comp = 0.000000
.et_adjacency = 20.000000
.depth = 0.000000
.inp_x_scale = 1.000000
.inp_y_scale = 1.000000
.etm_thickness = 20.000000
.etm_prim_sink_h = 0.000000
.etm_sec_sink_h = 0.000000
.etm_prim_sink_r = 0.000000
.etm_sec_sink_r = 0.000000
.etm_prim_sink_s = 0.000000
.etm_sec_sink_s = 0.000000
.etm_shift_x = 0.000000
.etm_shift_y = 0.000000
.etm_step_x = 0.000000
.etm_step_y = 0.000000
.etm_height = 20.000000
.layer_dielectric = 0.003000
.copper_weight = 1.000000
film_version = 000
stretchx = 100.0000
stretchy = 100.0000
projectx = 
projecty = 
normal_distancex = 
normal_distancey = 
distancex = 
distancey = 
out_strchx = 
out_strchy = 
in_strchx = 
in_strchy = 
smc_strchx = 
smc_strchy = 
sms_strchx = 
sms_strchy = 
legc_strchx = 
legc_strchy = 
legs_strchx = 
legs_strchy = 
copper_area = 
plot_user = 000000
plot_version = 00000000
gce_version = 
save_code = 
film_bar_code = 
sht_normal_distancex = 
sht_normal_distancey = 
sht_stretchx = 100.0000
sht_stretchy = 100.0000
pcb_serial = 00
work_serial = 00
stackx = 0
stacky = 0
out_projectx = 
out_projecty = 
number = 0000000
out_project3x = 
out_project3y = 
scpad_stretchx = 100.0000
scpad_stretchy = 100.0000
pcs_x = 
pcs_y = 
array_x = 
array_y = 
layer_lock = lock

### steps/drc/layers/l5/attrlist
.out_mirror = no
.lpol_done = no
.cu_base = no
.etm_mirror = no
.comment = 
.flipped_of = 
.inp_file = 
.eda_layers = "VIA CLASS:SIG5"&"PIN:SIG5"&"ETCH:SIG5"&"DRAWING FORMAT:ETCH_L5_TL"&"DRAWING FORMAT:ETCH_ALL_LAYERS_TL"&"DRAWING FORMAT:ALL_LAYERS_TL"
.action_mask_layer = 
.nec_n1_draw_num = 
.nec_n1_rev = 
.nec_n2_draw_num = 
.nec_n2_rev = 
.nec_n3_target_lyr = 
.nec_n3_edit_level = 
.nec_n3_lyr_type = 
.nec_n3_prod_rev = 
.nec_n3_pol = 
.nec_cbnk_blank_name = 
.numbered_layer = 
.layer_class = 
.se_coupon_method = none
.se_coupon_direct = 0
.se_coupon_dist_type = spacing
.action_mask_layer_type = exclude
.out_angle = 0.0
.cdr_mirror = unset
.cdr_drill_type = unset
.out_polarity = positive
.etm_rotate = 0
.layer_hdi_type = core
.drill_layer_direction = top2bottom
.se_coupon_min_hits = 0
.se_coupon_dist = 0.000000
.se_coupon_min_size = 0.000000
.se_coupon_max_size = 0.000000
.se_coupon_slot_length = 0.000000
.se_coupon_slot_angle = 0.000000
.out_x_scale = 1.000000
.out_y_scale = 1.000000
.out_comp = 0.000000
.et_adjacency = 20.000000
.depth = 0.000000
.inp_x_scale = 1.000000
.inp_y_scale = 1.000000
.etm_thickness = 20.000000
.etm_prim_sink_h = 0.000000
.etm_sec_sink_h = 0.000000
.etm_prim_sink_r = 0.000000
.etm_sec_sink_r = 0.000000
.etm_prim_sink_s = 0.000000
.etm_sec_sink_s = 0.000000
.etm_shift_x = 0.000000
.etm_shift_y = 0.000000
.etm_step_x = 0.000000
.etm_step_y = 0.000000
.etm_height = 20.000000
.layer_dielectric = 0.004200
.copper_weight = 1.000000
film_version = 000
stretchx = 100.0000
stretchy = 100.0000
projectx = 
projecty = 
normal_distancex = 
normal_distancey = 
distancex = 
distancey = 
out_strchx = 
out_strchy = 
in_strchx = 
in_strchy = 
smc_strchx = 
smc_strchy = 
sms_strchx = 
sms_strchy = 
legc_strchx = 
legc_strchy = 
legs_strchx = 
legs_strchy = 
copper_area = 
plot_user = 000000
plot_version = 00000000
gce_version = 
save_code = 
film_bar_code = 
sht_normal_distancex = 
sht_normal_distancey = 
sht_stretchx = 100.0000
sht_stretchy = 100.0000
pcb_serial = 00
work_serial = 00
stackx = 0
stacky = 0
out_projectx = 
out_projecty = 
number = 0000000
out_project3x = 
out_project3y = 
scpad_stretchx = 100.0000
scpad_stretchy = 100.0000
pcs_x = 
pcs_y = 
array_x = 
array_y = 
layer_lock = lock

### steps/drc/layers/l6/attrlist
.out_mirror = no
.lpol_done = no
.cu_base = no
.etm_mirror = no
.comment = 
.flipped_of = 
.inp_file = 
.eda_layers = "ANTI ETCH:ALL"&"ANTI ETCH:GND6"&"VIA CLASS:GND6"&"PIN:GND6"&"ETCH:GND6"&"DRAWING FORMAT:ETCH_L6_TL"&"DRAWING FORMAT:ETCH_ALL_LAYERS_TL"&"DRAWING FORMAT:ALL_LAYERS_TL"
.action_mask_layer = 
.nec_n1_draw_num = 
.nec_n1_rev = 
.nec_n2_draw_num = 
.nec_n2_rev = 
.nec_n3_target_lyr = 
.nec_n3_edit_level = 
.nec_n3_lyr_type = 
.nec_n3_prod_rev = 
.nec_n3_pol = 
.nec_cbnk_blank_name = 
.numbered_layer = 
.layer_class = 
.se_coupon_method = none
.se_coupon_direct = 0
.se_coupon_dist_type = spacing
.action_mask_layer_type = exclude
.out_angle = 0.0
.cdr_mirror = unset
.cdr_drill_type = unset
.out_polarity = positive
.etm_rotate = 0
.layer_hdi_type = core
.drill_layer_direction = top2bottom
.se_coupon_min_hits = 0
.se_coupon_dist = 0.000000
.se_coupon_min_size = 0.000000
.se_coupon_max_size = 0.000000
.se_coupon_slot_length = 0.000000
.se_coupon_slot_angle = 0.000000
.out_x_scale = 1.000000
.out_y_scale = 1.000000
.out_comp = 0.000000
.et_adjacency = 20.000000
.depth = 0.000000
.inp_x_scale = 1.000000
.inp_y_scale = 1.000000
.etm_thickness = 20.000000
.etm_prim_sink_h = 0.000000
.etm_sec_sink_h = 0.000000
.etm_prim_sink_r = 0.000000
.etm_sec_sink_r = 0.000000
.etm_prim_sink_s = 0.000000
.etm_sec_sink_s = 0.000000
.etm_shift_x = 0.000000
.etm_shift_y = 0.000000
.etm_step_x = 0.000000
.etm_step_y = 0.000000
.etm_height = 20.000000
.layer_dielectric = 0.009000
.copper_weight = 1.000000
film_version = 000
stretchx = 100.0000
stretchy = 100.0000
projectx = 
projecty = 
normal_distancex = 
normal_distancey = 
distancex = 
distancey = 
out_strchx = 
out_strchy = 
in_strchx = 
in_strchy = 
smc_strchx = 
smc_strchy = 
sms_strchx = 
sms_strchy = 
legc_strchx = 
legc_strchy = 
legs_strchx = 
legs_strchy = 
copper_area = 
plot_user = 000000
plot_version = 00000000
gce_version = 
save_code = 
film_bar_code = 
sht_normal_distancex = 
sht_normal_distancey = 
sht_stretchx = 100.0000
sht_stretchy = 100.0000
pcb_serial = 00
work_serial = 00
stackx = 0
stacky = 0
out_projectx = 
out_projecty = 
number = 0000000
out_project3x = 
out_project3y = 
scpad_stretchx = 100.0000
scpad_stretchy = 100.0000
pcs_x = 
pcs_y = 
array_x = 
array_y = 
layer_lock = lock

### steps/drc/layers/l7/attrlist
.out_mirror = no
.lpol_done = no
.cu_base = no
.etm_mirror = no
.comment = 
.flipped_of = 
.inp_file = 
.eda_layers = "ANTI ETCH:ALL"&"ANTI ETCH:PWR7"&"VIA CLASS:PWR7"&"PIN:PWR7"&"ETCH:PWR7"&"DRAWING FORMAT:ETCH_L7_TL"&"DRAWING FORMAT:ETCH_ALL_LAYERS_TL"&"DRAWING FORMAT:ALL_LAYERS_TL"
.action_mask_layer = 
.nec_n1_draw_num = 
.nec_n1_rev = 
.nec_n2_draw_num = 
.nec_n2_rev = 
.nec_n3_target_lyr = 
.nec_n3_edit_level = 
.nec_n3_lyr_type = 
.nec_n3_prod_rev = 
.nec_n3_pol = 
.nec_cbnk_blank_name = 
.numbered_layer = 
.layer_class = 
.se_coupon_method = none
.se_coupon_direct = 0
.se_coupon_dist_type = spacing
.action_mask_layer_type = exclude
.out_angle = 0.0
.cdr_mirror = unset
.cdr_drill_type = unset
.out_polarity = positive
.etm_rotate = 0
.layer_hdi_type = core
.drill_layer_direction = top2bottom
.se_coupon_min_hits = 0
.se_coupon_dist = 0.000000
.se_coupon_min_size = 0.000000
.se_coupon_max_size = 0.000000
.se_coupon_slot_length = 0.000000
.se_coupon_slot_angle = 0.000000
.out_x_scale = 1.000000
.out_y_scale = 1.000000
.out_comp = 0.000000
.et_adjacency = 20.000000
.depth = 0.000000
.inp_x_scale = 1.000000
.inp_y_scale = 1.000000
.etm_thickness = 20.000000
.etm_prim_sink_h = 0.000000
.etm_sec_sink_h = 0.000000
.etm_prim_sink_r = 0.000000
.etm_sec_sink_r = 0.000000
.etm_prim_sink_s = 0.000000
.etm_sec_sink_s = 0.000000
.etm_shift_x = 0.000000
.etm_shift_y = 0.000000
.etm_step_x = 0.000000
.etm_step_y = 0.000000
.etm_height = 20.000000
.layer_dielectric = 0.004200
.copper_weight = 1.000000
film_version = 000
stretchx = 100.0000
stretchy = 100.0000
projectx = 
projecty = 
normal_distancex = 
normal_distancey = 
distancex = 
distancey = 
out_strchx = 
out_strchy = 
in_strchx = 
in_strchy = 
smc_strchx = 
smc_strchy = 
sms_strchx = 
sms_strchy = 
legc_strchx = 
legc_strchy = 
legs_strchx = 
legs_strchy = 
copper_area = 
plot_user = 000000
plot_version = 00000000
gce_version = 
save_code = 
film_bar_code = 
sht_normal_distancex = 
sht_normal_distancey = 
sht_stretchx = 100.0000
sht_stretchy = 100.0000
pcb_serial = 00
work_serial = 00
stackx = 0
stacky = 0
out_projectx = 
out_projecty = 
number = 0000000
out_project3x = 
out_project3y = 
scpad_stretchx = 100.0000
scpad_stretchy = 100.0000
pcs_x = 
pcs_y = 
array_x = 
array_y = 
layer_lock = lock

### steps/drc/layers/l8/attrlist
.out_mirror = no
.lpol_done = no
.cu_base = no
.etm_mirror = no
.comment = 
.flipped_of = 
.inp_file = 
.eda_layers = "ANTI ETCH:ALL"&"ANTI ETCH:PWR8"&"VIA CLASS:PWR8"&"PIN:PWR8"&"ETCH:PWR8"&"DRAWING FORMAT:ETCH_L8_TL"&"DRAWING FORMAT:ETCH_ALL_LAYERS_TL"&"DRAWING FORMAT:ALL_LAYERS_TL"
.action_mask_layer = 
.nec_n1_draw_num = 
.nec_n1_rev = 
.nec_n2_draw_num = 
.nec_n2_rev = 
.nec_n3_target_lyr = 
.nec_n3_edit_level = 
.nec_n3_lyr_type = 
.nec_n3_prod_rev = 
.nec_n3_pol = 
.nec_cbnk_blank_name = 
.numbered_layer = 
.layer_class = 
.se_coupon_method = none
.se_coupon_direct = 0
.se_coupon_dist_type = spacing
.action_mask_layer_type = exclude
.out_angle = 0.0
.cdr_mirror = unset
.cdr_drill_type = unset
.out_polarity = positive
.etm_rotate = 0
.layer_hdi_type = core
.drill_layer_direction = top2bottom
.se_coupon_min_hits = 0
.se_coupon_dist = 0.000000
.se_coupon_min_size = 0.000000
.se_coupon_max_size = 0.000000
.se_coupon_slot_length = 0.000000
.se_coupon_slot_angle = 0.000000
.out_x_scale = 1.000000
.out_y_scale = 1.000000
.out_comp = 0.000000
.et_adjacency = 20.000000
.depth = 0.000000
.inp_x_scale = 1.000000
.inp_y_scale = 1.000000
.etm_thickness = 20.000000
.etm_prim_sink_h = 0.000000
.etm_sec_sink_h = 0.000000
.etm_prim_sink_r = 0.000000
.etm_sec_sink_r = 0.000000
.etm_prim_sink_s = 0.000000
.etm_sec_sink_s = 0.000000
.etm_shift_x = 0.000000
.etm_shift_y = 0.000000
.etm_step_x = 0.000000
.etm_step_y = 0.000000
.etm_height = 20.000000
.layer_dielectric = 0.003000
.copper_weight = 1.000000
film_version = 000
stretchx = 100.0000
stretchy = 100.0000
projectx = 
projecty = 
normal_distancex = 
normal_distancey = 
distancex = 
distancey = 
out_strchx = 
out_strchy = 
in_strchx = 
in_strchy = 
smc_strchx = 
smc_strchy = 
sms_strchx = 
sms_strchy = 
legc_strchx = 
legc_strchy = 
legs_strchx = 
legs_strchy = 
copper_area = 
plot_user = 000000
plot_version = 00000000
gce_version = 
save_code = 
film_bar_code = 
sht_normal_distancex = 
sht_normal_distancey = 
sht_stretchx = 100.0000
sht_stretchy = 100.0000
pcb_serial = 00
work_serial = 00
stackx = 0
stacky = 0
out_projectx = 
out_projecty = 
number = 0000000
out_project3x = 
out_project3y = 
scpad_stretchx = 100.0000
scpad_stretchy = 100.0000
pcs_x = 
pcs_y = 
array_x = 
array_y = 
layer_lock = lock

### steps/drc/layers/l9/attrlist
.out_mirror = no
.lpol_done = no
.cu_base = no
.etm_mirror = no
.comment = 
.flipped_of = 
.inp_file = 
.eda_layers = "ANTI ETCH:ALL"&"ANTI ETCH:GND9"&"VIA CLASS:GND9"&"PIN:GND9"&"ETCH:GND9"&"DRAWING FORMAT:ETCH_L9_TL"&"DRAWING FORMAT:ETCH_ALL_LAYERS_TL"&"DRAWING FORMAT:ALL_LAYERS_TL"
.action_mask_layer = 
.nec_n1_draw_num = 
.nec_n1_rev = 
.nec_n2_draw_num = 
.nec_n2_rev = 
.nec_n3_target_lyr = 
.nec_n3_edit_level = 
.nec_n3_lyr_type = 
.nec_n3_prod_rev = 
.nec_n3_pol = 
.nec_cbnk_blank_name = 
.numbered_layer = 
.layer_class = 
.se_coupon_method = none
.se_coupon_direct = 0
.se_coupon_dist_type = spacing
.action_mask_layer_type = exclude
.out_angle = 0.0
.cdr_mirror = unset
.cdr_drill_type = unset
.out_polarity = positive
.etm_rotate = 0
.layer_hdi_type = core
.drill_layer_direction = top2bottom
.se_coupon_min_hits = 0
.se_coupon_dist = 0.000000
.se_coupon_min_size = 0.000000
.se_coupon_max_size = 0.000000
.se_coupon_slot_length = 0.000000
.se_coupon_slot_angle = 0.000000
.out_x_scale = 1.000000
.out_y_scale = 1.000000
.out_comp = 0.000000
.et_adjacency = 20.000000
.depth = 0.000000
.inp_x_scale = 1.000000
.inp_y_scale = 1.000000
.etm_thickness = 20.000000
.etm_prim_sink_h = 0.000000
.etm_sec_sink_h = 0.000000
.etm_prim_sink_r = 0.000000
.etm_sec_sink_r = 0.000000
.etm_prim_sink_s = 0.000000
.etm_sec_sink_s = 0.000000
.etm_shift_x = 0.000000
.etm_shift_y = 0.000000
.etm_step_x = 0.000000
.etm_step_y = 0.000000
.etm_height = 20.000000
.layer_dielectric = 0.004200
.copper_weight = 1.000000
film_version = 000
stretchx = 100.0000
stretchy = 100.0000
projectx = 
projecty = 
normal_distancex = 
normal_distancey = 
distancex = 
distancey = 
out_strchx = 
out_strchy = 
in_strchx = 
in_strchy = 
smc_strchx = 
smc_strchy = 
sms_strchx = 
sms_strchy = 
legc_strchx = 
legc_strchy = 
legs_strchx = 
legs_strchy = 
copper_area = 
plot_user = 000000
plot_version = 00000000
gce_version = 
save_code = 
film_bar_code = 
sht_normal_distancex = 
sht_normal_distancey = 
sht_stretchx = 100.0000
sht_stretchy = 100.0000
pcb_serial = 00
work_serial = 00
stackx = 0
stacky = 0
out_projectx = 
out_projecty = 
number = 0000000
out_project3x = 
out_project3y = 
scpad_stretchx = 100.0000
scpad_stretchy = 100.0000
pcs_x = 
pcs_y = 
array_x = 
array_y = 
layer_lock = lock

### steps/drc/layers/lc/attrlist
.out_mirror = no
.lpol_done = no
.cu_base = no
.etm_mirror = no
.comment = 
.flipped_of = 
.inp_file = 
.eda_layers = "VIA CLASS:TOP"&"PIN:TOP"&"ETCH:TOP"&"DRAWING FORMAT:TOP"&"DRAWING FORMAT:ETCH_TOP_TL"&"DRAWING FORMAT:ETCH_ALL_LAYERS_TL"&"DRAWING FORMAT:ALL_LAYERS_TL"
.action_mask_layer = 
.nec_n1_draw_num = 
.nec_n1_rev = 
.nec_n2_draw_num = 
.nec_n2_rev = 
.nec_n3_target_lyr = 
.nec_n3_edit_level = 
.nec_n3_lyr_type = 
.nec_n3_prod_rev = 
.nec_n3_pol = 
.nec_cbnk_blank_name = 
.numbered_layer = 
.layer_class = 
.se_coupon_method = none
.se_coupon_direct = 0
.se_coupon_dist_type = spacing
.action_mask_layer_type = exclude
.out_angle = 0.0
.cdr_mirror = unset
.cdr_drill_type = unset
.out_polarity = positive
.etm_rotate = 0
.layer_hdi_type = core
.drill_layer_direction = top2bottom
.se_coupon_min_hits = 0
.se_coupon_dist = 0.000000
.se_coupon_min_size = 0.000000
.se_coupon_max_size = 0.000000
.se_coupon_slot_length = 0.000000
.se_coupon_slot_angle = 0.000000
.out_x_scale = 1.000000
.out_y_scale = 1.000000
.out_comp = 0.000000
.et_adjacency = 20.000000
.depth = 0.000000
.inp_x_scale = 1.000000
.inp_y_scale = 1.000000
.etm_thickness = 20.000000
.etm_prim_sink_h = 0.000000
.etm_sec_sink_h = 0.000000
.etm_prim_sink_r = 0.000000
.etm_sec_sink_r = 0.000000
.etm_prim_sink_s = 0.000000
.etm_sec_sink_s = 0.000000
.etm_shift_x = 0.000000
.etm_shift_y = 0.000000
.etm_step_x = 0.000000
.etm_step_y = 0.000000
.etm_height = 20.000000
.layer_dielectric = 0.003600
.copper_weight = 1.000000
film_version = 000
stretchx = 100.0000
stretchy = 100.0000
projectx = 
projecty = 
normal_distancex = 
normal_distancey = 
distancex = 
distancey = 
out_strchx = 
out_strchy = 
in_strchx = 
in_strchy = 
smc_strchx = 
smc_strchy = 
sms_strchx = 
sms_strchy = 
legc_strchx = 
legc_strchy = 
legs_strchx = 
legs_strchy = 
copper_area = 
plot_user = 000000
plot_version = 00000000
gce_version = 
save_code = 
film_bar_code = 
sht_normal_distancex = 
sht_normal_distancey = 
sht_stretchx = 100.0000
sht_stretchy = 100.0000
pcb_serial = 00
work_serial = 00
stackx = 0
stacky = 0
out_projectx = 
out_projecty = 
number = 0000000
out_project3x = 
out_project3y = 
scpad_stretchx = 100.0000
scpad_stretchy = 100.0000
pcs_x = 
pcs_y = 
array_x = 
array_y = 
layer_lock = lock

### steps/drc/layers/legc/attrlist
.out_mirror = no
.lpol_done = no
.cu_base = no
.etm_mirror = no
.comment = 
.flipped_of = 
.inp_file = 
.eda_layers = "REF DES:SILKSCREEN_TOP"&"PACKAGE GEOMETRY:SILKSCREEN_TOP"&"DRAWING FORMAT:LEGEND_TOP_TL"&"DRAWING FORMAT:ALL_LAYERS_TL"&"BOARD GEOMETRY:SILKSCREEN_TOP"
.action_mask_layer = 
.nec_n1_draw_num = 
.nec_n1_rev = 
.nec_n2_draw_num = 
.nec_n2_rev = 
.nec_n3_target_lyr = 
.nec_n3_edit_level = 
.nec_n3_lyr_type = 
.nec_n3_prod_rev = 
.nec_n3_pol = 
.nec_cbnk_blank_name = 
.numbered_layer = 
.layer_class = 
.se_coupon_method = none
.se_coupon_direct = 0
.se_coupon_dist_type = spacing
.action_mask_layer_type = exclude
.out_angle = 0.0
.cdr_mirror = unset
.cdr_drill_type = unset
.out_polarity = positive
.etm_rotate = 0
.layer_hdi_type = core
.drill_layer_direction = top2bottom
.se_coupon_min_hits = 0
.se_coupon_dist = 0.000000
.se_coupon_min_size = 0.000000
.se_coupon_max_size = 0.000000
.se_coupon_slot_length = 0.000000
.se_coupon_slot_angle = 0.000000
.out_x_scale = 1.000000
.out_y_scale = 1.000000
.out_comp = 0.000000
.et_adjacency = 20.000000
.depth = 0.000000
.inp_x_scale = 1.000000
.inp_y_scale = 1.000000
.etm_thickness = 20.000000
.etm_prim_sink_h = 0.000000
.etm_sec_sink_h = 0.000000
.etm_prim_sink_r = 0.000000
.etm_sec_sink_r = 0.000000
.etm_prim_sink_s = 0.000000
.etm_sec_sink_s = 0.000000
.etm_shift_x = 0.000000
.etm_shift_y = 0.000000
.etm_step_x = 0.000000
.etm_step_y = 0.000000
.etm_height = 20.000000
.layer_dielectric = 0.000000
.copper_weight = 1.000000
film_version = 000
stretchx = 100.0000
stretchy = 100.0000
projectx = 
projecty = 
normal_distancex = 
normal_distancey = 
distancex = 
distancey = 
out_strchx = 
out_strchy = 
in_strchx = 
in_strchy = 
smc_strchx = 
smc_strchy = 
sms_strchx = 
sms_strchy = 
legc_strchx = 
legc_strchy = 
legs_strchx = 
legs_strchy = 
copper_area = 
plot_user = 000000
plot_version = 00000000
gce_version = 
save_code = 
film_bar_code = 
sht_normal_distancex = 
sht_normal_distancey = 
sht_stretchx = 100.0000
sht_stretchy = 100.0000
pcb_serial = 00
work_serial = 00
stackx = 0
stacky = 0
out_projectx = 
out_projecty = 
number = 0000000
out_project3x = 
out_project3y = 
scpad_stretchx = 100.0000
scpad_stretchy = 100.0000
pcs_x = 
pcs_y = 
array_x = 
array_y = 
layer_lock = lock

### steps/drc/layers/legs/attrlist
.out_mirror = no
.lpol_done = no
.cu_base = no
.etm_mirror = no
.comment = 
.flipped_of = 
.inp_file = 
.eda_layers = "REF DES:SILKSCREEN_BOTTOM"&"PACKAGE GEOMETRY:SILKSCREEN_BOTTOM"&"DRAWING FORMAT:LEGEND_BOT_TL"&"DRAWING FORMAT:ALL_LAYERS_TL"&"BOARD GEOMETRY:SILKSCREEN_BOTTOM"
.action_mask_layer = 
.nec_n1_draw_num = 
.nec_n1_rev = 
.nec_n2_draw_num = 
.nec_n2_rev = 
.nec_n3_target_lyr = 
.nec_n3_edit_level = 
.nec_n3_lyr_type = 
.nec_n3_prod_rev = 
.nec_n3_pol = 
.nec_cbnk_blank_name = 
.numbered_layer = 
.layer_class = 
.se_coupon_method = none
.se_coupon_direct = 0
.se_coupon_dist_type = spacing
.action_mask_layer_type = exclude
.out_angle = 0.0
.cdr_mirror = unset
.cdr_drill_type = unset
.out_polarity = positive
.etm_rotate = 0
.layer_hdi_type = core
.drill_layer_direction = top2bottom
.se_coupon_min_hits = 0
.se_coupon_dist = 0.000000
.se_coupon_min_size = 0.000000
.se_coupon_max_size = 0.000000
.se_coupon_slot_length = 0.000000
.se_coupon_slot_angle = 0.000000
.out_x_scale = 1.000000
.out_y_scale = 1.000000
.out_comp = 0.000000
.et_adjacency = 20.000000
.depth = 0.000000
.inp_x_scale = 1.000000
.inp_y_scale = 1.000000
.etm_thickness = 20.000000
.etm_prim_sink_h = 0.000000
.etm_sec_sink_h = 0.000000
.etm_prim_sink_r = 0.000000
.etm_sec_sink_r = 0.000000
.etm_prim_sink_s = 0.000000
.etm_sec_sink_s = 0.000000
.etm_shift_x = 0.000000
.etm_shift_y = 0.000000
.etm_step_x = 0.000000
.etm_step_y = 0.000000
.etm_height = 20.000000
.layer_dielectric = 0.000000
.copper_weight = 1.000000
film_version = 000
stretchx = 100.0000
stretchy = 100.0000
projectx = 
projecty = 
normal_distancex = 
normal_distancey = 
distancex = 
distancey = 
out_strchx = 
out_strchy = 
in_strchx = 
in_strchy = 
smc_strchx = 
smc_strchy = 
sms_strchx = 
sms_strchy = 
legc_strchx = 
legc_strchy = 
legs_strchx = 
legs_strchy = 
copper_area = 
plot_user = 000000
plot_version = 00000000
gce_version = 
save_code = 
film_bar_code = 
sht_normal_distancex = 
sht_normal_distancey = 
sht_stretchx = 100.0000
sht_stretchy = 100.0000
pcb_serial = 00
work_serial = 00
stackx = 0
stacky = 0
out_projectx = 
out_projecty = 
number = 0000000
out_project3x = 
out_project3y = 
scpad_stretchx = 100.0000
scpad_stretchy = 100.0000
pcs_x = 
pcs_y = 
array_x = 
array_y = 
layer_lock = lock

### steps/drc/layers/ls/attrlist
.out_mirror = no
.lpol_done = no
.cu_base = no
.etm_mirror = no
.comment = 
.flipped_of = 
.inp_file = 
.eda_layers = "VIA CLASS:BOTTOM"&"PIN:BOTTOM"&"ETCH:BOTTOM"&"DRAWING FORMAT:ETCH_BOT_TL"&"DRAWING FORMAT:ETCH_ALL_LAYERS_TL"&"DRAWING FORMAT:ALL_LAYERS_TL"
.action_mask_layer = 
.nec_n1_draw_num = 
.nec_n1_rev = 
.nec_n2_draw_num = 
.nec_n2_rev = 
.nec_n3_target_lyr = 
.nec_n3_edit_level = 
.nec_n3_lyr_type = 
.nec_n3_prod_rev = 
.nec_n3_pol = 
.nec_cbnk_blank_name = 
.numbered_layer = 
.layer_class = 
.se_coupon_method = none
.se_coupon_direct = 0
.se_coupon_dist_type = spacing
.action_mask_layer_type = exclude
.out_angle = 0.0
.cdr_mirror = unset
.cdr_drill_type = unset
.out_polarity = positive
.etm_rotate = 0
.layer_hdi_type = core
.drill_layer_direction = top2bottom
.se_coupon_min_hits = 0
.se_coupon_dist = 0.000000
.se_coupon_min_size = 0.000000
.se_coupon_max_size = 0.000000
.se_coupon_slot_length = 0.000000
.se_coupon_slot_angle = 0.000000
.out_x_scale = 1.000000
.out_y_scale = 1.000000
.out_comp = 0.000000
.et_adjacency = 20.000000
.depth = 0.000000
.inp_x_scale = 1.000000
.inp_y_scale = 1.000000
.etm_thickness = 20.000000
.etm_prim_sink_h = 0.000000
.etm_sec_sink_h = 0.000000
.etm_prim_sink_r = 0.000000
.etm_sec_sink_r = 0.000000
.etm_prim_sink_s = 0.000000
.etm_sec_sink_s = 0.000000
.etm_shift_x = 0.000000
.etm_shift_y = 0.000000
.etm_step_x = 0.000000
.etm_step_y = 0.000000
.etm_height = 20.000000
.layer_dielectric = 0.000000
.copper_weight = 1.000000
film_version = 000
stretchx = 100.0000
stretchy = 100.0000
projectx = 
projecty = 
normal_distancex = 
normal_distancey = 
distancex = 
distancey = 
out_strchx = 
out_strchy = 
in_strchx = 
in_strchy = 
smc_strchx = 
smc_strchy = 
sms_strchx = 
sms_strchy = 
legc_strchx = 
legc_strchy = 
legs_strchx = 
legs_strchy = 
copper_area = 
plot_user = 000000
plot_version = 00000000
gce_version = 
save_code = 
film_bar_code = 
sht_normal_distancex = 
sht_normal_distancey = 
sht_stretchx = 100.0000
sht_stretchy = 100.0000
pcb_serial = 00
work_serial = 00
stackx = 0
stacky = 0
out_projectx = 
out_projecty = 
number = 0000000
out_project3x = 
out_project3y = 
scpad_stretchx = 100.0000
scpad_stretchy = 100.0000
pcs_x = 
pcs_y = 
array_x = 
array_y = 
layer_lock = lock

### steps/drc/layers/rout/attrlist
.out_mirror = no
.lpol_done = no
.cu_base = no
.etm_mirror = no
.comment = 
.flipped_of = 
.inp_file = 
.eda_layers = "BOARD GEOMETRY:OUTLINE"
.action_mask_layer = 
.nec_n1_draw_num = 
.nec_n1_rev = 
.nec_n2_draw_num = 
.nec_n2_rev = 
.nec_n3_target_lyr = 
.nec_n3_edit_level = 
.nec_n3_lyr_type = 
.nec_n3_prod_rev = 
.nec_n3_pol = 
.nec_cbnk_blank_name = 
.numbered_layer = 
.layer_class = 
.se_coupon_method = none
.se_coupon_direct = 0
.se_coupon_dist_type = spacing
.action_mask_layer_type = exclude
.out_angle = 0.0
.cdr_mirror = unset
.cdr_drill_type = unset
.out_polarity = positive
.etm_rotate = 0
.layer_hdi_type = core
.drill_layer_direction = top2bottom
.se_coupon_min_hits = 0
.se_coupon_dist = 0.000000
.se_coupon_min_size = 0.000000
.se_coupon_max_size = 0.000000
.se_coupon_slot_length = 0.000000
.se_coupon_slot_angle = 0.000000
.out_x_scale = 1.000000
.out_y_scale = 1.000000
.out_comp = 0.000000
.et_adjacency = 20.000000
.depth = 0.000000
.inp_x_scale = 1.000000
.inp_y_scale = 1.000000
.etm_thickness = 20.000000
.etm_prim_sink_h = 0.000000
.etm_sec_sink_h = 0.000000
.etm_prim_sink_r = 0.000000
.etm_sec_sink_r = 0.000000
.etm_prim_sink_s = 0.000000
.etm_sec_sink_s = 0.000000
.etm_shift_x = 0.000000
.etm_shift_y = 0.000000
.etm_step_x = 0.000000
.etm_step_y = 0.000000
.etm_height = 20.000000
.layer_dielectric = 0.000000
.copper_weight = 1.000000
film_version = 000
stretchx = 100.0000
stretchy = 100.0000
projectx = 
projecty = 
normal_distancex = 
normal_distancey = 
distancex = 
distancey = 
out_strchx = 
out_strchy = 
in_strchx = 
in_strchy = 
smc_strchx = 
smc_strchy = 
sms_strchx = 
sms_strchy = 
legc_strchx = 
legc_strchy = 
legs_strchx = 
legs_strchy = 
copper_area = 
plot_user = 000000
plot_version = 00000000
gce_version = 
save_code = 
film_bar_code = 
sht_normal_distancex = 
sht_normal_distancey = 
sht_stretchx = 100.0000
sht_stretchy = 100.0000
pcb_serial = 00
work_serial = 00
stackx = 0
stacky = 0
out_projectx = 
out_projecty = 
number = 0000000
out_project3x = 
out_project3y = 
scpad_stretchx = 100.0000
scpad_stretchy = 100.0000
pcs_x = 
pcs_y = 
array_x = 
array_y = 
layer_lock = lock

### steps/drc/layers/s-paste/attrlist
.out_mirror = no
.lpol_done = no
.cu_base = no
.etm_mirror = no
.comment = 
.flipped_of = 
.inp_file = 
.eda_layers = "VIA CLASS:PASTEMASK_BOTTOM"&"PIN:PASTEMASK_BOTTOM"&"PACKAGE GEOMETRY:PASTEMASK_BOTTOM"&"DRAWING FORMAT:PASTE_BOTTOM"&"DRAWING FORMAT:PASTE_BOT_TL"&"DRAWING FORMAT:ALL_LAYERS_TL"
.action_mask_layer = 
.nec_n1_draw_num = 
.nec_n1_rev = 
.nec_n2_draw_num = 
.nec_n2_rev = 
.nec_n3_target_lyr = 
.nec_n3_edit_level = 
.nec_n3_lyr_type = 
.nec_n3_prod_rev = 
.nec_n3_pol = 
.nec_cbnk_blank_name = 
.numbered_layer = 
.layer_class = 
.se_coupon_method = none
.se_coupon_direct = 0
.se_coupon_dist_type = spacing
.action_mask_layer_type = exclude
.out_angle = 0.0
.cdr_mirror = unset
.cdr_drill_type = unset
.out_polarity = positive
.etm_rotate = 0
.layer_hdi_type = core
.drill_layer_direction = top2bottom
.se_coupon_min_hits = 0
.se_coupon_dist = 0.000000
.se_coupon_min_size = 0.000000
.se_coupon_max_size = 0.000000
.se_coupon_slot_length = 0.000000
.se_coupon_slot_angle = 0.000000
.out_x_scale = 1.000000
.out_y_scale = 1.000000
.out_comp = 0.000000
.et_adjacency = 20.000000
.depth = 0.000000
.inp_x_scale = 1.000000
.inp_y_scale = 1.000000
.etm_thickness = 20.000000
.etm_prim_sink_h = 0.000000
.etm_sec_sink_h = 0.000000
.etm_prim_sink_r = 0.000000
.etm_sec_sink_r = 0.000000
.etm_prim_sink_s = 0.000000
.etm_sec_sink_s = 0.000000
.etm_shift_x = 0.000000
.etm_shift_y = 0.000000
.etm_step_x = 0.000000
.etm_step_y = 0.000000
.etm_height = 20.000000
.layer_dielectric = 0.000000
.copper_weight = 1.000000
film_version = 000
stretchx = 100.0000
stretchy = 100.0000
projectx = 
projecty = 
normal_distancex = 
normal_distancey = 
distancex = 
distancey = 
out_strchx = 
out_strchy = 
in_strchx = 
in_strchy = 
smc_strchx = 
smc_strchy = 
sms_strchx = 
sms_strchy = 
legc_strchx = 
legc_strchy = 
legs_strchx = 
legs_strchy = 
copper_area = 
plot_user = 000000
plot_version = 00000000
gce_version = 
save_code = 
film_bar_code = 
sht_normal_distancex = 
sht_normal_distancey = 
sht_stretchx = 100.0000
sht_stretchy = 100.0000
pcb_serial = 00
work_serial = 00
stackx = 0
stacky = 0
out_projectx = 
out_projecty = 
number = 0000000
out_project3x = 
out_project3y = 
scpad_stretchx = 100.0000
scpad_stretchy = 100.0000
pcs_x = 
pcs_y = 
array_x = 
array_y = 
layer_lock = lock

### steps/drc/layers/smc/attrlist
.out_mirror = no
.lpol_done = no
.cu_base = no
.etm_mirror = no
.comment = 
.flipped_of = 
.inp_file = 
.eda_layers = "VIA CLASS:SOLDERMASK_TOP"&"PIN:SOLDERMASK_TOP"&"PACKAGE GEOMETRY:SOLDERMASK_TOP"&"DRAWING FORMAT:SM_TOP_TL"&"DRAWING FORMAT:ALL_LAYERS_TL"&"BOARD GEOMETRY:SOLDERMASK_TOP"
.action_mask_layer = 
.nec_n1_draw_num = 
.nec_n1_rev = 
.nec_n2_draw_num = 
.nec_n2_rev = 
.nec_n3_target_lyr = 
.nec_n3_edit_level = 
.nec_n3_lyr_type = 
.nec_n3_prod_rev = 
.nec_n3_pol = 
.nec_cbnk_blank_name = 
.numbered_layer = 
.layer_class = 
.se_coupon_method = none
.se_coupon_direct = 0
.se_coupon_dist_type = spacing
.action_mask_layer_type = exclude
.out_angle = 0.0
.cdr_mirror = unset
.cdr_drill_type = unset
.out_polarity = positive
.etm_rotate = 0
.layer_hdi_type = core
.drill_layer_direction = top2bottom
.se_coupon_min_hits = 0
.se_coupon_dist = 0.000000
.se_coupon_min_size = 0.000000
.se_coupon_max_size = 0.000000
.se_coupon_slot_length = 0.000000
.se_coupon_slot_angle = 0.000000
.out_x_scale = 1.000000
.out_y_scale = 1.000000
.out_comp = 0.000000
.et_adjacency = 20.000000
.depth = 0.000000
.inp_x_scale = 1.000000
.inp_y_scale = 1.000000
.etm_thickness = 20.000000
.etm_prim_sink_h = 0.000000
.etm_sec_sink_h = 0.000000
.etm_prim_sink_r = 0.000000
.etm_sec_sink_r = 0.000000
.etm_prim_sink_s = 0.000000
.etm_sec_sink_s = 0.000000
.etm_shift_x = 0.000000
.etm_shift_y = 0.000000
.etm_step_x = 0.000000
.etm_step_y = 0.000000
.etm_height = 20.000000
.layer_dielectric = 0.000000
.copper_weight = 1.000000
film_version = 000
stretchx = 100.0000
stretchy = 100.0000
projectx = 
projecty = 
normal_distancex = 
normal_distancey = 
distancex = 
distancey = 
out_strchx = 
out_strchy = 
in_strchx = 
in_strchy = 
smc_strchx = 
smc_strchy = 
sms_strchx = 
sms_strchy = 
legc_strchx = 
legc_strchy = 
legs_strchx = 
legs_strchy = 
copper_area = 
plot_user = 000000
plot_version = 00000000
gce_version = 
save_code = 
film_bar_code = 
sht_normal_distancex = 
sht_normal_distancey = 
sht_stretchx = 100.0000
sht_stretchy = 100.0000
pcb_serial = 00
work_serial = 00
stackx = 0
stacky = 0
out_projectx = 
out_projecty = 
number = 0000000
out_project3x = 
out_project3y = 
scpad_stretchx = 100.0000
scpad_stretchy = 100.0000
pcs_x = 
pcs_y = 
array_x = 
array_y = 
layer_lock = lock

### steps/drc/layers/sms/attrlist
.out_mirror = no
.lpol_done = no
.cu_base = no
.etm_mirror = no
.comment = 
.flipped_of = 
.inp_file = 
.eda_layers = "VIA CLASS:SOLDERMASK_BOTTOM"&"PIN:SOLDERMASK_BOTTOM"&"PACKAGE GEOMETRY:SOLDERMASK_BOTTOM"&"DRAWING FORMAT:SM_BOT_TL"&"DRAWING FORMAT:ALL_LAYERS_TL"&"BOARD GEOMETRY:SOLDERMASK_BOTTOM"
.action_mask_layer = 
.nec_n1_draw_num = 
.nec_n1_rev = 
.nec_n2_draw_num = 
.nec_n2_rev = 
.nec_n3_target_lyr = 
.nec_n3_edit_level = 
.nec_n3_lyr_type = 
.nec_n3_prod_rev = 
.nec_n3_pol = 
.nec_cbnk_blank_name = 
.numbered_layer = 
.layer_class = 
.se_coupon_method = none
.se_coupon_direct = 0
.se_coupon_dist_type = spacing
.action_mask_layer_type = exclude
.out_angle = 0.0
.cdr_mirror = unset
.cdr_drill_type = unset
.out_polarity = positive
.etm_rotate = 0
.layer_hdi_type = core
.drill_layer_direction = top2bottom
.se_coupon_min_hits = 0
.se_coupon_dist = 0.000000
.se_coupon_min_size = 0.000000
.se_coupon_max_size = 0.000000
.se_coupon_slot_length = 0.000000
.se_coupon_slot_angle = 0.000000
.out_x_scale = 1.000000
.out_y_scale = 1.000000
.out_comp = 0.000000
.et_adjacency = 20.000000
.depth = 0.000000
.inp_x_scale = 1.000000
.inp_y_scale = 1.000000
.etm_thickness = 20.000000
.etm_prim_sink_h = 0.000000
.etm_sec_sink_h = 0.000000
.etm_prim_sink_r = 0.000000
.etm_sec_sink_r = 0.000000
.etm_prim_sink_s = 0.000000
.etm_sec_sink_s = 0.000000
.etm_shift_x = 0.000000
.etm_shift_y = 0.000000
.etm_step_x = 0.000000
.etm_step_y = 0.000000
.etm_height = 20.000000
.layer_dielectric = 0.000000
.copper_weight = 1.000000
film_version = 000
stretchx = 100.0000
stretchy = 100.0000
projectx = 
projecty = 
normal_distancex = 
normal_distancey = 
distancex = 
distancey = 
out_strchx = 
out_strchy = 
in_strchx = 
in_strchy = 
smc_strchx = 
smc_strchy = 
sms_strchx = 
sms_strchy = 
legc_strchx = 
legc_strchy = 
legs_strchx = 
legs_strchy = 
copper_area = 
plot_user = 000000
plot_version = 00000000
gce_version = 
save_code = 
film_bar_code = 
sht_normal_distancex = 
sht_normal_distancey = 
sht_stretchx = 100.0000
sht_stretchy = 100.0000
pcb_serial = 00
work_serial = 00
stackx = 0
stacky = 0
out_projectx = 
out_projecty = 
number = 0000000
out_project3x = 
out_project3y = 
scpad_stretchx = 100.0000
scpad_stretchy = 100.0000
pcs_x = 
pcs_y = 
array_x = 
array_y = 
layer_lock = lock

### steps/drc/profile
#
#Layer features
#
S P 0
OB 12.84646003937 6.023619980315 I
OC 12.9252 5.944880019685 12.84646003937 5.944880019685 Y
OS 12.9252 0.07873996063
OC 12.84646003937 0 12.84646003937 0.07873996063 Y
OS 6.66536003937 0
OC 6.586619980315 0.07873996063 6.665359940945 0.07873996063 Y
OS 6.586619980315 0.354330019685
OC 6.507880019685 0.433069980315 6.507880019685 0.354330019685 N
OS 4.933080019685 0.433069980315
OC 4.85433996063 0.354330019685 4.93307992126 0.354330019685 N
OS 4.85433996063 0.07873996063
OC 4.775589862205 0 4.775599901575 0.07873996063 Y
OS 0.07873996063 0
OC 0 0.07873996063 0.07873996063 0.07873996063 Y
OS 0 5.944880019685
OC 0.07873996063 6.023619980315 0.07873996063 5.944880019685 Y
OS 12.84646003937 6.023619980315
OE
SE

### steps/drc/netlists/cadnet/netlist
H optimize n staggered n
$0 PE_E0_PE1_CP0_DAT_C_02_P
$1 PE_E0_PE1_CP0_DAT_02_P
$2 P5V
$3 GND
$4 PE_E0_PE1_CP0_DAT_C_03_P
$5 PE_E0_PE1_CP0_DAT_03_P
$6 P3V3_AUX
$7 FF_CLK_EN
$8 P1V8
$9 PE_E0_PE3_CP1_DAT_C_15_P
$10 PE_E0_PE3_CP1_DAT_15_P
$11 PE_E0_PE3_CP1_DAT_C_15_N
$12 PE_E0_PE3_CP1_DAT_15_N
$13 PE_E0_PE3_CP1_DAT_C_14_P
$14 PE_E0_PE3_CP1_DAT_14_P
$15 PE_E0_PE3_CP1_DAT_C_14_N
$16 PE_E0_PE3_CP1_DAT_14_N
$17 PE_E0_PE3_CP1_DAT_C_13_P
$18 PE_E0_PE3_CP1_DAT_13_P
$19 PE_E0_PE3_CP1_DAT_C_13_N
$20 PE_E0_PE3_CP1_DAT_13_N
$21 PE_E0_PE3_CP1_DAT_C_12_P
$22 PE_E0_PE3_CP1_DAT_12_P
$23 PE_E0_PE3_CP1_DAT_C_12_N
$24 PE_E0_PE3_CP1_DAT_12_N
$25 PE_E0_PE3_CP1_DAT_C_11_P
$26 PE_E0_PE3_CP1_DAT_11_P
$27 PE_E0_PE3_CP1_DAT_C_11_N
$28 PE_E0_PE3_CP1_DAT_11_N
$29 PE_E0_PE3_CP1_DAT_C_10_P
$30 PE_E0_PE3_CP1_DAT_10_P
$31 PE_E0_PE3_CP1_DAT_C_10_N
$32 PE_E0_PE3_CP1_DAT_10_N
$33 PE_E0_PE3_CP1_DAT_C_09_P
$34 PE_E0_PE3_CP1_DAT_09_P
$35 PE_E0_PE3_CP1_DAT_C_09_N
$36 PE_E0_PE3_CP1_DAT_09_N
$37 PE_E0_PE3_CP1_DAT_C_08_P
$38 PE_E0_PE3_CP1_DAT_08_P
$39 PE_E0_PE3_CP1_DAT_C_08_N
$40 PE_E0_PE3_CP1_DAT_08_N
$41 PE_E0_PE3_CP1_DAT_C_07_P
$42 PE_E0_PE3_CP1_DAT_07_P
$43 PE_E0_PE3_CP1_DAT_C_07_N
$44 PE_E0_PE3_CP1_DAT_07_N
$45 PE_E0_PE3_CP1_DAT_C_06_P
$46 PE_E0_PE3_CP1_DAT_06_P
$47 PE_E0_PE3_CP1_DAT_C_06_N
$48 PE_E0_PE3_CP1_DAT_06_N
$49 PE_E0_PE3_CP1_DAT_C_05_P
$50 PE_E0_PE3_CP1_DAT_05_P
$51 PE_E0_PE3_CP1_DAT_C_05_N
$52 PE_E0_PE3_CP1_DAT_05_N
$53 PE_E0_PE3_CP1_DAT_C_04_P
$54 PE_E0_PE3_CP1_DAT_04_P
$55 PE_E0_PE3_CP1_DAT_C_04_N
$56 PE_E0_PE3_CP1_DAT_04_N
$57 PE_E0_PE3_CP1_DAT_C_03_P
$58 PE_E0_PE3_CP1_DAT_03_P
$59 PE_E0_PE3_CP1_DAT_C_03_N
$60 PE_E0_PE3_CP1_DAT_03_N
$61 PE_E0_PE3_CP1_DAT_C_02_P
$62 PE_E0_PE3_CP1_DAT_02_P
$63 PE_E0_PE3_CP1_DAT_C_02_N
$64 PE_E0_PE3_CP1_DAT_02_N
$65 PE_E0_PE3_CP1_DAT_C_01_P
$66 PE_E0_PE3_CP1_DAT_01_P
$67 PE_E0_PE3_CP1_DAT_C_01_N
$68 PE_E0_PE3_CP1_DAT_01_N
$69 PE_E0_PE3_CP1_DAT_C_00_P
$70 PE_E0_PE3_CP1_DAT_00_P
$71 PE_E0_PE3_CP1_DAT_C_00_N
$72 PE_E0_PE3_CP1_DAT_00_N
$73 PE_E0_PE1_CP0_DAT_C_01_P
$74 PE_E0_PE1_CP0_DAT_01_P
$75 GPU0_PWR_1_R_EN
$76 GPU1_PWR_1_R_EN
$77 CT
$78 PE_E0_PE1_CP0_DAT_C_04_N
$79 PE_E0_PE1_CP0_DAT_04_N
$80 PE_E0_PE1_CP0_DAT_C_06_P
$81 PE_E0_PE1_CP0_DAT_06_P
$82 P12V
$83 PE_E0_PE1_CP0_DAT_C_00_P
$84 PE_E0_PE1_CP0_DAT_00_P
$85 PE_E0_PE1_CP0_DAT_C_00_N
$86 PE_E0_PE1_CP0_DAT_00_N
$87 PE_E0_PE1_CP0_DAT_C_01_N
$88 PE_E0_PE1_CP0_DAT_01_N
$89 PE_E0_PE1_CP0_DAT_C_02_N
$90 PE_E0_PE1_CP0_DAT_02_N
$91 PE_E0_PE1_CP0_DAT_C_03_N
$92 PE_E0_PE1_CP0_DAT_03_N
$93 PE_E0_PE1_CP0_DAT_C_04_P
$94 PE_E0_PE1_CP0_DAT_04_P
$95 PE_E0_PE1_CP0_DAT_C_05_P
$96 PE_E0_PE1_CP0_DAT_05_P
$97 PE_E0_PE1_CP0_DAT_C_05_N
$98 PE_E0_PE1_CP0_DAT_05_N
$99 PE_E0_PE1_CP0_DAT_C_06_N
$100 PE_E0_PE1_CP0_DAT_06_N
$101 PE_E0_PE1_CP0_DAT_C_08_P
$102 PE_E0_PE1_CP0_DAT_08_P
$103 PE_E0_PE1_CP0_DAT_C_08_N
$104 PE_E0_PE1_CP0_DAT_08_N
$105 PE_E0_PE1_CP0_DAT_C_09_P
$106 PE_E0_PE1_CP0_DAT_09_P
$107 PE_E0_PE1_CP0_DAT_C_09_N
$108 PE_E0_PE1_CP0_DAT_09_N
$109 PE_E0_PE1_CP0_DAT_C_10_P
$110 PE_E0_PE1_CP0_DAT_10_P
$111 PE_E0_PE1_CP0_DAT_C_10_N
$112 PE_E0_PE1_CP0_DAT_10_N
$113 PE_E0_PE1_CP0_DAT_C_11_P
$114 PE_E0_PE1_CP0_DAT_11_P
$115 PE_E0_PE1_CP0_DAT_C_11_N
$116 PE_E0_PE1_CP0_DAT_11_N
$117 PE_E0_PE1_CP0_DAT_C_12_P
$118 PE_E0_PE1_CP0_DAT_12_P
$119 PE_E0_PE1_CP0_DAT_C_12_N
$120 PE_E0_PE1_CP0_DAT_12_N
$121 PE_E0_PE1_CP0_DAT_C_13_P
$122 PE_E0_PE1_CP0_DAT_13_P
$123 PE_E0_PE1_CP0_DAT_C_13_N
$124 PE_E0_PE1_CP0_DAT_13_N
$125 PE_E0_PE1_CP0_DAT_C_14_P
$126 PE_E0_PE1_CP0_DAT_14_P
$127 PE_E0_PE1_CP0_DAT_C_14_N
$128 PE_E0_PE1_CP0_DAT_14_N
$129 PE_E0_PE1_CP0_DAT_C_15_P
$130 PE_E0_PE1_CP0_DAT_15_P
$131 PE_E0_PE1_CP0_DAT_C_15_N
$132 PE_E0_PE1_CP0_DAT_15_N
$133 PE_E0_PE1_CP0_DAT_C_07_P
$134 PE_E0_PE1_CP0_DAT_07_P
$135 PE_E0_PE1_CP0_DAT_C_07_N
$136 PE_E0_PE1_CP0_DAT_07_N
$137 P12V_GPU0
$138 P12V_GPU1
$139 G0_JTAG_TMS
$140 G0_JTAG_TRST_N
$141 G0_JTAG_TDI
$142 G0_JTAG_TDO
$143 G0_JTAG_TCLK
$144 G0_JTAG_SEL
$145 G1_JTAG_TMS
$146 G1_JTAG_TRST_N
$147 G1_JTAG_TDI
$148 G1_JTAG_TDO
$149 G1_JTAG_TCLK
$150 G1_JTAG_SEL
$151 NV0_CP0_P_PIN_DAT_09_N
$152 NV0_CP0_P_PIN_DAT_09_P
$153 NV0_CP0_P_PIN_DAT_07_N
$154 NV0_CP0_P_PIN_DAT_07_P
$155 NV0_CP0_P_PIN_DAT_03_N
$156 NV0_CP0_P_PIN_DAT_03_P
$157 NV0_CP0_P_PIN_DAT_01_N
$158 NV0_CP0_P_PIN_DAT_01_P
$159 CP0_P_NV0A_I2C_SCL
$160 CP0_P_NV0A_I2C_SDA
$161 NV0_PIN_P_CP0_DAT_01_P
$162 NV0_PIN_P_CP0_DAT_01_N
$163 NV0_PIN_P_CP0_DAT_03_P
$164 NV0_PIN_P_CP0_DAT_03_N
$165 NV0_PIN_P_CP0_DAT_07_P
$166 NV0_PIN_P_CP0_DAT_07_N
$167 NV0_PIN_P_CP0_DAT_09_P
$168 NV0_PIN_P_CP0_DAT_09_N
$169 NV0_PIN_P_CP0_DAT_10_P
$170 NV0_PIN_P_CP0_DAT_10_N
$171 NV0_CP0_P_PIN_DAT_10_N
$172 NV0_CP0_P_PIN_DAT_10_P
$173 NV0_CP0_P_PIN_DAT_08_N
$174 NV0_CP0_P_PIN_DAT_08_P
$175 NV0_CP0_P_PIN_DAT_02_N
$176 NV0_CP0_P_PIN_DAT_02_P
$177 NV0_CP0_P_PIN_DAT_00_N
$178 NV0_CP0_P_PIN_DAT_00_P
$179 CP0_PRE_DETECT_BOT
$180 CP0_INT_BOT
$181 NV0_PIN_P_CP0_DAT_00_P
$182 NV0_PIN_P_CP0_DAT_00_N
$183 NV0_PIN_P_CP0_DAT_02_P
$184 NV0_PIN_P_CP0_DAT_02_N
$185 PV_CP0_P_GPU0_REFCLK_156MHZ_P
$186 PV_CP0_P_GPU0_REFCLK_156MHZ_N
$187 NV0_CP0_CLK_CABLE_PRESENT
$188 NV0_PIN_P_CP0_DAT_08_P
$189 NV0_PIN_P_CP0_DAT_08_N
$190 NV0_CP0_P_PIN_DAT_22_N
$191 NV0_CP0_P_PIN_DAT_22_P
$192 NV0_CP0_P_PIN_DAT_20_N
$193 NV0_CP0_P_PIN_DAT_20_P
$194 NV0_CP0_P_PIN_DAT_16_N
$195 NV0_CP0_P_PIN_DAT_16_P
$196 NV0_CP0_P_PIN_DAT_14_N
$197 NV0_CP0_P_PIN_DAT_14_P
$198 CP0_P_NV0B_I2C_SCL
$199 CP0_P_NV0B_I2C_SDA
$200 NV0_PIN_P_CP0_DAT_14_P
$201 NV0_PIN_P_CP0_DAT_14_N
$202 NV0_PIN_P_CP0_DAT_16_P
$203 NV0_PIN_P_CP0_DAT_16_N
$204 NV0_PIN_P_CP0_DAT_20_P
$205 NV0_PIN_P_CP0_DAT_20_N
$206 NV0_PIN_P_CP0_DAT_22_P
$207 NV0_PIN_P_CP0_DAT_22_N
$208 NV0_PIN_P_CP0_DAT_23_P
$209 NV0_PIN_P_CP0_DAT_23_N
$210 NV0_CP0_P_PIN_DAT_23_N
$211 NV0_CP0_P_PIN_DAT_23_P
$212 NV0_CP0_P_PIN_DAT_21_N
$213 NV0_CP0_P_PIN_DAT_21_P
$214 NV0_CP0_P_PIN_DAT_15_N
$215 NV0_CP0_P_PIN_DAT_15_P
$216 NV0_CP0_P_PIN_DAT_13_N
$217 NV0_CP0_P_PIN_DAT_13_P
$218 CP0_PRE_DETECT_TOP
$219 CP0_INT_TOP
$220 NV0_PIN_P_CP0_DAT_13_P
$221 NV0_PIN_P_CP0_DAT_13_N
$222 NV0_PIN_P_CP0_DAT_15_P
$223 NV0_PIN_P_CP0_DAT_15_N
$224 NV0_PIN_P_CP0_DAT_21_P
$225 NV0_PIN_P_CP0_DAT_21_N
$226 NV0_CP1_P_PIN_DAT_09_N
$227 NV0_CP1_P_PIN_DAT_09_P
$228 NV0_CP1_P_PIN_DAT_07_N
$229 NV0_CP1_P_PIN_DAT_07_P
$230 NV0_CP1_P_PIN_DAT_03_N
$231 NV0_CP1_P_PIN_DAT_03_P
$232 NV0_CP1_P_PIN_DAT_01_N
$233 NV0_CP1_P_PIN_DAT_01_P
$234 CP1_P_NV0A_I2C_SCL
$235 CP1_P_NV0A_I2C_SDA
$236 NV0_PIN_P_CP1_DAT_01_P
$237 NV0_PIN_P_CP1_DAT_01_N
$238 NV0_PIN_P_CP1_DAT_03_P
$239 NV0_PIN_P_CP1_DAT_03_N
$240 NV0_PIN_P_CP1_DAT_07_P
$241 NV0_PIN_P_CP1_DAT_07_N
$242 NV0_PIN_P_CP1_DAT_09_P
$243 NV0_PIN_P_CP1_DAT_09_N
$244 NV0_PIN_P_CP1_DAT_10_P
$245 NV0_PIN_P_CP1_DAT_10_N
$246 NV0_CP1_P_PIN_DAT_10_N
$247 NV0_CP1_P_PIN_DAT_10_P
$248 NV0_CP1_P_PIN_DAT_08_N
$249 NV0_CP1_P_PIN_DAT_08_P
$250 NV0_CP1_P_PIN_DAT_02_N
$251 NV0_CP1_P_PIN_DAT_02_P
$252 NV0_CP1_P_PIN_DAT_00_N
$253 NV0_CP1_P_PIN_DAT_00_P
$254 CP1_PRE_DETECT_BOT
$255 CP1_INT_BOT
$256 NV0_PIN_P_CP1_DAT_00_P
$257 NV0_PIN_P_CP1_DAT_00_N
$258 NV0_PIN_P_CP1_DAT_02_P
$259 NV0_PIN_P_CP1_DAT_02_N
$260 PV_CP1_P_GPU1_REFCLK_156MHZ_P
$261 PV_CP1_P_GPU1_REFCLK_156MHZ_N
$262 NV0_CP1_CLK_CABLE_PRESENT
$263 NV0_PIN_P_CP1_DAT_08_P
$264 NV0_PIN_P_CP1_DAT_08_N
$265 NV0_CP1_P_PIN_DAT_22_N
$266 NV0_CP1_P_PIN_DAT_22_P
$267 NV0_CP1_P_PIN_DAT_20_N
$268 NV0_CP1_P_PIN_DAT_20_P
$269 NV0_CP1_P_PIN_DAT_16_N
$270 NV0_CP1_P_PIN_DAT_16_P
$271 NV0_CP1_P_PIN_DAT_14_N
$272 NV0_CP1_P_PIN_DAT_14_P
$273 CP1_P_NV0B_I2C_SCL
$274 CP1_P_NV0B_I2C_SDA
$275 NV0_PIN_P_CP1_DAT_14_P
$276 NV0_PIN_P_CP1_DAT_14_N
$277 NV0_PIN_P_CP1_DAT_16_P
$278 NV0_PIN_P_CP1_DAT_16_N
$279 NV0_PIN_P_CP1_DAT_20_P
$280 NV0_PIN_P_CP1_DAT_20_N
$281 NV0_PIN_P_CP1_DAT_22_P
$282 NV0_PIN_P_CP1_DAT_22_N
$283 NV0_PIN_P_CP1_DAT_23_P
$284 NV0_PIN_P_CP1_DAT_23_N
$285 NV0_CP1_P_PIN_DAT_23_N
$286 NV0_CP1_P_PIN_DAT_23_P
$287 NV0_CP1_P_PIN_DAT_21_N
$288 NV0_CP1_P_PIN_DAT_21_P
$289 NV0_CP1_P_PIN_DAT_15_N
$290 NV0_CP1_P_PIN_DAT_15_P
$291 NV0_CP1_P_PIN_DAT_13_N
$292 NV0_CP1_P_PIN_DAT_13_P
$293 CP1_PRE_DETECT_TOP
$294 CP1_INT_TOP
$295 NV0_PIN_P_CP1_DAT_13_P
$296 NV0_PIN_P_CP1_DAT_13_N
$297 NV0_PIN_P_CP1_DAT_15_P
$298 NV0_PIN_P_CP1_DAT_15_N
$299 NV0_PIN_P_CP1_DAT_21_P
$300 NV0_PIN_P_CP1_DAT_21_N
$301 G0_PRSNT12_B_R
$302 G0_PRSNT1_A
$303 G0_NVHS_REFCLK_DN
$304 I2C_GPU0_SDA
$305 G0_NVHS_REFCLK_DP
$306 I2C_GPU0_SCL
$307 G1_PRSNT12_B_R
$308 G1_PRSNT1_A
$309 G1_NVHS_REFCLK_DN
$310 I2C_GPU1_SDA
$311 G1_NVHS_REFCLK_DP
$312 I2C_GPU1_SCL
$313 PCIE_PE1_PRSNT1_N
$314 PCIE1_PERST_N
$315 PE_E0_CP0_PE1_CLK_P
$316 PE_E0_CP0_PE1_CLK_N
$317 NC_SLOT_PE1_ALERT_N
$318 NC_SLOT_PE1_A50
$319 NC_SLOT_PE1_WAKE_N
$320 NC_SLOT_PE1_B12
$321 PE_E0_CP0_PE1_DAT_00_P
$322 PE_E0_CP0_PE1_DAT_00_N
$323 PE_E0A_PE1_CP0_PRSNT_N_R
$324 PE_E0_CP0_PE1_DAT_01_P
$325 PE_E0_CP0_PE1_DAT_01_N
$326 PE_E0_CP0_PE1_DAT_02_P
$327 PE_E0_CP0_PE1_DAT_02_N
$328 PE_E0_CP0_PE1_DAT_03_P
$329 PE_E0_CP0_PE1_DAT_03_N
$330 NC_PE_SLOT_PE1_X8UP_R
$331 PE_E0_CP0_PE1_DAT_04_P
$332 PE_E0_CP0_PE1_DAT_04_N
$333 PE_E0_CP0_PE1_DAT_05_P
$334 PE_E0_CP0_PE1_DAT_05_N
$335 PE_E0_CP0_PE1_DAT_06_P
$336 PE_E0_CP0_PE1_DAT_06_N
$337 PE_E0_CP0_PE1_DAT_07_P
$338 PE_E0_CP0_PE1_DAT_07_N
$339 PE_E0_CP0_PE1_DAT_08_P
$340 PE_E0_CP0_PE1_DAT_08_N
$341 PE_E0_CP0_PE1_DAT_09_P
$342 PE_E0_CP0_PE1_DAT_09_N
$343 PE_E0_CP0_PE1_DAT_10_P
$344 PE_E0_CP0_PE1_DAT_10_N
$345 PE_E0_CP0_PE1_DAT_11_P
$346 PE_E0_CP0_PE1_DAT_11_N
$347 PE_E0_CP0_PE1_DAT_12_P
$348 PE_E0_CP0_PE1_DAT_12_N
$349 PE_E0_CP0_PE1_DAT_13_P
$350 PE_E0_CP0_PE1_DAT_13_N
$351 PE_E0_CP0_PE1_DAT_14_P
$352 PE_E0_CP0_PE1_DAT_14_N
$353 PE_E0_CP0_PE1_DAT_15_P
$354 PE_E0_CP0_PE1_DAT_15_N
$355 NC_SLOT_PE1_B82
$356 PCIE_PE3_PRSNT1_N
$357 PCIE3_PERST_N
$358 PE_E0_CP1_PE3_CLK_P
$359 PE_E0_CP1_PE3_CLK_N
$360 NC_SLOT_PE3_ALERT_N
$361 NC_SLOT_PE3_A50
$362 NC_SLOT_PE3_WAKE_N
$363 NC_SLOT_PE3_B12
$364 PE_E0_CP1_PE3_DAT_00_P
$365 PE_E0_CP1_PE3_DAT_00_N
$366 PE_E0A_PE3_CP1_PRSNT_N_R
$367 PE_E0_CP1_PE3_DAT_01_P
$368 PE_E0_CP1_PE3_DAT_01_N
$369 PE_E0_CP1_PE3_DAT_02_P
$370 PE_E0_CP1_PE3_DAT_02_N
$371 PE_E0_CP1_PE3_DAT_03_P
$372 PE_E0_CP1_PE3_DAT_03_N
$373 NC_PE_SLOT_PE3_X8UP_R
$374 PE_E0_CP1_PE3_DAT_04_P
$375 PE_E0_CP1_PE3_DAT_04_N
$376 PE_E0_CP1_PE3_DAT_05_P
$377 PE_E0_CP1_PE3_DAT_05_N
$378 PE_E0_CP1_PE3_DAT_06_P
$379 PE_E0_CP1_PE3_DAT_06_N
$380 PE_E0_CP1_PE3_DAT_07_P
$381 PE_E0_CP1_PE3_DAT_07_N
$382 PE_E0_CP1_PE3_DAT_08_P
$383 PE_E0_CP1_PE3_DAT_08_N
$384 PE_E0_CP1_PE3_DAT_09_P
$385 PE_E0_CP1_PE3_DAT_09_N
$386 PE_E0_CP1_PE3_DAT_10_P
$387 PE_E0_CP1_PE3_DAT_10_N
$388 PE_E0_CP1_PE3_DAT_11_P
$389 PE_E0_CP1_PE3_DAT_11_N
$390 PE_E0_CP1_PE3_DAT_12_P
$391 PE_E0_CP1_PE3_DAT_12_N
$392 PE_E0_CP1_PE3_DAT_13_P
$393 PE_E0_CP1_PE3_DAT_13_N
$394 PE_E0_CP1_PE3_DAT_14_P
$395 PE_E0_CP1_PE3_DAT_14_N
$396 PE_E0_CP1_PE3_DAT_15_P
$397 PE_E0_CP1_PE3_DAT_15_N
$398 NC_SLOT_PE3_B82
$399 NC_G0_RSVD_SNN_A15
$400 NC_G0_RSVD_SNN_A16
$401 GPU0_PWR_EN
$402 G0_THERM_OVERT_N
$403 NC_G0_RSVD_SNN_B16
$404 NC_G0_RSVD_SNN_B17
$405 NC_G0_RSVD_C15
$406 NC_G0_RSVD_C16
$407 G0_I2C_ADDR1
$408 NC_G0_RSVD_D16
$409 NC_G0_RSVD_D17
$410 G0_PEX_REFCLK_DN
$411 G0_PWR_BRAKE_N
$412 G0_PEX_REFCLK_DP
$413 G0_PEX_RST_N
$414 NC_G0_RSVD_SNN_G16
$415 NC_G0_RSVD_SNN_G17
$416 NC_G0_RSVD_SNN_H15
$417 NC_G0_RSVD_SNN_H16
$418 G0_I2C_ADDR0
$419 G0_PRSNT2_A
$420 NC_G0_RSVD_J16
$421 NC_G0_RSVD_J17
$422 NC_G0_RSVD_K15
$423 NC_G0_RSVD_K16
$424 G0_PWR_GOOD
$425 G0_PRSNT12_B
$426 NC_G1_RSVD_SNN_A15
$427 NC_G1_RSVD_SNN_A16
$428 GPU1_PWR_EN
$429 G1_THERM_OVERT_N
$430 NC_G1_RSVD_SNN_B16
$431 NC_G1_RSVD_SNN_B17
$432 NC_G1_RSVD_C15
$433 NC_G1_RSVD_C16
$434 G1_I2C_ADDR1
$435 NC_G1_RSVD_D16
$436 NC_G1_RSVD_D17
$437 G1_PEX_REFCLK_DN
$438 G1_PWR_BRAKE_N
$439 G1_PEX_REFCLK_DP
$440 G1_PEX_RST_N
$441 NC_G1_RSVD_SNN_G16
$442 NC_G1_RSVD_SNN_G17
$443 NC_G1_RSVD_SNN_H15
$444 NC_G1_RSVD_SNN_H16
$445 G1_I2C_ADDR0
$446 G1_PRSNT2_A
$447 NC_G1_RSVD_J16
$448 NC_G1_RSVD_J17
$449 NC_G1_RSVD_K15
$450 NC_G1_RSVD_K16
$451 G1_PWR_GOOD
$452 G1_PRSNT12_B
$453 GPU_SIG_PRSNT_N
$454 GPU0_PRSNT1_N
$455 P1V8_PGOOD
$456 GPU1_PRSNT1_N
$457 UCD_FF_CLR_N
$458 UCD_GPU_TH_OVERT_N
$459 UCD_PWR_EN
$460 GPU_PWR_GOOD
$461 GPU_PWR_BRAKE_FORCE_N
$462 GPU0_PWR_1_EN
$463 GPU1_PWR_1_EN
$464 GPU_LED_PG
$465 P5V_FB
$466 P5V_VO
$467 P5V_VIN
$468 P5V_PGOOD
$469 P5V_VBST_R
$470 P5V_SW
$471 P5V_EN
$472 P5V_VREG_5V
$473 P5V_SNR
$474 P5V_VDD
$475 P5V_EN_R
$476 P5V_SNR_R
$477 P5V_MODE
$478 P5V_TRIP
$479 P5V_RF
$480 P5V_PG
$481 P5V_VBST
$482 GPU_LED_R_PG
$483 GPU_PWR_BRK_N
$484 GPU_PWR_BRK_R_N
$485 UCD_GPU_TH_OVERT_R_N
$486 G0_PRSNT_A_R
$487 GPU0_PRSNT1_R_N
$488 G1_PRSNT_A_R
$489 GPU1_PRSNT1_R_N
$490 FF_PWR_EN_R
$491 FF_PWR_EN
$492 GPU1_PWR_2_EN
$493 I2C_GPU0_R_SDA
$494 I2C_GPU0_R_SCL
$495 I2C_GPU0_EN
$496 CP0_P_NV0A_I2C_R_SDA
$497 CP0_P_NV0A_I2C_R_SCL
$498 CP1_P_NV0A_I2C_R_SDA
$499 I2C_GPU1_R_SDA
$500 CP1_P_NV0A_I2C_R_SCL
$501 I2C_GPU1_R_SCL
$502 I2C_GPU1_EN
$503 GPU0_PEX_RST_N
$504 GPU1_PEX_RST_N
$505 GPU01_PWR_GOOD_R
$506 GPU01_PWR_GOOD
$507 GPU0_PWR_2_EN
$508 UCD_PWR_R_EN
$509 UCD_GPU_PWR_R_EN
$510 UCD_GPU_PWR_EN
$511 GPU_PG_R
$512 VR_PG
$513 VR_PG_R
$514 HW_GPU_PWR_R_EN
$515 HW_GPU_PWR_EN
$516 MR_N
$517 HW_GPU01_PWR_EN
$518 TEST_GND
$519 L1_45Z_7.7MIL
$520 L10_45Z_4.5MIL
$521 L12_45Z_7.7MIL
$522 L3_45Z_4.5MIL
$523 L5_45Z_4.5MIL
$524 DIFF_GND
$525 L1_85Z_6MIL_5.1MIL_DP
$526 L1_85Z_6MIL_5.1MIL_DN
$527 L10_85Z_3.7MIL_3.8MIL_DP
$528 L10_85Z_3.7MIL_3.8MIL_DN
$529 L12_85Z_6MIL_5.1MIL_DP
$530 L12_85Z_6MIL_5.1MIL_DN
$531 L3_85Z_3.7MIL_3.8MIL_DP
$532 L3_85Z_3.7MIL_3.8MIL_DN
$533 L5_85Z_3.7MIL_3.8MIL_DP
$534 L5_85Z_3.7MIL_3.8MIL_DN
#
#Netlist points
#
0 0.0126 4.90768 1.94115 T e e  arsize_top=0 arsize_bot=0 is_shrink=n
0 0 5.30875 1.6008 D 0.02 0.02 e e staggered 0 0 0  is_shrink=n
0 0.004 4.93268 1.91615 B m e v  arsize_top=0 arsize_bot=0 is_shrink=n
1 0.01378 0.17323 2.35827 B e e  arsize_top=0 arsize_bot=0 is_shrink=n
1 0 5.34275 1.6008 D 0.02 0.02 e e staggered 0 0 0  is_shrink=n
1 0.004 5.42048 1.6033 B m e v  arsize_top=0 arsize_bot=0 is_shrink=n
2 0 6.21194 4.77205 T 0.07283 0.1378 e e staggered 0 0 0  is_shrink=n
2 0 6.42419 5.09705 T 0.02 0.02 e e staggered 0 0 0  is_shrink=n
2 0 5.49094 4.6201 T 0.02 0.02 e e staggered 0 0 0  is_shrink=n
2 0 5.59779 4.6352 T 0.05 0.05 e e staggered 0 0 0  is_shrink=n
2 0 5.67709 4.6352 T 0.05 0.05 e e staggered 0 0 0  is_shrink=n
2 0 5.83709 4.6352 T 0.05 0.05 e e staggered 0 0 0  is_shrink=n
2 0 5.75709 4.6352 T 0.05 0.05 e e staggered 0 0 0  is_shrink=n
2 0 6.07709 4.6352 T 0.05 0.05 e e staggered 0 0 0  is_shrink=n
2 0 5.91709 4.6352 T 0.05 0.05 e e staggered 0 0 0  is_shrink=n
2 0 5.99709 4.6352 T 0.05 0.05 e e staggered 0 0 0  is_shrink=n
2 0 5.53594 4.6201 T 0.02 0.02 e e staggered 0 0 0  is_shrink=n
2 0.0126 4.85768 2.84115 T e e  arsize_top=0 arsize_bot=0 is_shrink=n
2 0.0126 4.90768 2.84115 T e e  arsize_top=0 arsize_bot=0 is_shrink=n
2 0.0126 4.95768 2.84115 T e e  arsize_top=0 arsize_bot=0 is_shrink=n
2 0.0126 5.00768 2.84115 T e e  arsize_top=0 arsize_bot=0 is_shrink=n
2 0.0126 5.05768 2.84115 T e e  arsize_top=0 arsize_bot=0 is_shrink=n
2 0.0126 10.86161 2.84115 T e e  arsize_top=0 arsize_bot=0 is_shrink=n
2 0.0126 10.91161 2.84115 T e e  arsize_top=0 arsize_bot=0 is_shrink=n
2 0.0126 10.96161 2.84115 T e e  arsize_top=0 arsize_bot=0 is_shrink=n
2 0.0126 11.01161 2.84115 T e e  arsize_top=0 arsize_bot=0 is_shrink=n
2 0.0126 11.06161 2.84115 T e e  arsize_top=0 arsize_bot=0 is_shrink=n
2 0 5.67709 4.6352 D 0.05 0.05 e e staggered 0 0 0  is_shrink=n
2 0 5.59779 4.6352 D 0.05 0.05 e e staggered 0 0 0  is_shrink=n
2 0 5.75709 4.6352 D 0.05 0.05 e e staggered 0 0 0  is_shrink=n
2 0 5.83709 4.6352 D 0.05 0.05 e e staggered 0 0 0  is_shrink=n
2 0 6.07709 4.6352 D 0.05 0.05 e e staggered 0 0 0  is_shrink=n
2 0 5.91709 4.6352 D 0.05 0.05 e e staggered 0 0 0  is_shrink=n
2 0 5.99709 4.6352 D 0.05 0.05 e e staggered 0 0 0  is_shrink=n
2 0 6.19209 4.7202 D 0.05 0.05 e e staggered 0 0 0  is_shrink=n
2 0 6.19209 4.6402 D 0.05 0.05 e e staggered 0 0 0  is_shrink=n
2 0 6.19209 4.8802 D 0.05 0.05 e e staggered 0 0 0  is_shrink=n
2 0 6.19209 4.8002 D 0.05 0.05 e e staggered 0 0 0  is_shrink=n
2 0 11.32779 2.96 D 0.05 0.05 e e staggered 0 0 0  is_shrink=n
2 0 11.32779 3.12 D 0.05 0.05 e e staggered 0 0 0  is_shrink=n
2 0 11.32779 3.04 D 0.05 0.05 e e staggered 0 0 0  is_shrink=n
2 0 11.32779 3.2 D 0.05 0.05 e e staggered 0 0 0  is_shrink=n
2 0 11.32779 3.28 D 0.05 0.05 e e staggered 0 0 0  is_shrink=n
2 0 5.32386 3.12 D 0.05 0.05 e e staggered 0 0 0  is_shrink=n
2 0 5.32386 3.04 D 0.05 0.05 e e staggered 0 0 0  is_shrink=n
2 0 5.32386 3.28 D 0.05 0.05 e e staggered 0 0 0  is_shrink=n
2 0 5.32386 3.2 D 0.05 0.05 e e staggered 0 0 0  is_shrink=n
2 0 5.32386 2.96 D 0.05 0.05 e e staggered 0 0 0  is_shrink=n
2 0.015 6.09 4.925 D m e v t  arsize_top=0 arsize_bot=0 is_shrink=n
2 0.004 10.88661 2.81615 B m e v  arsize_top=0 arsize_bot=0 is_shrink=n
2 0.004 10.93661 2.81615 B m e v  arsize_top=0 arsize_bot=0 is_shrink=n
2 0.004 10.98661 2.81615 B m e v  arsize_top=0 arsize_bot=0 is_shrink=n
2 0.004 11.03661 2.81615 B m e v  arsize_top=0 arsize_bot=0 is_shrink=n
2 0.004 11.08661 2.81615 B m e v  arsize_top=0 arsize_bot=0 is_shrink=n
2 0.004 4.88268 2.81615 B m e v  arsize_top=0 arsize_bot=0 is_shrink=n
2 0.004 4.93268 2.81615 B m e v  arsize_top=0 arsize_bot=0 is_shrink=n
2 0.004 4.98268 2.81615 B m e v  arsize_top=0 arsize_bot=0 is_shrink=n
2 0.004 5.03268 2.81615 B m e v  arsize_top=0 arsize_bot=0 is_shrink=n
2 0.004 5.08268 2.81615 B m e v  arsize_top=0 arsize_bot=0 is_shrink=n
2 0.005 11.28279 2.9414 B m e v  arsize_top=0 arsize_bot=0 is_shrink=n
2 0.005 11.28279 2.9764 B m e v  arsize_top=0 arsize_bot=0 is_shrink=n
2 0.005 11.28279 3.0214 B m e v  arsize_top=0 arsize_bot=0 is_shrink=n
2 0.005 11.28279 3.0564 B m e v  arsize_top=0 arsize_bot=0 is_shrink=n
2 0.005 11.28279 3.1014 B m e v  arsize_top=0 arsize_bot=0 is_shrink=n
2 0.005 11.28279 3.1364 B m e v  arsize_top=0 arsize_bot=0 is_shrink=n
2 0.005 11.28279 3.1814 B m e v  arsize_top=0 arsize_bot=0 is_shrink=n
2 0.005 11.28279 3.2164 B m e v  arsize_top=0 arsize_bot=0 is_shrink=n
2 0.005 11.28279 3.2614 B m e v  arsize_top=0 arsize_bot=0 is_shrink=n
2 0.005 11.28279 3.2964 B m e v  arsize_top=0 arsize_bot=0 is_shrink=n
2 0.005 5.27886 2.9414 B m e v  arsize_top=0 arsize_bot=0 is_shrink=n
2 0.005 5.27886 2.9764 B m e v  arsize_top=0 arsize_bot=0 is_shrink=n
2 0.005 5.27886 3.0214 B m e v  arsize_top=0 arsize_bot=0 is_shrink=n
2 0.005 5.27886 3.0564 B m e v  arsize_top=0 arsize_bot=0 is_shrink=n
2 0.005 5.27886 3.1014 B m e v  arsize_top=0 arsize_bot=0 is_shrink=n
2 0.005 5.27886 3.1364 B m e v  arsize_top=0 arsize_bot=0 is_shrink=n
2 0.005 5.27886 3.1814 B m e v  arsize_top=0 arsize_bot=0 is_shrink=n
2 0.005 5.27886 3.2164 B m e v  arsize_top=0 arsize_bot=0 is_shrink=n
2 0.005 5.27886 3.2614 B m e v  arsize_top=0 arsize_bot=0 is_shrink=n
2 0.005 5.27886 3.2964 B m e v  arsize_top=0 arsize_bot=0 is_shrink=n
2 0.005 5.57709 4.6802 B m e v  arsize_top=0 arsize_bot=0 is_shrink=n
2 0.005 5.59709 4.7302 B m e v  arsize_top=0 arsize_bot=0 is_shrink=n
2 0.005 5.59709 4.7702 B m e v  arsize_top=0 arsize_bot=0 is_shrink=n
2 0.005 5.59709 4.8102 B m e v  arsize_top=0 arsize_bot=0 is_shrink=n
2 0.005 5.61709 4.6802 B m e v  arsize_top=0 arsize_bot=0 is_shrink=n
2 0.005 5.65709 4.6802 B m e v  arsize_top=0 arsize_bot=0 is_shrink=n
2 0.005 5.67709 4.7302 B m e v  arsize_top=0 arsize_bot=0 is_shrink=n
2 0.005 5.67709 4.7702 B m e v  arsize_top=0 arsize_bot=0 is_shrink=n
2 0.005 5.67709 4.8102 B m e v  arsize_top=0 arsize_bot=0 is_shrink=n
2 0.005 5.69709 4.6802 B m e v  arsize_top=0 arsize_bot=0 is_shrink=n
2 0.005 5.73709 4.6802 B m e v  arsize_top=0 arsize_bot=0 is_shrink=n
2 0.005 5.75709 4.7302 B m e v  arsize_top=0 arsize_bot=0 is_shrink=n
2 0.005 5.75709 4.7702 B m e v  arsize_top=0 arsize_bot=0 is_shrink=n
2 0.005 5.75709 4.8102 B m e v  arsize_top=0 arsize_bot=0 is_shrink=n
2 0.005 5.77709 4.6802 B m e v  arsize_top=0 arsize_bot=0 is_shrink=n
2 0.005 5.81709 4.6802 B m e v  arsize_top=0 arsize_bot=0 is_shrink=n
2 0.005 5.83709 4.7302 B m e v  arsize_top=0 arsize_bot=0 is_shrink=n
2 0.005 5.83709 4.7702 B m e v  arsize_top=0 arsize_bot=0 is_shrink=n
2 0.005 5.83709 4.8102 B m e v  arsize_top=0 arsize_bot=0 is_shrink=n
2 0.005 5.85709 4.6802 B m e v  arsize_top=0 arsize_bot=0 is_shrink=n
2 0.005 5.89709 4.6802 B m e v  arsize_top=0 arsize_bot=0 is_shrink=n
2 0.005 5.91709 4.7302 B m e v  arsize_top=0 arsize_bot=0 is_shrink=n
2 0.005 5.91709 4.7702 B m e v  arsize_top=0 arsize_bot=0 is_shrink=n
2 0.005 5.91709 4.8102 B m e v  arsize_top=0 arsize_bot=0 is_shrink=n
2 0.005 5.93709 4.6802 B m e v  arsize_top=0 arsize_bot=0 is_shrink=n
2 0.005 5.97709 4.6802 B m e v  arsize_top=0 arsize_bot=0 is_shrink=n
2 0.005 5.99709 4.7302 B m e v  arsize_top=0 arsize_bot=0 is_shrink=n
2 0.005 5.99709 4.7702 B m e v  arsize_top=0 arsize_bot=0 is_shrink=n
2 0.005 5.99709 4.8102 B m e v  arsize_top=0 arsize_bot=0 is_shrink=n
2 0.005 6.01709 4.6802 B m e v  arsize_top=0 arsize_bot=0 is_shrink=n
2 0.005 6.05709 4.6802 B m e v  arsize_top=0 arsize_bot=0 is_shrink=n
2 0.005 6.07709 4.7302 B m e v  arsize_top=0 arsize_bot=0 is_shrink=n
2 0.005 6.07709 4.7702 B m e v  arsize_top=0 arsize_bot=0 is_shrink=n
2 0.005 6.07709 4.8102 B m e v  arsize_top=0 arsize_bot=0 is_shrink=n
2 0.005 6.09709 4.6802 B m e v  arsize_top=0 arsize_bot=0 is_shrink=n
2 0.005 6.13709 4.6402 B m e v  arsize_top=0 arsize_bot=0 is_shrink=n
2 0.005 6.13709 4.6802 B m e v  arsize_top=0 arsize_bot=0 is_shrink=n
2 0.005 6.13709 4.7202 B m e v  arsize_top=0 arsize_bot=0 is_shrink=n
2 0.005 6.13709 4.7602 B m e v  arsize_top=0 arsize_bot=0 is_shrink=n
2 0.005 6.13709 4.8002 B m e v  arsize_top=0 arsize_bot=0 is_shrink=n
2 0.005 6.13709 4.8402 B m e v  arsize_top=0 arsize_bot=0 is_shrink=n
2 0.005 6.13709 4.8852 B m e v  arsize_top=0 arsize_bot=0 is_shrink=n
2 0.005 6.13709 4.9252 B m e v  arsize_top=0 arsize_bot=0 is_shrink=n
3 0.005 7.17717 5.93307 B e e  arsize_top=0 arsize_bot=0 is_shrink=n
3 0.005 7.28017 5.8904 B e e  arsize_top=0 arsize_bot=0 is_shrink=n
3 0.005 7.32284 5.7874 B e e  arsize_top=0 arsize_bot=0 is_shrink=n
3 0.005 7.28017 5.6844 B e e  arsize_top=0 arsize_bot=0 is_shrink=n
3 0.005 7.17717 5.64173 B e e  arsize_top=0 arsize_bot=0 is_shrink=n
3 0.005 7.07417 5.6844 B e e  arsize_top=0 arsize_bot=0 is_shrink=n
3 0.005 7.0315 5.7874 B e e  arsize_top=0 arsize_bot=0 is_shrink=n
3 0.005 7.07417 5.8904 B e e  arsize_top=0 arsize_bot=0 is_shrink=n
3 0.005 7.17717 0.38189 B e e  arsize_top=0 arsize_bot=0 is_shrink=n
3 0.005 7.28017 0.33922 B e e  arsize_top=0 arsize_bot=0 is_shrink=n
3 0.005 7.32284 0.23622 B e e  arsize_top=0 arsize_bot=0 is_shrink=n
3 0.005 7.28017 0.13322 B e e  arsize_top=0 arsize_bot=0 is_shrink=n
3 0.005 7.17717 0.09055 B e e  arsize_top=0 arsize_bot=0 is_shrink=n
3 0.005 7.07417 0.13322 B e e  arsize_top=0 arsize_bot=0 is_shrink=n
3 0.005 7.0315 0.23622 B e e  arsize_top=0 arsize_bot=0 is_shrink=n
3 0.005 7.07417 0.33922 B e e  arsize_top=0 arsize_bot=0 is_shrink=n
3 0.005 0.22245 0.8189 B e e  arsize_top=0 arsize_bot=0 is_shrink=n
3 0.005 0.313 0.77953 B e e  arsize_top=0 arsize_bot=0 is_shrink=n
3 0.005 0.35237 0.68898 B e e  arsize_top=0 arsize_bot=0 is_shrink=n
3 0.005 0.313 0.59843 B e e  arsize_top=0 arsize_bot=0 is_shrink=n
3 0.005 0.22245 0.55906 B e e  arsize_top=0 arsize_bot=0 is_shrink=n
3 0.005 0.1319 0.59843 B e e  arsize_top=0 arsize_bot=0 is_shrink=n
3 0.005 0.09253 0.68898 B e e  arsize_top=0 arsize_bot=0 is_shrink=n
3 0.005 0.1319 0.77953 B e e  arsize_top=0 arsize_bot=0 is_shrink=n
3 0.005 0.22245 5.24803 B e e  arsize_top=0 arsize_bot=0 is_shrink=n
3 0.005 0.313 5.20866 B e e  arsize_top=0 arsize_bot=0 is_shrink=n
3 0.005 0.35237 5.11811 B e e  arsize_top=0 arsize_bot=0 is_shrink=n
3 0.005 0.313 5.02756 B e e  arsize_top=0 arsize_bot=0 is_shrink=n
3 0.005 0.22245 4.98819 B e e  arsize_top=0 arsize_bot=0 is_shrink=n
3 0.005 0.1319 5.02756 B e e  arsize_top=0 arsize_bot=0 is_shrink=n
3 0.005 0.09253 5.11811 B e e  arsize_top=0 arsize_bot=0 is_shrink=n
3 0.005 0.1319 5.20866 B e e  arsize_top=0 arsize_bot=0 is_shrink=n
3 0.005 12.68702 5.2874 B e e  arsize_top=0 arsize_bot=0 is_shrink=n
3 0.005 12.77757 5.24803 B e e  arsize_top=0 arsize_bot=0 is_shrink=n
3 0.005 12.81694 5.15748 B e e  arsize_top=0 arsize_bot=0 is_shrink=n
3 0.005 12.77757 5.06693 B e e  arsize_top=0 arsize_bot=0 is_shrink=n
3 0.005 12.68702 5.02756 B e e  arsize_top=0 arsize_bot=0 is_shrink=n
3 0.005 12.59647 5.06693 B e e  arsize_top=0 arsize_bot=0 is_shrink=n
3 0.005 12.5571 5.15748 B e e  arsize_top=0 arsize_bot=0 is_shrink=n
3 0.005 12.59647 5.24803 B e e  arsize_top=0 arsize_bot=0 is_shrink=n
3 0.005 12.68702 0.85827 B e e  arsize_top=0 arsize_bot=0 is_shrink=n
3 0.005 12.77757 0.8189 B e e  arsize_top=0 arsize_bot=0 is_shrink=n
3 0.005 12.81694 0.72835 B e e  arsize_top=0 arsize_bot=0 is_shrink=n
3 0.005 12.77757 0.6378 B e e  arsize_top=0 arsize_bot=0 is_shrink=n
3 0.005 12.68702 0.59843 B e e  arsize_top=0 arsize_bot=0 is_shrink=n
3 0.005 12.59647 0.6378 B e e  arsize_top=0 arsize_bot=0 is_shrink=n
3 0.005 12.5571 0.72835 B e e  arsize_top=0 arsize_bot=0 is_shrink=n
3 0.005 12.59647 0.8189 B e e  arsize_top=0 arsize_bot=0 is_shrink=n
3 0.005 6.11811 1.39764 B e e  arsize_top=0 arsize_bot=0 is_shrink=n
3 0.005 6.02756 1.43701 B e e  arsize_top=0 arsize_bot=0 is_shrink=n
3 0.005 5.98819 1.52756 B e e  arsize_top=0 arsize_bot=0 is_shrink=n
3 0.005 6.02756 1.61811 B e e  arsize_top=0 arsize_bot=0 is_shrink=n
3 0.005 6.11811 1.65748 B e e  arsize_top=0 arsize_bot=0 is_shrink=n
3 0.005 6.20866 1.61811 B e e  arsize_top=0 arsize_bot=0 is_shrink=n
3 0.005 6.24803 1.52756 B e e  arsize_top=0 arsize_bot=0 is_shrink=n
3 0.005 6.20866 1.43701 B e e  arsize_top=0 arsize_bot=0 is_shrink=n
3 0.005 4.83268 1.37795 B e e  arsize_top=0 arsize_bot=0 is_shrink=n
3 0.005 4.74081 1.416 B e e  arsize_top=0 arsize_bot=0 is_shrink=n
3 0.005 4.70276 1.50787 B e e  arsize_top=0 arsize_bot=0 is_shrink=n
3 0.005 4.74081 1.59975 B e e  arsize_top=0 arsize_bot=0 is_shrink=n
3 0.005 4.83268 1.6378 B e e  arsize_top=0 arsize_bot=0 is_shrink=n
3 0.005 4.92455 1.59975 B e e  arsize_top=0 arsize_bot=0 is_shrink=n
3 0.005 4.9626 1.50787 B e e  arsize_top=0 arsize_bot=0 is_shrink=n
3 0.005 4.92455 1.416 B e e  arsize_top=0 arsize_bot=0 is_shrink=n
3 0.005 2.24606 1.37795 B e e  arsize_top=0 arsize_bot=0 is_shrink=n
3 0.005 2.15419 1.416 B e e  arsize_top=0 arsize_bot=0 is_shrink=n
3 0.005 2.11614 1.50787 B e e  arsize_top=0 arsize_bot=0 is_shrink=n
3 0.005 2.15419 1.59975 B e e  arsize_top=0 arsize_bot=0 is_shrink=n
3 0.005 2.24606 1.6378 B e e  arsize_top=0 arsize_bot=0 is_shrink=n
3 0.005 2.33793 1.59975 B e e  arsize_top=0 arsize_bot=0 is_shrink=n
3 0.005 2.37598 1.50787 B e e  arsize_top=0 arsize_bot=0 is_shrink=n
3 0.005 2.33793 1.416 B e e  arsize_top=0 arsize_bot=0 is_shrink=n
3 0.005 0.96063 1.39764 B e e  arsize_top=0 arsize_bot=0 is_shrink=n
3 0.005 0.86876 1.43569 B e e  arsize_top=0 arsize_bot=0 is_shrink=n
3 0.005 0.83071 1.52756 B e e  arsize_top=0 arsize_bot=0 is_shrink=n
3 0.005 0.86876 1.61943 B e e  arsize_top=0 arsize_bot=0 is_shrink=n
3 0.005 0.96063 1.65748 B e e  arsize_top=0 arsize_bot=0 is_shrink=n
3 0.005 1.0525 1.61943 B e e  arsize_top=0 arsize_bot=0 is_shrink=n
3 0.005 1.09055 1.52756 B e e  arsize_top=0 arsize_bot=0 is_shrink=n
3 0.005 1.0525 1.43569 B e e  arsize_top=0 arsize_bot=0 is_shrink=n
3 0.005 0.96063 4.0748 B e e  arsize_top=0 arsize_bot=0 is_shrink=n
3 0.005 0.86876 4.11286 B e e  arsize_top=0 arsize_bot=0 is_shrink=n
3 0.005 0.83071 4.20473 B e e  arsize_top=0 arsize_bot=0 is_shrink=n
3 0.005 0.86876 4.2966 B e e  arsize_top=0 arsize_bot=0 is_shrink=n
3 0.005 0.96063 4.33465 B e e  arsize_top=0 arsize_bot=0 is_shrink=n
3 0.005 1.0525 4.2966 B e e  arsize_top=0 arsize_bot=0 is_shrink=n
3 0.005 1.09055 4.20473 B e e  arsize_top=0 arsize_bot=0 is_shrink=n
3 0.005 1.0525 4.11286 B e e  arsize_top=0 arsize_bot=0 is_shrink=n
3 0.005 2.24606 4.09449 B e e  arsize_top=0 arsize_bot=0 is_shrink=n
3 0.005 2.15419 4.13254 B e e  arsize_top=0 arsize_bot=0 is_shrink=n
3 0.005 2.11614 4.22441 B e e  arsize_top=0 arsize_bot=0 is_shrink=n
3 0.005 2.15419 4.31628 B e e  arsize_top=0 arsize_bot=0 is_shrink=n
3 0.005 2.24606 4.35433 B e e  arsize_top=0 arsize_bot=0 is_shrink=n
3 0.005 2.33793 4.31628 B e e  arsize_top=0 arsize_bot=0 is_shrink=n
3 0.005 2.37598 4.22441 B e e  arsize_top=0 arsize_bot=0 is_shrink=n
3 0.005 2.33793 4.13254 B e e  arsize_top=0 arsize_bot=0 is_shrink=n
3 0.005 4.83268 4.09449 B e e  arsize_top=0 arsize_bot=0 is_shrink=n
3 0.005 4.74081 4.13254 B e e  arsize_top=0 arsize_bot=0 is_shrink=n
3 0.005 4.70276 4.22441 B e e  arsize_top=0 arsize_bot=0 is_shrink=n
3 0.005 4.74081 4.31628 B e e  arsize_top=0 arsize_bot=0 is_shrink=n
3 0.005 4.83268 4.35433 B e e  arsize_top=0 arsize_bot=0 is_shrink=n
3 0.005 4.92455 4.31628 B e e  arsize_top=0 arsize_bot=0 is_shrink=n
3 0.005 4.9626 4.22441 B e e  arsize_top=0 arsize_bot=0 is_shrink=n
3 0.005 4.92455 4.13254 B e e  arsize_top=0 arsize_bot=0 is_shrink=n
3 0.005 6.11811 4.0748 B e e  arsize_top=0 arsize_bot=0 is_shrink=n
3 0.005 6.02624 4.11286 B e e  arsize_top=0 arsize_bot=0 is_shrink=n
3 0.005 5.98819 4.20473 B e e  arsize_top=0 arsize_bot=0 is_shrink=n
3 0.005 6.02624 4.2966 B e e  arsize_top=0 arsize_bot=0 is_shrink=n
3 0.005 6.11811 4.33465 B e e  arsize_top=0 arsize_bot=0 is_shrink=n
3 0.005 6.20998 4.2966 B e e  arsize_top=0 arsize_bot=0 is_shrink=n
3 0.005 6.24803 4.20473 B e e  arsize_top=0 arsize_bot=0 is_shrink=n
3 0.005 6.20998 4.11286 B e e  arsize_top=0 arsize_bot=0 is_shrink=n
3 0 4.29724 2.86614 T 0.23622 1.61417 e e staggered 0 0 0  is_shrink=n
3 0 2.7815 2.86614 T 0.23622 1.61417 e e staggered 0 0 0  is_shrink=n
3 0.005 12.12205 1.39764 B e e  arsize_top=0 arsize_bot=0 is_shrink=n
3 0.005 12.0315 1.43701 B e e  arsize_top=0 arsize_bot=0 is_shrink=n
3 0.005 11.99213 1.52756 B e e  arsize_top=0 arsize_bot=0 is_shrink=n
3 0.005 12.0315 1.61811 B e e  arsize_top=0 arsize_bot=0 is_shrink=n
3 0.005 12.12205 1.65748 B e e  arsize_top=0 arsize_bot=0 is_shrink=n
3 0.005 12.2126 1.61811 B e e  arsize_top=0 arsize_bot=0 is_shrink=n
3 0.005 12.25197 1.52756 B e e  arsize_top=0 arsize_bot=0 is_shrink=n
3 0.005 12.2126 1.43701 B e e  arsize_top=0 arsize_bot=0 is_shrink=n
3 0.005 10.83662 1.37795 B e e  arsize_top=0 arsize_bot=0 is_shrink=n
3 0.005 10.74475 1.416 B e e  arsize_top=0 arsize_bot=0 is_shrink=n
3 0.005 10.7067 1.50787 B e e  arsize_top=0 arsize_bot=0 is_shrink=n
3 0.005 10.74475 1.59975 B e e  arsize_top=0 arsize_bot=0 is_shrink=n
3 0.005 10.83662 1.6378 B e e  arsize_top=0 arsize_bot=0 is_shrink=n
3 0.005 10.92849 1.59975 B e e  arsize_top=0 arsize_bot=0 is_shrink=n
3 0.005 10.96654 1.50787 B e e  arsize_top=0 arsize_bot=0 is_shrink=n
3 0.005 10.92849 1.416 B e e  arsize_top=0 arsize_bot=0 is_shrink=n
3 0.005 8.25 1.37795 B e e  arsize_top=0 arsize_bot=0 is_shrink=n
3 0.005 8.15813 1.416 B e e  arsize_top=0 arsize_bot=0 is_shrink=n
3 0.005 8.12008 1.50787 B e e  arsize_top=0 arsize_bot=0 is_shrink=n
3 0.005 8.15813 1.59975 B e e  arsize_top=0 arsize_bot=0 is_shrink=n
3 0.005 8.25 1.6378 B e e  arsize_top=0 arsize_bot=0 is_shrink=n
3 0.005 8.34187 1.59975 B e e  arsize_top=0 arsize_bot=0 is_shrink=n
3 0.005 8.37992 1.50787 B e e  arsize_top=0 arsize_bot=0 is_shrink=n
3 0.005 8.34187 1.416 B e e  arsize_top=0 arsize_bot=0 is_shrink=n
3 0.005 6.96457 1.39764 B e e  arsize_top=0 arsize_bot=0 is_shrink=n
3 0.005 6.8727 1.43569 B e e  arsize_top=0 arsize_bot=0 is_shrink=n
3 0.005 6.83465 1.52756 B e e  arsize_top=0 arsize_bot=0 is_shrink=n
3 0.005 6.8727 1.61943 B e e  arsize_top=0 arsize_bot=0 is_shrink=n
3 0.005 6.96457 1.65748 B e e  arsize_top=0 arsize_bot=0 is_shrink=n
3 0.005 7.05644 1.61943 B e e  arsize_top=0 arsize_bot=0 is_shrink=n
3 0.005 7.09449 1.52756 B e e  arsize_top=0 arsize_bot=0 is_shrink=n
3 0.005 7.05644 1.43569 B e e  arsize_top=0 arsize_bot=0 is_shrink=n
3 0.005 6.96457 4.0748 B e e  arsize_top=0 arsize_bot=0 is_shrink=n
3 0.005 6.8727 4.11286 B e e  arsize_top=0 arsize_bot=0 is_shrink=n
3 0.005 6.83465 4.20473 B e e  arsize_top=0 arsize_bot=0 is_shrink=n
3 0.005 6.8727 4.2966 B e e  arsize_top=0 arsize_bot=0 is_shrink=n
3 0.005 6.96457 4.33465 B e e  arsize_top=0 arsize_bot=0 is_shrink=n
3 0.005 7.05644 4.2966 B e e  arsize_top=0 arsize_bot=0 is_shrink=n
3 0.005 7.09449 4.20473 B e e  arsize_top=0 arsize_bot=0 is_shrink=n
3 0.005 7.05644 4.11286 B e e  arsize_top=0 arsize_bot=0 is_shrink=n
3 0.005 8.25 4.09449 B e e  arsize_top=0 arsize_bot=0 is_shrink=n
3 0.005 8.15813 4.13254 B e e  arsize_top=0 arsize_bot=0 is_shrink=n
3 0.005 8.12008 4.22441 B e e  arsize_top=0 arsize_bot=0 is_shrink=n
3 0.005 8.15813 4.31628 B e e  arsize_top=0 arsize_bot=0 is_shrink=n
3 0.005 8.25 4.35433 B e e  arsize_top=0 arsize_bot=0 is_shrink=n
3 0.005 8.34187 4.31628 B e e  arsize_top=0 arsize_bot=0 is_shrink=n
3 0.005 8.37992 4.22441 B e e  arsize_top=0 arsize_bot=0 is_shrink=n
3 0.005 8.34187 4.13254 B e e  arsize_top=0 arsize_bot=0 is_shrink=n
3 0.005 10.83662 4.09449 B e e  arsize_top=0 arsize_bot=0 is_shrink=n
3 0.005 10.74475 4.13254 B e e  arsize_top=0 arsize_bot=0 is_shrink=n
3 0.005 10.7067 4.22441 B e e  arsize_top=0 arsize_bot=0 is_shrink=n
3 0.005 10.74475 4.31628 B e e  arsize_top=0 arsize_bot=0 is_shrink=n
3 0.005 10.83662 4.35433 B e e  arsize_top=0 arsize_bot=0 is_shrink=n
3 0.005 10.92849 4.31628 B e e  arsize_top=0 arsize_bot=0 is_shrink=n
3 0.005 10.96654 4.22441 B e e  arsize_top=0 arsize_bot=0 is_shrink=n
3 0.005 10.92849 4.13254 B e e  arsize_top=0 arsize_bot=0 is_shrink=n
3 0.005 12.12205 4.0748 B e e  arsize_top=0 arsize_bot=0 is_shrink=n
3 0.005 12.03018 4.11286 B e e  arsize_top=0 arsize_bot=0 is_shrink=n
3 0.005 11.99213 4.20473 B e e  arsize_top=0 arsize_bot=0 is_shrink=n
3 0.005 12.03018 4.2966 B e e  arsize_top=0 arsize_bot=0 is_shrink=n
3 0.005 12.12205 4.33465 B e e  arsize_top=0 arsize_bot=0 is_shrink=n
3 0.005 12.21392 4.2966 B e e  arsize_top=0 arsize_bot=0 is_shrink=n
3 0.005 12.25197 4.20473 B e e  arsize_top=0 arsize_bot=0 is_shrink=n
3 0.005 12.21392 4.11286 B e e  arsize_top=0 arsize_bot=0 is_shrink=n
3 0 10.30118 2.86614 T 0.23622 1.61417 e e staggered 0 0 0  is_shrink=n
3 0 8.78544 2.86614 T 0.23622 1.61417 e e staggered 0 0 0  is_shrink=n
3 0.0275599 12.14961 5.49685 B e e  arsize_top=0 arsize_bot=0 is_shrink=n
3 0.0275599 11.98425 5.49685 B e e  arsize_top=0 arsize_bot=0 is_shrink=n
3 0.0275599 11.8189 5.49685 B e e  arsize_top=0 arsize_bot=0 is_shrink=n
3 0.0275599 11.65354 5.49685 B e e  arsize_top=0 arsize_bot=0 is_shrink=n
3 0.0275599 11.48819 5.49685 B e e  arsize_top=0 arsize_bot=0 is_shrink=n
3 0.0275599 11.32284 5.49685 B e e  arsize_top=0 arsize_bot=0 is_shrink=n
3 0.0275599 11.15748 5.49685 B e e  arsize_top=0 arsize_bot=0 is_shrink=n
3 0.0275599 10.99213 5.49685 B e e  arsize_top=0 arsize_bot=0 is_shrink=n
3 0.0275599 10.82677 5.49685 B e e  arsize_top=0 arsize_bot=0 is_shrink=n
3 0 2.72681 4.85788 T 0.01378 0.05118 e e staggered 0 0 0  is_shrink=n
3 0 2.79768 4.85788 T 0.01378 0.05118 e e staggered 0 0 0  is_shrink=n
3 0 2.86855 4.85788 T 0.01378 0.05118 e e staggered 0 0 0  is_shrink=n
3 0 2.89217 4.85788 T 0.01378 0.05118 e e staggered 0 0 0  is_shrink=n
3 0 2.91579 4.85788 T 0.01378 0.05118 e e staggered 0 0 0  is_shrink=n
3 0 2.93941 4.85788 T 0.01378 0.05118 e e staggered 0 0 0  is_shrink=n
3 0 3.01028 4.85788 T 0.01378 0.05118 e e staggered 0 0 0  is_shrink=n
3 0 3.08114 4.85788 T 0.01378 0.05118 e e staggered 0 0 0  is_shrink=n
3 0 3.15201 4.85788 T 0.01378 0.05118 e e staggered 0 0 0  is_shrink=n
3 0 3.22288 4.85788 T 0.01378 0.05118 e e staggered 0 0 0  is_shrink=n
3 0 3.29374 4.85788 T 0.01378 0.05118 e e staggered 0 0 0  is_shrink=n
3 0 3.31736 4.85788 T 0.01378 0.05118 e e staggered 0 0 0  is_shrink=n
3 0 3.34099 4.85788 T 0.01378 0.05118 e e staggered 0 0 0  is_shrink=n
3 0 3.36461 4.85788 T 0.01378 0.05118 e e staggered 0 0 0  is_shrink=n
3 0 3.43547 4.85788 T 0.01378 0.05118 e e staggered 0 0 0  is_shrink=n
3 0 3.50634 4.85788 T 0.01378 0.05118 e e staggered 0 0 0  is_shrink=n
3 0 3.57721 4.85788 T 0.01378 0.05118 e e staggered 0 0 0  is_shrink=n
3 0 2.72681 4.97914 T 0.01378 0.05118 e e staggered 0 0 0  is_shrink=n
3 0 2.79768 4.97914 T 0.01378 0.05118 e e staggered 0 0 0  is_shrink=n
3 0 2.86855 4.97914 T 0.01378 0.05118 e e staggered 0 0 0  is_shrink=n
3 0 2.89217 4.97914 T 0.01378 0.05118 e e staggered 0 0 0  is_shrink=n
3 0 2.91579 4.97914 T 0.01378 0.05118 e e staggered 0 0 0  is_shrink=n
3 0 2.93941 4.97914 T 0.01378 0.05118 e e staggered 0 0 0  is_shrink=n
3 0 2.96303 4.97914 T 0.01378 0.05118 e e staggered 0 0 0  is_shrink=n
3 0 2.98666 4.97914 T 0.01378 0.05118 e e staggered 0 0 0  is_shrink=n
3 0 3.01028 4.97914 T 0.01378 0.05118 e e staggered 0 0 0  is_shrink=n
3 0 3.08114 4.97914 T 0.01378 0.05118 e e staggered 0 0 0  is_shrink=n
3 0 3.15201 4.97914 T 0.01378 0.05118 e e staggered 0 0 0  is_shrink=n
3 0 3.22288 4.97914 T 0.01378 0.05118 e e staggered 0 0 0  is_shrink=n
3 0 3.29374 4.97914 T 0.01378 0.05118 e e staggered 0 0 0  is_shrink=n
3 0 3.36461 4.97914 T 0.01378 0.05118 e e staggered 0 0 0  is_shrink=n
3 0 3.43547 4.97914 T 0.01378 0.05118 e e staggered 0 0 0  is_shrink=n
3 0 3.48272 4.97914 T 0.01378 0.05118 e e staggered 0 0 0  is_shrink=n
3 0 3.50634 4.97914 T 0.01378 0.05118 e e staggered 0 0 0  is_shrink=n
3 0 3.57721 4.97914 T 0.01378 0.05118 e e staggered 0 0 0  is_shrink=n
3 0.0149599 2.69925 5.05827 B e e  arsize_top=0 arsize_bot=0 is_shrink=n
3 0.0149599 3.60477 5.05827 B e e  arsize_top=0 arsize_bot=0 is_shrink=n
3 0.0149599 2.67957 4.77875 B e e  arsize_top=0 arsize_bot=0 is_shrink=n
3 0.0149599 3.60477 4.77875 B e e  arsize_top=0 arsize_bot=0 is_shrink=n
3 0 8.73035 4.85788 T 0.01378 0.05118 e e staggered 0 0 0  is_shrink=n
3 0 8.80122 4.85788 T 0.01378 0.05118 e e staggered 0 0 0  is_shrink=n
3 0 8.87209 4.85788 T 0.01378 0.05118 e e staggered 0 0 0  is_shrink=n
3 0 8.89571 4.85788 T 0.01378 0.05118 e e staggered 0 0 0  is_shrink=n
3 0 8.91933 4.85788 T 0.01378 0.05118 e e staggered 0 0 0  is_shrink=n
3 0 8.94295 4.85788 T 0.01378 0.05118 e e staggered 0 0 0  is_shrink=n
3 0 9.01382 4.85788 T 0.01378 0.05118 e e staggered 0 0 0  is_shrink=n
3 0 9.08468 4.85788 T 0.01378 0.05118 e e staggered 0 0 0  is_shrink=n
3 0 9.15555 4.85788 T 0.01378 0.05118 e e staggered 0 0 0  is_shrink=n
3 0 9.22642 4.85788 T 0.01378 0.05118 e e staggered 0 0 0  is_shrink=n
3 0 9.29728 4.85788 T 0.01378 0.05118 e e staggered 0 0 0  is_shrink=n
3 0 9.3209 4.85788 T 0.01378 0.05118 e e staggered 0 0 0  is_shrink=n
3 0 9.34453 4.85788 T 0.01378 0.05118 e e staggered 0 0 0  is_shrink=n
3 0 9.36815 4.85788 T 0.01378 0.05118 e e staggered 0 0 0  is_shrink=n
3 0 9.43901 4.85788 T 0.01378 0.05118 e e staggered 0 0 0  is_shrink=n
3 0 9.50988 4.85788 T 0.01378 0.05118 e e staggered 0 0 0  is_shrink=n
3 0 9.58075 4.85788 T 0.01378 0.05118 e e staggered 0 0 0  is_shrink=n
3 0 8.73035 4.97914 T 0.01378 0.05118 e e staggered 0 0 0  is_shrink=n
3 0 8.80122 4.97914 T 0.01378 0.05118 e e staggered 0 0 0  is_shrink=n
3 0 8.87209 4.97914 T 0.01378 0.05118 e e staggered 0 0 0  is_shrink=n
3 0 8.89571 4.97914 T 0.01378 0.05118 e e staggered 0 0 0  is_shrink=n
3 0 8.91933 4.97914 T 0.01378 0.05118 e e staggered 0 0 0  is_shrink=n
3 0 8.94295 4.97914 T 0.01378 0.05118 e e staggered 0 0 0  is_shrink=n
3 0 8.96657 4.97914 T 0.01378 0.05118 e e staggered 0 0 0  is_shrink=n
3 0 8.9902 4.97914 T 0.01378 0.05118 e e staggered 0 0 0  is_shrink=n
3 0 9.01382 4.97914 T 0.01378 0.05118 e e staggered 0 0 0  is_shrink=n
3 0 9.08468 4.97914 T 0.01378 0.05118 e e staggered 0 0 0  is_shrink=n
3 0 9.15555 4.97914 T 0.01378 0.05118 e e staggered 0 0 0  is_shrink=n
3 0 9.22642 4.97914 T 0.01378 0.05118 e e staggered 0 0 0  is_shrink=n
3 0 9.29728 4.97914 T 0.01378 0.05118 e e staggered 0 0 0  is_shrink=n
3 0 9.36815 4.97914 T 0.01378 0.05118 e e staggered 0 0 0  is_shrink=n
3 0 9.43901 4.97914 T 0.01378 0.05118 e e staggered 0 0 0  is_shrink=n
3 0 9.48626 4.97914 T 0.01378 0.05118 e e staggered 0 0 0  is_shrink=n
3 0 9.50988 4.97914 T 0.01378 0.05118 e e staggered 0 0 0  is_shrink=n
3 0 9.58075 4.97914 T 0.01378 0.05118 e e staggered 0 0 0  is_shrink=n
3 0.0149599 8.70279 5.05827 B e e  arsize_top=0 arsize_bot=0 is_shrink=n
3 0.0149599 9.60831 5.05827 B e e  arsize_top=0 arsize_bot=0 is_shrink=n
3 0.0149599 8.68311 4.77875 B e e  arsize_top=0 arsize_bot=0 is_shrink=n
3 0.0149599 9.60831 4.77875 B e e  arsize_top=0 arsize_bot=0 is_shrink=n
3 0 1.56221 4.85788 T 0.01378 0.05118 e e staggered 0 0 0  is_shrink=n
3 0 1.63308 4.85788 T 0.01378 0.05118 e e staggered 0 0 0  is_shrink=n
3 0 1.70395 4.85788 T 0.01378 0.05118 e e staggered 0 0 0  is_shrink=n
3 0 1.72757 4.85788 T 0.01378 0.05118 e e staggered 0 0 0  is_shrink=n
3 0 1.75119 4.85788 T 0.01378 0.05118 e e staggered 0 0 0  is_shrink=n
3 0 1.77481 4.85788 T 0.01378 0.05118 e e staggered 0 0 0  is_shrink=n
3 0 1.84568 4.85788 T 0.01378 0.05118 e e staggered 0 0 0  is_shrink=n
3 0 1.91654 4.85788 T 0.01378 0.05118 e e staggered 0 0 0  is_shrink=n
3 0 1.98741 4.85788 T 0.01378 0.05118 e e staggered 0 0 0  is_shrink=n
3 0 2.05828 4.85788 T 0.01378 0.05118 e e staggered 0 0 0  is_shrink=n
3 0 2.12914 4.85788 T 0.01378 0.05118 e e staggered 0 0 0  is_shrink=n
3 0 2.15276 4.85788 T 0.01378 0.05118 e e staggered 0 0 0  is_shrink=n
3 0 2.17639 4.85788 T 0.01378 0.05118 e e staggered 0 0 0  is_shrink=n
3 0 2.20001 4.85788 T 0.01378 0.05118 e e staggered 0 0 0  is_shrink=n
3 0 2.27087 4.85788 T 0.01378 0.05118 e e staggered 0 0 0  is_shrink=n
3 0 2.34174 4.85788 T 0.01378 0.05118 e e staggered 0 0 0  is_shrink=n
3 0 2.41261 4.85788 T 0.01378 0.05118 e e staggered 0 0 0  is_shrink=n
3 0 1.56221 4.97914 T 0.01378 0.05118 e e staggered 0 0 0  is_shrink=n
3 0 1.63308 4.97914 T 0.01378 0.05118 e e staggered 0 0 0  is_shrink=n
3 0 1.70395 4.97914 T 0.01378 0.05118 e e staggered 0 0 0  is_shrink=n
3 0 1.72757 4.97914 T 0.01378 0.05118 e e staggered 0 0 0  is_shrink=n
3 0 1.75119 4.97914 T 0.01378 0.05118 e e staggered 0 0 0  is_shrink=n
3 0 1.77481 4.97914 T 0.01378 0.05118 e e staggered 0 0 0  is_shrink=n
3 0 1.79843 4.97914 T 0.01378 0.05118 e e staggered 0 0 0  is_shrink=n
3 0 1.82206 4.97914 T 0.01378 0.05118 e e staggered 0 0 0  is_shrink=n
3 0 1.84568 4.97914 T 0.01378 0.05118 e e staggered 0 0 0  is_shrink=n
3 0 1.91654 4.97914 T 0.01378 0.05118 e e staggered 0 0 0  is_shrink=n
3 0 1.98741 4.97914 T 0.01378 0.05118 e e staggered 0 0 0  is_shrink=n
3 0 2.05828 4.97914 T 0.01378 0.05118 e e staggered 0 0 0  is_shrink=n
3 0 2.12914 4.97914 T 0.01378 0.05118 e e staggered 0 0 0  is_shrink=n
3 0 2.20001 4.97914 T 0.01378 0.05118 e e staggered 0 0 0  is_shrink=n
3 0 2.22363 4.97914 T 0.01378 0.05118 e e staggered 0 0 0  is_shrink=n
3 0 2.24725 4.97914 T 0.01378 0.05118 e e staggered 0 0 0  is_shrink=n
3 0 2.27087 4.97914 T 0.01378 0.05118 e e staggered 0 0 0  is_shrink=n
3 0 2.2945 4.97914 T 0.01378 0.05118 e e staggered 0 0 0  is_shrink=n
3 0 2.31812 4.97914 T 0.01378 0.05118 e e staggered 0 0 0  is_shrink=n
3 0 2.34174 4.97914 T 0.01378 0.05118 e e staggered 0 0 0  is_shrink=n
3 0 2.41261 4.97914 T 0.01378 0.05118 e e staggered 0 0 0  is_shrink=n
3 0.0149599 1.53465 5.05827 B e e  arsize_top=0 arsize_bot=0 is_shrink=n
3 0.0149599 2.44017 5.05827 B e e  arsize_top=0 arsize_bot=0 is_shrink=n
3 0.0149599 1.51497 4.77875 B e e  arsize_top=0 arsize_bot=0 is_shrink=n
3 0.0149599 2.45985 4.77875 B e e  arsize_top=0 arsize_bot=0 is_shrink=n
3 0 7.56575 4.85788 T 0.01378 0.05118 e e staggered 0 0 0  is_shrink=n
3 0 7.63662 4.85788 T 0.01378 0.05118 e e staggered 0 0 0  is_shrink=n
3 0 7.70749 4.85788 T 0.01378 0.05118 e e staggered 0 0 0  is_shrink=n
3 0 7.73111 4.85788 T 0.01378 0.05118 e e staggered 0 0 0  is_shrink=n
3 0 7.75473 4.85788 T 0.01378 0.05118 e e staggered 0 0 0  is_shrink=n
3 0 7.77835 4.85788 T 0.01378 0.05118 e e staggered 0 0 0  is_shrink=n
3 0 7.84922 4.85788 T 0.01378 0.05118 e e staggered 0 0 0  is_shrink=n
3 0 7.92008 4.85788 T 0.01378 0.05118 e e staggered 0 0 0  is_shrink=n
3 0 7.99095 4.85788 T 0.01378 0.05118 e e staggered 0 0 0  is_shrink=n
3 0 8.06182 4.85788 T 0.01378 0.05118 e e staggered 0 0 0  is_shrink=n
3 0 8.13268 4.85788 T 0.01378 0.05118 e e staggered 0 0 0  is_shrink=n
3 0 8.1563 4.85788 T 0.01378 0.05118 e e staggered 0 0 0  is_shrink=n
3 0 8.17993 4.85788 T 0.01378 0.05118 e e staggered 0 0 0  is_shrink=n
3 0 8.20355 4.85788 T 0.01378 0.05118 e e staggered 0 0 0  is_shrink=n
3 0 8.27441 4.85788 T 0.01378 0.05118 e e staggered 0 0 0  is_shrink=n
3 0 8.34528 4.85788 T 0.01378 0.05118 e e staggered 0 0 0  is_shrink=n
3 0 8.41615 4.85788 T 0.01378 0.05118 e e staggered 0 0 0  is_shrink=n
3 0 7.56575 4.97914 T 0.01378 0.05118 e e staggered 0 0 0  is_shrink=n
3 0 7.63662 4.97914 T 0.01378 0.05118 e e staggered 0 0 0  is_shrink=n
3 0 7.70749 4.97914 T 0.01378 0.05118 e e staggered 0 0 0  is_shrink=n
3 0 7.73111 4.97914 T 0.01378 0.05118 e e staggered 0 0 0  is_shrink=n
3 0 7.75473 4.97914 T 0.01378 0.05118 e e staggered 0 0 0  is_shrink=n
3 0 7.77835 4.97914 T 0.01378 0.05118 e e staggered 0 0 0  is_shrink=n
3 0 7.80197 4.97914 T 0.01378 0.05118 e e staggered 0 0 0  is_shrink=n
3 0 7.8256 4.97914 T 0.01378 0.05118 e e staggered 0 0 0  is_shrink=n
3 0 7.84922 4.97914 T 0.01378 0.05118 e e staggered 0 0 0  is_shrink=n
3 0 7.92008 4.97914 T 0.01378 0.05118 e e staggered 0 0 0  is_shrink=n
3 0 7.99095 4.97914 T 0.01378 0.05118 e e staggered 0 0 0  is_shrink=n
3 0 8.06182 4.97914 T 0.01378 0.05118 e e staggered 0 0 0  is_shrink=n
3 0 8.13268 4.97914 T 0.01378 0.05118 e e staggered 0 0 0  is_shrink=n
3 0 8.20355 4.97914 T 0.01378 0.05118 e e staggered 0 0 0  is_shrink=n
3 0 8.22717 4.97914 T 0.01378 0.05118 e e staggered 0 0 0  is_shrink=n
3 0 8.25079 4.97914 T 0.01378 0.05118 e e staggered 0 0 0  is_shrink=n
3 0 8.27441 4.97914 T 0.01378 0.05118 e e staggered 0 0 0  is_shrink=n
3 0 8.29804 4.97914 T 0.01378 0.05118 e e staggered 0 0 0  is_shrink=n
3 0 8.32166 4.97914 T 0.01378 0.05118 e e staggered 0 0 0  is_shrink=n
3 0 8.34528 4.97914 T 0.01378 0.05118 e e staggered 0 0 0  is_shrink=n
3 0 8.41615 4.97914 T 0.01378 0.05118 e e staggered 0 0 0  is_shrink=n
3 0.0149599 7.53819 5.05827 B e e  arsize_top=0 arsize_bot=0 is_shrink=n
3 0.0149599 8.44371 5.05827 B e e  arsize_top=0 arsize_bot=0 is_shrink=n
3 0.0149599 7.51851 4.77875 B e e  arsize_top=0 arsize_bot=0 is_shrink=n
3 0.0149599 8.46339 4.77875 B e e  arsize_top=0 arsize_bot=0 is_shrink=n
3 0 4.76 5.54929 T 0.07874 0.03543 e e staggered 0 0 0  is_shrink=n
3 0 4.92 5.65315 T 0.02362 0.04134 e e staggered 0 0 0  is_shrink=n
3 0.00394 6.58969 4.82847 T e e  arsize_top=0 arsize_bot=0 is_shrink=n
3 0.00394 6.60544 4.82847 T e e  arsize_top=0 arsize_bot=0 is_shrink=n
3 0.00394 6.62119 4.82847 T e e  arsize_top=0 arsize_bot=0 is_shrink=n
3 0.00394 6.63694 4.82847 T e e  arsize_top=0 arsize_bot=0 is_shrink=n
3 0.00394 6.65269 4.82847 T e e  arsize_top=0 arsize_bot=0 is_shrink=n
3 0.00394 6.69009 4.96429 T e e  arsize_top=0 arsize_bot=0 is_shrink=n
3 0.00394 6.60544 5.00563 T e e  arsize_top=0 arsize_bot=0 is_shrink=n
3 0.00394 6.58969 5.00563 T e e  arsize_top=0 arsize_bot=0 is_shrink=n
3 0 6.62119 4.91705 T 0.08268 0.12205 e e staggered 0 0 0  is_shrink=n
3 0 6.87019 4.88705 T 0.03 0.03 e e staggered 0 0 0  is_shrink=n
3 0 6.87019 4.94705 T 0.03 0.03 e e staggered 0 0 0  is_shrink=n
3 0 3.88313 5.18321 T 0.01575 0.06693 e e staggered 0 0 0  is_shrink=n
3 0.01378 0.09449 1.45276 B e e  arsize_top=0 arsize_bot=0 is_shrink=n
3 0.01378 0.09449 1.84646 B e e  arsize_top=0 arsize_bot=0 is_shrink=n
3 0.01378 0.17323 1.96457 B e e  arsize_top=0 arsize_bot=0 is_shrink=n
3 0.01378 0.09449 2.08268 B e e  arsize_top=0 arsize_bot=0 is_shrink=n
3 0.01378 0.09449 2.16142 B e e  arsize_top=0 arsize_bot=0 is_shrink=n
3 0.01378 0.17323 2.27953 B e e  arsize_top=0 arsize_bot=0 is_shrink=n
3 0.01378 0.09449 2.3189 B e e  arsize_top=0 arsize_bot=0 is_shrink=n
3 0.01378 0.17323 2.43701 B e e  arsize_top=0 arsize_bot=0 is_shrink=n
3 0.01378 0.09449 2.47638 B e e  arsize_top=0 arsize_bot=0 is_shrink=n
3 0.01378 0.17323 2.59449 B e e  arsize_top=0 arsize_bot=0 is_shrink=n
3 0.01378 0.09449 2.7126 B e e  arsize_top=0 arsize_bot=0 is_shrink=n
3 0.01378 0.17323 2.83071 B e e  arsize_top=0 arsize_bot=0 is_shrink=n
3 0.01378 0.09449 2.87008 B e e  arsize_top=0 arsize_bot=0 is_shrink=n
3 0.01378 0.17323 2.98819 B e e  arsize_top=0 arsize_bot=0 is_shrink=n
3 0.01378 0.09449 3.02756 B e e  arsize_top=0 arsize_bot=0 is_shrink=n
3 0.01378 0.17323 3.14567 B e e  arsize_top=0 arsize_bot=0 is_shrink=n
3 0.01378 0.09449 3.18504 B e e  arsize_top=0 arsize_bot=0 is_shrink=n
3 0.01378 0.17323 3.30315 B e e  arsize_top=0 arsize_bot=0 is_shrink=n
3 0.01378 0.17323 3.38189 B e e  arsize_top=0 arsize_bot=0 is_shrink=n
3 0.01378 0.09449 3.5 B e e  arsize_top=0 arsize_bot=0 is_shrink=n
3 0.01378 0.17323 3.53937 B e e  arsize_top=0 arsize_bot=0 is_shrink=n
3 0.01378 0.09449 3.65748 B e e  arsize_top=0 arsize_bot=0 is_shrink=n
3 0.01378 0.17323 3.69685 B e e  arsize_top=0 arsize_bot=0 is_shrink=n
3 0.01378 0.09449 3.81496 B e e  arsize_top=0 arsize_bot=0 is_shrink=n
3 0.01378 0.17323 3.85433 B e e  arsize_top=0 arsize_bot=0 is_shrink=n
3 0.01378 0.09449 3.97244 B e e  arsize_top=0 arsize_bot=0 is_shrink=n
3 0.01378 0.17323 4.01181 B e e  arsize_top=0 arsize_bot=0 is_shrink=n
3 0.01378 0.09449 4.12992 B e e  arsize_top=0 arsize_bot=0 is_shrink=n
3 0.01378 0.17323 4.16929 B e e  arsize_top=0 arsize_bot=0 is_shrink=n
3 0.01378 0.09449 4.2874 B e e  arsize_top=0 arsize_bot=0 is_shrink=n
3 0.01378 0.17323 4.32677 B e e  arsize_top=0 arsize_bot=0 is_shrink=n
3 0.01378 0.09449 4.44488 B e e  arsize_top=0 arsize_bot=0 is_shrink=n
3 0.01378 0.17323 4.48425 B e e  arsize_top=0 arsize_bot=0 is_shrink=n
3 0.01378 0.09449 4.60237 B e e  arsize_top=0 arsize_bot=0 is_shrink=n
3 0.01378 0.35039 1.45276 B e e  arsize_top=0 arsize_bot=0 is_shrink=n
3 0.01378 0.27165 1.57087 B e e  arsize_top=0 arsize_bot=0 is_shrink=n
3 0.01378 0.27165 1.88583 B e e  arsize_top=0 arsize_bot=0 is_shrink=n
3 0.01378 0.35039 2.00394 B e e  arsize_top=0 arsize_bot=0 is_shrink=n
3 0.01378 0.35039 2.08268 B e e  arsize_top=0 arsize_bot=0 is_shrink=n
3 0.01378 0.27165 2.20079 B e e  arsize_top=0 arsize_bot=0 is_shrink=n
3 0.01378 0.35039 2.24016 B e e  arsize_top=0 arsize_bot=0 is_shrink=n
3 0.01378 0.27165 2.35827 B e e  arsize_top=0 arsize_bot=0 is_shrink=n
3 0.01378 0.35039 2.39764 B e e  arsize_top=0 arsize_bot=0 is_shrink=n
3 0.01378 0.27165 2.51575 B e e  arsize_top=0 arsize_bot=0 is_shrink=n
3 0.01378 0.35039 2.63386 B e e  arsize_top=0 arsize_bot=0 is_shrink=n
3 0.01378 0.27165 2.75197 B e e  arsize_top=0 arsize_bot=0 is_shrink=n
3 0.01378 0.35039 2.79134 B e e  arsize_top=0 arsize_bot=0 is_shrink=n
3 0.01378 0.27165 2.90945 B e e  arsize_top=0 arsize_bot=0 is_shrink=n
3 0.01378 0.35039 2.94882 B e e  arsize_top=0 arsize_bot=0 is_shrink=n
3 0.01378 0.27165 3.06693 B e e  arsize_top=0 arsize_bot=0 is_shrink=n
3 0.01378 0.35039 3.1063 B e e  arsize_top=0 arsize_bot=0 is_shrink=n
3 0.01378 0.27165 3.22441 B e e  arsize_top=0 arsize_bot=0 is_shrink=n
3 0.01378 0.27165 3.30315 B e e  arsize_top=0 arsize_bot=0 is_shrink=n
3 0.01378 0.35039 3.42126 B e e  arsize_top=0 arsize_bot=0 is_shrink=n
3 0.01378 0.27165 3.46063 B e e  arsize_top=0 arsize_bot=0 is_shrink=n
3 0.01378 0.35039 3.57874 B e e  arsize_top=0 arsize_bot=0 is_shrink=n
3 0.01378 0.27165 3.61811 B e e  arsize_top=0 arsize_bot=0 is_shrink=n
3 0.01378 0.35039 3.73622 B e e  arsize_top=0 arsize_bot=0 is_shrink=n
3 0.01378 0.27165 3.77559 B e e  arsize_top=0 arsize_bot=0 is_shrink=n
3 0.01378 0.35039 3.8937 B e e  arsize_top=0 arsize_bot=0 is_shrink=n
3 0.01378 0.27165 3.93307 B e e  arsize_top=0 arsize_bot=0 is_shrink=n
3 0.01378 0.35039 4.05118 B e e  arsize_top=0 arsize_bot=0 is_shrink=n
3 0.01378 0.27165 4.09055 B e e  arsize_top=0 arsize_bot=0 is_shrink=n
3 0.01378 0.35039 4.20866 B e e  arsize_top=0 arsize_bot=0 is_shrink=n
3 0.01378 0.27165 4.24803 B e e  arsize_top=0 arsize_bot=0 is_shrink=n
3 0.01378 0.35039 4.36614 B e e  arsize_top=0 arsize_bot=0 is_shrink=n
3 0.01378 0.27165 4.40551 B e e  arsize_top=0 arsize_bot=0 is_shrink=n
3 0.01378 0.35039 4.52362 B e e  arsize_top=0 arsize_bot=0 is_shrink=n
3 0.01378 12.55905 1.49213 B e e  arsize_top=0 arsize_bot=0 is_shrink=n
3 0.01378 12.55905 1.88583 B e e  arsize_top=0 arsize_bot=0 is_shrink=n
3 0.01378 12.63779 2.00394 B e e  arsize_top=0 arsize_bot=0 is_shrink=n
3 0.01378 12.55905 2.12205 B e e  arsize_top=0 arsize_bot=0 is_shrink=n
3 0.01378 12.55905 2.20079 B e e  arsize_top=0 arsize_bot=0 is_shrink=n
3 0.01378 12.63779 2.3189 B e e  arsize_top=0 arsize_bot=0 is_shrink=n
3 0.01378 12.55905 2.35827 B e e  arsize_top=0 arsize_bot=0 is_shrink=n
3 0.01378 12.63779 2.47638 B e e  arsize_top=0 arsize_bot=0 is_shrink=n
3 0.01378 12.55905 2.51575 B e e  arsize_top=0 arsize_bot=0 is_shrink=n
3 0.01378 12.63779 2.63386 B e e  arsize_top=0 arsize_bot=0 is_shrink=n
3 0.01378 12.55905 2.75197 B e e  arsize_top=0 arsize_bot=0 is_shrink=n
3 0.01378 12.63779 2.87008 B e e  arsize_top=0 arsize_bot=0 is_shrink=n
3 0.01378 12.55905 2.90945 B e e  arsize_top=0 arsize_bot=0 is_shrink=n
3 0.01378 12.63779 3.02756 B e e  arsize_top=0 arsize_bot=0 is_shrink=n
3 0.01378 12.55905 3.06693 B e e  arsize_top=0 arsize_bot=0 is_shrink=n
3 0.01378 12.63779 3.18504 B e e  arsize_top=0 arsize_bot=0 is_shrink=n
3 0.01378 12.55905 3.22441 B e e  arsize_top=0 arsize_bot=0 is_shrink=n
3 0.01378 12.63779 3.34252 B e e  arsize_top=0 arsize_bot=0 is_shrink=n
3 0.01378 12.63779 3.42126 B e e  arsize_top=0 arsize_bot=0 is_shrink=n
3 0.01378 12.55905 3.53937 B e e  arsize_top=0 arsize_bot=0 is_shrink=n
3 0.01378 12.63779 3.57874 B e e  arsize_top=0 arsize_bot=0 is_shrink=n
3 0.01378 12.55905 3.69685 B e e  arsize_top=0 arsize_bot=0 is_shrink=n
3 0.01378 12.63779 3.73622 B e e  arsize_top=0 arsize_bot=0 is_shrink=n
3 0.01378 12.55905 3.85433 B e e  arsize_top=0 arsize_bot=0 is_shrink=n
3 0.01378 12.63779 3.8937 B e e  arsize_top=0 arsize_bot=0 is_shrink=n
3 0.01378 12.55905 4.01181 B e e  arsize_top=0 arsize_bot=0 is_shrink=n
3 0.01378 12.63779 4.05118 B e e  arsize_top=0 arsize_bot=0 is_shrink=n
3 0.01378 12.55905 4.16929 B e e  arsize_top=0 arsize_bot=0 is_shrink=n
3 0.01378 12.63779 4.20866 B e e  arsize_top=0 arsize_bot=0 is_shrink=n
3 0.01378 12.55905 4.32677 B e e  arsize_top=0 arsize_bot=0 is_shrink=n
3 0.01378 12.63779 4.36614 B e e  arsize_top=0 arsize_bot=0 is_shrink=n
3 0.01378 12.55905 4.48425 B e e  arsize_top=0 arsize_bot=0 is_shrink=n
3 0.01378 12.63779 4.52362 B e e  arsize_top=0 arsize_bot=0 is_shrink=n
3 0.01378 12.55905 4.64174 B e e  arsize_top=0 arsize_bot=0 is_shrink=n
3 0.01378 12.81495 1.49213 B e e  arsize_top=0 arsize_bot=0 is_shrink=n
3 0.01378 12.73621 1.61024 B e e  arsize_top=0 arsize_bot=0 is_shrink=n
3 0.01378 12.73621 1.9252 B e e  arsize_top=0 arsize_bot=0 is_shrink=n
3 0.01378 12.81495 2.04331 B e e  arsize_top=0 arsize_bot=0 is_shrink=n
3 0.01378 12.81495 2.12205 B e e  arsize_top=0 arsize_bot=0 is_shrink=n
3 0.01378 12.73621 2.24016 B e e  arsize_top=0 arsize_bot=0 is_shrink=n
3 0.01378 12.81495 2.27953 B e e  arsize_top=0 arsize_bot=0 is_shrink=n
3 0.01378 12.73621 2.39764 B e e  arsize_top=0 arsize_bot=0 is_shrink=n
3 0.01378 12.81495 2.43701 B e e  arsize_top=0 arsize_bot=0 is_shrink=n
3 0.01378 12.73621 2.55512 B e e  arsize_top=0 arsize_bot=0 is_shrink=n
3 0.01378 12.81495 2.67323 B e e  arsize_top=0 arsize_bot=0 is_shrink=n
3 0.01378 12.73621 2.79134 B e e  arsize_top=0 arsize_bot=0 is_shrink=n
3 0.01378 12.81495 2.83071 B e e  arsize_top=0 arsize_bot=0 is_shrink=n
3 0.01378 12.73621 2.94882 B e e  arsize_top=0 arsize_bot=0 is_shrink=n
3 0.01378 12.81495 2.98819 B e e  arsize_top=0 arsize_bot=0 is_shrink=n
3 0.01378 12.73621 3.1063 B e e  arsize_top=0 arsize_bot=0 is_shrink=n
3 0.01378 12.81495 3.14567 B e e  arsize_top=0 arsize_bot=0 is_shrink=n
3 0.01378 12.73621 3.26378 B e e  arsize_top=0 arsize_bot=0 is_shrink=n
3 0.01378 12.73621 3.34252 B e e  arsize_top=0 arsize_bot=0 is_shrink=n
3 0.01378 12.81495 3.46063 B e e  arsize_top=0 arsize_bot=0 is_shrink=n
3 0.01378 12.73621 3.5 B e e  arsize_top=0 arsize_bot=0 is_shrink=n
3 0.01378 12.81495 3.61811 B e e  arsize_top=0 arsize_bot=0 is_shrink=n
3 0.01378 12.73621 3.65748 B e e  arsize_top=0 arsize_bot=0 is_shrink=n
3 0.01378 12.81495 3.77559 B e e  arsize_top=0 arsize_bot=0 is_shrink=n
3 0.01378 12.73621 3.81496 B e e  arsize_top=0 arsize_bot=0 is_shrink=n
3 0.01378 12.81495 3.93307 B e e  arsize_top=0 arsize_bot=0 is_shrink=n
3 0.01378 12.73621 3.97244 B e e  arsize_top=0 arsize_bot=0 is_shrink=n
3 0.01378 12.81495 4.09055 B e e  arsize_top=0 arsize_bot=0 is_shrink=n
3 0.01378 12.73621 4.12992 B e e  arsize_top=0 arsize_bot=0 is_shrink=n
3 0.01378 12.81495 4.24803 B e e  arsize_top=0 arsize_bot=0 is_shrink=n
3 0.01378 12.73621 4.2874 B e e  arsize_top=0 arsize_bot=0 is_shrink=n
3 0.01378 12.81495 4.40551 B e e  arsize_top=0 arsize_bot=0 is_shrink=n
3 0.01378 12.73621 4.44488 B e e  arsize_top=0 arsize_bot=0 is_shrink=n
3 0.01378 12.81495 4.56299 B e e  arsize_top=0 arsize_bot=0 is_shrink=n
3 0 6.62419 5.09705 T 0.02 0.02 e e staggered 0 0 0  is_shrink=n
3 0 6.57319 5.09705 T 0.02 0.02 e e staggered 0 0 0  is_shrink=n
3 0 6.837 5 T 0.02 0.02 e e staggered 0 0 0  is_shrink=n
3 0 3.81999 0.7751 T 0.02 0.02 e e staggered 0 0 0  is_shrink=n
3 0 3.60999 0.2711 T 0.02 0.02 e e staggered 0 0 0  is_shrink=n
3 0 9.40795 0.29243 T 0.02 0.02 e e staggered 0 0 0  is_shrink=n
3 0 9.61795 0.79643 T 0.02 0.02 e e staggered 0 0 0  is_shrink=n
3 0 0.705 5.383 T 0.02 0.02 e e staggered 0 0 0  is_shrink=n
3 0 10.36699 5.02086 T 0.07874 0.15748 e e staggered 0 0 0  is_shrink=n
3 0 10.75699 5.02086 T 0.07874 0.15748 e e staggered 0 0 0  is_shrink=n
3 0 4.75305 5.02086 T 0.07874 0.15748 e e staggered 0 0 0  is_shrink=n
3 0 4.36305 5.02086 T 0.07874 0.15748 e e staggered 0 0 0  is_shrink=n
3 0 11.87126 4.88 T 0.16142 0.07874 e e staggered 0 0 0  is_shrink=n
3 0 5.59779 4.5552 T 0.05 0.05 e e staggered 0 0 0  is_shrink=n
3 0 5.67709 4.5552 T 0.05 0.05 e e staggered 0 0 0  is_shrink=n
3 0 5.83709 4.5552 T 0.05 0.05 e e staggered 0 0 0  is_shrink=n
3 0 5.75709 4.5552 T 0.05 0.05 e e staggered 0 0 0  is_shrink=n
3 0 6.07709 4.5552 T 0.05 0.05 e e staggered 0 0 0  is_shrink=n
3 0 5.91709 4.5552 T 0.05 0.05 e e staggered 0 0 0  is_shrink=n
3 0 5.99709 4.5552 T 0.05 0.05 e e staggered 0 0 0  is_shrink=n
3 0 6.66209 4.7052 T 0.05 0.05 e e staggered 0 0 0  is_shrink=n
3 0 6.66209 4.6252 T 0.05 0.05 e e staggered 0 0 0  is_shrink=n
3 0 6.91119 4.81705 T 0.05 0.05 e e staggered 0 0 0  is_shrink=n
3 0 12.04 4.96 T 0.05 0.05 e e staggered 0 0 0  is_shrink=n
3 0 12.2 4.96 T 0.05 0.05 e e staggered 0 0 0  is_shrink=n
3 0 10.51 5.18 T 0.05 0.05 e e staggered 0 0 0  is_shrink=n
3 0 10.51 5.26 T 0.05 0.05 e e staggered 0 0 0  is_shrink=n
3 0 9.91 4.667 T 0.02 0.02 e e staggered 0 0 0  is_shrink=n
3 0 3.57 4.483 T 0.02 0.02 e e staggered 0 0 0  is_shrink=n
3 0 4.81 5.408 T 0.02 0.02 e e staggered 0 0 0  is_shrink=n
3 0 5.16 5.617 T 0.02 0.02 e e staggered 0 0 0  is_shrink=n
3 0 4.96 5.408 T 0.02 0.02 e e staggered 0 0 0  is_shrink=n
3 0 3.72 4.483 T 0.02 0.02 e e staggered 0 0 0  is_shrink=n
3 0 10.03 4.543 T 0.02 0.02 e e staggered 0 0 0  is_shrink=n
3 0 4.14 4.683 T 0.02 0.02 e e staggered 0 0 0  is_shrink=n
3 0 5.53594 4.5861 T 0.02 0.02 e e staggered 0 0 0  is_shrink=n
3 0 6.42419 4.99705 T 0.02 0.02 e e staggered 0 0 0  is_shrink=n
3 0 6.42419 5.04705 T 0.02 0.02 e e staggered 0 0 0  is_shrink=n
3 0 6.57619 4.76905 T 0.02 0.02 e e staggered 0 0 0  is_shrink=n
3 0 6.67919 4.77205 T 0.02 0.02 e e staggered 0 0 0  is_shrink=n
3 0 4.1049 4.79499 T 0.02 0.02 e e staggered 0 0 0  is_shrink=n
3 0 1.31 5.383 T 0.02 0.02 e e staggered 0 0 0  is_shrink=n
3 0 12.12 4.993 T 0.02 0.02 e e staggered 0 0 0  is_shrink=n
3 0 10.543 5.32 T 0.02 0.02 e e staggered 0 0 0  is_shrink=n
3 0 1.405 5.857 T 0.02 0.02 e e staggered 0 0 0  is_shrink=n
3 0 1.305 5.857 T 0.02 0.02 e e staggered 0 0 0  is_shrink=n
3 0 1.46 5.383 T 0.02 0.02 e e staggered 0 0 0  is_shrink=n
3 0 1.41 5.383 T 0.02 0.02 e e staggered 0 0 0  is_shrink=n
3 0 0.73 5.147 T 0.02 0.02 e e staggered 0 0 0  is_shrink=n
3 0 0.73 5.267 T 0.02 0.02 e e staggered 0 0 0  is_shrink=n
3 0 3.77 4.827 T 0.02 0.02 e e staggered 0 0 0  is_shrink=n
3 0 7.2426 4.63151 T 0.02 0.02 e e staggered 0 0 0  is_shrink=n
3 0 7.1926 5.01551 T 0.02 0.02 e e staggered 0 0 0  is_shrink=n
3 0 1.23906 4.63151 T 0.02 0.02 e e staggered 0 0 0  is_shrink=n
3 0 1.18906 5.01551 T 0.02 0.02 e e staggered 0 0 0  is_shrink=n
3 0 1.455 5.857 T 0.02 0.02 e e staggered 0 0 0  is_shrink=n
3 0 1.355 5.857 T 0.02 0.02 e e staggered 0 0 0  is_shrink=n
3 0 1.36 5.383 T 0.02 0.02 e e staggered 0 0 0  is_shrink=n
3 0 1.03 5.093 T 0.02 0.02 e e staggered 0 0 0  is_shrink=n
3 0 0.4826 5.85528 T 0.02362 0.0374 e e staggered 0 0 0  is_shrink=n
3 0 5.04441 5.64035 T 0.01575 0.03543 e e staggered 0 0 0  is_shrink=n
3 0 3.99965 4.66441 T 0.03543 0.01575 e e staggered 0 0 0  is_shrink=n
3 0 9.97441 4.73035 T 0.01575 0.03543 e e staggered 0 0 0  is_shrink=n
3 0 3.64441 4.67035 T 0.01575 0.03543 e e staggered 0 0 0  is_shrink=n
3 0 0.97441 5.29035 T 0.01575 0.03543 e e staggered 0 0 0  is_shrink=n
3 0 3.82559 4.63965 T 0.01575 0.03543 e e staggered 0 0 0  is_shrink=n
3 0 0.84953 5.1239 T 0.01102 0.04331 e e staggered 0 0 0  is_shrink=n
3 0 1.32745 4.79682 T 0.01575 0.06693 e e staggered 0 0 0  is_shrink=n
3 0 7.33099 4.79682 T 0.01575 0.06693 e e staggered 0 0 0  is_shrink=n
3 0 3.65999 0.40688 T 0.0252 0.07244 e e staggered 0 0 0  is_shrink=n
3 0 9.45795 0.42821 T 0.0252 0.07244 e e staggered 0 0 0  is_shrink=n
3 0 1.12303 5.53642 T 0.03937 0.10827 e e staggered 0 0 0  is_shrink=n
3 0 1.20177 5.53642 T 0.03937 0.10827 e e staggered 0 0 0  is_shrink=n
3 0 1.20177 5.70374 T 0.03937 0.10827 e e staggered 0 0 0  is_shrink=n
3 0 1.28051 5.53642 T 0.03937 0.10827 e e staggered 0 0 0  is_shrink=n
3 0 1.28051 5.70374 T 0.03937 0.10827 e e staggered 0 0 0  is_shrink=n
3 0 1.51673 5.53642 T 0.03937 0.10827 e e staggered 0 0 0  is_shrink=n
3 0 1.51673 5.70374 T 0.03937 0.10827 e e staggered 0 0 0  is_shrink=n
3 0.0126 2.02106 1.89115 T e e  arsize_top=0 arsize_bot=0 is_shrink=n
3 0.0126 2.02106 1.94115 T e e  arsize_top=0 arsize_bot=0 is_shrink=n
3 0.0126 2.02106 1.99115 T e e  arsize_top=0 arsize_bot=0 is_shrink=n
3 0.0126 2.02106 2.04115 T e e  arsize_top=0 arsize_bot=0 is_shrink=n
3 0.0126 2.02106 2.09115 T e e  arsize_top=0 arsize_bot=0 is_shrink=n
3 0.0126 2.02106 2.14115 T e e  arsize_top=0 arsize_bot=0 is_shrink=n
3 0.0126 2.02106 2.19115 T e e  arsize_top=0 arsize_bot=0 is_shrink=n
3 0.0126 2.02106 2.24115 T e e  arsize_top=0 arsize_bot=0 is_shrink=n
3 0.0126 2.02106 2.29115 T e e  arsize_top=0 arsize_bot=0 is_shrink=n
3 0.0126 2.02106 2.34115 T e e  arsize_top=0 arsize_bot=0 is_shrink=n
3 0.0126 2.02106 2.39115 T e e  arsize_top=0 arsize_bot=0 is_shrink=n
3 0.0126 2.02106 2.44115 T e e  arsize_top=0 arsize_bot=0 is_shrink=n
3 0.0126 2.02106 2.49115 T e e  arsize_top=0 arsize_bot=0 is_shrink=n
3 0.0126 2.02106 2.54115 T e e  arsize_top=0 arsize_bot=0 is_shrink=n
3 0.0126 2.02106 2.59115 T e e  arsize_top=0 arsize_bot=0 is_shrink=n
3 0.0126 2.02106 2.64115 T e e  arsize_top=0 arsize_bot=0 is_shrink=n
3 0.0126 2.02106 2.69115 T e e  arsize_top=0 arsize_bot=0 is_shrink=n
3 0.0126 2.02106 2.74115 T e e  arsize_top=0 arsize_bot=0 is_shrink=n
3 0.0126 2.02106 2.79115 T e e  arsize_top=0 arsize_bot=0 is_shrink=n
3 0.0126 2.02106 2.84115 T e e  arsize_top=0 arsize_bot=0 is_shrink=n
3 0.0126 2.02106 2.89115 T e e  arsize_top=0 arsize_bot=0 is_shrink=n
3 0.0126 2.02106 2.94115 T e e  arsize_top=0 arsize_bot=0 is_shrink=n
3 0.0126 2.02106 2.99115 T e e  arsize_top=0 arsize_bot=0 is_shrink=n
3 0.0126 2.02106 3.04115 T e e  arsize_top=0 arsize_bot=0 is_shrink=n
3 0.0126 2.02106 3.09115 T e e  arsize_top=0 arsize_bot=0 is_shrink=n
3 0.0126 2.02106 3.14115 T e e  arsize_top=0 arsize_bot=0 is_shrink=n
3 0.0126 2.02106 3.19115 T e e  arsize_top=0 arsize_bot=0 is_shrink=n
3 0.0126 2.02106 3.24115 T e e  arsize_top=0 arsize_bot=0 is_shrink=n
3 0.0126 2.02106 3.39115 T e e  arsize_top=0 arsize_bot=0 is_shrink=n
3 0.0126 2.02106 3.54115 T e e  arsize_top=0 arsize_bot=0 is_shrink=n
3 0.0126 2.02106 3.69115 T e e  arsize_top=0 arsize_bot=0 is_shrink=n
3 0.0126 2.02106 3.84115 T e e  arsize_top=0 arsize_bot=0 is_shrink=n
3 0.0126 2.07106 1.89115 T e e  arsize_top=0 arsize_bot=0 is_shrink=n
3 0.0126 2.07106 1.94115 T e e  arsize_top=0 arsize_bot=0 is_shrink=n
3 0.0126 2.07106 1.99115 T e e  arsize_top=0 arsize_bot=0 is_shrink=n
3 0.0126 2.07106 2.04115 T e e  arsize_top=0 arsize_bot=0 is_shrink=n
3 0.0126 2.07106 2.09115 T e e  arsize_top=0 arsize_bot=0 is_shrink=n
3 0.0126 2.07106 2.14115 T e e  arsize_top=0 arsize_bot=0 is_shrink=n
3 0.0126 2.07106 2.19115 T e e  arsize_top=0 arsize_bot=0 is_shrink=n
3 0.0126 2.07106 2.24115 T e e  arsize_top=0 arsize_bot=0 is_shrink=n
3 0.0126 2.07106 2.29115 T e e  arsize_top=0 arsize_bot=0 is_shrink=n
3 0.0126 2.07106 2.34115 T e e  arsize_top=0 arsize_bot=0 is_shrink=n
3 0.0126 2.07106 2.39115 T e e  arsize_top=0 arsize_bot=0 is_shrink=n
3 0.0126 2.07106 2.44115 T e e  arsize_top=0 arsize_bot=0 is_shrink=n
3 0.0126 2.07106 2.49115 T e e  arsize_top=0 arsize_bot=0 is_shrink=n
3 0.0126 2.07106 2.54115 T e e  arsize_top=0 arsize_bot=0 is_shrink=n
3 0.0126 2.07106 2.59115 T e e  arsize_top=0 arsize_bot=0 is_shrink=n
3 0.0126 2.07106 2.64115 T e e  arsize_top=0 arsize_bot=0 is_shrink=n
3 0.0126 2.07106 2.69115 T e e  arsize_top=0 arsize_bot=0 is_shrink=n
3 0.0126 2.07106 2.74115 T e e  arsize_top=0 arsize_bot=0 is_shrink=n
3 0.0126 2.07106 2.79115 T e e  arsize_top=0 arsize_bot=0 is_shrink=n
3 0.0126 2.07106 2.84115 T e e  arsize_top=0 arsize_bot=0 is_shrink=n
3 0.0126 2.07106 2.89115 T e e  arsize_top=0 arsize_bot=0 is_shrink=n
3 0.0126 2.07106 2.94115 T e e  arsize_top=0 arsize_bot=0 is_shrink=n
3 0.0126 2.07106 2.99115 T e e  arsize_top=0 arsize_bot=0 is_shrink=n
3 0.0126 2.07106 3.04115 T e e  arsize_top=0 arsize_bot=0 is_shrink=n
3 0.0126 2.07106 3.09115 T e e  arsize_top=0 arsize_bot=0 is_shrink=n
3 0.0126 2.07106 3.14115 T e e  arsize_top=0 arsize_bot=0 is_shrink=n
3 0.0126 2.07106 3.19115 T e e  arsize_top=0 arsize_bot=0 is_shrink=n
3 0.0126 2.07106 3.34115 T e e  arsize_top=0 arsize_bot=0 is_shrink=n
3 0.0126 2.07106 3.49115 T e e  arsize_top=0 arsize_bot=0 is_shrink=n
3 0.0126 2.07106 3.59115 T e e  arsize_top=0 arsize_bot=0 is_shrink=n
3 0.0126 2.07106 3.74115 T e e  arsize_top=0 arsize_bot=0 is_shrink=n
3 0.0126 2.12106 1.89115 T e e  arsize_top=0 arsize_bot=0 is_shrink=n
3 0.0126 2.12106 1.94115 T e e  arsize_top=0 arsize_bot=0 is_shrink=n
3 0.0126 2.12106 1.99115 T e e  arsize_top=0 arsize_bot=0 is_shrink=n
3 0.0126 2.12106 2.04115 T e e  arsize_top=0 arsize_bot=0 is_shrink=n
3 0.0126 2.12106 2.09115 T e e  arsize_top=0 arsize_bot=0 is_shrink=n
3 0.0126 2.12106 2.14115 T e e  arsize_top=0 arsize_bot=0 is_shrink=n
3 0.0126 2.12106 2.19115 T e e  arsize_top=0 arsize_bot=0 is_shrink=n
3 0.0126 2.12106 2.24115 T e e  arsize_top=0 arsize_bot=0 is_shrink=n
3 0.0126 2.12106 2.29115 T e e  arsize_top=0 arsize_bot=0 is_shrink=n
3 0.0126 2.12106 2.34115 T e e  arsize_top=0 arsize_bot=0 is_shrink=n
3 0.0126 2.12106 2.39115 T e e  arsize_top=0 arsize_bot=0 is_shrink=n
3 0.0126 2.12106 2.44115 T e e  arsize_top=0 arsize_bot=0 is_shrink=n
3 0.0126 2.12106 2.54115 T e e  arsize_top=0 arsize_bot=0 is_shrink=n
3 0.0126 2.12106 2.59115 T e e  arsize_top=0 arsize_bot=0 is_shrink=n
3 0.0126 2.12106 2.64115 T e e  arsize_top=0 arsize_bot=0 is_shrink=n
3 0.0126 2.12106 2.69115 T e e  arsize_top=0 arsize_bot=0 is_shrink=n
3 0.0126 2.12106 2.74115 T e e  arsize_top=0 arsize_bot=0 is_shrink=n
3 0.0126 2.12106 2.79115 T e e  arsize_top=0 arsize_bot=0 is_shrink=n
3 0.0126 2.12106 2.84115 T e e  arsize_top=0 arsize_bot=0 is_shrink=n
3 0.0126 2.12106 2.89115 T e e  arsize_top=0 arsize_bot=0 is_shrink=n
3 0.0126 2.12106 2.94115 T e e  arsize_top=0 arsize_bot=0 is_shrink=n
3 0.0126 2.12106 2.99115 T e e  arsize_top=0 arsize_bot=0 is_shrink=n
3 0.0126 2.12106 3.04115 T e e  arsize_top=0 arsize_bot=0 is_shrink=n
3 0.0126 2.12106 3.09115 T e e  arsize_top=0 arsize_bot=0 is_shrink=n
3 0.0126 2.12106 3.14115 T e e  arsize_top=0 arsize_bot=0 is_shrink=n
3 0.0126 2.12106 3.19115 T e e  arsize_top=0 arsize_bot=0 is_shrink=n
3 0.0126 2.12106 3.24115 T e e  arsize_top=0 arsize_bot=0 is_shrink=n
3 0.0126 2.12106 3.39115 T e e  arsize_top=0 arsize_bot=0 is_shrink=n
3 0.0126 2.12106 3.54115 T e e  arsize_top=0 arsize_bot=0 is_shrink=n
3 0.0126 2.12106 3.69115 T e e  arsize_top=0 arsize_bot=0 is_shrink=n
3 0.0126 2.12106 3.84115 T e e  arsize_top=0 arsize_bot=0 is_shrink=n
3 0.0126 2.17106 1.89115 T e e  arsize_top=0 arsize_bot=0 is_shrink=n
3 0.0126 2.17106 1.94115 T e e  arsize_top=0 arsize_bot=0 is_shrink=n
3 0.0126 2.17106 1.99115 T e e  arsize_top=0 arsize_bot=0 is_shrink=n
3 0.0126 2.17106 2.04115 T e e  arsize_top=0 arsize_bot=0 is_shrink=n
3 0.0126 2.17106 2.09115 T e e  arsize_top=0 arsize_bot=0 is_shrink=n
3 0.0126 2.17106 2.14115 T e e  arsize_top=0 arsize_bot=0 is_shrink=n
3 0.0126 2.17106 2.19115 T e e  arsize_top=0 arsize_bot=0 is_shrink=n
3 0.0126 2.17106 2.24115 T e e  arsize_top=0 arsize_bot=0 is_shrink=n
3 0.0126 2.17106 2.29115 T e e  arsize_top=0 arsize_bot=0 is_shrink=n
3 0.0126 2.17106 2.34115 T e e  arsize_top=0 arsize_bot=0 is_shrink=n
3 0.0126 2.17106 2.39115 T e e  arsize_top=0 arsize_bot=0 is_shrink=n
3 0.0126 2.17106 2.44115 T e e  arsize_top=0 arsize_bot=0 is_shrink=n
3 0.0126 2.17106 2.49115 T e e  arsize_top=0 arsize_bot=0 is_shrink=n
3 0.0126 2.17106 2.54115 T e e  arsize_top=0 arsize_bot=0 is_shrink=n
3 0.0126 2.17106 2.59115 T e e  arsize_top=0 arsize_bot=0 is_shrink=n
3 0.0126 2.17106 2.64115 T e e  arsize_top=0 arsize_bot=0 is_shrink=n
3 0.0126 2.17106 2.69115 T e e  arsize_top=0 arsize_bot=0 is_shrink=n
3 0.0126 2.17106 2.74115 T e e  arsize_top=0 arsize_bot=0 is_shrink=n
3 0.0126 2.17106 2.79115 T e e  arsize_top=0 arsize_bot=0 is_shrink=n
3 0.0126 2.17106 2.84115 T e e  arsize_top=0 arsize_bot=0 is_shrink=n
3 0.0126 2.17106 2.89115 T e e  arsize_top=0 arsize_bot=0 is_shrink=n
3 0.0126 2.17106 2.94115 T e e  arsize_top=0 arsize_bot=0 is_shrink=n
3 0.0126 2.17106 2.99115 T e e  arsize_top=0 arsize_bot=0 is_shrink=n
3 0.0126 2.17106 3.04115 T e e  arsize_top=0 arsize_bot=0 is_shrink=n
3 0.0126 2.17106 3.09115 T e e  arsize_top=0 arsize_bot=0 is_shrink=n
3 0.0126 2.17106 3.14115 T e e  arsize_top=0 arsize_bot=0 is_shrink=n
3 0.0126 2.17106 3.19115 T e e  arsize_top=0 arsize_bot=0 is_shrink=n
3 0.0126 2.17106 3.34115 T e e  arsize_top=0 arsize_bot=0 is_shrink=n
3 0.0126 2.17106 3.49115 T e e  arsize_top=0 arsize_bot=0 is_shrink=n
3 0.0126 2.17106 3.54115 T e e  arsize_top=0 arsize_bot=0 is_shrink=n
3 0.0126 2.17106 3.59115 T e e  arsize_top=0 arsize_bot=0 is_shrink=n
3 0.0126 2.17106 3.74115 T e e  arsize_top=0 arsize_bot=0 is_shrink=n
3 0.0126 2.22106 1.89115 T e e  arsize_top=0 arsize_bot=0 is_shrink=n
3 0.0126 2.22106 1.94115 T e e  arsize_top=0 arsize_bot=0 is_shrink=n
3 0.0126 2.22106 1.99115 T e e  arsize_top=0 arsize_bot=0 is_shrink=n
3 0.0126 2.22106 2.04115 T e e  arsize_top=0 arsize_bot=0 is_shrink=n
3 0.0126 2.22106 2.09115 T e e  arsize_top=0 arsize_bot=0 is_shrink=n
3 0.0126 2.22106 2.14115 T e e  arsize_top=0 arsize_bot=0 is_shrink=n
3 0.0126 2.22106 2.19115 T e e  arsize_top=0 arsize_bot=0 is_shrink=n
3 0.0126 2.22106 2.24115 T e e  arsize_top=0 arsize_bot=0 is_shrink=n
3 0.0126 2.22106 2.29115 T e e  arsize_top=0 arsize_bot=0 is_shrink=n
3 0.0126 2.22106 2.34115 T e e  arsize_top=0 arsize_bot=0 is_shrink=n
3 0.0126 2.22106 2.39115 T e e  arsize_top=0 arsize_bot=0 is_shrink=n
3 0.0126 2.22106 2.44115 T e e  arsize_top=0 arsize_bot=0 is_shrink=n
3 0.0126 2.22106 2.49115 T e e  arsize_top=0 arsize_bot=0 is_shrink=n
3 0.0126 2.22106 2.54115 T e e  arsize_top=0 arsize_bot=0 is_shrink=n
3 0.0126 2.22106 2.59115 T e e  arsize_top=0 arsize_bot=0 is_shrink=n
3 0.0126 2.22106 2.64115 T e e  arsize_top=0 arsize_bot=0 is_shrink=n
3 0.0126 2.22106 2.69115 T e e  arsize_top=0 arsize_bot=0 is_shrink=n
3 0.0126 2.22106 2.74115 T e e  arsize_top=0 arsize_bot=0 is_shrink=n
3 0.0126 2.22106 2.79115 T e e  arsize_top=0 arsize_bot=0 is_shrink=n
3 0.0126 2.22106 2.89115 T e e  arsize_top=0 arsize_bot=0 is_shrink=n
3 0.0126 2.22106 2.94115 T e e  arsize_top=0 arsize_bot=0 is_shrink=n
3 0.0126 2.22106 2.99115 T e e  arsize_top=0 arsize_bot=0 is_shrink=n
3 0.0126 2.22106 3.04115 T e e  arsize_top=0 arsize_bot=0 is_shrink=n
3 0.0126 2.22106 3.09115 T e e  arsize_top=0 arsize_bot=0 is_shrink=n
3 0.0126 2.22106 3.14115 T e e  arsize_top=0 arsize_bot=0 is_shrink=n
3 0.0126 2.22106 3.19115 T e e  arsize_top=0 arsize_bot=0 is_shrink=n
3 0.0126 2.22106 3.24115 T e e  arsize_top=0 arsize_bot=0 is_shrink=n
3 0.0126 2.22106 3.29115 T e e  arsize_top=0 arsize_bot=0 is_shrink=n
3 0.0126 2.22106 3.34115 T e e  arsize_top=0 arsize_bot=0 is_shrink=n
3 0.0126 2.22106 3.39115 T e e  arsize_top=0 arsize_bot=0 is_shrink=n
3 0.0126 2.22106 3.44115 T e e  arsize_top=0 arsize_bot=0 is_shrink=n
3 0.0126 2.22106 3.49115 T e e  arsize_top=0 arsize_bot=0 is_shrink=n
3 0.0126 2.22106 3.59115 T e e  arsize_top=0 arsize_bot=0 is_shrink=n
3 0.0126 2.22106 3.64115 T e e  arsize_top=0 arsize_bot=0 is_shrink=n
3 0.0126 2.22106 3.69115 T e e  arsize_top=0 arsize_bot=0 is_shrink=n
3 0.0126 2.22106 3.74115 T e e  arsize_top=0 arsize_bot=0 is_shrink=n
3 0.0126 2.22106 3.79115 T e e  arsize_top=0 arsize_bot=0 is_shrink=n
3 0.0126 2.22106 3.84115 T e e  arsize_top=0 arsize_bot=0 is_shrink=n
3 0.0126 2.27106 1.89115 T e e  arsize_top=0 arsize_bot=0 is_shrink=n
3 0.0126 2.27106 1.94115 T e e  arsize_top=0 arsize_bot=0 is_shrink=n
3 0.0126 2.27106 1.99115 T e e  arsize_top=0 arsize_bot=0 is_shrink=n
3 0.0126 2.27106 2.04115 T e e  arsize_top=0 arsize_bot=0 is_shrink=n
3 0.0126 2.27106 2.09115 T e e  arsize_top=0 arsize_bot=0 is_shrink=n
3 0.0126 2.27106 2.14115 T e e  arsize_top=0 arsize_bot=0 is_shrink=n
3 0.0126 2.27106 2.19115 T e e  arsize_top=0 arsize_bot=0 is_shrink=n
3 0.0126 2.27106 2.24115 T e e  arsize_top=0 arsize_bot=0 is_shrink=n
3 0.0126 2.27106 2.29115 T e e  arsize_top=0 arsize_bot=0 is_shrink=n
3 0.0126 2.27106 2.34115 T e e  arsize_top=0 arsize_bot=0 is_shrink=n
3 0.0126 2.27106 2.39115 T e e  arsize_top=0 arsize_bot=0 is_shrink=n
3 0.0126 2.27106 2.44115 T e e  arsize_top=0 arsize_bot=0 is_shrink=n
3 0.0126 2.27106 2.49115 T e e  arsize_top=0 arsize_bot=0 is_shrink=n
3 0.0126 2.27106 2.54115 T e e  arsize_top=0 arsize_bot=0 is_shrink=n
3 0.0126 2.27106 2.59115 T e e  arsize_top=0 arsize_bot=0 is_shrink=n
3 0.0126 2.27106 2.64115 T e e  arsize_top=0 arsize_bot=0 is_shrink=n
3 0.0126 2.27106 2.69115 T e e  arsize_top=0 arsize_bot=0 is_shrink=n
3 0.0126 2.27106 2.74115 T e e  arsize_top=0 arsize_bot=0 is_shrink=n
3 0.0126 2.27106 2.79115 T e e  arsize_top=0 arsize_bot=0 is_shrink=n
3 0.0126 2.27106 2.89115 T e e  arsize_top=0 arsize_bot=0 is_shrink=n
3 0.0126 2.27106 2.94115 T e e  arsize_top=0 arsize_bot=0 is_shrink=n
3 0.0126 2.27106 2.99115 T e e  arsize_top=0 arsize_bot=0 is_shrink=n
3 0.0126 2.27106 3.04115 T e e  arsize_top=0 arsize_bot=0 is_shrink=n
3 0.0126 2.27106 3.09115 T e e  arsize_top=0 arsize_bot=0 is_shrink=n
3 0.0126 2.27106 3.14115 T e e  arsize_top=0 arsize_bot=0 is_shrink=n
3 0.0126 2.27106 3.19115 T e e  arsize_top=0 arsize_bot=0 is_shrink=n
3 0.0126 2.27106 3.24115 T e e  arsize_top=0 arsize_bot=0 is_shrink=n
3 0.0126 2.27106 3.29115 T e e  arsize_top=0 arsize_bot=0 is_shrink=n
3 0.0126 2.27106 3.34115 T e e  arsize_top=0 arsize_bot=0 is_shrink=n
3 0.0126 2.27106 3.39115 T e e  arsize_top=0 arsize_bot=0 is_shrink=n
3 0.0126 2.27106 3.44115 T e e  arsize_top=0 arsize_bot=0 is_shrink=n
3 0.0126 2.27106 3.49115 T e e  arsize_top=0 arsize_bot=0 is_shrink=n
3 0.0126 2.27106 3.59115 T e e  arsize_top=0 arsize_bot=0 is_shrink=n
3 0.0126 2.27106 3.64115 T e e  arsize_top=0 arsize_bot=0 is_shrink=n
3 0.0126 2.27106 3.69115 T e e  arsize_top=0 arsize_bot=0 is_shrink=n
3 0.0126 2.27106 3.74115 T e e  arsize_top=0 arsize_bot=0 is_shrink=n
3 0.0126 2.27106 3.79115 T e e  arsize_top=0 arsize_bot=0 is_shrink=n
3 0.0126 2.27106 3.84115 T e e  arsize_top=0 arsize_bot=0 is_shrink=n
3 0.0126 2.32106 1.89115 T e e  arsize_top=0 arsize_bot=0 is_shrink=n
3 0.0126 2.32106 1.94115 T e e  arsize_top=0 arsize_bot=0 is_shrink=n
3 0.0126 2.32106 1.99115 T e e  arsize_top=0 arsize_bot=0 is_shrink=n
3 0.0126 2.32106 2.04115 T e e  arsize_top=0 arsize_bot=0 is_shrink=n
3 0.0126 2.32106 2.09115 T e e  arsize_top=0 arsize_bot=0 is_shrink=n
3 0.0126 2.32106 2.14115 T e e  arsize_top=0 arsize_bot=0 is_shrink=n
3 0.0126 2.32106 2.19115 T e e  arsize_top=0 arsize_bot=0 is_shrink=n
3 0.0126 2.32106 2.24115 T e e  arsize_top=0 arsize_bot=0 is_shrink=n
3 0.0126 2.32106 2.29115 T e e  arsize_top=0 arsize_bot=0 is_shrink=n
3 0.0126 2.32106 2.34115 T e e  arsize_top=0 arsize_bot=0 is_shrink=n
3 0.0126 2.32106 2.39115 T e e  arsize_top=0 arsize_bot=0 is_shrink=n
3 0.0126 2.32106 2.44115 T e e  arsize_top=0 arsize_bot=0 is_shrink=n
3 0.0126 2.32106 2.49115 T e e  arsize_top=0 arsize_bot=0 is_shrink=n
3 0.0126 2.32106 2.54115 T e e  arsize_top=0 arsize_bot=0 is_shrink=n
3 0.0126 2.32106 2.59115 T e e  arsize_top=0 arsize_bot=0 is_shrink=n
3 0.0126 2.32106 2.64115 T e e  arsize_top=0 arsize_bot=0 is_shrink=n
3 0.0126 2.32106 2.69115 T e e  arsize_top=0 arsize_bot=0 is_shrink=n
3 0.0126 2.32106 2.74115 T e e  arsize_top=0 arsize_bot=0 is_shrink=n
3 0.0126 2.32106 2.79115 T e e  arsize_top=0 arsize_bot=0 is_shrink=n
3 0.0126 2.32106 2.84115 T e e  arsize_top=0 arsize_bot=0 is_shrink=n
3 0.0126 2.32106 2.89115 T e e  arsize_top=0 arsize_bot=0 is_shrink=n
3 0.0126 2.32106 2.94115 T e e  arsize_top=0 arsize_bot=0 is_shrink=n
3 0.0126 2.32106 2.99115 T e e  arsize_top=0 arsize_bot=0 is_shrink=n
3 0.0126 2.32106 3.04115 T e e  arsize_top=0 arsize_bot=0 is_shrink=n
3 0.0126 2.32106 3.09115 T e e  arsize_top=0 arsize_bot=0 is_shrink=n
3 0.0126 2.32106 3.14115 T e e  arsize_top=0 arsize_bot=0 is_shrink=n
3 0.0126 2.32106 3.19115 T e e  arsize_top=0 arsize_bot=0 is_shrink=n
3 0.0126 2.32106 3.34115 T e e  arsize_top=0 arsize_bot=0 is_shrink=n
3 0.0126 2.32106 3.49115 T e e  arsize_top=0 arsize_bot=0 is_shrink=n
3 0.0126 2.32106 3.54115 T e e  arsize_top=0 arsize_bot=0 is_shrink=n
3 0.0126 2.32106 3.59115 T e e  arsize_top=0 arsize_bot=0 is_shrink=n
3 0.0126 2.32106 3.74115 T e e  arsize_top=0 arsize_bot=0 is_shrink=n
3 0.0126 2.37106 1.89115 T e e  arsize_top=0 arsize_bot=0 is_shrink=n
3 0.0126 2.37106 1.94115 T e e  arsize_top=0 arsize_bot=0 is_shrink=n
3 0.0126 2.37106 1.99115 T e e  arsize_top=0 arsize_bot=0 is_shrink=n
3 0.0126 2.37106 2.04115 T e e  arsize_top=0 arsize_bot=0 is_shrink=n
3 0.0126 2.37106 2.09115 T e e  arsize_top=0 arsize_bot=0 is_shrink=n
3 0.0126 2.37106 2.14115 T e e  arsize_top=0 arsize_bot=0 is_shrink=n
3 0.0126 2.37106 2.19115 T e e  arsize_top=0 arsize_bot=0 is_shrink=n
3 0.0126 2.37106 2.24115 T e e  arsize_top=0 arsize_bot=0 is_shrink=n
3 0.0126 2.37106 2.29115 T e e  arsize_top=0 arsize_bot=0 is_shrink=n
3 0.0126 2.37106 2.34115 T e e  arsize_top=0 arsize_bot=0 is_shrink=n
3 0.0126 2.37106 2.39115 T e e  arsize_top=0 arsize_bot=0 is_shrink=n
3 0.0126 2.37106 2.44115 T e e  arsize_top=0 arsize_bot=0 is_shrink=n
3 0.0126 2.37106 2.49115 T e e  arsize_top=0 arsize_bot=0 is_shrink=n
3 0.0126 2.37106 2.54115 T e e  arsize_top=0 arsize_bot=0 is_shrink=n
3 0.0126 2.37106 2.59115 T e e  arsize_top=0 arsize_bot=0 is_shrink=n
3 0.0126 2.37106 2.64115 T e e  arsize_top=0 arsize_bot=0 is_shrink=n
3 0.0126 2.37106 2.69115 T e e  arsize_top=0 arsize_bot=0 is_shrink=n
3 0.0126 2.37106 2.74115 T e e  arsize_top=0 arsize_bot=0 is_shrink=n
3 0.0126 2.37106 2.79115 T e e  arsize_top=0 arsize_bot=0 is_shrink=n
3 0.0126 2.37106 2.84115 T e e  arsize_top=0 arsize_bot=0 is_shrink=n
3 0.0126 2.37106 2.89115 T e e  arsize_top=0 arsize_bot=0 is_shrink=n
3 0.0126 2.37106 2.94115 T e e  arsize_top=0 arsize_bot=0 is_shrink=n
3 0.0126 2.37106 2.99115 T e e  arsize_top=0 arsize_bot=0 is_shrink=n
3 0.0126 2.37106 3.04115 T e e  arsize_top=0 arsize_bot=0 is_shrink=n
3 0.0126 2.37106 3.09115 T e e  arsize_top=0 arsize_bot=0 is_shrink=n
3 0.0126 2.37106 3.14115 T e e  arsize_top=0 arsize_bot=0 is_shrink=n
3 0.0126 2.37106 3.19115 T e e  arsize_top=0 arsize_bot=0 is_shrink=n
3 0.0126 2.37106 3.24115 T e e  arsize_top=0 arsize_bot=0 is_shrink=n
3 0.0126 2.37106 3.39115 T e e  arsize_top=0 arsize_bot=0 is_shrink=n
3 0.0126 2.37106 3.54115 T e e  arsize_top=0 arsize_bot=0 is_shrink=n
3 0.0126 2.37106 3.69115 T e e  arsize_top=0 arsize_bot=0 is_shrink=n
3 0.0126 2.37106 3.84115 T e e  arsize_top=0 arsize_bot=0 is_shrink=n
3 0.0126 2.42106 1.89115 T e e  arsize_top=0 arsize_bot=0 is_shrink=n
3 0.0126 2.42106 1.94115 T e e  arsize_top=0 arsize_bot=0 is_shrink=n
3 0.0126 2.42106 1.99115 T e e  arsize_top=0 arsize_bot=0 is_shrink=n
3 0.0126 2.42106 2.04115 T e e  arsize_top=0 arsize_bot=0 is_shrink=n
3 0.0126 2.42106 2.09115 T e e  arsize_top=0 arsize_bot=0 is_shrink=n
3 0.0126 2.42106 2.14115 T e e  arsize_top=0 arsize_bot=0 is_shrink=n
3 0.0126 2.42106 2.19115 T e e  arsize_top=0 arsize_bot=0 is_shrink=n
3 0.0126 2.42106 2.24115 T e e  arsize_top=0 arsize_bot=0 is_shrink=n
3 0.0126 2.42106 2.29115 T e e  arsize_top=0 arsize_bot=0 is_shrink=n
3 0.0126 2.42106 2.34115 T e e  arsize_top=0 arsize_bot=0 is_shrink=n
3 0.0126 2.42106 2.39115 T e e  arsize_top=0 arsize_bot=0 is_shrink=n
3 0.0126 2.42106 2.44115 T e e  arsize_top=0 arsize_bot=0 is_shrink=n
3 0.0126 2.42106 2.49115 T e e  arsize_top=0 arsize_bot=0 is_shrink=n
3 0.0126 2.42106 2.54115 T e e  arsize_top=0 arsize_bot=0 is_shrink=n
3 0.0126 2.42106 2.59115 T e e  arsize_top=0 arsize_bot=0 is_shrink=n
3 0.0126 2.42106 2.64115 T e e  arsize_top=0 arsize_bot=0 is_shrink=n
3 0.0126 2.42106 2.69115 T e e  arsize_top=0 arsize_bot=0 is_shrink=n
3 0.0126 2.42106 2.74115 T e e  arsize_top=0 arsize_bot=0 is_shrink=n
3 0.0126 2.42106 2.79115 T e e  arsize_top=0 arsize_bot=0 is_shrink=n
3 0.0126 2.42106 2.84115 T e e  arsize_top=0 arsize_bot=0 is_shrink=n
3 0.0126 2.42106 2.89115 T e e  arsize_top=0 arsize_bot=0 is_shrink=n
3 0.0126 2.42106 2.94115 T e e  arsize_top=0 arsize_bot=0 is_shrink=n
3 0.0126 2.42106 2.99115 T e e  arsize_top=0 arsize_bot=0 is_shrink=n
3 0.0126 2.42106 3.04115 T e e  arsize_top=0 arsize_bot=0 is_shrink=n
3 0.0126 2.42106 3.09115 T e e  arsize_top=0 arsize_bot=0 is_shrink=n
3 0.0126 2.42106 3.14115 T e e  arsize_top=0 arsize_bot=0 is_shrink=n
3 0.0126 2.42106 3.19115 T e e  arsize_top=0 arsize_bot=0 is_shrink=n
3 0.0126 2.42106 3.34115 T e e  arsize_top=0 arsize_bot=0 is_shrink=n
3 0.0126 2.42106 3.49115 T e e  arsize_top=0 arsize_bot=0 is_shrink=n
3 0.0126 2.42106 3.54115 T e e  arsize_top=0 arsize_bot=0 is_shrink=n
3 0.0126 2.42106 3.59115 T e e  arsize_top=0 arsize_bot=0 is_shrink=n
3 0.0126 2.42106 3.74115 T e e  arsize_top=0 arsize_bot=0 is_shrink=n
3 0.0126 2.47106 1.89115 T e e  arsize_top=0 arsize_bot=0 is_shrink=n
3 0.0126 2.47106 1.94115 T e e  arsize_top=0 arsize_bot=0 is_shrink=n
3 0.0126 2.47106 1.99115 T e e  arsize_top=0 arsize_bot=0 is_shrink=n
3 0.0126 2.47106 2.04115 T e e  arsize_top=0 arsize_bot=0 is_shrink=n
3 0.0126 2.47106 2.09115 T e e  arsize_top=0 arsize_bot=0 is_shrink=n
3 0.0126 2.47106 2.14115 T e e  arsize_top=0 arsize_bot=0 is_shrink=n
3 0.0126 2.47106 2.19115 T e e  arsize_top=0 arsize_bot=0 is_shrink=n
3 0.0126 2.47106 2.24115 T e e  arsize_top=0 arsize_bot=0 is_shrink=n
3 0.0126 2.47106 2.29115 T e e  arsize_top=0 arsize_bot=0 is_shrink=n
3 0.0126 2.47106 2.34115 T e e  arsize_top=0 arsize_bot=0 is_shrink=n
3 0.0126 2.47106 2.39115 T e e  arsize_top=0 arsize_bot=0 is_shrink=n
3 0.0126 2.47106 2.44115 T e e  arsize_top=0 arsize_bot=0 is_shrink=n
3 0.0126 2.47106 2.49115 T e e  arsize_top=0 arsize_bot=0 is_shrink=n
3 0.0126 2.47106 2.54115 T e e  arsize_top=0 arsize_bot=0 is_shrink=n
3 0.0126 2.47106 2.59115 T e e  arsize_top=0 arsize_bot=0 is_shrink=n
3 0.0126 2.47106 2.64115 T e e  arsize_top=0 arsize_bot=0 is_shrink=n
3 0.0126 2.47106 2.69115 T e e  arsize_top=0 arsize_bot=0 is_shrink=n
3 0.0126 2.47106 2.74115 T e e  arsize_top=0 arsize_bot=0 is_shrink=n
3 0.0126 2.47106 2.79115 T e e  arsize_top=0 arsize_bot=0 is_shrink=n
3 0.0126 2.47106 2.84115 T e e  arsize_top=0 arsize_bot=0 is_shrink=n
3 0.0126 2.47106 2.89115 T e e  arsize_top=0 arsize_bot=0 is_shrink=n
3 0.0126 2.47106 2.94115 T e e  arsize_top=0 arsize_bot=0 is_shrink=n
3 0.0126 2.47106 2.99115 T e e  arsize_top=0 arsize_bot=0 is_shrink=n
3 0.0126 2.47106 3.04115 T e e  arsize_top=0 arsize_bot=0 is_shrink=n
3 0.0126 2.47106 3.09115 T e e  arsize_top=0 arsize_bot=0 is_shrink=n
3 0.0126 2.47106 3.14115 T e e  arsize_top=0 arsize_bot=0 is_shrink=n
3 0.0126 2.47106 3.19115 T e e  arsize_top=0 arsize_bot=0 is_shrink=n
3 0.0126 2.47106 3.24115 T e e  arsize_top=0 arsize_bot=0 is_shrink=n
3 0.0126 2.47106 3.39115 T e e  arsize_top=0 arsize_bot=0 is_shrink=n
3 0.0126 2.47106 3.54115 T e e  arsize_top=0 arsize_bot=0 is_shrink=n
3 0.0126 2.47106 3.69115 T e e  arsize_top=0 arsize_bot=0 is_shrink=n
3 0.0126 2.47106 3.84115 T e e  arsize_top=0 arsize_bot=0 is_shrink=n
3 0.0126 8.025 1.89115 T e e  arsize_top=0 arsize_bot=0 is_shrink=n
3 0.0126 8.025 1.94115 T e e  arsize_top=0 arsize_bot=0 is_shrink=n
3 0.0126 8.025 1.99115 T e e  arsize_top=0 arsize_bot=0 is_shrink=n
3 0.0126 8.025 2.04115 T e e  arsize_top=0 arsize_bot=0 is_shrink=n
3 0.0126 8.025 2.09115 T e e  arsize_top=0 arsize_bot=0 is_shrink=n
3 0.0126 8.025 2.14115 T e e  arsize_top=0 arsize_bot=0 is_shrink=n
3 0.0126 8.025 2.19115 T e e  arsize_top=0 arsize_bot=0 is_shrink=n
3 0.0126 8.025 2.24115 T e e  arsize_top=0 arsize_bot=0 is_shrink=n
3 0.0126 8.025 2.29115 T e e  arsize_top=0 arsize_bot=0 is_shrink=n
3 0.0126 8.025 2.34115 T e e  arsize_top=0 arsize_bot=0 is_shrink=n
3 0.0126 8.025 2.39115 T e e  arsize_top=0 arsize_bot=0 is_shrink=n
3 0.0126 8.025 2.44115 T e e  arsize_top=0 arsize_bot=0 is_shrink=n
3 0.0126 8.025 2.49115 T e e  arsize_top=0 arsize_bot=0 is_shrink=n
3 0.0126 8.025 2.54115 T e e  arsize_top=0 arsize_bot=0 is_shrink=n
3 0.0126 8.025 2.59115 T e e  arsize_top=0 arsize_bot=0 is_shrink=n
3 0.0126 8.025 2.64115 T e e  arsize_top=0 arsize_bot=0 is_shrink=n
3 0.0126 8.025 2.69115 T e e  arsize_top=0 arsize_bot=0 is_shrink=n
3 0.0126 8.025 2.74115 T e e  arsize_top=0 arsize_bot=0 is_shrink=n
3 0.0126 8.025 2.79115 T e e  arsize_top=0 arsize_bot=0 is_shrink=n
3 0.0126 8.025 2.84115 T e e  arsize_top=0 arsize_bot=0 is_shrink=n
3 0.0126 8.025 2.89115 T e e  arsize_top=0 arsize_bot=0 is_shrink=n
3 0.0126 8.025 2.94115 T e e  arsize_top=0 arsize_bot=0 is_shrink=n
3 0.0126 8.025 2.99115 T e e  arsize_top=0 arsize_bot=0 is_shrink=n
3 0.0126 8.025 3.04115 T e e  arsize_top=0 arsize_bot=0 is_shrink=n
3 0.0126 8.025 3.09115 T e e  arsize_top=0 arsize_bot=0 is_shrink=n
3 0.0126 8.025 3.14115 T e e  arsize_top=0 arsize_bot=0 is_shrink=n
3 0.0126 8.025 3.19115 T e e  arsize_top=0 arsize_bot=0 is_shrink=n
3 0.0126 8.025 3.24115 T e e  arsize_top=0 arsize_bot=0 is_shrink=n
3 0.0126 8.025 3.39115 T e e  arsize_top=0 arsize_bot=0 is_shrink=n
3 0.0126 8.025 3.54115 T e e  arsize_top=0 arsize_bot=0 is_shrink=n
3 0.0126 8.025 3.69115 T e e  arsize_top=0 arsize_bot=0 is_shrink=n
3 0.0126 8.025 3.84115 T e e  arsize_top=0 arsize_bot=0 is_shrink=n
3 0.0126 8.075 1.89115 T e e  arsize_top=0 arsize_bot=0 is_shrink=n
3 0.0126 8.075 1.94115 T e e  arsize_top=0 arsize_bot=0 is_shrink=n
3 0.0126 8.075 1.99115 T e e  arsize_top=0 arsize_bot=0 is_shrink=n
3 0.0126 8.075 2.04115 T e e  arsize_top=0 arsize_bot=0 is_shrink=n
3 0.0126 8.075 2.09115 T e e  arsize_top=0 arsize_bot=0 is_shrink=n
3 0.0126 8.075 2.14115 T e e  arsize_top=0 arsize_bot=0 is_shrink=n
3 0.0126 8.075 2.19115 T e e  arsize_top=0 arsize_bot=0 is_shrink=n
3 0.0126 8.075 2.24115 T e e  arsize_top=0 arsize_bot=0 is_shrink=n
3 0.0126 8.075 2.29115 T e e  arsize_top=0 arsize_bot=0 is_shrink=n
3 0.0126 8.075 2.34115 T e e  arsize_top=0 arsize_bot=0 is_shrink=n
3 0.0126 8.075 2.39115 T e e  arsize_top=0 arsize_bot=0 is_shrink=n
3 0.0126 8.075 2.44115 T e e  arsize_top=0 arsize_bot=0 is_shrink=n
3 0.0126 8.075 2.49115 T e e  arsize_top=0 arsize_bot=0 is_shrink=n
3 0.0126 8.075 2.54115 T e e  arsize_top=0 arsize_bot=0 is_shrink=n
3 0.0126 8.075 2.59115 T e e  arsize_top=0 arsize_bot=0 is_shrink=n
3 0.0126 8.075 2.64115 T e e  arsize_top=0 arsize_bot=0 is_shrink=n
3 0.0126 8.075 2.69115 T e e  arsize_top=0 arsize_bot=0 is_shrink=n
3 0.0126 8.075 2.74115 T e e  arsize_top=0 arsize_bot=0 is_shrink=n
3 0.0126 8.075 2.79115 T e e  arsize_top=0 arsize_bot=0 is_shrink=n
3 0.0126 8.075 2.84115 T e e  arsize_top=0 arsize_bot=0 is_shrink=n
3 0.0126 8.075 2.89115 T e e  arsize_top=0 arsize_bot=0 is_shrink=n
3 0.0126 8.075 2.94115 T e e  arsize_top=0 arsize_bot=0 is_shrink=n
3 0.0126 8.075 2.99115 T e e  arsize_top=0 arsize_bot=0 is_shrink=n
3 0.0126 8.075 3.04115 T e e  arsize_top=0 arsize_bot=0 is_shrink=n
3 0.0126 8.075 3.09115 T e e  arsize_top=0 arsize_bot=0 is_shrink=n
3 0.0126 8.075 3.14115 T e e  arsize_top=0 arsize_bot=0 is_shrink=n
3 0.0126 8.075 3.19115 T e e  arsize_top=0 arsize_bot=0 is_shrink=n
3 0.0126 8.075 3.34115 T e e  arsize_top=0 arsize_bot=0 is_shrink=n
3 0.0126 8.075 3.49115 T e e  arsize_top=0 arsize_bot=0 is_shrink=n
3 0.0126 8.075 3.59115 T e e  arsize_top=0 arsize_bot=0 is_shrink=n
3 0.0126 8.075 3.74115 T e e  arsize_top=0 arsize_bot=0 is_shrink=n
3 0.0126 8.125 1.89115 T e e  arsize_top=0 arsize_bot=0 is_shrink=n
3 0.0126 8.125 1.94115 T e e  arsize_top=0 arsize_bot=0 is_shrink=n
3 0.0126 8.125 1.99115 T e e  arsize_top=0 arsize_bot=0 is_shrink=n
3 0.0126 8.125 2.04115 T e e  arsize_top=0 arsize_bot=0 is_shrink=n
3 0.0126 8.125 2.09115 T e e  arsize_top=0 arsize_bot=0 is_shrink=n
3 0.0126 8.125 2.14115 T e e  arsize_top=0 arsize_bot=0 is_shrink=n
3 0.0126 8.125 2.19115 T e e  arsize_top=0 arsize_bot=0 is_shrink=n
3 0.0126 8.125 2.24115 T e e  arsize_top=0 arsize_bot=0 is_shrink=n
3 0.0126 8.125 2.29115 T e e  arsize_top=0 arsize_bot=0 is_shrink=n
3 0.0126 8.125 2.34115 T e e  arsize_top=0 arsize_bot=0 is_shrink=n
3 0.0126 8.125 2.39115 T e e  arsize_top=0 arsize_bot=0 is_shrink=n
3 0.0126 8.125 2.44115 T e e  arsize_top=0 arsize_bot=0 is_shrink=n
3 0.0126 8.125 2.54115 T e e  arsize_top=0 arsize_bot=0 is_shrink=n
3 0.0126 8.125 2.59115 T e e  arsize_top=0 arsize_bot=0 is_shrink=n
3 0.0126 8.125 2.64115 T e e  arsize_top=0 arsize_bot=0 is_shrink=n
3 0.0126 8.125 2.69115 T e e  arsize_top=0 arsize_bot=0 is_shrink=n
3 0.0126 8.125 2.74115 T e e  arsize_top=0 arsize_bot=0 is_shrink=n
3 0.0126 8.125 2.79115 T e e  arsize_top=0 arsize_bot=0 is_shrink=n
3 0.0126 8.125 2.84115 T e e  arsize_top=0 arsize_bot=0 is_shrink=n
3 0.0126 8.125 2.89115 T e e  arsize_top=0 arsize_bot=0 is_shrink=n
3 0.0126 8.125 2.94115 T e e  arsize_top=0 arsize_bot=0 is_shrink=n
3 0.0126 8.125 2.99115 T e e  arsize_top=0 arsize_bot=0 is_shrink=n
3 0.0126 8.125 3.04115 T e e  arsize_top=0 arsize_bot=0 is_shrink=n
3 0.0126 8.125 3.09115 T e e  arsize_top=0 arsize_bot=0 is_shrink=n
3 0.0126 8.125 3.14115 T e e  arsize_top=0 arsize_bot=0 is_shrink=n
3 0.0126 8.125 3.19115 T e e  arsize_top=0 arsize_bot=0 is_shrink=n
3 0.0126 8.125 3.24115 T e e  arsize_top=0 arsize_bot=0 is_shrink=n
3 0.0126 8.125 3.39115 T e e  arsize_top=0 arsize_bot=0 is_shrink=n
3 0.0126 8.125 3.54115 T e e  arsize_top=0 arsize_bot=0 is_shrink=n
3 0.0126 8.125 3.69115 T e e  arsize_top=0 arsize_bot=0 is_shrink=n
3 0.0126 8.125 3.84115 T e e  arsize_top=0 arsize_bot=0 is_shrink=n
3 0.0126 8.175 1.89115 T e e  arsize_top=0 arsize_bot=0 is_shrink=n
3 0.0126 8.175 1.94115 T e e  arsize_top=0 arsize_bot=0 is_shrink=n
3 0.0126 8.175 1.99115 T e e  arsize_top=0 arsize_bot=0 is_shrink=n
3 0.0126 8.175 2.04115 T e e  arsize_top=0 arsize_bot=0 is_shrink=n
3 0.0126 8.175 2.09115 T e e  arsize_top=0 arsize_bot=0 is_shrink=n
3 0.0126 8.175 2.14115 T e e  arsize_top=0 arsize_bot=0 is_shrink=n
3 0.0126 8.175 2.19115 T e e  arsize_top=0 arsize_bot=0 is_shrink=n
3 0.0126 8.175 2.24115 T e e  arsize_top=0 arsize_bot=0 is_shrink=n
3 0.0126 8.175 2.29115 T e e  arsize_top=0 arsize_bot=0 is_shrink=n
3 0.0126 8.175 2.34115 T e e  arsize_top=0 arsize_bot=0 is_shrink=n
3 0.0126 8.175 2.39115 T e e  arsize_top=0 arsize_bot=0 is_shrink=n
3 0.0126 8.175 2.44115 T e e  arsize_top=0 arsize_bot=0 is_shrink=n
3 0.0126 8.175 2.49115 T e e  arsize_top=0 arsize_bot=0 is_shrink=n
3 0.0126 8.175 2.54115 T e e  arsize_top=0 arsize_bot=0 is_shrink=n
3 0.0126 8.175 2.59115 T e e  arsize_top=0 arsize_bot=0 is_shrink=n
3 0.0126 8.175 2.64115 T e e  arsize_top=0 arsize_bot=0 is_shrink=n
3 0.0126 8.175 2.69115 T e e  arsize_top=0 arsize_bot=0 is_shrink=n
3 0.0126 8.175 2.74115 T e e  arsize_top=0 arsize_bot=0 is_shrink=n
3 0.0126 8.175 2.79115 T e e  arsize_top=0 arsize_bot=0 is_shrink=n
3 0.0126 8.175 2.84115 T e e  arsize_top=0 arsize_bot=0 is_shrink=n
3 0.0126 8.175 2.89115 T e e  arsize_top=0 arsize_bot=0 is_shrink=n
3 0.0126 8.175 2.94115 T e e  arsize_top=0 arsize_bot=0 is_shrink=n
3 0.0126 8.175 2.99115 T e e  arsize_top=0 arsize_bot=0 is_shrink=n
3 0.0126 8.175 3.04115 T e e  arsize_top=0 arsize_bot=0 is_shrink=n
3 0.0126 8.175 3.09115 T e e  arsize_top=0 arsize_bot=0 is_shrink=n
3 0.0126 8.175 3.14115 T e e  arsize_top=0 arsize_bot=0 is_shrink=n
3 0.0126 8.175 3.19115 T e e  arsize_top=0 arsize_bot=0 is_shrink=n
3 0.0126 8.175 3.34115 T e e  arsize_top=0 arsize_bot=0 is_shrink=n
3 0.0126 8.175 3.49115 T e e  arsize_top=0 arsize_bot=0 is_shrink=n
3 0.0126 8.175 3.54115 T e e  arsize_top=0 arsize_bot=0 is_shrink=n
3 0.0126 8.175 3.59115 T e e  arsize_top=0 arsize_bot=0 is_shrink=n
3 0.0126 8.175 3.74115 T e e  arsize_top=0 arsize_bot=0 is_shrink=n
3 0.0126 8.225 1.89115 T e e  arsize_top=0 arsize_bot=0 is_shrink=n
3 0.0126 8.225 1.94115 T e e  arsize_top=0 arsize_bot=0 is_shrink=n
3 0.0126 8.225 1.99115 T e e  arsize_top=0 arsize_bot=0 is_shrink=n
3 0.0126 8.225 2.04115 T e e  arsize_top=0 arsize_bot=0 is_shrink=n
3 0.0126 8.225 2.09115 T e e  arsize_top=0 arsize_bot=0 is_shrink=n
3 0.0126 8.225 2.14115 T e e  arsize_top=0 arsize_bot=0 is_shrink=n
3 0.0126 8.225 2.19115 T e e  arsize_top=0 arsize_bot=0 is_shrink=n
3 0.0126 8.225 2.24115 T e e  arsize_top=0 arsize_bot=0 is_shrink=n
3 0.0126 8.225 2.29115 T e e  arsize_top=0 arsize_bot=0 is_shrink=n
3 0.0126 8.225 2.34115 T e e  arsize_top=0 arsize_bot=0 is_shrink=n
3 0.0126 8.225 2.39115 T e e  arsize_top=0 arsize_bot=0 is_shrink=n
3 0.0126 8.225 2.44115 T e e  arsize_top=0 arsize_bot=0 is_shrink=n
3 0.0126 8.225 2.49115 T e e  arsize_top=0 arsize_bot=0 is_shrink=n
3 0.0126 8.225 2.54115 T e e  arsize_top=0 arsize_bot=0 is_shrink=n
3 0.0126 8.225 2.59115 T e e  arsize_top=0 arsize_bot=0 is_shrink=n
3 0.0126 8.225 2.64115 T e e  arsize_top=0 arsize_bot=0 is_shrink=n
3 0.0126 8.225 2.69115 T e e  arsize_top=0 arsize_bot=0 is_shrink=n
3 0.0126 8.225 2.74115 T e e  arsize_top=0 arsize_bot=0 is_shrink=n
3 0.0126 8.225 2.79115 T e e  arsize_top=0 arsize_bot=0 is_shrink=n
3 0.0126 8.225 2.89115 T e e  arsize_top=0 arsize_bot=0 is_shrink=n
3 0.0126 8.225 2.94115 T e e  arsize_top=0 arsize_bot=0 is_shrink=n
3 0.0126 8.225 2.99115 T e e  arsize_top=0 arsize_bot=0 is_shrink=n
3 0.0126 8.225 3.04115 T e e  arsize_top=0 arsize_bot=0 is_shrink=n
3 0.0126 8.225 3.09115 T e e  arsize_top=0 arsize_bot=0 is_shrink=n
3 0.0126 8.225 3.14115 T e e  arsize_top=0 arsize_bot=0 is_shrink=n
3 0.0126 8.225 3.19115 T e e  arsize_top=0 arsize_bot=0 is_shrink=n
3 0.0126 8.225 3.24115 T e e  arsize_top=0 arsize_bot=0 is_shrink=n
3 0.0126 8.225 3.29115 T e e  arsize_top=0 arsize_bot=0 is_shrink=n
3 0.0126 8.225 3.34115 T e e  arsize_top=0 arsize_bot=0 is_shrink=n
3 0.0126 8.225 3.39115 T e e  arsize_top=0 arsize_bot=0 is_shrink=n
3 0.0126 8.225 3.44115 T e e  arsize_top=0 arsize_bot=0 is_shrink=n
3 0.0126 8.225 3.49115 T e e  arsize_top=0 arsize_bot=0 is_shrink=n
3 0.0126 8.225 3.59115 T e e  arsize_top=0 arsize_bot=0 is_shrink=n
3 0.0126 8.225 3.64115 T e e  arsize_top=0 arsize_bot=0 is_shrink=n
3 0.0126 8.225 3.69115 T e e  arsize_top=0 arsize_bot=0 is_shrink=n
3 0.0126 8.225 3.74115 T e e  arsize_top=0 arsize_bot=0 is_shrink=n
3 0.0126 8.225 3.79115 T e e  arsize_top=0 arsize_bot=0 is_shrink=n
3 0.0126 8.225 3.84115 T e e  arsize_top=0 arsize_bot=0 is_shrink=n
3 0.0126 8.275 1.89115 T e e  arsize_top=0 arsize_bot=0 is_shrink=n
3 0.0126 8.275 1.94115 T e e  arsize_top=0 arsize_bot=0 is_shrink=n
3 0.0126 8.275 1.99115 T e e  arsize_top=0 arsize_bot=0 is_shrink=n
3 0.0126 8.275 2.04115 T e e  arsize_top=0 arsize_bot=0 is_shrink=n
3 0.0126 8.275 2.09115 T e e  arsize_top=0 arsize_bot=0 is_shrink=n
3 0.0126 8.275 2.14115 T e e  arsize_top=0 arsize_bot=0 is_shrink=n
3 0.0126 8.275 2.19115 T e e  arsize_top=0 arsize_bot=0 is_shrink=n
3 0.0126 8.275 2.24115 T e e  arsize_top=0 arsize_bot=0 is_shrink=n
3 0.0126 8.275 2.29115 T e e  arsize_top=0 arsize_bot=0 is_shrink=n
3 0.0126 8.275 2.34115 T e e  arsize_top=0 arsize_bot=0 is_shrink=n
3 0.0126 8.275 2.39115 T e e  arsize_top=0 arsize_bot=0 is_shrink=n
3 0.0126 8.275 2.44115 T e e  arsize_top=0 arsize_bot=0 is_shrink=n
3 0.0126 8.275 2.49115 T e e  arsize_top=0 arsize_bot=0 is_shrink=n
3 0.0126 8.275 2.54115 T e e  arsize_top=0 arsize_bot=0 is_shrink=n
3 0.0126 8.275 2.59115 T e e  arsize_top=0 arsize_bot=0 is_shrink=n
3 0.0126 8.275 2.64115 T e e  arsize_top=0 arsize_bot=0 is_shrink=n
3 0.0126 8.275 2.69115 T e e  arsize_top=0 arsize_bot=0 is_shrink=n
3 0.0126 8.275 2.74115 T e e  arsize_top=0 arsize_bot=0 is_shrink=n
3 0.0126 8.275 2.79115 T e e  arsize_top=0 arsize_bot=0 is_shrink=n
3 0.0126 8.275 2.89115 T e e  arsize_top=0 arsize_bot=0 is_shrink=n
3 0.0126 8.275 2.94115 T e e  arsize_top=0 arsize_bot=0 is_shrink=n
3 0.0126 8.275 2.99115 T e e  arsize_top=0 arsize_bot=0 is_shrink=n
3 0.0126 8.275 3.04115 T e e  arsize_top=0 arsize_bot=0 is_shrink=n
3 0.0126 8.275 3.09115 T e e  arsize_top=0 arsize_bot=0 is_shrink=n
3 0.0126 8.275 3.14115 T e e  arsize_top=0 arsize_bot=0 is_shrink=n
3 0.0126 8.275 3.19115 T e e  arsize_top=0 arsize_bot=0 is_shrink=n
3 0.0126 8.275 3.24115 T e e  arsize_top=0 arsize_bot=0 is_shrink=n
3 0.0126 8.275 3.29115 T e e  arsize_top=0 arsize_bot=0 is_shrink=n
3 0.0126 8.275 3.34115 T e e  arsize_top=0 arsize_bot=0 is_shrink=n
3 0.0126 8.275 3.39115 T e e  arsize_top=0 arsize_bot=0 is_shrink=n
3 0.0126 8.275 3.44115 T e e  arsize_top=0 arsize_bot=0 is_shrink=n
3 0.0126 8.275 3.49115 T e e  arsize_top=0 arsize_bot=0 is_shrink=n
3 0.0126 8.275 3.59115 T e e  arsize_top=0 arsize_bot=0 is_shrink=n
3 0.0126 8.275 3.64115 T e e  arsize_top=0 arsize_bot=0 is_shrink=n
3 0.0126 8.275 3.69115 T e e  arsize_top=0 arsize_bot=0 is_shrink=n
3 0.0126 8.275 3.74115 T e e  arsize_top=0 arsize_bot=0 is_shrink=n
3 0.0126 8.275 3.79115 T e e  arsize_top=0 arsize_bot=0 is_shrink=n
3 0.0126 8.275 3.84115 T e e  arsize_top=0 arsize_bot=0 is_shrink=n
3 0.0126 8.325 1.89115 T e e  arsize_top=0 arsize_bot=0 is_shrink=n
3 0.0126 8.325 1.94115 T e e  arsize_top=0 arsize_bot=0 is_shrink=n
3 0.0126 8.325 1.99115 T e e  arsize_top=0 arsize_bot=0 is_shrink=n
3 0.0126 8.325 2.04115 T e e  arsize_top=0 arsize_bot=0 is_shrink=n
3 0.0126 8.325 2.09115 T e e  arsize_top=0 arsize_bot=0 is_shrink=n
3 0.0126 8.325 2.14115 T e e  arsize_top=0 arsize_bot=0 is_shrink=n
3 0.0126 8.325 2.19115 T e e  arsize_top=0 arsize_bot=0 is_shrink=n
3 0.0126 8.325 2.24115 T e e  arsize_top=0 arsize_bot=0 is_shrink=n
3 0.0126 8.325 2.29115 T e e  arsize_top=0 arsize_bot=0 is_shrink=n
3 0.0126 8.325 2.34115 T e e  arsize_top=0 arsize_bot=0 is_shrink=n
3 0.0126 8.325 2.39115 T e e  arsize_top=0 arsize_bot=0 is_shrink=n
3 0.0126 8.325 2.44115 T e e  arsize_top=0 arsize_bot=0 is_shrink=n
3 0.0126 8.325 2.49115 T e e  arsize_top=0 arsize_bot=0 is_shrink=n
3 0.0126 8.325 2.54115 T e e  arsize_top=0 arsize_bot=0 is_shrink=n
3 0.0126 8.325 2.59115 T e e  arsize_top=0 arsize_bot=0 is_shrink=n
3 0.0126 8.325 2.64115 T e e  arsize_top=0 arsize_bot=0 is_shrink=n
3 0.0126 8.325 2.69115 T e e  arsize_top=0 arsize_bot=0 is_shrink=n
3 0.0126 8.325 2.74115 T e e  arsize_top=0 arsize_bot=0 is_shrink=n
3 0.0126 8.325 2.79115 T e e  arsize_top=0 arsize_bot=0 is_shrink=n
3 0.0126 8.325 2.84115 T e e  arsize_top=0 arsize_bot=0 is_shrink=n
3 0.0126 8.325 2.89115 T e e  arsize_top=0 arsize_bot=0 is_shrink=n
3 0.0126 8.325 2.94115 T e e  arsize_top=0 arsize_bot=0 is_shrink=n
3 0.0126 8.325 2.99115 T e e  arsize_top=0 arsize_bot=0 is_shrink=n
3 0.0126 8.325 3.04115 T e e  arsize_top=0 arsize_bot=0 is_shrink=n
3 0.0126 8.325 3.09115 T e e  arsize_top=0 arsize_bot=0 is_shrink=n
3 0.0126 8.325 3.14115 T e e  arsize_top=0 arsize_bot=0 is_shrink=n
3 0.0126 8.325 3.19115 T e e  arsize_top=0 arsize_bot=0 is_shrink=n
3 0.0126 8.325 3.34115 T e e  arsize_top=0 arsize_bot=0 is_shrink=n
3 0.0126 8.325 3.49115 T e e  arsize_top=0 arsize_bot=0 is_shrink=n
3 0.0126 8.325 3.54115 T e e  arsize_top=0 arsize_bot=0 is_shrink=n
3 0.0126 8.325 3.59115 T e e  arsize_top=0 arsize_bot=0 is_shrink=n
3 0.0126 8.325 3.74115 T e e  arsize_top=0 arsize_bot=0 is_shrink=n
3 0.0126 8.375 1.89115 T e e  arsize_top=0 arsize_bot=0 is_shrink=n
3 0.0126 8.375 1.94115 T e e  arsize_top=0 arsize_bot=0 is_shrink=n
3 0.0126 8.375 1.99115 T e e  arsize_top=0 arsize_bot=0 is_shrink=n
3 0.0126 8.375 2.04115 T e e  arsize_top=0 arsize_bot=0 is_shrink=n
3 0.0126 8.375 2.09115 T e e  arsize_top=0 arsize_bot=0 is_shrink=n
3 0.0126 8.375 2.14115 T e e  arsize_top=0 arsize_bot=0 is_shrink=n
3 0.0126 8.375 2.19115 T e e  arsize_top=0 arsize_bot=0 is_shrink=n
3 0.0126 8.375 2.24115 T e e  arsize_top=0 arsize_bot=0 is_shrink=n
3 0.0126 8.375 2.29115 T e e  arsize_top=0 arsize_bot=0 is_shrink=n
3 0.0126 8.375 2.34115 T e e  arsize_top=0 arsize_bot=0 is_shrink=n
3 0.0126 8.375 2.39115 T e e  arsize_top=0 arsize_bot=0 is_shrink=n
3 0.0126 8.375 2.44115 T e e  arsize_top=0 arsize_bot=0 is_shrink=n
3 0.0126 8.375 2.49115 T e e  arsize_top=0 arsize_bot=0 is_shrink=n
3 0.0126 8.375 2.54115 T e e  arsize_top=0 arsize_bot=0 is_shrink=n
3 0.0126 8.375 2.59115 T e e  arsize_top=0 arsize_bot=0 is_shrink=n
3 0.0126 8.375 2.64115 T e e  arsize_top=0 arsize_bot=0 is_shrink=n
3 0.0126 8.375 2.69115 T e e  arsize_top=0 arsize_bot=0 is_shrink=n
3 0.0126 8.375 2.74115 T e e  arsize_top=0 arsize_bot=0 is_shrink=n
3 0.0126 8.375 2.79115 T e e  arsize_top=0 arsize_bot=0 is_shrink=n
3 0.0126 8.375 2.84115 T e e  arsize_top=0 arsize_bot=0 is_shrink=n
3 0.0126 8.375 2.89115 T e e  arsize_top=0 arsize_bot=0 is_shrink=n
3 0.0126 8.375 2.94115 T e e  arsize_top=0 arsize_bot=0 is_shrink=n
3 0.0126 8.375 2.99115 T e e  arsize_top=0 arsize_bot=0 is_shrink=n
3 0.0126 8.375 3.04115 T e e  arsize_top=0 arsize_bot=0 is_shrink=n
3 0.0126 8.375 3.09115 T e e  arsize_top=0 arsize_bot=0 is_shrink=n
3 0.0126 8.375 3.14115 T e e  arsize_top=0 arsize_bot=0 is_shrink=n
3 0.0126 8.375 3.19115 T e e  arsize_top=0 arsize_bot=0 is_shrink=n
3 0.0126 8.375 3.24115 T e e  arsize_top=0 arsize_bot=0 is_shrink=n
3 0.0126 8.375 3.39115 T e e  arsize_top=0 arsize_bot=0 is_shrink=n
3 0.0126 8.375 3.54115 T e e  arsize_top=0 arsize_bot=0 is_shrink=n
3 0.0126 8.375 3.69115 T e e  arsize_top=0 arsize_bot=0 is_shrink=n
3 0.0126 8.375 3.84115 T e e  arsize_top=0 arsize_bot=0 is_shrink=n
3 0.0126 8.425 1.89115 T e e  arsize_top=0 arsize_bot=0 is_shrink=n
3 0.0126 8.425 1.94115 T e e  arsize_top=0 arsize_bot=0 is_shrink=n
3 0.0126 8.425 1.99115 T e e  arsize_top=0 arsize_bot=0 is_shrink=n
3 0.0126 8.425 2.04115 T e e  arsize_top=0 arsize_bot=0 is_shrink=n
3 0.0126 8.425 2.09115 T e e  arsize_top=0 arsize_bot=0 is_shrink=n
3 0.0126 8.425 2.14115 T e e  arsize_top=0 arsize_bot=0 is_shrink=n
3 0.0126 8.425 2.19115 T e e  arsize_top=0 arsize_bot=0 is_shrink=n
3 0.0126 8.425 2.24115 T e e  arsize_top=0 arsize_bot=0 is_shrink=n
3 0.0126 8.425 2.29115 T e e  arsize_top=0 arsize_bot=0 is_shrink=n
3 0.0126 8.425 2.34115 T e e  arsize_top=0 arsize_bot=0 is_shrink=n
3 0.0126 8.425 2.39115 T e e  arsize_top=0 arsize_bot=0 is_shrink=n
3 0.0126 8.425 2.44115 T e e  arsize_top=0 arsize_bot=0 is_shrink=n
3 0.0126 8.425 2.49115 T e e  arsize_top=0 arsize_bot=0 is_shrink=n
3 0.0126 8.425 2.54115 T e e  arsize_top=0 arsize_bot=0 is_shrink=n
3 0.0126 8.425 2.59115 T e e  arsize_top=0 arsize_bot=0 is_shrink=n
3 0.0126 8.425 2.64115 T e e  arsize_top=0 arsize_bot=0 is_shrink=n
3 0.0126 8.425 2.69115 T e e  arsize_top=0 arsize_bot=0 is_shrink=n
3 0.0126 8.425 2.74115 T e e  arsize_top=0 arsize_bot=0 is_shrink=n
3 0.0126 8.425 2.79115 T e e  arsize_top=0 arsize_bot=0 is_shrink=n
3 0.0126 8.425 2.84115 T e e  arsize_top=0 arsize_bot=0 is_shrink=n
3 0.0126 8.425 2.89115 T e e  arsize_top=0 arsize_bot=0 is_shrink=n
3 0.0126 8.425 2.94115 T e e  arsize_top=0 arsize_bot=0 is_shrink=n
3 0.0126 8.425 2.99115 T e e  arsize_top=0 arsize_bot=0 is_shrink=n
3 0.0126 8.425 3.04115 T e e  arsize_top=0 arsize_bot=0 is_shrink=n
3 0.0126 8.425 3.09115 T e e  arsize_top=0 arsize_bot=0 is_shrink=n
3 0.0126 8.425 3.14115 T e e  arsize_top=0 arsize_bot=0 is_shrink=n
3 0.0126 8.425 3.19115 T e e  arsize_top=0 arsize_bot=0 is_shrink=n
3 0.0126 8.425 3.34115 T e e  arsize_top=0 arsize_bot=0 is_shrink=n
3 0.0126 8.425 3.49115 T e e  arsize_top=0 arsize_bot=0 is_shrink=n
3 0.0126 8.425 3.54115 T e e  arsize_top=0 arsize_bot=0 is_shrink=n
3 0.0126 8.425 3.59115 T e e  arsize_top=0 arsize_bot=0 is_shrink=n
3 0.0126 8.425 3.74115 T e e  arsize_top=0 arsize_bot=0 is_shrink=n
3 0.0126 8.475 1.89115 T e e  arsize_top=0 arsize_bot=0 is_shrink=n
3 0.0126 8.475 1.94115 T e e  arsize_top=0 arsize_bot=0 is_shrink=n
3 0.0126 8.475 1.99115 T e e  arsize_top=0 arsize_bot=0 is_shrink=n
3 0.0126 8.475 2.04115 T e e  arsize_top=0 arsize_bot=0 is_shrink=n
3 0.0126 8.475 2.09115 T e e  arsize_top=0 arsize_bot=0 is_shrink=n
3 0.0126 8.475 2.14115 T e e  arsize_top=0 arsize_bot=0 is_shrink=n
3 0.0126 8.475 2.19115 T e e  arsize_top=0 arsize_bot=0 is_shrink=n
3 0.0126 8.475 2.24115 T e e  arsize_top=0 arsize_bot=0 is_shrink=n
3 0.0126 8.475 2.29115 T e e  arsize_top=0 arsize_bot=0 is_shrink=n
3 0.0126 8.475 2.34115 T e e  arsize_top=0 arsize_bot=0 is_shrink=n
3 0.0126 8.475 2.39115 T e e  arsize_top=0 arsize_bot=0 is_shrink=n
3 0.0126 8.475 2.44115 T e e  arsize_top=0 arsize_bot=0 is_shrink=n
3 0.0126 8.475 2.49115 T e e  arsize_top=0 arsize_bot=0 is_shrink=n
3 0.0126 8.475 2.54115 T e e  arsize_top=0 arsize_bot=0 is_shrink=n
3 0.0126 8.475 2.59115 T e e  arsize_top=0 arsize_bot=0 is_shrink=n
3 0.0126 8.475 2.64115 T e e  arsize_top=0 arsize_bot=0 is_shrink=n
3 0.0126 8.475 2.69115 T e e  arsize_top=0 arsize_bot=0 is_shrink=n
3 0.0126 8.475 2.74115 T e e  arsize_top=0 arsize_bot=0 is_shrink=n
3 0.0126 8.475 2.79115 T e e  arsize_top=0 arsize_bot=0 is_shrink=n
3 0.0126 8.475 2.84115 T e e  arsize_top=0 arsize_bot=0 is_shrink=n
3 0.0126 8.475 2.89115 T e e  arsize_top=0 arsize_bot=0 is_shrink=n
3 0.0126 8.475 2.94115 T e e  arsize_top=0 arsize_bot=0 is_shrink=n
3 0.0126 8.475 2.99115 T e e  arsize_top=0 arsize_bot=0 is_shrink=n
3 0.0126 8.475 3.04115 T e e  arsize_top=0 arsize_bot=0 is_shrink=n
3 0.0126 8.475 3.09115 T e e  arsize_top=0 arsize_bot=0 is_shrink=n
3 0.0126 8.475 3.14115 T e e  arsize_top=0 arsize_bot=0 is_shrink=n
3 0.0126 8.475 3.19115 T e e  arsize_top=0 arsize_bot=0 is_shrink=n
3 0.0126 8.475 3.24115 T e e  arsize_top=0 arsize_bot=0 is_shrink=n
3 0.0126 8.475 3.39115 T e e  arsize_top=0 arsize_bot=0 is_shrink=n
3 0.0126 8.475 3.54115 T e e  arsize_top=0 arsize_bot=0 is_shrink=n
3 0.0126 8.475 3.69115 T e e  arsize_top=0 arsize_bot=0 is_shrink=n
3 0.0126 8.475 3.84115 T e e  arsize_top=0 arsize_bot=0 is_shrink=n
3 0.0126 4.60768 1.89115 T e e  arsize_top=0 arsize_bot=0 is_shrink=n
3 0.0126 4.60768 2.04115 T e e  arsize_top=0 arsize_bot=0 is_shrink=n
3 0.0126 4.60768 2.19115 T e e  arsize_top=0 arsize_bot=0 is_shrink=n
3 0.0126 4.60768 2.34115 T e e  arsize_top=0 arsize_bot=0 is_shrink=n
3 0.0126 4.60768 2.49115 T e e  arsize_top=0 arsize_bot=0 is_shrink=n
3 0.0126 4.60768 2.54115 T e e  arsize_top=0 arsize_bot=0 is_shrink=n
3 0.0126 4.60768 2.69115 T e e  arsize_top=0 arsize_bot=0 is_shrink=n
3 0.0126 4.60768 2.89115 T e e  arsize_top=0 arsize_bot=0 is_shrink=n
3 0.0126 4.60768 3.04115 T e e  arsize_top=0 arsize_bot=0 is_shrink=n
3 0.0126 4.60768 3.19115 T e e  arsize_top=0 arsize_bot=0 is_shrink=n
3 0.0126 4.60768 3.34115 T e e  arsize_top=0 arsize_bot=0 is_shrink=n
3 0.0126 4.60768 3.49115 T e e  arsize_top=0 arsize_bot=0 is_shrink=n
3 0.0126 4.60768 3.64115 T e e  arsize_top=0 arsize_bot=0 is_shrink=n
3 0.0126 4.60768 3.79115 T e e  arsize_top=0 arsize_bot=0 is_shrink=n
3 0.0126 4.65768 1.99115 T e e  arsize_top=0 arsize_bot=0 is_shrink=n
3 0.0126 4.65768 2.14115 T e e  arsize_top=0 arsize_bot=0 is_shrink=n
3 0.0126 4.65768 2.19115 T e e  arsize_top=0 arsize_bot=0 is_shrink=n
3 0.0126 4.65768 2.24115 T e e  arsize_top=0 arsize_bot=0 is_shrink=n
3 0.0126 4.65768 2.39115 T e e  arsize_top=0 arsize_bot=0 is_shrink=n
3 0.0126 4.65768 2.54115 T e e  arsize_top=0 arsize_bot=0 is_shrink=n
3 0.0126 4.65768 2.59115 T e e  arsize_top=0 arsize_bot=0 is_shrink=n
3 0.0126 4.65768 2.74115 T e e  arsize_top=0 arsize_bot=0 is_shrink=n
3 0.0126 4.65768 2.79115 T e e  arsize_top=0 arsize_bot=0 is_shrink=n
3 0.0126 4.65768 2.89115 T e e  arsize_top=0 arsize_bot=0 is_shrink=n
3 0.0126 4.65768 3.04115 T e e  arsize_top=0 arsize_bot=0 is_shrink=n
3 0.0126 4.65768 3.19115 T e e  arsize_top=0 arsize_bot=0 is_shrink=n
3 0.0126 4.65768 3.34115 T e e  arsize_top=0 arsize_bot=0 is_shrink=n
3 0.0126 4.65768 3.49115 T e e  arsize_top=0 arsize_bot=0 is_shrink=n
3 0.0126 4.65768 3.64115 T e e  arsize_top=0 arsize_bot=0 is_shrink=n
3 0.0126 4.65768 3.79115 T e e  arsize_top=0 arsize_bot=0 is_shrink=n
3 0.0126 4.70768 1.89115 T e e  arsize_top=0 arsize_bot=0 is_shrink=n
3 0.0126 4.70768 2.04115 T e e  arsize_top=0 arsize_bot=0 is_shrink=n
3 0.0126 4.70768 2.19115 T e e  arsize_top=0 arsize_bot=0 is_shrink=n
3 0.0126 4.70768 2.34115 T e e  arsize_top=0 arsize_bot=0 is_shrink=n
3 0.0126 4.70768 2.49115 T e e  arsize_top=0 arsize_bot=0 is_shrink=n
3 0.0126 4.70768 2.54115 T e e  arsize_top=0 arsize_bot=0 is_shrink=n
3 0.0126 4.70768 2.69115 T e e  arsize_top=0 arsize_bot=0 is_shrink=n
3 0.0126 4.70768 2.89115 T e e  arsize_top=0 arsize_bot=0 is_shrink=n
3 0.0126 4.70768 3.04115 T e e  arsize_top=0 arsize_bot=0 is_shrink=n
3 0.0126 4.70768 3.19115 T e e  arsize_top=0 arsize_bot=0 is_shrink=n
3 0.0126 4.70768 3.34115 T e e  arsize_top=0 arsize_bot=0 is_shrink=n
3 0.0126 4.70768 3.49115 T e e  arsize_top=0 arsize_bot=0 is_shrink=n
3 0.0126 4.70768 3.64115 T e e  arsize_top=0 arsize_bot=0 is_shrink=n
3 0.0126 4.70768 3.79115 T e e  arsize_top=0 arsize_bot=0 is_shrink=n
3 0.0126 4.75768 1.99115 T e e  arsize_top=0 arsize_bot=0 is_shrink=n
3 0.0126 4.75768 2.14115 T e e  arsize_top=0 arsize_bot=0 is_shrink=n
3 0.0126 4.75768 2.19115 T e e  arsize_top=0 arsize_bot=0 is_shrink=n
3 0.0126 4.75768 2.24115 T e e  arsize_top=0 arsize_bot=0 is_shrink=n
3 0.0126 4.75768 2.39115 T e e  arsize_top=0 arsize_bot=0 is_shrink=n
3 0.0126 4.75768 2.54115 T e e  arsize_top=0 arsize_bot=0 is_shrink=n
3 0.0126 4.75768 2.59115 T e e  arsize_top=0 arsize_bot=0 is_shrink=n
3 0.0126 4.75768 2.74115 T e e  arsize_top=0 arsize_bot=0 is_shrink=n
3 0.0126 4.75768 2.79115 T e e  arsize_top=0 arsize_bot=0 is_shrink=n
3 0.0126 4.75768 2.89115 T e e  arsize_top=0 arsize_bot=0 is_shrink=n
3 0.0126 4.75768 3.04115 T e e  arsize_top=0 arsize_bot=0 is_shrink=n
3 0.0126 4.75768 3.19115 T e e  arsize_top=0 arsize_bot=0 is_shrink=n
3 0.0126 4.75768 3.34115 T e e  arsize_top=0 arsize_bot=0 is_shrink=n
3 0.0126 4.75768 3.49115 T e e  arsize_top=0 arsize_bot=0 is_shrink=n
3 0.0126 4.75768 3.64115 T e e  arsize_top=0 arsize_bot=0 is_shrink=n
3 0.0126 4.75768 3.79115 T e e  arsize_top=0 arsize_bot=0 is_shrink=n
3 0.0126 4.80768 1.89115 T e e  arsize_top=0 arsize_bot=0 is_shrink=n
3 0.0126 4.80768 1.94115 T e e  arsize_top=0 arsize_bot=0 is_shrink=n
3 0.0126 4.80768 1.99115 T e e  arsize_top=0 arsize_bot=0 is_shrink=n
3 0.0126 4.80768 2.04115 T e e  arsize_top=0 arsize_bot=0 is_shrink=n
3 0.0126 4.80768 2.09115 T e e  arsize_top=0 arsize_bot=0 is_shrink=n
3 0.0126 4.80768 2.14115 T e e  arsize_top=0 arsize_bot=0 is_shrink=n
3 0.0126 4.80768 2.24115 T e e  arsize_top=0 arsize_bot=0 is_shrink=n
3 0.0126 4.80768 2.29115 T e e  arsize_top=0 arsize_bot=0 is_shrink=n
3 0.0126 4.80768 2.34115 T e e  arsize_top=0 arsize_bot=0 is_shrink=n
3 0.0126 4.80768 2.39115 T e e  arsize_top=0 arsize_bot=0 is_shrink=n
3 0.0126 4.80768 2.44115 T e e  arsize_top=0 arsize_bot=0 is_shrink=n
3 0.0126 4.80768 2.49115 T e e  arsize_top=0 arsize_bot=0 is_shrink=n
3 0.0126 4.80768 2.54115 T e e  arsize_top=0 arsize_bot=0 is_shrink=n
3 0.0126 4.80768 2.59115 T e e  arsize_top=0 arsize_bot=0 is_shrink=n
3 0.0126 4.80768 2.64115 T e e  arsize_top=0 arsize_bot=0 is_shrink=n
3 0.0126 4.80768 2.69115 T e e  arsize_top=0 arsize_bot=0 is_shrink=n
3 0.0126 4.80768 2.79115 T e e  arsize_top=0 arsize_bot=0 is_shrink=n
3 0.0126 4.80768 2.89115 T e e  arsize_top=0 arsize_bot=0 is_shrink=n
3 0.0126 4.80768 3.04115 T e e  arsize_top=0 arsize_bot=0 is_shrink=n
3 0.0126 4.80768 3.19115 T e e  arsize_top=0 arsize_bot=0 is_shrink=n
3 0.0126 4.80768 3.34115 T e e  arsize_top=0 arsize_bot=0 is_shrink=n
3 0.0126 4.80768 3.49115 T e e  arsize_top=0 arsize_bot=0 is_shrink=n
3 0.0126 4.80768 3.64115 T e e  arsize_top=0 arsize_bot=0 is_shrink=n
3 0.0126 4.80768 3.79115 T e e  arsize_top=0 arsize_bot=0 is_shrink=n
3 0.0126 4.85768 1.89115 T e e  arsize_top=0 arsize_bot=0 is_shrink=n
3 0.0126 4.85768 1.94115 T e e  arsize_top=0 arsize_bot=0 is_shrink=n
3 0.0126 4.85768 1.99115 T e e  arsize_top=0 arsize_bot=0 is_shrink=n
3 0.0126 4.85768 2.04115 T e e  arsize_top=0 arsize_bot=0 is_shrink=n
3 0.0126 4.85768 2.09115 T e e  arsize_top=0 arsize_bot=0 is_shrink=n
3 0.0126 4.85768 2.14115 T e e  arsize_top=0 arsize_bot=0 is_shrink=n
3 0.0126 4.85768 2.24115 T e e  arsize_top=0 arsize_bot=0 is_shrink=n
3 0.0126 4.85768 2.29115 T e e  arsize_top=0 arsize_bot=0 is_shrink=n
3 0.0126 4.85768 2.34115 T e e  arsize_top=0 arsize_bot=0 is_shrink=n
3 0.0126 4.85768 2.39115 T e e  arsize_top=0 arsize_bot=0 is_shrink=n
3 0.0126 4.85768 2.44115 T e e  arsize_top=0 arsize_bot=0 is_shrink=n
3 0.0126 4.85768 2.49115 T e e  arsize_top=0 arsize_bot=0 is_shrink=n
3 0.0126 4.85768 2.54115 T e e  arsize_top=0 arsize_bot=0 is_shrink=n
3 0.0126 4.85768 2.59115 T e e  arsize_top=0 arsize_bot=0 is_shrink=n
3 0.0126 4.85768 2.64115 T e e  arsize_top=0 arsize_bot=0 is_shrink=n
3 0.0126 4.85768 2.69115 T e e  arsize_top=0 arsize_bot=0 is_shrink=n
3 0.0126 4.85768 2.79115 T e e  arsize_top=0 arsize_bot=0 is_shrink=n
3 0.0126 4.85768 2.89115 T e e  arsize_top=0 arsize_bot=0 is_shrink=n
3 0.0126 4.85768 3.04115 T e e  arsize_top=0 arsize_bot=0 is_shrink=n
3 0.0126 4.85768 3.19115 T e e  arsize_top=0 arsize_bot=0 is_shrink=n
3 0.0126 4.85768 3.34115 T e e  arsize_top=0 arsize_bot=0 is_shrink=n
3 0.0126 4.85768 3.49115 T e e  arsize_top=0 arsize_bot=0 is_shrink=n
3 0.0126 4.85768 3.64115 T e e  arsize_top=0 arsize_bot=0 is_shrink=n
3 0.0126 4.85768 3.79115 T e e  arsize_top=0 arsize_bot=0 is_shrink=n
3 0.0126 4.90768 1.99115 T e e  arsize_top=0 arsize_bot=0 is_shrink=n
3 0.0126 4.90768 2.14115 T e e  arsize_top=0 arsize_bot=0 is_shrink=n
3 0.0126 4.90768 2.19115 T e e  arsize_top=0 arsize_bot=0 is_shrink=n
3 0.0126 4.90768 2.24115 T e e  arsize_top=0 arsize_bot=0 is_shrink=n
3 0.0126 4.90768 2.39115 T e e  arsize_top=0 arsize_bot=0 is_shrink=n
3 0.0126 4.90768 2.54115 T e e  arsize_top=0 arsize_bot=0 is_shrink=n
3 0.0126 4.90768 2.59115 T e e  arsize_top=0 arsize_bot=0 is_shrink=n
3 0.0126 4.90768 2.74115 T e e  arsize_top=0 arsize_bot=0 is_shrink=n
3 0.0126 4.90768 2.79115 T e e  arsize_top=0 arsize_bot=0 is_shrink=n
3 0.0126 4.90768 2.89115 T e e  arsize_top=0 arsize_bot=0 is_shrink=n
3 0.0126 4.90768 3.04115 T e e  arsize_top=0 arsize_bot=0 is_shrink=n
3 0.0126 4.90768 3.19115 T e e  arsize_top=0 arsize_bot=0 is_shrink=n
3 0.0126 4.90768 3.34115 T e e  arsize_top=0 arsize_bot=0 is_shrink=n
3 0.0126 4.90768 3.49115 T e e  arsize_top=0 arsize_bot=0 is_shrink=n
3 0.0126 4.90768 3.64115 T e e  arsize_top=0 arsize_bot=0 is_shrink=n
3 0.0126 4.90768 3.79115 T e e  arsize_top=0 arsize_bot=0 is_shrink=n
3 0.0126 4.95768 1.89115 T e e  arsize_top=0 arsize_bot=0 is_shrink=n
3 0.0126 4.95768 2.04115 T e e  arsize_top=0 arsize_bot=0 is_shrink=n
3 0.0126 4.95768 2.19115 T e e  arsize_top=0 arsize_bot=0 is_shrink=n
3 0.0126 4.95768 2.34115 T e e  arsize_top=0 arsize_bot=0 is_shrink=n
3 0.0126 4.95768 2.49115 T e e  arsize_top=0 arsize_bot=0 is_shrink=n
3 0.0126 4.95768 2.54115 T e e  arsize_top=0 arsize_bot=0 is_shrink=n
3 0.0126 4.95768 2.69115 T e e  arsize_top=0 arsize_bot=0 is_shrink=n
3 0.0126 4.95768 2.79115 T e e  arsize_top=0 arsize_bot=0 is_shrink=n
3 0.0126 4.95768 2.89115 T e e  arsize_top=0 arsize_bot=0 is_shrink=n
3 0.0126 4.95768 3.04115 T e e  arsize_top=0 arsize_bot=0 is_shrink=n
3 0.0126 4.95768 3.19115 T e e  arsize_top=0 arsize_bot=0 is_shrink=n
3 0.0126 4.95768 3.34115 T e e  arsize_top=0 arsize_bot=0 is_shrink=n
3 0.0126 4.95768 3.49115 T e e  arsize_top=0 arsize_bot=0 is_shrink=n
3 0.0126 4.95768 3.64115 T e e  arsize_top=0 arsize_bot=0 is_shrink=n
3 0.0126 4.95768 3.79115 T e e  arsize_top=0 arsize_bot=0 is_shrink=n
3 0.0126 5.00768 1.99115 T e e  arsize_top=0 arsize_bot=0 is_shrink=n
3 0.0126 5.00768 2.14115 T e e  arsize_top=0 arsize_bot=0 is_shrink=n
3 0.0126 5.00768 2.24115 T e e  arsize_top=0 arsize_bot=0 is_shrink=n
3 0.0126 5.00768 2.39115 T e e  arsize_top=0 arsize_bot=0 is_shrink=n
3 0.0126 5.00768 2.54115 T e e  arsize_top=0 arsize_bot=0 is_shrink=n
3 0.0126 5.00768 2.59115 T e e  arsize_top=0 arsize_bot=0 is_shrink=n
3 0.0126 5.00768 2.74115 T e e  arsize_top=0 arsize_bot=0 is_shrink=n
3 0.0126 5.00768 2.79115 T e e  arsize_top=0 arsize_bot=0 is_shrink=n
3 0.0126 5.00768 2.89115 T e e  arsize_top=0 arsize_bot=0 is_shrink=n
3 0.0126 5.00768 3.04115 T e e  arsize_top=0 arsize_bot=0 is_shrink=n
3 0.0126 5.00768 3.19115 T e e  arsize_top=0 arsize_bot=0 is_shrink=n
3 0.0126 5.00768 3.34115 T e e  arsize_top=0 arsize_bot=0 is_shrink=n
3 0.0126 5.00768 3.49115 T e e  arsize_top=0 arsize_bot=0 is_shrink=n
3 0.0126 5.00768 3.64115 T e e  arsize_top=0 arsize_bot=0 is_shrink=n
3 0.0126 5.00768 3.79115 T e e  arsize_top=0 arsize_bot=0 is_shrink=n
3 0.0126 5.05768 1.89115 T e e  arsize_top=0 arsize_bot=0 is_shrink=n
3 0.0126 5.05768 2.04115 T e e  arsize_top=0 arsize_bot=0 is_shrink=n
3 0.0126 5.05768 2.19115 T e e  arsize_top=0 arsize_bot=0 is_shrink=n
3 0.0126 5.05768 2.34115 T e e  arsize_top=0 arsize_bot=0 is_shrink=n
3 0.0126 5.05768 2.49115 T e e  arsize_top=0 arsize_bot=0 is_shrink=n
3 0.0126 5.05768 2.54115 T e e  arsize_top=0 arsize_bot=0 is_shrink=n
3 0.0126 5.05768 2.69115 T e e  arsize_top=0 arsize_bot=0 is_shrink=n
3 0.0126 5.05768 2.79115 T e e  arsize_top=0 arsize_bot=0 is_shrink=n
3 0.0126 5.05768 2.89115 T e e  arsize_top=0 arsize_bot=0 is_shrink=n
3 0.0126 5.05768 3.04115 T e e  arsize_top=0 arsize_bot=0 is_shrink=n
3 0.0126 5.05768 3.19115 T e e  arsize_top=0 arsize_bot=0 is_shrink=n
3 0.0126 5.05768 3.34115 T e e  arsize_top=0 arsize_bot=0 is_shrink=n
3 0.0126 5.05768 3.49115 T e e  arsize_top=0 arsize_bot=0 is_shrink=n
3 0.0126 5.05768 3.64115 T e e  arsize_top=0 arsize_bot=0 is_shrink=n
3 0.0126 10.61161 1.89115 T e e  arsize_top=0 arsize_bot=0 is_shrink=n
3 0.0126 10.61161 2.04115 T e e  arsize_top=0 arsize_bot=0 is_shrink=n
3 0.0126 10.61161 2.19115 T e e  arsize_top=0 arsize_bot=0 is_shrink=n
3 0.0126 10.61161 2.34115 T e e  arsize_top=0 arsize_bot=0 is_shrink=n
3 0.0126 10.61161 2.49115 T e e  arsize_top=0 arsize_bot=0 is_shrink=n
3 0.0126 10.61161 2.54115 T e e  arsize_top=0 arsize_bot=0 is_shrink=n
3 0.0126 10.61161 2.69115 T e e  arsize_top=0 arsize_bot=0 is_shrink=n
3 0.0126 10.61161 2.89115 T e e  arsize_top=0 arsize_bot=0 is_shrink=n
3 0.0126 10.61161 3.04115 T e e  arsize_top=0 arsize_bot=0 is_shrink=n
3 0.0126 10.61161 3.19115 T e e  arsize_top=0 arsize_bot=0 is_shrink=n
3 0.0126 10.61161 3.34115 T e e  arsize_top=0 arsize_bot=0 is_shrink=n
3 0.0126 10.61161 3.49115 T e e  arsize_top=0 arsize_bot=0 is_shrink=n
3 0.0126 10.61161 3.64115 T e e  arsize_top=0 arsize_bot=0 is_shrink=n
3 0.0126 10.61161 3.79115 T e e  arsize_top=0 arsize_bot=0 is_shrink=n
3 0.0126 10.66161 1.99115 T e e  arsize_top=0 arsize_bot=0 is_shrink=n
3 0.0126 10.66161 2.14115 T e e  arsize_top=0 arsize_bot=0 is_shrink=n
3 0.0126 10.66161 2.19115 T e e  arsize_top=0 arsize_bot=0 is_shrink=n
3 0.0126 10.66161 2.24115 T e e  arsize_top=0 arsize_bot=0 is_shrink=n
3 0.0126 10.66161 2.39115 T e e  arsize_top=0 arsize_bot=0 is_shrink=n
3 0.0126 10.66161 2.54115 T e e  arsize_top=0 arsize_bot=0 is_shrink=n
3 0.0126 10.66161 2.59115 T e e  arsize_top=0 arsize_bot=0 is_shrink=n
3 0.0126 10.66161 2.74115 T e e  arsize_top=0 arsize_bot=0 is_shrink=n
3 0.0126 10.66161 2.79115 T e e  arsize_top=0 arsize_bot=0 is_shrink=n
3 0.0126 10.66161 2.89115 T e e  arsize_top=0 arsize_bot=0 is_shrink=n
3 0.0126 10.66161 3.04115 T e e  arsize_top=0 arsize_bot=0 is_shrink=n
3 0.0126 10.66161 3.19115 T e e  arsize_top=0 arsize_bot=0 is_shrink=n
3 0.0126 10.66161 3.34115 T e e  arsize_top=0 arsize_bot=0 is_shrink=n
3 0.0126 10.66161 3.49115 T e e  arsize_top=0 arsize_bot=0 is_shrink=n
3 0.0126 10.66161 3.64115 T e e  arsize_top=0 arsize_bot=0 is_shrink=n
3 0.0126 10.66161 3.79115 T e e  arsize_top=0 arsize_bot=0 is_shrink=n
3 0.0126 10.71161 1.89115 T e e  arsize_top=0 arsize_bot=0 is_shrink=n
3 0.0126 10.71161 2.04115 T e e  arsize_top=0 arsize_bot=0 is_shrink=n
3 0.0126 10.71161 2.19115 T e e  arsize_top=0 arsize_bot=0 is_shrink=n
3 0.0126 10.71161 2.34115 T e e  arsize_top=0 arsize_bot=0 is_shrink=n
3 0.0126 10.71161 2.49115 T e e  arsize_top=0 arsize_bot=0 is_shrink=n
3 0.0126 10.71161 2.54115 T e e  arsize_top=0 arsize_bot=0 is_shrink=n
3 0.0126 10.71161 2.69115 T e e  arsize_top=0 arsize_bot=0 is_shrink=n
3 0.0126 10.71161 2.89115 T e e  arsize_top=0 arsize_bot=0 is_shrink=n
3 0.0126 10.71161 3.04115 T e e  arsize_top=0 arsize_bot=0 is_shrink=n
3 0.0126 10.71161 3.19115 T e e  arsize_top=0 arsize_bot=0 is_shrink=n
3 0.0126 10.71161 3.34115 T e e  arsize_top=0 arsize_bot=0 is_shrink=n
3 0.0126 10.71161 3.49115 T e e  arsize_top=0 arsize_bot=0 is_shrink=n
3 0.0126 10.71161 3.64115 T e e  arsize_top=0 arsize_bot=0 is_shrink=n
3 0.0126 10.71161 3.79115 T e e  arsize_top=0 arsize_bot=0 is_shrink=n
3 0.0126 10.76161 1.99115 T e e  arsize_top=0 arsize_bot=0 is_shrink=n
3 0.0126 10.76161 2.14115 T e e  arsize_top=0 arsize_bot=0 is_shrink=n
3 0.0126 10.76161 2.19115 T e e  arsize_top=0 arsize_bot=0 is_shrink=n
3 0.0126 10.76161 2.24115 T e e  arsize_top=0 arsize_bot=0 is_shrink=n
3 0.0126 10.76161 2.39115 T e e  arsize_top=0 arsize_bot=0 is_shrink=n
3 0.0126 10.76161 2.54115 T e e  arsize_top=0 arsize_bot=0 is_shrink=n
3 0.0126 10.76161 2.59115 T e e  arsize_top=0 arsize_bot=0 is_shrink=n
3 0.0126 10.76161 2.74115 T e e  arsize_top=0 arsize_bot=0 is_shrink=n
3 0.0126 10.76161 2.79115 T e e  arsize_top=0 arsize_bot=0 is_shrink=n
3 0.0126 10.76161 2.89115 T e e  arsize_top=0 arsize_bot=0 is_shrink=n
3 0.0126 10.76161 3.04115 T e e  arsize_top=0 arsize_bot=0 is_shrink=n
3 0.0126 10.76161 3.19115 T e e  arsize_top=0 arsize_bot=0 is_shrink=n
3 0.0126 10.76161 3.34115 T e e  arsize_top=0 arsize_bot=0 is_shrink=n
3 0.0126 10.76161 3.49115 T e e  arsize_top=0 arsize_bot=0 is_shrink=n
3 0.0126 10.76161 3.64115 T e e  arsize_top=0 arsize_bot=0 is_shrink=n
3 0.0126 10.76161 3.79115 T e e  arsize_top=0 arsize_bot=0 is_shrink=n
3 0.0126 10.81161 1.89115 T e e  arsize_top=0 arsize_bot=0 is_shrink=n
3 0.0126 10.81161 1.94115 T e e  arsize_top=0 arsize_bot=0 is_shrink=n
3 0.0126 10.81161 1.99115 T e e  arsize_top=0 arsize_bot=0 is_shrink=n
3 0.0126 10.81161 2.04115 T e e  arsize_top=0 arsize_bot=0 is_shrink=n
3 0.0126 10.81161 2.09115 T e e  arsize_top=0 arsize_bot=0 is_shrink=n
3 0.0126 10.81161 2.14115 T e e  arsize_top=0 arsize_bot=0 is_shrink=n
3 0.0126 10.81161 2.24115 T e e  arsize_top=0 arsize_bot=0 is_shrink=n
3 0.0126 10.81161 2.29115 T e e  arsize_top=0 arsize_bot=0 is_shrink=n
3 0.0126 10.81161 2.34115 T e e  arsize_top=0 arsize_bot=0 is_shrink=n
3 0.0126 10.81161 2.39115 T e e  arsize_top=0 arsize_bot=0 is_shrink=n
3 0.0126 10.81161 2.44115 T e e  arsize_top=0 arsize_bot=0 is_shrink=n
3 0.0126 10.81161 2.49115 T e e  arsize_top=0 arsize_bot=0 is_shrink=n
3 0.0126 10.81161 2.54115 T e e  arsize_top=0 arsize_bot=0 is_shrink=n
3 0.0126 10.81161 2.59115 T e e  arsize_top=0 arsize_bot=0 is_shrink=n
3 0.0126 10.81161 2.64115 T e e  arsize_top=0 arsize_bot=0 is_shrink=n
3 0.0126 10.81161 2.69115 T e e  arsize_top=0 arsize_bot=0 is_shrink=n
3 0.0126 10.81161 2.79115 T e e  arsize_top=0 arsize_bot=0 is_shrink=n
3 0.0126 10.81161 2.89115 T e e  arsize_top=0 arsize_bot=0 is_shrink=n
3 0.0126 10.81161 3.04115 T e e  arsize_top=0 arsize_bot=0 is_shrink=n
3 0.0126 10.81161 3.19115 T e e  arsize_top=0 arsize_bot=0 is_shrink=n
3 0.0126 10.81161 3.34115 T e e  arsize_top=0 arsize_bot=0 is_shrink=n
3 0.0126 10.81161 3.49115 T e e  arsize_top=0 arsize_bot=0 is_shrink=n
3 0.0126 10.81161 3.64115 T e e  arsize_top=0 arsize_bot=0 is_shrink=n
3 0.0126 10.81161 3.79115 T e e  arsize_top=0 arsize_bot=0 is_shrink=n
3 0.0126 10.86161 1.89115 T e e  arsize_top=0 arsize_bot=0 is_shrink=n
3 0.0126 10.86161 1.94115 T e e  arsize_top=0 arsize_bot=0 is_shrink=n
3 0.0126 10.86161 1.99115 T e e  arsize_top=0 arsize_bot=0 is_shrink=n
3 0.0126 10.86161 2.04115 T e e  arsize_top=0 arsize_bot=0 is_shrink=n
3 0.0126 10.86161 2.09115 T e e  arsize_top=0 arsize_bot=0 is_shrink=n
3 0.0126 10.86161 2.14115 T e e  arsize_top=0 arsize_bot=0 is_shrink=n
3 0.0126 10.86161 2.24115 T e e  arsize_top=0 arsize_bot=0 is_shrink=n
3 0.0126 10.86161 2.29115 T e e  arsize_top=0 arsize_bot=0 is_shrink=n
3 0.0126 10.86161 2.34115 T e e  arsize_top=0 arsize_bot=0 is_shrink=n
3 0.0126 10.86161 2.39115 T e e  arsize_top=0 arsize_bot=0 is_shrink=n
3 0.0126 10.86161 2.44115 T e e  arsize_top=0 arsize_bot=0 is_shrink=n
3 0.0126 10.86161 2.49115 T e e  arsize_top=0 arsize_bot=0 is_shrink=n
3 0.0126 10.86161 2.54115 T e e  arsize_top=0 arsize_bot=0 is_shrink=n
3 0.0126 10.86161 2.59115 T e e  arsize_top=0 arsize_bot=0 is_shrink=n
3 0.0126 10.86161 2.64115 T e e  arsize_top=0 arsize_bot=0 is_shrink=n
3 0.0126 10.86161 2.69115 T e e  arsize_top=0 arsize_bot=0 is_shrink=n
3 0.0126 10.86161 2.79115 T e e  arsize_top=0 arsize_bot=0 is_shrink=n
3 0.0126 10.86161 2.89115 T e e  arsize_top=0 arsize_bot=0 is_shrink=n
3 0.0126 10.86161 3.04115 T e e  arsize_top=0 arsize_bot=0 is_shrink=n
3 0.0126 10.86161 3.19115 T e e  arsize_top=0 arsize_bot=0 is_shrink=n
3 0.0126 10.86161 3.34115 T e e  arsize_top=0 arsize_bot=0 is_shrink=n
3 0.0126 10.86161 3.49115 T e e  arsize_top=0 arsize_bot=0 is_shrink=n
3 0.0126 10.86161 3.64115 T e e  arsize_top=0 arsize_bot=0 is_shrink=n
3 0.0126 10.86161 3.79115 T e e  arsize_top=0 arsize_bot=0 is_shrink=n
3 0.0126 10.91161 1.99115 T e e  arsize_top=0 arsize_bot=0 is_shrink=n
3 0.0126 10.91161 2.14115 T e e  arsize_top=0 arsize_bot=0 is_shrink=n
3 0.0126 10.91161 2.19115 T e e  arsize_top=0 arsize_bot=0 is_shrink=n
3 0.0126 10.91161 2.24115 T e e  arsize_top=0 arsize_bot=0 is_shrink=n
3 0.0126 10.91161 2.39115 T e e  arsize_top=0 arsize_bot=0 is_shrink=n
3 0.0126 10.91161 2.54115 T e e  arsize_top=0 arsize_bot=0 is_shrink=n
3 0.0126 10.91161 2.59115 T e e  arsize_top=0 arsize_bot=0 is_shrink=n
3 0.0126 10.91161 2.74115 T e e  arsize_top=0 arsize_bot=0 is_shrink=n
3 0.0126 10.91161 2.79115 T e e  arsize_top=0 arsize_bot=0 is_shrink=n
3 0.0126 10.91161 2.89115 T e e  arsize_top=0 arsize_bot=0 is_shrink=n
3 0.0126 10.91161 3.04115 T e e  arsize_top=0 arsize_bot=0 is_shrink=n
3 0.0126 10.91161 3.19115 T e e  arsize_top=0 arsize_bot=0 is_shrink=n
3 0.0126 10.91161 3.34115 T e e  arsize_top=0 arsize_bot=0 is_shrink=n
3 0.0126 10.91161 3.49115 T e e  arsize_top=0 arsize_bot=0 is_shrink=n
3 0.0126 10.91161 3.64115 T e e  arsize_top=0 arsize_bot=0 is_shrink=n
3 0.0126 10.91161 3.79115 T e e  arsize_top=0 arsize_bot=0 is_shrink=n
3 0.0126 10.96161 1.89115 T e e  arsize_top=0 arsize_bot=0 is_shrink=n
3 0.0126 10.96161 2.04115 T e e  arsize_top=0 arsize_bot=0 is_shrink=n
3 0.0126 10.96161 2.19115 T e e  arsize_top=0 arsize_bot=0 is_shrink=n
3 0.0126 10.96161 2.34115 T e e  arsize_top=0 arsize_bot=0 is_shrink=n
3 0.0126 10.96161 2.49115 T e e  arsize_top=0 arsize_bot=0 is_shrink=n
3 0.0126 10.96161 2.54115 T e e  arsize_top=0 arsize_bot=0 is_shrink=n
3 0.0126 10.96161 2.69115 T e e  arsize_top=0 arsize_bot=0 is_shrink=n
3 0.0126 10.96161 2.79115 T e e  arsize_top=0 arsize_bot=0 is_shrink=n
3 0.0126 10.96161 2.89115 T e e  arsize_top=0 arsize_bot=0 is_shrink=n
3 0.0126 10.96161 3.04115 T e e  arsize_top=0 arsize_bot=0 is_shrink=n
3 0.0126 10.96161 3.19115 T e e  arsize_top=0 arsize_bot=0 is_shrink=n
3 0.0126 10.96161 3.34115 T e e  arsize_top=0 arsize_bot=0 is_shrink=n
3 0.0126 10.96161 3.49115 T e e  arsize_top=0 arsize_bot=0 is_shrink=n
3 0.0126 10.96161 3.64115 T e e  arsize_top=0 arsize_bot=0 is_shrink=n
3 0.0126 10.96161 3.79115 T e e  arsize_top=0 arsize_bot=0 is_shrink=n
3 0.0126 11.01161 1.99115 T e e  arsize_top=0 arsize_bot=0 is_shrink=n
3 0.0126 11.01161 2.14115 T e e  arsize_top=0 arsize_bot=0 is_shrink=n
3 0.0126 11.01161 2.24115 T e e  arsize_top=0 arsize_bot=0 is_shrink=n
3 0.0126 11.01161 2.39115 T e e  arsize_top=0 arsize_bot=0 is_shrink=n
3 0.0126 11.01161 2.54115 T e e  arsize_top=0 arsize_bot=0 is_shrink=n
3 0.0126 11.01161 2.59115 T e e  arsize_top=0 arsize_bot=0 is_shrink=n
3 0.0126 11.01161 2.74115 T e e  arsize_top=0 arsize_bot=0 is_shrink=n
3 0.0126 11.01161 2.79115 T e e  arsize_top=0 arsize_bot=0 is_shrink=n
3 0.0126 11.01161 2.89115 T e e  arsize_top=0 arsize_bot=0 is_shrink=n
3 0.0126 11.01161 3.04115 T e e  arsize_top=0 arsize_bot=0 is_shrink=n
3 0.0126 11.01161 3.19115 T e e  arsize_top=0 arsize_bot=0 is_shrink=n
3 0.0126 11.01161 3.34115 T e e  arsize_top=0 arsize_bot=0 is_shrink=n
3 0.0126 11.01161 3.49115 T e e  arsize_top=0 arsize_bot=0 is_shrink=n
3 0.0126 11.01161 3.64115 T e e  arsize_top=0 arsize_bot=0 is_shrink=n
3 0.0126 11.01161 3.79115 T e e  arsize_top=0 arsize_bot=0 is_shrink=n
3 0.0126 11.06161 1.89115 T e e  arsize_top=0 arsize_bot=0 is_shrink=n
3 0.0126 11.06161 2.04115 T e e  arsize_top=0 arsize_bot=0 is_shrink=n
3 0.0126 11.06161 2.19115 T e e  arsize_top=0 arsize_bot=0 is_shrink=n
3 0.0126 11.06161 2.34115 T e e  arsize_top=0 arsize_bot=0 is_shrink=n
3 0.0126 11.06161 2.49115 T e e  arsize_top=0 arsize_bot=0 is_shrink=n
3 0.0126 11.06161 2.54115 T e e  arsize_top=0 arsize_bot=0 is_shrink=n
3 0.0126 11.06161 2.69115 T e e  arsize_top=0 arsize_bot=0 is_shrink=n
3 0.0126 11.06161 2.79115 T e e  arsize_top=0 arsize_bot=0 is_shrink=n
3 0.0126 11.06161 2.89115 T e e  arsize_top=0 arsize_bot=0 is_shrink=n
3 0.0126 11.06161 3.04115 T e e  arsize_top=0 arsize_bot=0 is_shrink=n
3 0.0126 11.06161 3.19115 T e e  arsize_top=0 arsize_bot=0 is_shrink=n
3 0.0126 11.06161 3.34115 T e e  arsize_top=0 arsize_bot=0 is_shrink=n
3 0.0126 11.06161 3.49115 T e e  arsize_top=0 arsize_bot=0 is_shrink=n
3 0.0126 11.06161 3.64115 T e e  arsize_top=0 arsize_bot=0 is_shrink=n
3 0 6.42419 5.04705 D 0.02 0.02 e e staggered 0 0 0  is_shrink=n
3 0 6.34949 4.99705 D 0.02 0.02 e e staggered 0 0 0  is_shrink=n
3 0 6.837 5 D 0.02 0.02 e e staggered 0 0 0  is_shrink=n
3 0 5.6152 3 D 0.02 0.02 e e staggered 0 0 0  is_shrink=n
3 0 9.1 5.332 D 0.02 0.02 e e staggered 0 0 0  is_shrink=n
3 0 9.235 5.332 D 0.02 0.02 e e staggered 0 0 0  is_shrink=n
3 0 9.385 5.332 D 0.02 0.02 e e staggered 0 0 0  is_shrink=n
3 0 3.38146 5.332 D 0.02 0.02 e e staggered 0 0 0  is_shrink=n
3 0 12.30798 2.155 D 0.02 0.02 e e staggered 0 0 0  is_shrink=n
3 0 0.61698 2.045 D 0.02 0.02 e e staggered 0 0 0  is_shrink=n
3 0 8.12 5.377 D 0.02 0.02 e e staggered 0 0 0  is_shrink=n
3 0 3.23146 5.332 D 0.02 0.02 e e staggered 0 0 0  is_shrink=n
3 0 2.11646 5.377 D 0.02 0.02 e e staggered 0 0 0  is_shrink=n
3 0 7.955 5.377 D 0.02 0.02 e e staggered 0 0 0  is_shrink=n
3 0 1.95146 5.377 D 0.02 0.02 e e staggered 0 0 0  is_shrink=n
3 0 3.09646 5.332 D 0.02 0.02 e e staggered 0 0 0  is_shrink=n
3 0 7.82415 2.4781 D 0.02 0.02 e e staggered 0 0 0  is_shrink=n
3 0 1.82021 2.4781 D 0.02 0.02 e e staggered 0 0 0  is_shrink=n
3 0 5.46169 2.73 D 0.02 0.02 e e staggered 0 0 0  is_shrink=n
3 0 11.47062 2.73 D 0.02 0.02 e e staggered 0 0 0  is_shrink=n
3 0 11.47062 2.8 D 0.02 0.02 e e staggered 0 0 0  is_shrink=n
3 0 5.46169 2.8 D 0.02 0.02 e e staggered 0 0 0  is_shrink=n
3 0 5.67709 4.5552 D 0.05 0.05 e e staggered 0 0 0  is_shrink=n
3 0 5.59779 4.5552 D 0.05 0.05 e e staggered 0 0 0  is_shrink=n
3 0 5.75709 4.5552 D 0.05 0.05 e e staggered 0 0 0  is_shrink=n
3 0 5.83709 4.5552 D 0.05 0.05 e e staggered 0 0 0  is_shrink=n
3 0 6.07709 4.5552 D 0.05 0.05 e e staggered 0 0 0  is_shrink=n
3 0 5.91709 4.5552 D 0.05 0.05 e e staggered 0 0 0  is_shrink=n
3 0 5.99709 4.5552 D 0.05 0.05 e e staggered 0 0 0  is_shrink=n
3 0 6.27209 4.7202 D 0.05 0.05 e e staggered 0 0 0  is_shrink=n
3 0 6.27209 4.6402 D 0.05 0.05 e e staggered 0 0 0  is_shrink=n
3 0 6.27209 4.8802 D 0.05 0.05 e e staggered 0 0 0  is_shrink=n
3 0 6.27209 4.8002 D 0.05 0.05 e e staggered 0 0 0  is_shrink=n
3 0 6.66209 4.7052 D 0.05 0.05 e e staggered 0 0 0  is_shrink=n
3 0 6.66209 4.6252 D 0.05 0.05 e e staggered 0 0 0  is_shrink=n
3 0 6.91119 4.73868 D 0.05 0.05 e e staggered 0 0 0  is_shrink=n
3 0 6.91119 4.81705 D 0.05 0.05 e e staggered 0 0 0  is_shrink=n
3 0 11.40779 2.96 D 0.05 0.05 e e staggered 0 0 0  is_shrink=n
3 0 11.40779 3.12 D 0.05 0.05 e e staggered 0 0 0  is_shrink=n
3 0 11.40779 3.04 D 0.05 0.05 e e staggered 0 0 0  is_shrink=n
3 0 11.40779 3.2 D 0.05 0.05 e e staggered 0 0 0  is_shrink=n
3 0 11.40779 3.28 D 0.05 0.05 e e staggered 0 0 0  is_shrink=n
3 0 5.40386 3.12 D 0.05 0.05 e e staggered 0 0 0  is_shrink=n
3 0 5.40386 3.04 D 0.05 0.05 e e staggered 0 0 0  is_shrink=n
3 0 5.40386 3.28 D 0.05 0.05 e e staggered 0 0 0  is_shrink=n
3 0 5.40386 3.2 D 0.05 0.05 e e staggered 0 0 0  is_shrink=n
3 0 5.40386 2.96 D 0.05 0.05 e e staggered 0 0 0  is_shrink=n
3 0 11.61662 2.855 D 0.02 0.02 e e staggered 0 0 0  is_shrink=n
3 0 5.61269 2.855 D 0.02 0.02 e e staggered 0 0 0  is_shrink=n
3 0 5.917 2.97 D 0.02 0.02 e e staggered 0 0 0  is_shrink=n
3 0 10.13479 2.82 D 0.02 0.02 e e staggered 0 0 0  is_shrink=n
3 0 4.09086 2.59 D 0.02 0.02 e e staggered 0 0 0  is_shrink=n
3 0 3.91351 2.64559 D 0.03543 0.01575 e e staggered 0 0 0  is_shrink=n
3 0 9.95744 2.87559 D 0.03543 0.01575 e e staggered 0 0 0  is_shrink=n
3 0 5.72185 3.02559 D 0.03543 0.01575 e e staggered 0 0 0  is_shrink=n
3 0 11.80693 2.85 D 0.03543 0.01575 e e staggered 0 0 0  is_shrink=n
3 0 5.803 2.85 D 0.03543 0.01575 e e staggered 0 0 0  is_shrink=n
3 0.015 4.755 5.03 D m e v t  arsize_top=0 arsize_bot=0 is_shrink=n
3 0.015 5.59 4.475 D m e v t  arsize_top=0 arsize_bot=0 is_shrink=n
3 0.015 6.645 4.83 D m e v t  arsize_top=0 arsize_bot=0 is_shrink=n
3 0.005 10.38499 4.9231 B m e v  arsize_top=0 arsize_bot=0 is_shrink=n
3 0.005 3.86 0.7751 B m e v  arsize_top=0 arsize_bot=0 is_shrink=n
3 0.005 0.66 2.045 B m e v  arsize_top=0 arsize_bot=0 is_shrink=n
3 0.005 0.7 5.267 B m e v  arsize_top=0 arsize_bot=0 is_shrink=n
3 0.005 7.78 2.4781 B m e v  arsize_top=0 arsize_bot=0 is_shrink=n
3 0.004 10.58661 1.86615 B m e v  arsize_top=0 arsize_bot=0 is_shrink=n
3 0.004 10.58661 2.01615 B m e v  arsize_top=0 arsize_bot=0 is_shrink=n
3 0.004 10.58661 2.16615 B m e v  arsize_top=0 arsize_bot=0 is_shrink=n
3 0.004 10.58661 2.31615 B m e v  arsize_top=0 arsize_bot=0 is_shrink=n
3 0.004 10.58661 2.46615 B m e v  arsize_top=0 arsize_bot=0 is_shrink=n
3 0.004 10.58661 2.51615 B m e v  arsize_top=0 arsize_bot=0 is_shrink=n
3 0.004 10.58661 2.66615 B m e v  arsize_top=0 arsize_bot=0 is_shrink=n
3 0.004 10.58661 2.91615 B m e v  arsize_top=0 arsize_bot=0 is_shrink=n
3 0.004 10.58661 3.06615 B m e v  arsize_top=0 arsize_bot=0 is_shrink=n
3 0.004 10.58661 3.21615 B m e v  arsize_top=0 arsize_bot=0 is_shrink=n
3 0.004 10.58661 3.36615 B m e v  arsize_top=0 arsize_bot=0 is_shrink=n
3 0.004 10.58661 3.51615 B m e v  arsize_top=0 arsize_bot=0 is_shrink=n
3 0.004 10.58661 3.66615 B m e v  arsize_top=0 arsize_bot=0 is_shrink=n
3 0.004 10.58661 3.81615 B m e v  arsize_top=0 arsize_bot=0 is_shrink=n
3 0.004 10.63661 1.96615 B m e v  arsize_top=0 arsize_bot=0 is_shrink=n
3 0.004 10.63661 2.11615 B m e v  arsize_top=0 arsize_bot=0 is_shrink=n
3 0.004 10.63661 2.16615 B m e v  arsize_top=0 arsize_bot=0 is_shrink=n
3 0.004 10.63661 2.21615 B m e v  arsize_top=0 arsize_bot=0 is_shrink=n
3 0.004 10.63661 2.36615 B m e v  arsize_top=0 arsize_bot=0 is_shrink=n
3 0.004 10.63661 2.51615 B m e v  arsize_top=0 arsize_bot=0 is_shrink=n
3 0.004 10.63661 2.56615 B m e v  arsize_top=0 arsize_bot=0 is_shrink=n
3 0.004 10.63661 2.71615 B m e v  arsize_top=0 arsize_bot=0 is_shrink=n
3 0.004 10.63661 2.76615 B m e v  arsize_top=0 arsize_bot=0 is_shrink=n
3 0.004 10.63661 2.91615 B m e v  arsize_top=0 arsize_bot=0 is_shrink=n
3 0.004 10.63661 3.06615 B m e v  arsize_top=0 arsize_bot=0 is_shrink=n
3 0.004 10.63661 3.21615 B m e v  arsize_top=0 arsize_bot=0 is_shrink=n
3 0.004 10.63661 3.36615 B m e v  arsize_top=0 arsize_bot=0 is_shrink=n
3 0.004 10.63661 3.51615 B m e v  arsize_top=0 arsize_bot=0 is_shrink=n
3 0.004 10.63661 3.66615 B m e v  arsize_top=0 arsize_bot=0 is_shrink=n
3 0.004 10.63661 3.81615 B m e v  arsize_top=0 arsize_bot=0 is_shrink=n
3 0.004 10.68661 1.86615 B m e v  arsize_top=0 arsize_bot=0 is_shrink=n
3 0.004 10.68661 2.01615 B m e v  arsize_top=0 arsize_bot=0 is_shrink=n
3 0.004 10.68661 2.16615 B m e v  arsize_top=0 arsize_bot=0 is_shrink=n
3 0.004 10.68661 2.31615 B m e v  arsize_top=0 arsize_bot=0 is_shrink=n
3 0.004 10.68661 2.46615 B m e v  arsize_top=0 arsize_bot=0 is_shrink=n
3 0.004 10.68661 2.51615 B m e v  arsize_top=0 arsize_bot=0 is_shrink=n
3 0.004 10.68661 2.66615 B m e v  arsize_top=0 arsize_bot=0 is_shrink=n
3 0.004 10.68661 2.91615 B m e v  arsize_top=0 arsize_bot=0 is_shrink=n
3 0.004 10.68661 3.06615 B m e v  arsize_top=0 arsize_bot=0 is_shrink=n
3 0.004 10.68661 3.21615 B m e v  arsize_top=0 arsize_bot=0 is_shrink=n
3 0.004 10.68661 3.36615 B m e v  arsize_top=0 arsize_bot=0 is_shrink=n
3 0.004 10.68661 3.51615 B m e v  arsize_top=0 arsize_bot=0 is_shrink=n
3 0.004 10.68661 3.66615 B m e v  arsize_top=0 arsize_bot=0 is_shrink=n
3 0.004 10.68661 3.81615 B m e v  arsize_top=0 arsize_bot=0 is_shrink=n
3 0.004 10.73661 1.96615 B m e v  arsize_top=0 arsize_bot=0 is_shrink=n
3 0.004 10.73661 2.11615 B m e v  arsize_top=0 arsize_bot=0 is_shrink=n
3 0.004 10.73661 2.16615 B m e v  arsize_top=0 arsize_bot=0 is_shrink=n
3 0.004 10.73661 2.21615 B m e v  arsize_top=0 arsize_bot=0 is_shrink=n
3 0.004 10.73661 2.36615 B m e v  arsize_top=0 arsize_bot=0 is_shrink=n
3 0.004 10.73661 2.51615 B m e v  arsize_top=0 arsize_bot=0 is_shrink=n
3 0.004 10.73661 2.56615 B m e v  arsize_top=0 arsize_bot=0 is_shrink=n
3 0.004 10.73661 2.71615 B m e v  arsize_top=0 arsize_bot=0 is_shrink=n
3 0.004 10.73661 2.76615 B m e v  arsize_top=0 arsize_bot=0 is_shrink=n
3 0.004 10.73661 2.91615 B m e v  arsize_top=0 arsize_bot=0 is_shrink=n
3 0.004 10.73661 3.06615 B m e v  arsize_top=0 arsize_bot=0 is_shrink=n
3 0.004 10.73661 3.21615 B m e v  arsize_top=0 arsize_bot=0 is_shrink=n
3 0.004 10.73661 3.36615 B m e v  arsize_top=0 arsize_bot=0 is_shrink=n
3 0.004 10.73661 3.51615 B m e v  arsize_top=0 arsize_bot=0 is_shrink=n
3 0.004 10.73661 3.66615 B m e v  arsize_top=0 arsize_bot=0 is_shrink=n
3 0.004 10.73661 3.81615 B m e v  arsize_top=0 arsize_bot=0 is_shrink=n
3 0.004 10.78661 1.86615 B m e v  arsize_top=0 arsize_bot=0 is_shrink=n
3 0.004 10.78661 1.91615 B m e v  arsize_top=0 arsize_bot=0 is_shrink=n
3 0.004 10.78661 1.96615 B m e v  arsize_top=0 arsize_bot=0 is_shrink=n
3 0.004 10.78661 2.01615 B m e v  arsize_top=0 arsize_bot=0 is_shrink=n
3 0.004 10.78661 2.06615 B m e v  arsize_top=0 arsize_bot=0 is_shrink=n
3 0.004 10.78661 2.11615 B m e v  arsize_top=0 arsize_bot=0 is_shrink=n
3 0.004 10.78661 2.21615 B m e v  arsize_top=0 arsize_bot=0 is_shrink=n
3 0.004 10.78661 2.26615 B m e v  arsize_top=0 arsize_bot=0 is_shrink=n
3 0.004 10.78661 2.31615 B m e v  arsize_top=0 arsize_bot=0 is_shrink=n
3 0.004 10.78661 2.36615 B m e v  arsize_top=0 arsize_bot=0 is_shrink=n
3 0.004 10.78661 2.41615 B m e v  arsize_top=0 arsize_bot=0 is_shrink=n
3 0.004 10.78661 2.46615 B m e v  arsize_top=0 arsize_bot=0 is_shrink=n
3 0.004 10.78661 2.51615 B m e v  arsize_top=0 arsize_bot=0 is_shrink=n
3 0.004 10.78661 2.56615 B m e v  arsize_top=0 arsize_bot=0 is_shrink=n
3 0.004 10.78661 2.61615 B m e v  arsize_top=0 arsize_bot=0 is_shrink=n
3 0.004 10.78661 2.66615 B m e v  arsize_top=0 arsize_bot=0 is_shrink=n
3 0.004 10.78661 2.76615 B m e v  arsize_top=0 arsize_bot=0 is_shrink=n
3 0.004 10.78661 2.91615 B m e v  arsize_top=0 arsize_bot=0 is_shrink=n
3 0.004 10.78661 3.06615 B m e v  arsize_top=0 arsize_bot=0 is_shrink=n
3 0.004 10.78661 3.21615 B m e v  arsize_top=0 arsize_bot=0 is_shrink=n
3 0.004 10.78661 3.36615 B m e v  arsize_top=0 arsize_bot=0 is_shrink=n
3 0.004 10.78661 3.51615 B m e v  arsize_top=0 arsize_bot=0 is_shrink=n
3 0.004 10.78661 3.66615 B m e v  arsize_top=0 arsize_bot=0 is_shrink=n
3 0.004 10.78661 3.81615 B m e v  arsize_top=0 arsize_bot=0 is_shrink=n
3 0.004 10.83661 2.91615 B m e v  arsize_top=0 arsize_bot=0 is_shrink=n
3 0.004 10.83661 3.06615 B m e v  arsize_top=0 arsize_bot=0 is_shrink=n
3 0.004 10.83661 3.21615 B m e v  arsize_top=0 arsize_bot=0 is_shrink=n
3 0.004 10.83661 3.36615 B m e v  arsize_top=0 arsize_bot=0 is_shrink=n
3 0.004 10.83661 3.51615 B m e v  arsize_top=0 arsize_bot=0 is_shrink=n
3 0.004 10.83661 3.66615 B m e v  arsize_top=0 arsize_bot=0 is_shrink=n
3 0.004 10.83661 3.81615 B m e v  arsize_top=0 arsize_bot=0 is_shrink=n
3 0.004 10.88661 1.86615 B m e v  arsize_top=0 arsize_bot=0 is_shrink=n
3 0.004 10.88661 1.91615 B m e v  arsize_top=0 arsize_bot=0 is_shrink=n
3 0.004 10.88661 1.96615 B m e v  arsize_top=0 arsize_bot=0 is_shrink=n
3 0.004 10.88661 2.01615 B m e v  arsize_top=0 arsize_bot=0 is_shrink=n
3 0.004 10.88661 2.06615 B m e v  arsize_top=0 arsize_bot=0 is_shrink=n
3 0.004 10.88661 2.11615 B m e v  arsize_top=0 arsize_bot=0 is_shrink=n
3 0.004 10.88661 2.21615 B m e v  arsize_top=0 arsize_bot=0 is_shrink=n
3 0.004 10.88661 2.26615 B m e v  arsize_top=0 arsize_bot=0 is_shrink=n
3 0.004 10.88661 2.31615 B m e v  arsize_top=0 arsize_bot=0 is_shrink=n
3 0.004 10.88661 2.36615 B m e v  arsize_top=0 arsize_bot=0 is_shrink=n
3 0.004 10.88661 2.41615 B m e v  arsize_top=0 arsize_bot=0 is_shrink=n
3 0.004 10.88661 2.46615 B m e v  arsize_top=0 arsize_bot=0 is_shrink=n
3 0.004 10.88661 2.51615 B m e v  arsize_top=0 arsize_bot=0 is_shrink=n
3 0.004 10.88661 2.56615 B m e v  arsize_top=0 arsize_bot=0 is_shrink=n
3 0.004 10.88661 2.61615 B m e v  arsize_top=0 arsize_bot=0 is_shrink=n
3 0.004 10.88661 2.66615 B m e v  arsize_top=0 arsize_bot=0 is_shrink=n
3 0.004 10.88661 2.76615 B m e v  arsize_top=0 arsize_bot=0 is_shrink=n
3 0.004 10.88661 2.91615 B m e v  arsize_top=0 arsize_bot=0 is_shrink=n
3 0.004 10.88661 3.06615 B m e v  arsize_top=0 arsize_bot=0 is_shrink=n
3 0.004 10.88661 3.21615 B m e v  arsize_top=0 arsize_bot=0 is_shrink=n
3 0.004 10.88661 3.36615 B m e v  arsize_top=0 arsize_bot=0 is_shrink=n
3 0.004 10.88661 3.51615 B m e v  arsize_top=0 arsize_bot=0 is_shrink=n
3 0.004 10.88661 3.66615 B m e v  arsize_top=0 arsize_bot=0 is_shrink=n
3 0.004 10.88661 3.81615 B m e v  arsize_top=0 arsize_bot=0 is_shrink=n
3 0.004 10.93661 1.96615 B m e v  arsize_top=0 arsize_bot=0 is_shrink=n
3 0.004 10.93661 2.11615 B m e v  arsize_top=0 arsize_bot=0 is_shrink=n
3 0.004 10.93661 2.16615 B m e v  arsize_top=0 arsize_bot=0 is_shrink=n
3 0.004 10.93661 2.21615 B m e v  arsize_top=0 arsize_bot=0 is_shrink=n
3 0.004 10.93661 2.36615 B m e v  arsize_top=0 arsize_bot=0 is_shrink=n
3 0.004 10.93661 2.51615 B m e v  arsize_top=0 arsize_bot=0 is_shrink=n
3 0.004 10.93661 2.56615 B m e v  arsize_top=0 arsize_bot=0 is_shrink=n
3 0.004 10.93661 2.71615 B m e v  arsize_top=0 arsize_bot=0 is_shrink=n
3 0.004 10.93661 2.76615 B m e v  arsize_top=0 arsize_bot=0 is_shrink=n
3 0.004 10.93661 2.91615 B m e v  arsize_top=0 arsize_bot=0 is_shrink=n
3 0.004 10.93661 3.06615 B m e v  arsize_top=0 arsize_bot=0 is_shrink=n
3 0.004 10.93661 3.21615 B m e v  arsize_top=0 arsize_bot=0 is_shrink=n
3 0.004 10.93661 3.36615 B m e v  arsize_top=0 arsize_bot=0 is_shrink=n
3 0.004 10.93661 3.51615 B m e v  arsize_top=0 arsize_bot=0 is_shrink=n
3 0.004 10.93661 3.66615 B m e v  arsize_top=0 arsize_bot=0 is_shrink=n
3 0.004 10.93661 3.81615 B m e v  arsize_top=0 arsize_bot=0 is_shrink=n
3 0.004 10.98661 1.86615 B m e v  arsize_top=0 arsize_bot=0 is_shrink=n
3 0.004 10.98661 2.01615 B m e v  arsize_top=0 arsize_bot=0 is_shrink=n
3 0.004 10.98661 2.16615 B m e v  arsize_top=0 arsize_bot=0 is_shrink=n
3 0.004 10.98661 2.31615 B m e v  arsize_top=0 arsize_bot=0 is_shrink=n
3 0.004 10.98661 2.46615 B m e v  arsize_top=0 arsize_bot=0 is_shrink=n
3 0.004 10.98661 2.51615 B m e v  arsize_top=0 arsize_bot=0 is_shrink=n
3 0.004 10.98661 2.66615 B m e v  arsize_top=0 arsize_bot=0 is_shrink=n
3 0.004 10.98661 2.76615 B m e v  arsize_top=0 arsize_bot=0 is_shrink=n
3 0.004 10.98661 2.91615 B m e v  arsize_top=0 arsize_bot=0 is_shrink=n
3 0.004 10.98661 3.06615 B m e v  arsize_top=0 arsize_bot=0 is_shrink=n
3 0.004 10.98661 3.21615 B m e v  arsize_top=0 arsize_bot=0 is_shrink=n
3 0.004 10.98661 3.36615 B m e v  arsize_top=0 arsize_bot=0 is_shrink=n
3 0.004 10.98661 3.51615 B m e v  arsize_top=0 arsize_bot=0 is_shrink=n
3 0.004 10.98661 3.66615 B m e v  arsize_top=0 arsize_bot=0 is_shrink=n
3 0.004 10.98661 3.81615 B m e v  arsize_top=0 arsize_bot=0 is_shrink=n
3 0.004 11.03661 1.96615 B m e v  arsize_top=0 arsize_bot=0 is_shrink=n
3 0.004 11.03661 2.11615 B m e v  arsize_top=0 arsize_bot=0 is_shrink=n
3 0.004 11.03661 2.21615 B m e v  arsize_top=0 arsize_bot=0 is_shrink=n
3 0.004 11.03661 2.36615 B m e v  arsize_top=0 arsize_bot=0 is_shrink=n
3 0.004 11.03661 2.41615 B m e v  arsize_top=0 arsize_bot=0 is_shrink=n
3 0.004 11.03661 2.56615 B m e v  arsize_top=0 arsize_bot=0 is_shrink=n
3 0.004 11.03661 2.71615 B m e v  arsize_top=0 arsize_bot=0 is_shrink=n
3 0.004 11.03661 2.76615 B m e v  arsize_top=0 arsize_bot=0 is_shrink=n
3 0.004 11.03661 2.91615 B m e v  arsize_top=0 arsize_bot=0 is_shrink=n
3 0.004 11.03661 3.06615 B m e v  arsize_top=0 arsize_bot=0 is_shrink=n
3 0.004 11.03661 3.21615 B m e v  arsize_top=0 arsize_bot=0 is_shrink=n
3 0.004 11.03661 3.36615 B m e v  arsize_top=0 arsize_bot=0 is_shrink=n
3 0.004 11.03661 3.51615 B m e v  arsize_top=0 arsize_bot=0 is_shrink=n
3 0.004 11.03661 3.66615 B m e v  arsize_top=0 arsize_bot=0 is_shrink=n
3 0.004 11.08661 1.86615 B m e v  arsize_top=0 arsize_bot=0 is_shrink=n
3 0.004 11.08661 2.01615 B m e v  arsize_top=0 arsize_bot=0 is_shrink=n
3 0.004 11.08661 2.16615 B m e v  arsize_top=0 arsize_bot=0 is_shrink=n
3 0.004 11.08661 2.31615 B m e v  arsize_top=0 arsize_bot=0 is_shrink=n
3 0.004 11.08661 2.46615 B m e v  arsize_top=0 arsize_bot=0 is_shrink=n
3 0.004 11.08661 2.51615 B m e v  arsize_top=0 arsize_bot=0 is_shrink=n
3 0.004 11.08661 2.66615 B m e v  arsize_top=0 arsize_bot=0 is_shrink=n
3 0.004 11.08661 2.76615 B m e v  arsize_top=0 arsize_bot=0 is_shrink=n
3 0.004 1.99606 2.71615 B m e v  arsize_top=0 arsize_bot=0 is_shrink=n
3 0.004 1.99606 2.76615 B m e v  arsize_top=0 arsize_bot=0 is_shrink=n
3 0.004 1.99606 2.81615 B m e v  arsize_top=0 arsize_bot=0 is_shrink=n
3 0.004 1.99606 2.86615 B m e v  arsize_top=0 arsize_bot=0 is_shrink=n
3 0.004 1.99606 3.41615 B m e v  arsize_top=0 arsize_bot=0 is_shrink=n
3 0.004 1.99606 3.56615 B m e v  arsize_top=0 arsize_bot=0 is_shrink=n
3 0.004 2.04606 1.86615 B m e v  arsize_top=0 arsize_bot=0 is_shrink=n
3 0.004 2.04606 1.91615 B m e v  arsize_top=0 arsize_bot=0 is_shrink=n
3 0.004 2.04606 1.96615 B m e v  arsize_top=0 arsize_bot=0 is_shrink=n
3 0.004 2.04606 2.01615 B m e v  arsize_top=0 arsize_bot=0 is_shrink=n
3 0.004 2.04606 2.06615 B m e v  arsize_top=0 arsize_bot=0 is_shrink=n
3 0.004 2.04606 2.11615 B m e v  arsize_top=0 arsize_bot=0 is_shrink=n
3 0.004 2.04606 2.16615 B m e v  arsize_top=0 arsize_bot=0 is_shrink=n
3 0.004 2.04606 2.21615 B m e v  arsize_top=0 arsize_bot=0 is_shrink=n
3 0.004 2.04606 2.26615 B m e v  arsize_top=0 arsize_bot=0 is_shrink=n
3 0.004 2.04606 2.31615 B m e v  arsize_top=0 arsize_bot=0 is_shrink=n
3 0.004 2.04606 2.36615 B m e v  arsize_top=0 arsize_bot=0 is_shrink=n
3 0.004 2.04606 2.41615 B m e v  arsize_top=0 arsize_bot=0 is_shrink=n
3 0.004 2.04606 2.46615 B m e v  arsize_top=0 arsize_bot=0 is_shrink=n
3 0.004 2.04606 2.51615 B m e v  arsize_top=0 arsize_bot=0 is_shrink=n
3 0.004 2.04606 2.56615 B m e v  arsize_top=0 arsize_bot=0 is_shrink=n
3 0.004 2.04606 2.61615 B m e v  arsize_top=0 arsize_bot=0 is_shrink=n
3 0.004 2.04606 2.66615 B m e v  arsize_top=0 arsize_bot=0 is_shrink=n
3 0.004 2.04606 2.71615 B m e v  arsize_top=0 arsize_bot=0 is_shrink=n
3 0.004 2.04606 2.76615 B m e v  arsize_top=0 arsize_bot=0 is_shrink=n
3 0.004 2.04606 2.81615 B m e v  arsize_top=0 arsize_bot=0 is_shrink=n
3 0.004 2.04606 2.86615 B m e v  arsize_top=0 arsize_bot=0 is_shrink=n
3 0.004 2.04606 2.91615 B m e v  arsize_top=0 arsize_bot=0 is_shrink=n
3 0.004 2.04606 2.96615 B m e v  arsize_top=0 arsize_bot=0 is_shrink=n
3 0.004 2.04606 3.01615 B m e v  arsize_top=0 arsize_bot=0 is_shrink=n
3 0.004 2.04606 3.06615 B m e v  arsize_top=0 arsize_bot=0 is_shrink=n
3 0.004 2.04606 3.11615 B m e v  arsize_top=0 arsize_bot=0 is_shrink=n
3 0.004 2.04606 3.16615 B m e v  arsize_top=0 arsize_bot=0 is_shrink=n
3 0.004 2.04606 3.21615 B m e v  arsize_top=0 arsize_bot=0 is_shrink=n
3 0.004 2.04606 3.26615 B m e v  arsize_top=0 arsize_bot=0 is_shrink=n
3 0.004 2.04606 3.41615 B m e v  arsize_top=0 arsize_bot=0 is_shrink=n
3 0.004 2.04606 3.46615 B m e v  arsize_top=0 arsize_bot=0 is_shrink=n
3 0.004 2.04606 3.51615 B m e v  arsize_top=0 arsize_bot=0 is_shrink=n
3 0.004 2.04606 3.56615 B m e v  arsize_top=0 arsize_bot=0 is_shrink=n
3 0.004 2.04606 3.71615 B m e v  arsize_top=0 arsize_bot=0 is_shrink=n
3 0.004 2.04606 3.86615 B m e v  arsize_top=0 arsize_bot=0 is_shrink=n
3 0.004 2.09606 1.86615 B m e v  arsize_top=0 arsize_bot=0 is_shrink=n
3 0.004 2.09606 1.91615 B m e v  arsize_top=0 arsize_bot=0 is_shrink=n
3 0.004 2.09606 1.96615 B m e v  arsize_top=0 arsize_bot=0 is_shrink=n
3 0.004 2.09606 2.01615 B m e v  arsize_top=0 arsize_bot=0 is_shrink=n
3 0.004 2.09606 2.06615 B m e v  arsize_top=0 arsize_bot=0 is_shrink=n
3 0.004 2.09606 2.11615 B m e v  arsize_top=0 arsize_bot=0 is_shrink=n
3 0.004 2.09606 2.16615 B m e v  arsize_top=0 arsize_bot=0 is_shrink=n
3 0.004 2.09606 2.21615 B m e v  arsize_top=0 arsize_bot=0 is_shrink=n
3 0.004 2.09606 2.26615 B m e v  arsize_top=0 arsize_bot=0 is_shrink=n
3 0.004 2.09606 2.31615 B m e v  arsize_top=0 arsize_bot=0 is_shrink=n
3 0.004 2.09606 2.36615 B m e v  arsize_top=0 arsize_bot=0 is_shrink=n
3 0.004 2.09606 2.41615 B m e v  arsize_top=0 arsize_bot=0 is_shrink=n
3 0.004 2.09606 2.46615 B m e v  arsize_top=0 arsize_bot=0 is_shrink=n
3 0.004 2.09606 2.51615 B m e v  arsize_top=0 arsize_bot=0 is_shrink=n
3 0.004 2.09606 2.56615 B m e v  arsize_top=0 arsize_bot=0 is_shrink=n
3 0.004 2.09606 2.61615 B m e v  arsize_top=0 arsize_bot=0 is_shrink=n
3 0.004 2.09606 2.66615 B m e v  arsize_top=0 arsize_bot=0 is_shrink=n
3 0.004 2.09606 2.71615 B m e v  arsize_top=0 arsize_bot=0 is_shrink=n
3 0.004 2.09606 2.76615 B m e v  arsize_top=0 arsize_bot=0 is_shrink=n
3 0.004 2.09606 2.81615 B m e v  arsize_top=0 arsize_bot=0 is_shrink=n
3 0.004 2.09606 2.86615 B m e v  arsize_top=0 arsize_bot=0 is_shrink=n
3 0.004 2.09606 2.91615 B m e v  arsize_top=0 arsize_bot=0 is_shrink=n
3 0.004 2.09606 2.96615 B m e v  arsize_top=0 arsize_bot=0 is_shrink=n
3 0.004 2.09606 3.01615 B m e v  arsize_top=0 arsize_bot=0 is_shrink=n
3 0.004 2.09606 3.06615 B m e v  arsize_top=0 arsize_bot=0 is_shrink=n
3 0.004 2.09606 3.11615 B m e v  arsize_top=0 arsize_bot=0 is_shrink=n
3 0.004 2.09606 3.16615 B m e v  arsize_top=0 arsize_bot=0 is_shrink=n
3 0.004 2.09606 3.21615 B m e v  arsize_top=0 arsize_bot=0 is_shrink=n
3 0.004 2.09606 3.36615 B m e v  arsize_top=0 arsize_bot=0 is_shrink=n
3 0.004 2.09606 3.51615 B m e v  arsize_top=0 arsize_bot=0 is_shrink=n
3 0.004 2.09606 3.61615 B m e v  arsize_top=0 arsize_bot=0 is_shrink=n
3 0.004 2.09606 3.76615 B m e v  arsize_top=0 arsize_bot=0 is_shrink=n
3 0.004 2.14606 1.86615 B m e v  arsize_top=0 arsize_bot=0 is_shrink=n
3 0.004 2.14606 1.91615 B m e v  arsize_top=0 arsize_bot=0 is_shrink=n
3 0.004 2.14606 1.96615 B m e v  arsize_top=0 arsize_bot=0 is_shrink=n
3 0.004 2.14606 2.01615 B m e v  arsize_top=0 arsize_bot=0 is_shrink=n
3 0.004 2.14606 2.06615 B m e v  arsize_top=0 arsize_bot=0 is_shrink=n
3 0.004 2.14606 2.11615 B m e v  arsize_top=0 arsize_bot=0 is_shrink=n
3 0.004 2.14606 2.16615 B m e v  arsize_top=0 arsize_bot=0 is_shrink=n
3 0.004 2.14606 2.21615 B m e v  arsize_top=0 arsize_bot=0 is_shrink=n
3 0.004 2.14606 2.26615 B m e v  arsize_top=0 arsize_bot=0 is_shrink=n
3 0.004 2.14606 2.31615 B m e v  arsize_top=0 arsize_bot=0 is_shrink=n
3 0.004 2.14606 2.36615 B m e v  arsize_top=0 arsize_bot=0 is_shrink=n
3 0.004 2.14606 2.41615 B m e v  arsize_top=0 arsize_bot=0 is_shrink=n
3 0.004 2.14606 2.46615 B m e v  arsize_top=0 arsize_bot=0 is_shrink=n
3 0.004 2.14606 2.56615 B m e v  arsize_top=0 arsize_bot=0 is_shrink=n
3 0.004 2.14606 2.61615 B m e v  arsize_top=0 arsize_bot=0 is_shrink=n
3 0.004 2.14606 2.66615 B m e v  arsize_top=0 arsize_bot=0 is_shrink=n
3 0.004 2.14606 2.71615 B m e v  arsize_top=0 arsize_bot=0 is_shrink=n
3 0.004 2.14606 2.76615 B m e v  arsize_top=0 arsize_bot=0 is_shrink=n
3 0.004 2.14606 2.81615 B m e v  arsize_top=0 arsize_bot=0 is_shrink=n
3 0.004 2.14606 2.86615 B m e v  arsize_top=0 arsize_bot=0 is_shrink=n
3 0.004 2.14606 2.91615 B m e v  arsize_top=0 arsize_bot=0 is_shrink=n
3 0.004 2.14606 2.96615 B m e v  arsize_top=0 arsize_bot=0 is_shrink=n
3 0.004 2.14606 3.01615 B m e v  arsize_top=0 arsize_bot=0 is_shrink=n
3 0.004 2.14606 3.06615 B m e v  arsize_top=0 arsize_bot=0 is_shrink=n
3 0.004 2.14606 3.11615 B m e v  arsize_top=0 arsize_bot=0 is_shrink=n
3 0.004 2.14606 3.16615 B m e v  arsize_top=0 arsize_bot=0 is_shrink=n
3 0.004 2.14606 3.21615 B m e v  arsize_top=0 arsize_bot=0 is_shrink=n
3 0.004 2.14606 3.26615 B m e v  arsize_top=0 arsize_bot=0 is_shrink=n
3 0.004 2.14606 3.41615 B m e v  arsize_top=0 arsize_bot=0 is_shrink=n
3 0.004 2.14606 3.56615 B m e v  arsize_top=0 arsize_bot=0 is_shrink=n
3 0.004 2.14606 3.71615 B m e v  arsize_top=0 arsize_bot=0 is_shrink=n
3 0.004 2.14606 3.86615 B m e v  arsize_top=0 arsize_bot=0 is_shrink=n
3 0.004 2.19606 1.86615 B m e v  arsize_top=0 arsize_bot=0 is_shrink=n
3 0.004 2.19606 1.91615 B m e v  arsize_top=0 arsize_bot=0 is_shrink=n
3 0.004 2.19606 1.96615 B m e v  arsize_top=0 arsize_bot=0 is_shrink=n
3 0.004 2.19606 2.01615 B m e v  arsize_top=0 arsize_bot=0 is_shrink=n
3 0.004 2.19606 2.06615 B m e v  arsize_top=0 arsize_bot=0 is_shrink=n
3 0.004 2.19606 2.11615 B m e v  arsize_top=0 arsize_bot=0 is_shrink=n
3 0.004 2.19606 2.16615 B m e v  arsize_top=0 arsize_bot=0 is_shrink=n
3 0.004 2.19606 2.21615 B m e v  arsize_top=0 arsize_bot=0 is_shrink=n
3 0.004 2.19606 2.26615 B m e v  arsize_top=0 arsize_bot=0 is_shrink=n
3 0.004 2.19606 2.31615 B m e v  arsize_top=0 arsize_bot=0 is_shrink=n
3 0.004 2.19606 2.36615 B m e v  arsize_top=0 arsize_bot=0 is_shrink=n
3 0.004 2.19606 2.41615 B m e v  arsize_top=0 arsize_bot=0 is_shrink=n
3 0.004 2.19606 2.46615 B m e v  arsize_top=0 arsize_bot=0 is_shrink=n
3 0.004 2.19606 2.51615 B m e v  arsize_top=0 arsize_bot=0 is_shrink=n
3 0.004 2.19606 2.56615 B m e v  arsize_top=0 arsize_bot=0 is_shrink=n
3 0.004 2.19606 2.61615 B m e v  arsize_top=0 arsize_bot=0 is_shrink=n
3 0.004 2.19606 2.66615 B m e v  arsize_top=0 arsize_bot=0 is_shrink=n
3 0.004 2.19606 2.71615 B m e v  arsize_top=0 arsize_bot=0 is_shrink=n
3 0.004 2.19606 2.76615 B m e v  arsize_top=0 arsize_bot=0 is_shrink=n
3 0.004 2.19606 2.81615 B m e v  arsize_top=0 arsize_bot=0 is_shrink=n
3 0.004 2.19606 2.86615 B m e v  arsize_top=0 arsize_bot=0 is_shrink=n
3 0.004 2.19606 2.91615 B m e v  arsize_top=0 arsize_bot=0 is_shrink=n
3 0.004 2.19606 2.96615 B m e v  arsize_top=0 arsize_bot=0 is_shrink=n
3 0.004 2.19606 3.01615 B m e v  arsize_top=0 arsize_bot=0 is_shrink=n
3 0.004 2.19606 3.06615 B m e v  arsize_top=0 arsize_bot=0 is_shrink=n
3 0.004 2.19606 3.11615 B m e v  arsize_top=0 arsize_bot=0 is_shrink=n
3 0.004 2.19606 3.16615 B m e v  arsize_top=0 arsize_bot=0 is_shrink=n
3 0.004 2.19606 3.21615 B m e v  arsize_top=0 arsize_bot=0 is_shrink=n
3 0.004 2.19606 3.36615 B m e v  arsize_top=0 arsize_bot=0 is_shrink=n
3 0.004 2.19606 3.51615 B m e v  arsize_top=0 arsize_bot=0 is_shrink=n
3 0.004 2.19606 3.56615 B m e v  arsize_top=0 arsize_bot=0 is_shrink=n
3 0.004 2.19606 3.61615 B m e v  arsize_top=0 arsize_bot=0 is_shrink=n
3 0.004 2.19606 3.76615 B m e v  arsize_top=0 arsize_bot=0 is_shrink=n
3 0.004 2.24606 1.86615 B m e v  arsize_top=0 arsize_bot=0 is_shrink=n
3 0.004 2.24606 1.91615 B m e v  arsize_top=0 arsize_bot=0 is_shrink=n
3 0.004 2.24606 1.96615 B m e v  arsize_top=0 arsize_bot=0 is_shrink=n
3 0.004 2.24606 2.01615 B m e v  arsize_top=0 arsize_bot=0 is_shrink=n
3 0.004 2.24606 2.06615 B m e v  arsize_top=0 arsize_bot=0 is_shrink=n
3 0.004 2.24606 2.11615 B m e v  arsize_top=0 arsize_bot=0 is_shrink=n
3 0.004 2.24606 2.16615 B m e v  arsize_top=0 arsize_bot=0 is_shrink=n
3 0.004 2.24606 2.21615 B m e v  arsize_top=0 arsize_bot=0 is_shrink=n
3 0.004 2.24606 2.26615 B m e v  arsize_top=0 arsize_bot=0 is_shrink=n
3 0.004 2.24606 2.31615 B m e v  arsize_top=0 arsize_bot=0 is_shrink=n
3 0.004 2.24606 2.36615 B m e v  arsize_top=0 arsize_bot=0 is_shrink=n
3 0.004 2.24606 2.41615 B m e v  arsize_top=0 arsize_bot=0 is_shrink=n
3 0.004 2.24606 2.46615 B m e v  arsize_top=0 arsize_bot=0 is_shrink=n
3 0.004 2.24606 2.51615 B m e v  arsize_top=0 arsize_bot=0 is_shrink=n
3 0.004 2.24606 2.56615 B m e v  arsize_top=0 arsize_bot=0 is_shrink=n
3 0.004 2.24606 2.61615 B m e v  arsize_top=0 arsize_bot=0 is_shrink=n
3 0.004 2.24606 2.66615 B m e v  arsize_top=0 arsize_bot=0 is_shrink=n
3 0.004 2.24606 2.71615 B m e v  arsize_top=0 arsize_bot=0 is_shrink=n
3 0.004 2.24606 2.76615 B m e v  arsize_top=0 arsize_bot=0 is_shrink=n
3 0.004 2.24606 2.81615 B m e v  arsize_top=0 arsize_bot=0 is_shrink=n
3 0.004 2.24606 2.91615 B m e v  arsize_top=0 arsize_bot=0 is_shrink=n
3 0.004 2.24606 2.96615 B m e v  arsize_top=0 arsize_bot=0 is_shrink=n
3 0.004 2.24606 3.01615 B m e v  arsize_top=0 arsize_bot=0 is_shrink=n
3 0.004 2.24606 3.06615 B m e v  arsize_top=0 arsize_bot=0 is_shrink=n
3 0.004 2.24606 3.11615 B m e v  arsize_top=0 arsize_bot=0 is_shrink=n
3 0.004 2.24606 3.16615 B m e v  arsize_top=0 arsize_bot=0 is_shrink=n
3 0.004 2.24606 3.21615 B m e v  arsize_top=0 arsize_bot=0 is_shrink=n
3 0.004 2.24606 3.26615 B m e v  arsize_top=0 arsize_bot=0 is_shrink=n
3 0.004 2.24606 3.31615 B m e v  arsize_top=0 arsize_bot=0 is_shrink=n
3 0.004 2.24606 3.36615 B m e v  arsize_top=0 arsize_bot=0 is_shrink=n
3 0.004 2.24606 3.41615 B m e v  arsize_top=0 arsize_bot=0 is_shrink=n
3 0.004 2.24606 3.46615 B m e v  arsize_top=0 arsize_bot=0 is_shrink=n
3 0.004 2.24606 3.51615 B m e v  arsize_top=0 arsize_bot=0 is_shrink=n
3 0.004 2.24606 3.61615 B m e v  arsize_top=0 arsize_bot=0 is_shrink=n
3 0.004 2.24606 3.66615 B m e v  arsize_top=0 arsize_bot=0 is_shrink=n
3 0.004 2.24606 3.71615 B m e v  arsize_top=0 arsize_bot=0 is_shrink=n
3 0.004 2.24606 3.76615 B m e v  arsize_top=0 arsize_bot=0 is_shrink=n
3 0.004 2.24606 3.81615 B m e v  arsize_top=0 arsize_bot=0 is_shrink=n
3 0.004 2.24606 3.86615 B m e v  arsize_top=0 arsize_bot=0 is_shrink=n
3 0.004 2.29606 1.86615 B m e v  arsize_top=0 arsize_bot=0 is_shrink=n
3 0.004 2.29606 1.91615 B m e v  arsize_top=0 arsize_bot=0 is_shrink=n
3 0.004 2.29606 1.96615 B m e v  arsize_top=0 arsize_bot=0 is_shrink=n
3 0.004 2.29606 2.01615 B m e v  arsize_top=0 arsize_bot=0 is_shrink=n
3 0.004 2.29606 2.06615 B m e v  arsize_top=0 arsize_bot=0 is_shrink=n
3 0.004 2.29606 2.11615 B m e v  arsize_top=0 arsize_bot=0 is_shrink=n
3 0.004 2.29606 2.16615 B m e v  arsize_top=0 arsize_bot=0 is_shrink=n
3 0.004 2.29606 2.21615 B m e v  arsize_top=0 arsize_bot=0 is_shrink=n
3 0.004 2.29606 2.26615 B m e v  arsize_top=0 arsize_bot=0 is_shrink=n
3 0.004 2.29606 2.31615 B m e v  arsize_top=0 arsize_bot=0 is_shrink=n
3 0.004 2.29606 2.36615 B m e v  arsize_top=0 arsize_bot=0 is_shrink=n
3 0.004 2.29606 2.41615 B m e v  arsize_top=0 arsize_bot=0 is_shrink=n
3 0.004 2.29606 2.46615 B m e v  arsize_top=0 arsize_bot=0 is_shrink=n
3 0.004 2.29606 2.51615 B m e v  arsize_top=0 arsize_bot=0 is_shrink=n
3 0.004 2.29606 2.56615 B m e v  arsize_top=0 arsize_bot=0 is_shrink=n
3 0.004 2.29606 2.61615 B m e v  arsize_top=0 arsize_bot=0 is_shrink=n
3 0.004 2.29606 2.66615 B m e v  arsize_top=0 arsize_bot=0 is_shrink=n
3 0.004 2.29606 2.71615 B m e v  arsize_top=0 arsize_bot=0 is_shrink=n
3 0.004 2.29606 2.76615 B m e v  arsize_top=0 arsize_bot=0 is_shrink=n
3 0.004 2.29606 2.81615 B m e v  arsize_top=0 arsize_bot=0 is_shrink=n
3 0.004 2.29606 2.91615 B m e v  arsize_top=0 arsize_bot=0 is_shrink=n
3 0.004 2.29606 2.96615 B m e v  arsize_top=0 arsize_bot=0 is_shrink=n
3 0.004 2.29606 3.01615 B m e v  arsize_top=0 arsize_bot=0 is_shrink=n
3 0.004 2.29606 3.06615 B m e v  arsize_top=0 arsize_bot=0 is_shrink=n
3 0.004 2.29606 3.11615 B m e v  arsize_top=0 arsize_bot=0 is_shrink=n
3 0.004 2.29606 3.16615 B m e v  arsize_top=0 arsize_bot=0 is_shrink=n
3 0.004 2.29606 3.21615 B m e v  arsize_top=0 arsize_bot=0 is_shrink=n
3 0.004 2.29606 3.26615 B m e v  arsize_top=0 arsize_bot=0 is_shrink=n
3 0.004 2.29606 3.31615 B m e v  arsize_top=0 arsize_bot=0 is_shrink=n
3 0.004 2.29606 3.36615 B m e v  arsize_top=0 arsize_bot=0 is_shrink=n
3 0.004 2.29606 3.41615 B m e v  arsize_top=0 arsize_bot=0 is_shrink=n
3 0.004 2.29606 3.46615 B m e v  arsize_top=0 arsize_bot=0 is_shrink=n
3 0.004 2.29606 3.51615 B m e v  arsize_top=0 arsize_bot=0 is_shrink=n
3 0.004 2.29606 3.61615 B m e v  arsize_top=0 arsize_bot=0 is_shrink=n
3 0.004 2.29606 3.66615 B m e v  arsize_top=0 arsize_bot=0 is_shrink=n
3 0.004 2.29606 3.71615 B m e v  arsize_top=0 arsize_bot=0 is_shrink=n
3 0.004 2.29606 3.76615 B m e v  arsize_top=0 arsize_bot=0 is_shrink=n
3 0.004 2.29606 3.81615 B m e v  arsize_top=0 arsize_bot=0 is_shrink=n
3 0.004 2.29606 3.86615 B m e v  arsize_top=0 arsize_bot=0 is_shrink=n
3 0.004 2.34606 1.86615 B m e v  arsize_top=0 arsize_bot=0 is_shrink=n
3 0.004 2.34606 1.91615 B m e v  arsize_top=0 arsize_bot=0 is_shrink=n
3 0.004 2.34606 1.96615 B m e v  arsize_top=0 arsize_bot=0 is_shrink=n
3 0.004 2.34606 2.01615 B m e v  arsize_top=0 arsize_bot=0 is_shrink=n
3 0.004 2.34606 2.06615 B m e v  arsize_top=0 arsize_bot=0 is_shrink=n
3 0.004 2.34606 2.11615 B m e v  arsize_top=0 arsize_bot=0 is_shrink=n
3 0.004 2.34606 2.16615 B m e v  arsize_top=0 arsize_bot=0 is_shrink=n
3 0.004 2.34606 2.21615 B m e v  arsize_top=0 arsize_bot=0 is_shrink=n
3 0.004 2.34606 2.26615 B m e v  arsize_top=0 arsize_bot=0 is_shrink=n
3 0.004 2.34606 2.31615 B m e v  arsize_top=0 arsize_bot=0 is_shrink=n
3 0.004 2.34606 2.36615 B m e v  arsize_top=0 arsize_bot=0 is_shrink=n
3 0.004 2.34606 2.41615 B m e v  arsize_top=0 arsize_bot=0 is_shrink=n
3 0.004 2.34606 2.46615 B m e v  arsize_top=0 arsize_bot=0 is_shrink=n
3 0.004 2.34606 2.51615 B m e v  arsize_top=0 arsize_bot=0 is_shrink=n
3 0.004 2.34606 2.56615 B m e v  arsize_top=0 arsize_bot=0 is_shrink=n
3 0.004 2.34606 2.61615 B m e v  arsize_top=0 arsize_bot=0 is_shrink=n
3 0.004 2.34606 2.66615 B m e v  arsize_top=0 arsize_bot=0 is_shrink=n
3 0.004 2.34606 2.71615 B m e v  arsize_top=0 arsize_bot=0 is_shrink=n
3 0.004 2.34606 2.76615 B m e v  arsize_top=0 arsize_bot=0 is_shrink=n
3 0.004 2.34606 2.81615 B m e v  arsize_top=0 arsize_bot=0 is_shrink=n
3 0.004 2.34606 2.86615 B m e v  arsize_top=0 arsize_bot=0 is_shrink=n
3 0.004 2.34606 2.91615 B m e v  arsize_top=0 arsize_bot=0 is_shrink=n
3 0.004 2.34606 2.96615 B m e v  arsize_top=0 arsize_bot=0 is_shrink=n
3 0.004 2.34606 3.01615 B m e v  arsize_top=0 arsize_bot=0 is_shrink=n
3 0.004 2.34606 3.06615 B m e v  arsize_top=0 arsize_bot=0 is_shrink=n
3 0.004 2.34606 3.11615 B m e v  arsize_top=0 arsize_bot=0 is_shrink=n
3 0.004 2.34606 3.16615 B m e v  arsize_top=0 arsize_bot=0 is_shrink=n
3 0.004 2.34606 3.21615 B m e v  arsize_top=0 arsize_bot=0 is_shrink=n
3 0.004 2.34606 3.36615 B m e v  arsize_top=0 arsize_bot=0 is_shrink=n
3 0.004 2.34606 3.51615 B m e v  arsize_top=0 arsize_bot=0 is_shrink=n
3 0.004 2.34606 3.56615 B m e v  arsize_top=0 arsize_bot=0 is_shrink=n
3 0.004 2.34606 3.61615 B m e v  arsize_top=0 arsize_bot=0 is_shrink=n
3 0.004 2.34606 3.76615 B m e v  arsize_top=0 arsize_bot=0 is_shrink=n
3 0.004 2.39606 1.86615 B m e v  arsize_top=0 arsize_bot=0 is_shrink=n
3 0.004 2.39606 1.91615 B m e v  arsize_top=0 arsize_bot=0 is_shrink=n
3 0.004 2.39606 1.96615 B m e v  arsize_top=0 arsize_bot=0 is_shrink=n
3 0.004 2.39606 2.01615 B m e v  arsize_top=0 arsize_bot=0 is_shrink=n
3 0.004 2.39606 2.06615 B m e v  arsize_top=0 arsize_bot=0 is_shrink=n
3 0.004 2.39606 2.11615 B m e v  arsize_top=0 arsize_bot=0 is_shrink=n
3 0.004 2.39606 2.16615 B m e v  arsize_top=0 arsize_bot=0 is_shrink=n
3 0.004 2.39606 2.21615 B m e v  arsize_top=0 arsize_bot=0 is_shrink=n
3 0.004 2.39606 2.26615 B m e v  arsize_top=0 arsize_bot=0 is_shrink=n
3 0.004 2.39606 2.31615 B m e v  arsize_top=0 arsize_bot=0 is_shrink=n
3 0.004 2.39606 2.36615 B m e v  arsize_top=0 arsize_bot=0 is_shrink=n
3 0.004 2.39606 2.41615 B m e v  arsize_top=0 arsize_bot=0 is_shrink=n
3 0.004 2.39606 2.46615 B m e v  arsize_top=0 arsize_bot=0 is_shrink=n
3 0.004 2.39606 2.51615 B m e v  arsize_top=0 arsize_bot=0 is_shrink=n
3 0.004 2.39606 2.56615 B m e v  arsize_top=0 arsize_bot=0 is_shrink=n
3 0.004 2.39606 2.61615 B m e v  arsize_top=0 arsize_bot=0 is_shrink=n
3 0.004 2.39606 2.66615 B m e v  arsize_top=0 arsize_bot=0 is_shrink=n
3 0.004 2.39606 2.71615 B m e v  arsize_top=0 arsize_bot=0 is_shrink=n
3 0.004 2.39606 2.76615 B m e v  arsize_top=0 arsize_bot=0 is_shrink=n
3 0.004 2.39606 2.81615 B m e v  arsize_top=0 arsize_bot=0 is_shrink=n
3 0.004 2.39606 2.86615 B m e v  arsize_top=0 arsize_bot=0 is_shrink=n
3 0.004 2.39606 2.91615 B m e v  arsize_top=0 arsize_bot=0 is_shrink=n
3 0.004 2.39606 2.96615 B m e v  arsize_top=0 arsize_bot=0 is_shrink=n
3 0.004 2.39606 3.01615 B m e v  arsize_top=0 arsize_bot=0 is_shrink=n
3 0.004 2.39606 3.06615 B m e v  arsize_top=0 arsize_bot=0 is_shrink=n
3 0.004 2.39606 3.11615 B m e v  arsize_top=0 arsize_bot=0 is_shrink=n
3 0.004 2.39606 3.16615 B m e v  arsize_top=0 arsize_bot=0 is_shrink=n
3 0.004 2.39606 3.21615 B m e v  arsize_top=0 arsize_bot=0 is_shrink=n
3 0.004 2.39606 3.26615 B m e v  arsize_top=0 arsize_bot=0 is_shrink=n
3 0.004 2.39606 3.41615 B m e v  arsize_top=0 arsize_bot=0 is_shrink=n
3 0.004 2.39606 3.56615 B m e v  arsize_top=0 arsize_bot=0 is_shrink=n
3 0.004 2.39606 3.71615 B m e v  arsize_top=0 arsize_bot=0 is_shrink=n
3 0.004 2.39606 3.86615 B m e v  arsize_top=0 arsize_bot=0 is_shrink=n
3 0.004 2.44606 1.86615 B m e v  arsize_top=0 arsize_bot=0 is_shrink=n
3 0.004 2.44606 1.91615 B m e v  arsize_top=0 arsize_bot=0 is_shrink=n
3 0.004 2.44606 1.96615 B m e v  arsize_top=0 arsize_bot=0 is_shrink=n
3 0.004 2.44606 2.01615 B m e v  arsize_top=0 arsize_bot=0 is_shrink=n
3 0.004 2.44606 2.06615 B m e v  arsize_top=0 arsize_bot=0 is_shrink=n
3 0.004 2.44606 2.11615 B m e v  arsize_top=0 arsize_bot=0 is_shrink=n
3 0.004 2.44606 2.16615 B m e v  arsize_top=0 arsize_bot=0 is_shrink=n
3 0.004 2.44606 2.21615 B m e v  arsize_top=0 arsize_bot=0 is_shrink=n
3 0.004 2.44606 2.26615 B m e v  arsize_top=0 arsize_bot=0 is_shrink=n
3 0.004 2.44606 2.31615 B m e v  arsize_top=0 arsize_bot=0 is_shrink=n
3 0.004 2.44606 2.36615 B m e v  arsize_top=0 arsize_bot=0 is_shrink=n
3 0.004 2.44606 2.41615 B m e v  arsize_top=0 arsize_bot=0 is_shrink=n
3 0.004 2.44606 2.46615 B m e v  arsize_top=0 arsize_bot=0 is_shrink=n
3 0.004 2.44606 2.51615 B m e v  arsize_top=0 arsize_bot=0 is_shrink=n
3 0.004 2.44606 2.56615 B m e v  arsize_top=0 arsize_bot=0 is_shrink=n
3 0.004 2.44606 2.61615 B m e v  arsize_top=0 arsize_bot=0 is_shrink=n
3 0.004 2.44606 2.66615 B m e v  arsize_top=0 arsize_bot=0 is_shrink=n
3 0.004 2.44606 2.71615 B m e v  arsize_top=0 arsize_bot=0 is_shrink=n
3 0.004 2.44606 2.76615 B m e v  arsize_top=0 arsize_bot=0 is_shrink=n
3 0.004 2.44606 2.81615 B m e v  arsize_top=0 arsize_bot=0 is_shrink=n
3 0.004 2.44606 2.86615 B m e v  arsize_top=0 arsize_bot=0 is_shrink=n
3 0.004 2.44606 2.91615 B m e v  arsize_top=0 arsize_bot=0 is_shrink=n
3 0.004 2.44606 2.96615 B m e v  arsize_top=0 arsize_bot=0 is_shrink=n
3 0.004 2.44606 3.01615 B m e v  arsize_top=0 arsize_bot=0 is_shrink=n
3 0.004 2.44606 3.06615 B m e v  arsize_top=0 arsize_bot=0 is_shrink=n
3 0.004 2.44606 3.11615 B m e v  arsize_top=0 arsize_bot=0 is_shrink=n
3 0.004 2.44606 3.16615 B m e v  arsize_top=0 arsize_bot=0 is_shrink=n
3 0.004 2.44606 3.21615 B m e v  arsize_top=0 arsize_bot=0 is_shrink=n
3 0.004 2.44606 3.36615 B m e v  arsize_top=0 arsize_bot=0 is_shrink=n
3 0.004 2.44606 3.51615 B m e v  arsize_top=0 arsize_bot=0 is_shrink=n
3 0.004 2.44606 3.56615 B m e v  arsize_top=0 arsize_bot=0 is_shrink=n
3 0.004 2.44606 3.61615 B m e v  arsize_top=0 arsize_bot=0 is_shrink=n
3 0.004 2.44606 3.76615 B m e v  arsize_top=0 arsize_bot=0 is_shrink=n
3 0.004 2.49606 1.86615 B m e v  arsize_top=0 arsize_bot=0 is_shrink=n
3 0.004 2.49606 1.91615 B m e v  arsize_top=0 arsize_bot=0 is_shrink=n
3 0.004 2.49606 1.96615 B m e v  arsize_top=0 arsize_bot=0 is_shrink=n
3 0.004 2.49606 2.01615 B m e v  arsize_top=0 arsize_bot=0 is_shrink=n
3 0.004 2.49606 2.06615 B m e v  arsize_top=0 arsize_bot=0 is_shrink=n
3 0.004 2.49606 2.11615 B m e v  arsize_top=0 arsize_bot=0 is_shrink=n
3 0.004 2.49606 2.16615 B m e v  arsize_top=0 arsize_bot=0 is_shrink=n
3 0.004 2.49606 2.21615 B m e v  arsize_top=0 arsize_bot=0 is_shrink=n
3 0.004 2.49606 2.26615 B m e v  arsize_top=0 arsize_bot=0 is_shrink=n
3 0.004 2.49606 2.31615 B m e v  arsize_top=0 arsize_bot=0 is_shrink=n
3 0.004 2.49606 2.36615 B m e v  arsize_top=0 arsize_bot=0 is_shrink=n
3 0.004 2.49606 2.41615 B m e v  arsize_top=0 arsize_bot=0 is_shrink=n
3 0.004 2.49606 2.46615 B m e v  arsize_top=0 arsize_bot=0 is_shrink=n
3 0.004 2.49606 2.51615 B m e v  arsize_top=0 arsize_bot=0 is_shrink=n
3 0.004 2.49606 2.56615 B m e v  arsize_top=0 arsize_bot=0 is_shrink=n
3 0.004 2.49606 2.61615 B m e v  arsize_top=0 arsize_bot=0 is_shrink=n
3 0.004 2.49606 2.66615 B m e v  arsize_top=0 arsize_bot=0 is_shrink=n
3 0.004 2.49606 2.71615 B m e v  arsize_top=0 arsize_bot=0 is_shrink=n
3 0.004 2.49606 2.76615 B m e v  arsize_top=0 arsize_bot=0 is_shrink=n
3 0.004 2.49606 2.81615 B m e v  arsize_top=0 arsize_bot=0 is_shrink=n
3 0.004 2.49606 2.86615 B m e v  arsize_top=0 arsize_bot=0 is_shrink=n
3 0.004 2.49606 2.91615 B m e v  arsize_top=0 arsize_bot=0 is_shrink=n
3 0.004 2.49606 2.96615 B m e v  arsize_top=0 arsize_bot=0 is_shrink=n
3 0.004 2.49606 3.01615 B m e v  arsize_top=0 arsize_bot=0 is_shrink=n
3 0.004 2.49606 3.06615 B m e v  arsize_top=0 arsize_bot=0 is_shrink=n
3 0.004 2.49606 3.11615 B m e v  arsize_top=0 arsize_bot=0 is_shrink=n
3 0.004 2.49606 3.16615 B m e v  arsize_top=0 arsize_bot=0 is_shrink=n
3 0.004 2.49606 3.21615 B m e v  arsize_top=0 arsize_bot=0 is_shrink=n
3 0.004 2.49606 3.26615 B m e v  arsize_top=0 arsize_bot=0 is_shrink=n
3 0.004 2.49606 3.41615 B m e v  arsize_top=0 arsize_bot=0 is_shrink=n
3 0.004 2.49606 3.56615 B m e v  arsize_top=0 arsize_bot=0 is_shrink=n
3 0.004 2.49606 3.71615 B m e v  arsize_top=0 arsize_bot=0 is_shrink=n
3 0.004 2.49606 3.86615 B m e v  arsize_top=0 arsize_bot=0 is_shrink=n
3 0.004 4.58268 1.86615 B m e v  arsize_top=0 arsize_bot=0 is_shrink=n
3 0.004 4.58268 2.01615 B m e v  arsize_top=0 arsize_bot=0 is_shrink=n
3 0.004 4.58268 2.31615 B m e v  arsize_top=0 arsize_bot=0 is_shrink=n
3 0.004 4.58268 2.46615 B m e v  arsize_top=0 arsize_bot=0 is_shrink=n
3 0.004 4.58268 2.51615 B m e v  arsize_top=0 arsize_bot=0 is_shrink=n
3 0.004 4.58268 2.66615 B m e v  arsize_top=0 arsize_bot=0 is_shrink=n
3 0.004 4.58268 2.91615 B m e v  arsize_top=0 arsize_bot=0 is_shrink=n
3 0.004 4.58268 3.06615 B m e v  arsize_top=0 arsize_bot=0 is_shrink=n
3 0.004 4.58268 3.21615 B m e v  arsize_top=0 arsize_bot=0 is_shrink=n
3 0.004 4.58268 3.36615 B m e v  arsize_top=0 arsize_bot=0 is_shrink=n
3 0.004 4.58268 3.51615 B m e v  arsize_top=0 arsize_bot=0 is_shrink=n
3 0.004 4.58268 3.66615 B m e v  arsize_top=0 arsize_bot=0 is_shrink=n
3 0.004 4.58268 3.81615 B m e v  arsize_top=0 arsize_bot=0 is_shrink=n
3 0.004 4.63268 1.96615 B m e v  arsize_top=0 arsize_bot=0 is_shrink=n
3 0.004 4.63268 2.11615 B m e v  arsize_top=0 arsize_bot=0 is_shrink=n
3 0.004 4.63268 2.16615 B m e v  arsize_top=0 arsize_bot=0 is_shrink=n
3 0.004 4.63268 2.21615 B m e v  arsize_top=0 arsize_bot=0 is_shrink=n
3 0.004 4.63268 2.36615 B m e v  arsize_top=0 arsize_bot=0 is_shrink=n
3 0.004 4.63268 2.51615 B m e v  arsize_top=0 arsize_bot=0 is_shrink=n
3 0.004 4.63268 2.56615 B m e v  arsize_top=0 arsize_bot=0 is_shrink=n
3 0.004 4.63268 2.71615 B m e v  arsize_top=0 arsize_bot=0 is_shrink=n
3 0.004 4.63268 2.76615 B m e v  arsize_top=0 arsize_bot=0 is_shrink=n
3 0.004 4.63268 2.91615 B m e v  arsize_top=0 arsize_bot=0 is_shrink=n
3 0.004 4.63268 3.06615 B m e v  arsize_top=0 arsize_bot=0 is_shrink=n
3 0.004 4.63268 3.21615 B m e v  arsize_top=0 arsize_bot=0 is_shrink=n
3 0.004 4.63268 3.36615 B m e v  arsize_top=0 arsize_bot=0 is_shrink=n
3 0.004 4.63268 3.51615 B m e v  arsize_top=0 arsize_bot=0 is_shrink=n
3 0.004 4.63268 3.66615 B m e v  arsize_top=0 arsize_bot=0 is_shrink=n
3 0.004 4.63268 3.81615 B m e v  arsize_top=0 arsize_bot=0 is_shrink=n
3 0.004 4.68268 1.86615 B m e v  arsize_top=0 arsize_bot=0 is_shrink=n
3 0.004 4.68268 2.01615 B m e v  arsize_top=0 arsize_bot=0 is_shrink=n
3 0.004 4.68268 2.16615 B m e v  arsize_top=0 arsize_bot=0 is_shrink=n
3 0.004 4.68268 2.31615 B m e v  arsize_top=0 arsize_bot=0 is_shrink=n
3 0.004 4.68268 2.46615 B m e v  arsize_top=0 arsize_bot=0 is_shrink=n
3 0.004 4.68268 2.51615 B m e v  arsize_top=0 arsize_bot=0 is_shrink=n
3 0.004 4.68268 2.66615 B m e v  arsize_top=0 arsize_bot=0 is_shrink=n
3 0.004 4.68268 2.91615 B m e v  arsize_top=0 arsize_bot=0 is_shrink=n
3 0.004 4.68268 3.06615 B m e v  arsize_top=0 arsize_bot=0 is_shrink=n
3 0.004 4.68268 3.21615 B m e v  arsize_top=0 arsize_bot=0 is_shrink=n
3 0.004 4.68268 3.36615 B m e v  arsize_top=0 arsize_bot=0 is_shrink=n
3 0.004 4.68268 3.51615 B m e v  arsize_top=0 arsize_bot=0 is_shrink=n
3 0.004 4.68268 3.66615 B m e v  arsize_top=0 arsize_bot=0 is_shrink=n
3 0.004 4.68268 3.81615 B m e v  arsize_top=0 arsize_bot=0 is_shrink=n
3 0.004 4.73268 1.96615 B m e v  arsize_top=0 arsize_bot=0 is_shrink=n
3 0.004 4.73268 2.11615 B m e v  arsize_top=0 arsize_bot=0 is_shrink=n
3 0.004 4.73268 2.16615 B m e v  arsize_top=0 arsize_bot=0 is_shrink=n
3 0.004 4.73268 2.21615 B m e v  arsize_top=0 arsize_bot=0 is_shrink=n
3 0.004 4.73268 2.36615 B m e v  arsize_top=0 arsize_bot=0 is_shrink=n
3 0.004 4.73268 2.51615 B m e v  arsize_top=0 arsize_bot=0 is_shrink=n
3 0.004 4.73268 2.56615 B m e v  arsize_top=0 arsize_bot=0 is_shrink=n
3 0.004 4.73268 2.71615 B m e v  arsize_top=0 arsize_bot=0 is_shrink=n
3 0.004 4.73268 2.76615 B m e v  arsize_top=0 arsize_bot=0 is_shrink=n
3 0.004 4.73268 2.91615 B m e v  arsize_top=0 arsize_bot=0 is_shrink=n
3 0.004 4.73268 3.06615 B m e v  arsize_top=0 arsize_bot=0 is_shrink=n
3 0.004 4.73268 3.21615 B m e v  arsize_top=0 arsize_bot=0 is_shrink=n
3 0.004 4.73268 3.36615 B m e v  arsize_top=0 arsize_bot=0 is_shrink=n
3 0.004 4.73268 3.51615 B m e v  arsize_top=0 arsize_bot=0 is_shrink=n
3 0.004 4.73268 3.66615 B m e v  arsize_top=0 arsize_bot=0 is_shrink=n
3 0.004 4.73268 3.81615 B m e v  arsize_top=0 arsize_bot=0 is_shrink=n
3 0.004 4.78268 1.86615 B m e v  arsize_top=0 arsize_bot=0 is_shrink=n
3 0.004 4.78268 1.91615 B m e v  arsize_top=0 arsize_bot=0 is_shrink=n
3 0.004 4.78268 1.96615 B m e v  arsize_top=0 arsize_bot=0 is_shrink=n
3 0.004 4.78268 2.01615 B m e v  arsize_top=0 arsize_bot=0 is_shrink=n
3 0.004 4.78268 2.06615 B m e v  arsize_top=0 arsize_bot=0 is_shrink=n
3 0.004 4.78268 2.11615 B m e v  arsize_top=0 arsize_bot=0 is_shrink=n
3 0.004 4.78268 2.16615 B m e v  arsize_top=0 arsize_bot=0 is_shrink=n
3 0.004 4.78268 2.21615 B m e v  arsize_top=0 arsize_bot=0 is_shrink=n
3 0.004 4.78268 2.26615 B m e v  arsize_top=0 arsize_bot=0 is_shrink=n
3 0.004 4.78268 2.31615 B m e v  arsize_top=0 arsize_bot=0 is_shrink=n
3 0.004 4.78268 2.36615 B m e v  arsize_top=0 arsize_bot=0 is_shrink=n
3 0.004 4.78268 2.41615 B m e v  arsize_top=0 arsize_bot=0 is_shrink=n
3 0.004 4.78268 2.46615 B m e v  arsize_top=0 arsize_bot=0 is_shrink=n
3 0.004 4.78268 2.51615 B m e v  arsize_top=0 arsize_bot=0 is_shrink=n
3 0.004 4.78268 2.56615 B m e v  arsize_top=0 arsize_bot=0 is_shrink=n
3 0.004 4.78268 2.61615 B m e v  arsize_top=0 arsize_bot=0 is_shrink=n
3 0.004 4.78268 2.66615 B m e v  arsize_top=0 arsize_bot=0 is_shrink=n
3 0.004 4.78268 2.76615 B m e v  arsize_top=0 arsize_bot=0 is_shrink=n
3 0.004 4.78268 2.91615 B m e v  arsize_top=0 arsize_bot=0 is_shrink=n
3 0.004 4.78268 3.06615 B m e v  arsize_top=0 arsize_bot=0 is_shrink=n
3 0.004 4.78268 3.21615 B m e v  arsize_top=0 arsize_bot=0 is_shrink=n
3 0.004 4.78268 3.36615 B m e v  arsize_top=0 arsize_bot=0 is_shrink=n
3 0.004 4.78268 3.51615 B m e v  arsize_top=0 arsize_bot=0 is_shrink=n
3 0.004 4.78268 3.66615 B m e v  arsize_top=0 arsize_bot=0 is_shrink=n
3 0.004 4.78268 3.81615 B m e v  arsize_top=0 arsize_bot=0 is_shrink=n
3 0.004 4.83268 2.91615 B m e v  arsize_top=0 arsize_bot=0 is_shrink=n
3 0.004 4.83268 3.06615 B m e v  arsize_top=0 arsize_bot=0 is_shrink=n
3 0.004 4.83268 3.21615 B m e v  arsize_top=0 arsize_bot=0 is_shrink=n
3 0.004 4.83268 3.36615 B m e v  arsize_top=0 arsize_bot=0 is_shrink=n
3 0.004 4.83268 3.51615 B m e v  arsize_top=0 arsize_bot=0 is_shrink=n
3 0.004 4.83268 3.66615 B m e v  arsize_top=0 arsize_bot=0 is_shrink=n
3 0.004 4.83268 3.81615 B m e v  arsize_top=0 arsize_bot=0 is_shrink=n
3 0.004 4.88268 1.86615 B m e v  arsize_top=0 arsize_bot=0 is_shrink=n
3 0.004 4.88268 1.91615 B m e v  arsize_top=0 arsize_bot=0 is_shrink=n
3 0.004 4.88268 1.96615 B m e v  arsize_top=0 arsize_bot=0 is_shrink=n
3 0.004 4.88268 2.01615 B m e v  arsize_top=0 arsize_bot=0 is_shrink=n
3 0.004 4.88268 2.06615 B m e v  arsize_top=0 arsize_bot=0 is_shrink=n
3 0.004 4.88268 2.11615 B m e v  arsize_top=0 arsize_bot=0 is_shrink=n
3 0.004 4.88268 2.21615 B m e v  arsize_top=0 arsize_bot=0 is_shrink=n
3 0.004 4.88268 2.26615 B m e v  arsize_top=0 arsize_bot=0 is_shrink=n
3 0.004 4.88268 2.31615 B m e v  arsize_top=0 arsize_bot=0 is_shrink=n
3 0.004 4.88268 2.36615 B m e v  arsize_top=0 arsize_bot=0 is_shrink=n
3 0.004 4.88268 2.41615 B m e v  arsize_top=0 arsize_bot=0 is_shrink=n
3 0.004 4.88268 2.46615 B m e v  arsize_top=0 arsize_bot=0 is_shrink=n
3 0.004 4.88268 2.51615 B m e v  arsize_top=0 arsize_bot=0 is_shrink=n
3 0.004 4.88268 2.56615 B m e v  arsize_top=0 arsize_bot=0 is_shrink=n
3 0.004 4.88268 2.61615 B m e v  arsize_top=0 arsize_bot=0 is_shrink=n
3 0.004 4.88268 2.66615 B m e v  arsize_top=0 arsize_bot=0 is_shrink=n
3 0.004 4.88268 2.76615 B m e v  arsize_top=0 arsize_bot=0 is_shrink=n
3 0.004 4.88268 2.91615 B m e v  arsize_top=0 arsize_bot=0 is_shrink=n
3 0.004 4.88268 3.06615 B m e v  arsize_top=0 arsize_bot=0 is_shrink=n
3 0.004 4.88268 3.21615 B m e v  arsize_top=0 arsize_bot=0 is_shrink=n
3 0.004 4.88268 3.36615 B m e v  arsize_top=0 arsize_bot=0 is_shrink=n
3 0.004 4.88268 3.51615 B m e v  arsize_top=0 arsize_bot=0 is_shrink=n
3 0.004 4.88268 3.66615 B m e v  arsize_top=0 arsize_bot=0 is_shrink=n
3 0.004 4.88268 3.81615 B m e v  arsize_top=0 arsize_bot=0 is_shrink=n
3 0.004 4.93268 1.96615 B m e v  arsize_top=0 arsize_bot=0 is_shrink=n
3 0.004 4.93268 2.11615 B m e v  arsize_top=0 arsize_bot=0 is_shrink=n
3 0.004 4.93268 2.16615 B m e v  arsize_top=0 arsize_bot=0 is_shrink=n
3 0.004 4.93268 2.21615 B m e v  arsize_top=0 arsize_bot=0 is_shrink=n
3 0.004 4.93268 2.36615 B m e v  arsize_top=0 arsize_bot=0 is_shrink=n
3 0.004 4.93268 2.51615 B m e v  arsize_top=0 arsize_bot=0 is_shrink=n
3 0.004 4.93268 2.56615 B m e v  arsize_top=0 arsize_bot=0 is_shrink=n
3 0.004 4.93268 2.71615 B m e v  arsize_top=0 arsize_bot=0 is_shrink=n
3 0.004 4.93268 2.76615 B m e v  arsize_top=0 arsize_bot=0 is_shrink=n
3 0.004 4.93268 2.91615 B m e v  arsize_top=0 arsize_bot=0 is_shrink=n
3 0.004 4.93268 3.06615 B m e v  arsize_top=0 arsize_bot=0 is_shrink=n
3 0.004 4.93268 3.21615 B m e v  arsize_top=0 arsize_bot=0 is_shrink=n
3 0.004 4.93268 3.36615 B m e v  arsize_top=0 arsize_bot=0 is_shrink=n
3 0.004 4.93268 3.51615 B m e v  arsize_top=0 arsize_bot=0 is_shrink=n
3 0.004 4.93268 3.66615 B m e v  arsize_top=0 arsize_bot=0 is_shrink=n
3 0.004 4.93268 3.81615 B m e v  arsize_top=0 arsize_bot=0 is_shrink=n
3 0.004 4.98268 1.86615 B m e v  arsize_top=0 arsize_bot=0 is_shrink=n
3 0.004 4.98268 2.01615 B m e v  arsize_top=0 arsize_bot=0 is_shrink=n
3 0.004 4.98268 2.16615 B m e v  arsize_top=0 arsize_bot=0 is_shrink=n
3 0.004 4.98268 2.31615 B m e v  arsize_top=0 arsize_bot=0 is_shrink=n
3 0.004 4.98268 2.46615 B m e v  arsize_top=0 arsize_bot=0 is_shrink=n
3 0.004 4.98268 2.51615 B m e v  arsize_top=0 arsize_bot=0 is_shrink=n
3 0.004 4.98268 2.66615 B m e v  arsize_top=0 arsize_bot=0 is_shrink=n
3 0.004 4.98268 2.76615 B m e v  arsize_top=0 arsize_bot=0 is_shrink=n
3 0.004 4.98268 2.91615 B m e v  arsize_top=0 arsize_bot=0 is_shrink=n
3 0.004 4.98268 3.06615 B m e v  arsize_top=0 arsize_bot=0 is_shrink=n
3 0.004 4.98268 3.21615 B m e v  arsize_top=0 arsize_bot=0 is_shrink=n
3 0.004 4.98268 3.36615 B m e v  arsize_top=0 arsize_bot=0 is_shrink=n
3 0.004 4.98268 3.51615 B m e v  arsize_top=0 arsize_bot=0 is_shrink=n
3 0.004 4.98268 3.66615 B m e v  arsize_top=0 arsize_bot=0 is_shrink=n
3 0.004 4.98268 3.81615 B m e v  arsize_top=0 arsize_bot=0 is_shrink=n
3 0.004 5.03268 1.96615 B m e v  arsize_top=0 arsize_bot=0 is_shrink=n
3 0.004 5.03268 2.11615 B m e v  arsize_top=0 arsize_bot=0 is_shrink=n
3 0.004 5.03268 2.21615 B m e v  arsize_top=0 arsize_bot=0 is_shrink=n
3 0.004 5.03268 2.36615 B m e v  arsize_top=0 arsize_bot=0 is_shrink=n
3 0.004 5.03268 2.41615 B m e v  arsize_top=0 arsize_bot=0 is_shrink=n
3 0.004 5.03268 2.56615 B m e v  arsize_top=0 arsize_bot=0 is_shrink=n
3 0.004 5.03268 2.71615 B m e v  arsize_top=0 arsize_bot=0 is_shrink=n
3 0.004 5.03268 2.76615 B m e v  arsize_top=0 arsize_bot=0 is_shrink=n
3 0.004 5.03268 2.91615 B m e v  arsize_top=0 arsize_bot=0 is_shrink=n
3 0.004 5.03268 3.06615 B m e v  arsize_top=0 arsize_bot=0 is_shrink=n
3 0.004 5.03268 3.21615 B m e v  arsize_top=0 arsize_bot=0 is_shrink=n
3 0.004 5.03268 3.36615 B m e v  arsize_top=0 arsize_bot=0 is_shrink=n
3 0.004 5.03268 3.51615 B m e v  arsize_top=0 arsize_bot=0 is_shrink=n
3 0.004 5.03268 3.66615 B m e v  arsize_top=0 arsize_bot=0 is_shrink=n
3 0.004 5.08268 1.86615 B m e v  arsize_top=0 arsize_bot=0 is_shrink=n
3 0.004 5.08268 2.01615 B m e v  arsize_top=0 arsize_bot=0 is_shrink=n
3 0.004 5.08268 2.16615 B m e v  arsize_top=0 arsize_bot=0 is_shrink=n
3 0.004 5.08268 2.31615 B m e v  arsize_top=0 arsize_bot=0 is_shrink=n
3 0.004 5.08268 2.46615 B m e v  arsize_top=0 arsize_bot=0 is_shrink=n
3 0.004 5.08268 2.51615 B m e v  arsize_top=0 arsize_bot=0 is_shrink=n
3 0.004 5.08268 2.66615 B m e v  arsize_top=0 arsize_bot=0 is_shrink=n
3 0.004 5.08268 2.76615 B m e v  arsize_top=0 arsize_bot=0 is_shrink=n
3 0.004 8 2.71615 B m e v  arsize_top=0 arsize_bot=0 is_shrink=n
3 0.004 8 2.76615 B m e v  arsize_top=0 arsize_bot=0 is_shrink=n
3 0.004 8 2.81615 B m e v  arsize_top=0 arsize_bot=0 is_shrink=n
3 0.004 8 2.86615 B m e v  arsize_top=0 arsize_bot=0 is_shrink=n
3 0.004 8 3.41615 B m e v  arsize_top=0 arsize_bot=0 is_shrink=n
3 0.004 8 3.56615 B m e v  arsize_top=0 arsize_bot=0 is_shrink=n
3 0.004 8.05 1.86615 B m e v  arsize_top=0 arsize_bot=0 is_shrink=n
3 0.004 8.05 1.91615 B m e v  arsize_top=0 arsize_bot=0 is_shrink=n
3 0.004 8.05 1.96615 B m e v  arsize_top=0 arsize_bot=0 is_shrink=n
3 0.004 8.05 2.01615 B m e v  arsize_top=0 arsize_bot=0 is_shrink=n
3 0.004 8.05 2.06615 B m e v  arsize_top=0 arsize_bot=0 is_shrink=n
3 0.004 8.05 2.11615 B m e v  arsize_top=0 arsize_bot=0 is_shrink=n
3 0.004 8.05 2.16615 B m e v  arsize_top=0 arsize_bot=0 is_shrink=n
3 0.004 8.05 2.21615 B m e v  arsize_top=0 arsize_bot=0 is_shrink=n
3 0.004 8.05 2.26615 B m e v  arsize_top=0 arsize_bot=0 is_shrink=n
3 0.004 8.05 2.31615 B m e v  arsize_top=0 arsize_bot=0 is_shrink=n
3 0.004 8.05 2.36615 B m e v  arsize_top=0 arsize_bot=0 is_shrink=n
3 0.004 8.05 2.41615 B m e v  arsize_top=0 arsize_bot=0 is_shrink=n
3 0.004 8.05 2.46615 B m e v  arsize_top=0 arsize_bot=0 is_shrink=n
3 0.004 8.05 2.51615 B m e v  arsize_top=0 arsize_bot=0 is_shrink=n
3 0.004 8.05 2.56615 B m e v  arsize_top=0 arsize_bot=0 is_shrink=n
3 0.004 8.05 2.61615 B m e v  arsize_top=0 arsize_bot=0 is_shrink=n
3 0.004 8.05 2.66615 B m e v  arsize_top=0 arsize_bot=0 is_shrink=n
3 0.004 8.05 2.71615 B m e v  arsize_top=0 arsize_bot=0 is_shrink=n
3 0.004 8.05 2.76615 B m e v  arsize_top=0 arsize_bot=0 is_shrink=n
3 0.004 8.05 2.81615 B m e v  arsize_top=0 arsize_bot=0 is_shrink=n
3 0.004 8.05 2.86615 B m e v  arsize_top=0 arsize_bot=0 is_shrink=n
3 0.004 8.05 2.91615 B m e v  arsize_top=0 arsize_bot=0 is_shrink=n
3 0.004 8.05 2.96615 B m e v  arsize_top=0 arsize_bot=0 is_shrink=n
3 0.004 8.05 3.01615 B m e v  arsize_top=0 arsize_bot=0 is_shrink=n
3 0.004 8.05 3.06615 B m e v  arsize_top=0 arsize_bot=0 is_shrink=n
3 0.004 8.05 3.11615 B m e v  arsize_top=0 arsize_bot=0 is_shrink=n
3 0.004 8.05 3.16615 B m e v  arsize_top=0 arsize_bot=0 is_shrink=n
3 0.004 8.05 3.21615 B m e v  arsize_top=0 arsize_bot=0 is_shrink=n
3 0.004 8.05 3.26615 B m e v  arsize_top=0 arsize_bot=0 is_shrink=n
3 0.004 8.05 3.41615 B m e v  arsize_top=0 arsize_bot=0 is_shrink=n
3 0.004 8.05 3.46615 B m e v  arsize_top=0 arsize_bot=0 is_shrink=n
3 0.004 8.05 3.51615 B m e v  arsize_top=0 arsize_bot=0 is_shrink=n
3 0.004 8.05 3.56615 B m e v  arsize_top=0 arsize_bot=0 is_shrink=n
3 0.004 8.05 3.71615 B m e v  arsize_top=0 arsize_bot=0 is_shrink=n
3 0.004 8.05 3.86615 B m e v  arsize_top=0 arsize_bot=0 is_shrink=n
3 0.004 8.1 1.86615 B m e v  arsize_top=0 arsize_bot=0 is_shrink=n
3 0.004 8.1 1.91615 B m e v  arsize_top=0 arsize_bot=0 is_shrink=n
3 0.004 8.1 1.96615 B m e v  arsize_top=0 arsize_bot=0 is_shrink=n
3 0.004 8.1 2.01615 B m e v  arsize_top=0 arsize_bot=0 is_shrink=n
3 0.004 8.1 2.06615 B m e v  arsize_top=0 arsize_bot=0 is_shrink=n
3 0.004 8.1 2.11615 B m e v  arsize_top=0 arsize_bot=0 is_shrink=n
3 0.004 8.1 2.16615 B m e v  arsize_top=0 arsize_bot=0 is_shrink=n
3 0.004 8.1 2.21615 B m e v  arsize_top=0 arsize_bot=0 is_shrink=n
3 0.004 8.1 2.26615 B m e v  arsize_top=0 arsize_bot=0 is_shrink=n
3 0.004 8.1 2.31615 B m e v  arsize_top=0 arsize_bot=0 is_shrink=n
3 0.004 8.1 2.36615 B m e v  arsize_top=0 arsize_bot=0 is_shrink=n
3 0.004 8.1 2.41615 B m e v  arsize_top=0 arsize_bot=0 is_shrink=n
3 0.004 8.1 2.46615 B m e v  arsize_top=0 arsize_bot=0 is_shrink=n
3 0.004 8.1 2.51615 B m e v  arsize_top=0 arsize_bot=0 is_shrink=n
3 0.004 8.1 2.56615 B m e v  arsize_top=0 arsize_bot=0 is_shrink=n
3 0.004 8.1 2.61615 B m e v  arsize_top=0 arsize_bot=0 is_shrink=n
3 0.004 8.1 2.66615 B m e v  arsize_top=0 arsize_bot=0 is_shrink=n
3 0.004 8.1 2.71615 B m e v  arsize_top=0 arsize_bot=0 is_shrink=n
3 0.004 8.1 2.76615 B m e v  arsize_top=0 arsize_bot=0 is_shrink=n
3 0.004 8.1 2.81615 B m e v  arsize_top=0 arsize_bot=0 is_shrink=n
3 0.004 8.1 2.86615 B m e v  arsize_top=0 arsize_bot=0 is_shrink=n
3 0.004 8.1 2.91615 B m e v  arsize_top=0 arsize_bot=0 is_shrink=n
3 0.004 8.1 2.96615 B m e v  arsize_top=0 arsize_bot=0 is_shrink=n
3 0.004 8.1 3.01615 B m e v  arsize_top=0 arsize_bot=0 is_shrink=n
3 0.004 8.1 3.06615 B m e v  arsize_top=0 arsize_bot=0 is_shrink=n
3 0.004 8.1 3.11615 B m e v  arsize_top=0 arsize_bot=0 is_shrink=n
3 0.004 8.1 3.16615 B m e v  arsize_top=0 arsize_bot=0 is_shrink=n
3 0.004 8.1 3.21615 B m e v  arsize_top=0 arsize_bot=0 is_shrink=n
3 0.004 8.1 3.36615 B m e v  arsize_top=0 arsize_bot=0 is_shrink=n
3 0.004 8.1 3.51615 B m e v  arsize_top=0 arsize_bot=0 is_shrink=n
3 0.004 8.1 3.61615 B m e v  arsize_top=0 arsize_bot=0 is_shrink=n
3 0.004 8.1 3.76615 B m e v  arsize_top=0 arsize_bot=0 is_shrink=n
3 0.004 8.15 1.86615 B m e v  arsize_top=0 arsize_bot=0 is_shrink=n
3 0.004 8.15 1.91615 B m e v  arsize_top=0 arsize_bot=0 is_shrink=n
3 0.004 8.15 1.96615 B m e v  arsize_top=0 arsize_bot=0 is_shrink=n
3 0.004 8.15 2.01615 B m e v  arsize_top=0 arsize_bot=0 is_shrink=n
3 0.004 8.15 2.06615 B m e v  arsize_top=0 arsize_bot=0 is_shrink=n
3 0.004 8.15 2.11615 B m e v  arsize_top=0 arsize_bot=0 is_shrink=n
3 0.004 8.15 2.16615 B m e v  arsize_top=0 arsize_bot=0 is_shrink=n
3 0.004 8.15 2.21615 B m e v  arsize_top=0 arsize_bot=0 is_shrink=n
3 0.004 8.15 2.26615 B m e v  arsize_top=0 arsize_bot=0 is_shrink=n
3 0.004 8.15 2.31615 B m e v  arsize_top=0 arsize_bot=0 is_shrink=n
3 0.004 8.15 2.36615 B m e v  arsize_top=0 arsize_bot=0 is_shrink=n
3 0.004 8.15 2.41615 B m e v  arsize_top=0 arsize_bot=0 is_shrink=n
3 0.004 8.15 2.46615 B m e v  arsize_top=0 arsize_bot=0 is_shrink=n
3 0.004 8.15 2.56615 B m e v  arsize_top=0 arsize_bot=0 is_shrink=n
3 0.004 8.15 2.61615 B m e v  arsize_top=0 arsize_bot=0 is_shrink=n
3 0.004 8.15 2.66615 B m e v  arsize_top=0 arsize_bot=0 is_shrink=n
3 0.004 8.15 2.71615 B m e v  arsize_top=0 arsize_bot=0 is_shrink=n
3 0.004 8.15 2.76615 B m e v  arsize_top=0 arsize_bot=0 is_shrink=n
3 0.004 8.15 2.81615 B m e v  arsize_top=0 arsize_bot=0 is_shrink=n
3 0.004 8.15 2.86615 B m e v  arsize_top=0 arsize_bot=0 is_shrink=n
3 0.004 8.15 2.91615 B m e v  arsize_top=0 arsize_bot=0 is_shrink=n
3 0.004 8.15 2.96615 B m e v  arsize_top=0 arsize_bot=0 is_shrink=n
3 0.004 8.15 3.01615 B m e v  arsize_top=0 arsize_bot=0 is_shrink=n
3 0.004 8.15 3.06615 B m e v  arsize_top=0 arsize_bot=0 is_shrink=n
3 0.004 8.15 3.11615 B m e v  arsize_top=0 arsize_bot=0 is_shrink=n
3 0.004 8.15 3.16615 B m e v  arsize_top=0 arsize_bot=0 is_shrink=n
3 0.004 8.15 3.21615 B m e v  arsize_top=0 arsize_bot=0 is_shrink=n
3 0.004 8.15 3.26615 B m e v  arsize_top=0 arsize_bot=0 is_shrink=n
3 0.004 8.15 3.41615 B m e v  arsize_top=0 arsize_bot=0 is_shrink=n
3 0.004 8.15 3.56615 B m e v  arsize_top=0 arsize_bot=0 is_shrink=n
3 0.004 8.15 3.71615 B m e v  arsize_top=0 arsize_bot=0 is_shrink=n
3 0.004 8.15 3.86615 B m e v  arsize_top=0 arsize_bot=0 is_shrink=n
3 0.004 8.2 1.86615 B m e v  arsize_top=0 arsize_bot=0 is_shrink=n
3 0.004 8.2 1.91615 B m e v  arsize_top=0 arsize_bot=0 is_shrink=n
3 0.004 8.2 1.96615 B m e v  arsize_top=0 arsize_bot=0 is_shrink=n
3 0.004 8.2 2.01615 B m e v  arsize_top=0 arsize_bot=0 is_shrink=n
3 0.004 8.2 2.06615 B m e v  arsize_top=0 arsize_bot=0 is_shrink=n
3 0.004 8.2 2.11615 B m e v  arsize_top=0 arsize_bot=0 is_shrink=n
3 0.004 8.2 2.16615 B m e v  arsize_top=0 arsize_bot=0 is_shrink=n
3 0.004 8.2 2.21615 B m e v  arsize_top=0 arsize_bot=0 is_shrink=n
3 0.004 8.2 2.26615 B m e v  arsize_top=0 arsize_bot=0 is_shrink=n
3 0.004 8.2 2.31615 B m e v  arsize_top=0 arsize_bot=0 is_shrink=n
3 0.004 8.2 2.36615 B m e v  arsize_top=0 arsize_bot=0 is_shrink=n
3 0.004 8.2 2.41615 B m e v  arsize_top=0 arsize_bot=0 is_shrink=n
3 0.004 8.2 2.46615 B m e v  arsize_top=0 arsize_bot=0 is_shrink=n
3 0.004 8.2 2.51615 B m e v  arsize_top=0 arsize_bot=0 is_shrink=n
3 0.004 8.2 2.56615 B m e v  arsize_top=0 arsize_bot=0 is_shrink=n
3 0.004 8.2 2.61615 B m e v  arsize_top=0 arsize_bot=0 is_shrink=n
3 0.004 8.2 2.66615 B m e v  arsize_top=0 arsize_bot=0 is_shrink=n
3 0.004 8.2 2.71615 B m e v  arsize_top=0 arsize_bot=0 is_shrink=n
3 0.004 8.2 2.76615 B m e v  arsize_top=0 arsize_bot=0 is_shrink=n
3 0.004 8.2 2.81615 B m e v  arsize_top=0 arsize_bot=0 is_shrink=n
3 0.004 8.2 2.86615 B m e v  arsize_top=0 arsize_bot=0 is_shrink=n
3 0.004 8.2 2.91615 B m e v  arsize_top=0 arsize_bot=0 is_shrink=n
3 0.004 8.2 2.96615 B m e v  arsize_top=0 arsize_bot=0 is_shrink=n
3 0.004 8.2 3.01615 B m e v  arsize_top=0 arsize_bot=0 is_shrink=n
3 0.004 8.2 3.06615 B m e v  arsize_top=0 arsize_bot=0 is_shrink=n
3 0.004 8.2 3.11615 B m e v  arsize_top=0 arsize_bot=0 is_shrink=n
3 0.004 8.2 3.16615 B m e v  arsize_top=0 arsize_bot=0 is_shrink=n
3 0.004 8.2 3.21615 B m e v  arsize_top=0 arsize_bot=0 is_shrink=n
3 0.004 8.2 3.36615 B m e v  arsize_top=0 arsize_bot=0 is_shrink=n
3 0.004 8.2 3.51615 B m e v  arsize_top=0 arsize_bot=0 is_shrink=n
3 0.004 8.2 3.56615 B m e v  arsize_top=0 arsize_bot=0 is_shrink=n
3 0.004 8.2 3.61615 B m e v  arsize_top=0 arsize_bot=0 is_shrink=n
3 0.004 8.2 3.76615 B m e v  arsize_top=0 arsize_bot=0 is_shrink=n
3 0.004 8.25 1.86615 B m e v  arsize_top=0 arsize_bot=0 is_shrink=n
3 0.004 8.25 1.91615 B m e v  arsize_top=0 arsize_bot=0 is_shrink=n
3 0.004 8.25 1.96615 B m e v  arsize_top=0 arsize_bot=0 is_shrink=n
3 0.004 8.25 2.01615 B m e v  arsize_top=0 arsize_bot=0 is_shrink=n
3 0.004 8.25 2.06615 B m e v  arsize_top=0 arsize_bot=0 is_shrink=n
3 0.004 8.25 2.11615 B m e v  arsize_top=0 arsize_bot=0 is_shrink=n
3 0.004 8.25 2.16615 B m e v  arsize_top=0 arsize_bot=0 is_shrink=n
3 0.004 8.25 2.21615 B m e v  arsize_top=0 arsize_bot=0 is_shrink=n
3 0.004 8.25 2.26615 B m e v  arsize_top=0 arsize_bot=0 is_shrink=n
3 0.004 8.25 2.31615 B m e v  arsize_top=0 arsize_bot=0 is_shrink=n
3 0.004 8.25 2.36615 B m e v  arsize_top=0 arsize_bot=0 is_shrink=n
3 0.004 8.25 2.41615 B m e v  arsize_top=0 arsize_bot=0 is_shrink=n
3 0.004 8.25 2.46615 B m e v  arsize_top=0 arsize_bot=0 is_shrink=n
3 0.004 8.25 2.51615 B m e v  arsize_top=0 arsize_bot=0 is_shrink=n
3 0.004 8.25 2.56615 B m e v  arsize_top=0 arsize_bot=0 is_shrink=n
3 0.004 8.25 2.61615 B m e v  arsize_top=0 arsize_bot=0 is_shrink=n
3 0.004 8.25 2.66615 B m e v  arsize_top=0 arsize_bot=0 is_shrink=n
3 0.004 8.25 2.71615 B m e v  arsize_top=0 arsize_bot=0 is_shrink=n
3 0.004 8.25 2.76615 B m e v  arsize_top=0 arsize_bot=0 is_shrink=n
3 0.004 8.25 2.81615 B m e v  arsize_top=0 arsize_bot=0 is_shrink=n
3 0.004 8.25 2.91615 B m e v  arsize_top=0 arsize_bot=0 is_shrink=n
3 0.004 8.25 2.96615 B m e v  arsize_top=0 arsize_bot=0 is_shrink=n
3 0.004 8.25 3.01615 B m e v  arsize_top=0 arsize_bot=0 is_shrink=n
3 0.004 8.25 3.06615 B m e v  arsize_top=0 arsize_bot=0 is_shrink=n
3 0.004 8.25 3.11615 B m e v  arsize_top=0 arsize_bot=0 is_shrink=n
3 0.004 8.25 3.16615 B m e v  arsize_top=0 arsize_bot=0 is_shrink=n
3 0.004 8.25 3.21615 B m e v  arsize_top=0 arsize_bot=0 is_shrink=n
3 0.004 8.25 3.26615 B m e v  arsize_top=0 arsize_bot=0 is_shrink=n
3 0.004 8.25 3.31615 B m e v  arsize_top=0 arsize_bot=0 is_shrink=n
3 0.004 8.25 3.36615 B m e v  arsize_top=0 arsize_bot=0 is_shrink=n
3 0.004 8.25 3.41615 B m e v  arsize_top=0 arsize_bot=0 is_shrink=n
3 0.004 8.25 3.46615 B m e v  arsize_top=0 arsize_bot=0 is_shrink=n
3 0.004 8.25 3.51615 B m e v  arsize_top=0 arsize_bot=0 is_shrink=n
3 0.004 8.25 3.61615 B m e v  arsize_top=0 arsize_bot=0 is_shrink=n
3 0.004 8.25 3.66615 B m e v  arsize_top=0 arsize_bot=0 is_shrink=n
3 0.004 8.25 3.71615 B m e v  arsize_top=0 arsize_bot=0 is_shrink=n
3 0.004 8.25 3.76615 B m e v  arsize_top=0 arsize_bot=0 is_shrink=n
3 0.004 8.25 3.81615 B m e v  arsize_top=0 arsize_bot=0 is_shrink=n
3 0.004 8.25 3.86615 B m e v  arsize_top=0 arsize_bot=0 is_shrink=n
3 0.004 8.3 1.86615 B m e v  arsize_top=0 arsize_bot=0 is_shrink=n
3 0.004 8.3 1.91615 B m e v  arsize_top=0 arsize_bot=0 is_shrink=n
3 0.004 8.3 1.96615 B m e v  arsize_top=0 arsize_bot=0 is_shrink=n
3 0.004 8.3 2.01615 B m e v  arsize_top=0 arsize_bot=0 is_shrink=n
3 0.004 8.3 2.06615 B m e v  arsize_top=0 arsize_bot=0 is_shrink=n
3 0.004 8.3 2.11615 B m e v  arsize_top=0 arsize_bot=0 is_shrink=n
3 0.004 8.3 2.16615 B m e v  arsize_top=0 arsize_bot=0 is_shrink=n
3 0.004 8.3 2.21615 B m e v  arsize_top=0 arsize_bot=0 is_shrink=n
3 0.004 8.3 2.26615 B m e v  arsize_top=0 arsize_bot=0 is_shrink=n
3 0.004 8.3 2.31615 B m e v  arsize_top=0 arsize_bot=0 is_shrink=n
3 0.004 8.3 2.36615 B m e v  arsize_top=0 arsize_bot=0 is_shrink=n
3 0.004 8.3 2.41615 B m e v  arsize_top=0 arsize_bot=0 is_shrink=n
3 0.004 8.3 2.46615 B m e v  arsize_top=0 arsize_bot=0 is_shrink=n
3 0.004 8.3 2.51615 B m e v  arsize_top=0 arsize_bot=0 is_shrink=n
3 0.004 8.3 2.56615 B m e v  arsize_top=0 arsize_bot=0 is_shrink=n
3 0.004 8.3 2.61615 B m e v  arsize_top=0 arsize_bot=0 is_shrink=n
3 0.004 8.3 2.66615 B m e v  arsize_top=0 arsize_bot=0 is_shrink=n
3 0.004 8.3 2.71615 B m e v  arsize_top=0 arsize_bot=0 is_shrink=n
3 0.004 8.3 2.76615 B m e v  arsize_top=0 arsize_bot=0 is_shrink=n
3 0.004 8.3 2.81615 B m e v  arsize_top=0 arsize_bot=0 is_shrink=n
3 0.004 8.3 2.91615 B m e v  arsize_top=0 arsize_bot=0 is_shrink=n
3 0.004 8.3 2.96615 B m e v  arsize_top=0 arsize_bot=0 is_shrink=n
3 0.004 8.3 3.01615 B m e v  arsize_top=0 arsize_bot=0 is_shrink=n
3 0.004 8.3 3.06615 B m e v  arsize_top=0 arsize_bot=0 is_shrink=n
3 0.004 8.3 3.11615 B m e v  arsize_top=0 arsize_bot=0 is_shrink=n
3 0.004 8.3 3.16615 B m e v  arsize_top=0 arsize_bot=0 is_shrink=n
3 0.004 8.3 3.21615 B m e v  arsize_top=0 arsize_bot=0 is_shrink=n
3 0.004 8.3 3.26615 B m e v  arsize_top=0 arsize_bot=0 is_shrink=n
3 0.004 8.3 3.31615 B m e v  arsize_top=0 arsize_bot=0 is_shrink=n
3 0.004 8.3 3.36615 B m e v  arsize_top=0 arsize_bot=0 is_shrink=n
3 0.004 8.3 3.41615 B m e v  arsize_top=0 arsize_bot=0 is_shrink=n
3 0.004 8.3 3.46615 B m e v  arsize_top=0 arsize_bot=0 is_shrink=n
3 0.004 8.3 3.51615 B m e v  arsize_top=0 arsize_bot=0 is_shrink=n
3 0.004 8.3 3.61615 B m e v  arsize_top=0 arsize_bot=0 is_shrink=n
3 0.004 8.3 3.66615 B m e v  arsize_top=0 arsize_bot=0 is_shrink=n
3 0.004 8.3 3.71615 B m e v  arsize_top=0 arsize_bot=0 is_shrink=n
3 0.004 8.3 3.76615 B m e v  arsize_top=0 arsize_bot=0 is_shrink=n
3 0.004 8.3 3.81615 B m e v  arsize_top=0 arsize_bot=0 is_shrink=n
3 0.004 8.3 3.86615 B m e v  arsize_top=0 arsize_bot=0 is_shrink=n
3 0.004 8.35 1.86615 B m e v  arsize_top=0 arsize_bot=0 is_shrink=n
3 0.004 8.35 1.91615 B m e v  arsize_top=0 arsize_bot=0 is_shrink=n
3 0.004 8.35 1.96615 B m e v  arsize_top=0 arsize_bot=0 is_shrink=n
3 0.004 8.35 2.01615 B m e v  arsize_top=0 arsize_bot=0 is_shrink=n
3 0.004 8.35 2.06615 B m e v  arsize_top=0 arsize_bot=0 is_shrink=n
3 0.004 8.35 2.11615 B m e v  arsize_top=0 arsize_bot=0 is_shrink=n
3 0.004 8.35 2.16615 B m e v  arsize_top=0 arsize_bot=0 is_shrink=n
3 0.004 8.35 2.21615 B m e v  arsize_top=0 arsize_bot=0 is_shrink=n
3 0.004 8.35 2.26615 B m e v  arsize_top=0 arsize_bot=0 is_shrink=n
3 0.004 8.35 2.31615 B m e v  arsize_top=0 arsize_bot=0 is_shrink=n
3 0.004 8.35 2.36615 B m e v  arsize_top=0 arsize_bot=0 is_shrink=n
3 0.004 8.35 2.41615 B m e v  arsize_top=0 arsize_bot=0 is_shrink=n
3 0.004 8.35 2.46615 B m e v  arsize_top=0 arsize_bot=0 is_shrink=n
3 0.004 8.35 2.51615 B m e v  arsize_top=0 arsize_bot=0 is_shrink=n
3 0.004 8.35 2.56615 B m e v  arsize_top=0 arsize_bot=0 is_shrink=n
3 0.004 8.35 2.61615 B m e v  arsize_top=0 arsize_bot=0 is_shrink=n
3 0.004 8.35 2.66615 B m e v  arsize_top=0 arsize_bot=0 is_shrink=n
3 0.004 8.35 2.71615 B m e v  arsize_top=0 arsize_bot=0 is_shrink=n
3 0.004 8.35 2.76615 B m e v  arsize_top=0 arsize_bot=0 is_shrink=n
3 0.004 8.35 2.81615 B m e v  arsize_top=0 arsize_bot=0 is_shrink=n
3 0.004 8.35 2.86615 B m e v  arsize_top=0 arsize_bot=0 is_shrink=n
3 0.004 8.35 2.91615 B m e v  arsize_top=0 arsize_bot=0 is_shrink=n
3 0.004 8.35 2.96615 B m e v  arsize_top=0 arsize_bot=0 is_shrink=n
3 0.004 8.35 3.01615 B m e v  arsize_top=0 arsize_bot=0 is_shrink=n
3 0.004 8.35 3.06615 B m e v  arsize_top=0 arsize_bot=0 is_shrink=n
3 0.004 8.35 3.11615 B m e v  arsize_top=0 arsize_bot=0 is_shrink=n
3 0.004 8.35 3.16615 B m e v  arsize_top=0 arsize_bot=0 is_shrink=n
3 0.004 8.35 3.21615 B m e v  arsize_top=0 arsize_bot=0 is_shrink=n
3 0.004 8.35 3.36615 B m e v  arsize_top=0 arsize_bot=0 is_shrink=n
3 0.004 8.35 3.51615 B m e v  arsize_top=0 arsize_bot=0 is_shrink=n
3 0.004 8.35 3.56615 B m e v  arsize_top=0 arsize_bot=0 is_shrink=n
3 0.004 8.35 3.61615 B m e v  arsize_top=0 arsize_bot=0 is_shrink=n
3 0.004 8.35 3.76615 B m e v  arsize_top=0 arsize_bot=0 is_shrink=n
3 0.004 8.4 1.86615 B m e v  arsize_top=0 arsize_bot=0 is_shrink=n
3 0.004 8.4 1.91615 B m e v  arsize_top=0 arsize_bot=0 is_shrink=n
3 0.004 8.4 1.96615 B m e v  arsize_top=0 arsize_bot=0 is_shrink=n
3 0.004 8.4 2.01615 B m e v  arsize_top=0 arsize_bot=0 is_shrink=n
3 0.004 8.4 2.06615 B m e v  arsize_top=0 arsize_bot=0 is_shrink=n
3 0.004 8.4 2.11615 B m e v  arsize_top=0 arsize_bot=0 is_shrink=n
3 0.004 8.4 2.16615 B m e v  arsize_top=0 arsize_bot=0 is_shrink=n
3 0.004 8.4 2.21615 B m e v  arsize_top=0 arsize_bot=0 is_shrink=n
3 0.004 8.4 2.26615 B m e v  arsize_top=0 arsize_bot=0 is_shrink=n
3 0.004 8.4 2.31615 B m e v  arsize_top=0 arsize_bot=0 is_shrink=n
3 0.004 8.4 2.36615 B m e v  arsize_top=0 arsize_bot=0 is_shrink=n
3 0.004 8.4 2.41615 B m e v  arsize_top=0 arsize_bot=0 is_shrink=n
3 0.004 8.4 2.46615 B m e v  arsize_top=0 arsize_bot=0 is_shrink=n
3 0.004 8.4 2.51615 B m e v  arsize_top=0 arsize_bot=0 is_shrink=n
3 0.004 8.4 2.56615 B m e v  arsize_top=0 arsize_bot=0 is_shrink=n
3 0.004 8.4 2.61615 B m e v  arsize_top=0 arsize_bot=0 is_shrink=n
3 0.004 8.4 2.66615 B m e v  arsize_top=0 arsize_bot=0 is_shrink=n
3 0.004 8.4 2.71615 B m e v  arsize_top=0 arsize_bot=0 is_shrink=n
3 0.004 8.4 2.76615 B m e v  arsize_top=0 arsize_bot=0 is_shrink=n
3 0.004 8.4 2.81615 B m e v  arsize_top=0 arsize_bot=0 is_shrink=n
3 0.004 8.4 2.86615 B m e v  arsize_top=0 arsize_bot=0 is_shrink=n
3 0.004 8.4 2.91615 B m e v  arsize_top=0 arsize_bot=0 is_shrink=n
3 0.004 8.4 2.96615 B m e v  arsize_top=0 arsize_bot=0 is_shrink=n
3 0.004 8.4 3.01615 B m e v  arsize_top=0 arsize_bot=0 is_shrink=n
3 0.004 8.4 3.06615 B m e v  arsize_top=0 arsize_bot=0 is_shrink=n
3 0.004 8.4 3.11615 B m e v  arsize_top=0 arsize_bot=0 is_shrink=n
3 0.004 8.4 3.16615 B m e v  arsize_top=0 arsize_bot=0 is_shrink=n
3 0.004 8.4 3.21615 B m e v  arsize_top=0 arsize_bot=0 is_shrink=n
3 0.004 8.4 3.26615 B m e v  arsize_top=0 arsize_bot=0 is_shrink=n
3 0.004 8.4 3.41615 B m e v  arsize_top=0 arsize_bot=0 is_shrink=n
3 0.004 8.4 3.56615 B m e v  arsize_top=0 arsize_bot=0 is_shrink=n
3 0.004 8.4 3.71615 B m e v  arsize_top=0 arsize_bot=0 is_shrink=n
3 0.004 8.4 3.86615 B m e v  arsize_top=0 arsize_bot=0 is_shrink=n
3 0.004 8.45 1.86615 B m e v  arsize_top=0 arsize_bot=0 is_shrink=n
3 0.004 8.45 1.91615 B m e v  arsize_top=0 arsize_bot=0 is_shrink=n
3 0.004 8.45 1.96615 B m e v  arsize_top=0 arsize_bot=0 is_shrink=n
3 0.004 8.45 2.01615 B m e v  arsize_top=0 arsize_bot=0 is_shrink=n
3 0.004 8.45 2.06615 B m e v  arsize_top=0 arsize_bot=0 is_shrink=n
3 0.004 8.45 2.11615 B m e v  arsize_top=0 arsize_bot=0 is_shrink=n
3 0.004 8.45 2.16615 B m e v  arsize_top=0 arsize_bot=0 is_shrink=n
3 0.004 8.45 2.21615 B m e v  arsize_top=0 arsize_bot=0 is_shrink=n
3 0.004 8.45 2.26615 B m e v  arsize_top=0 arsize_bot=0 is_shrink=n
3 0.004 8.45 2.31615 B m e v  arsize_top=0 arsize_bot=0 is_shrink=n
3 0.004 8.45 2.36615 B m e v  arsize_top=0 arsize_bot=0 is_shrink=n
3 0.004 8.45 2.41615 B m e v  arsize_top=0 arsize_bot=0 is_shrink=n
3 0.004 8.45 2.46615 B m e v  arsize_top=0 arsize_bot=0 is_shrink=n
3 0.004 8.45 2.51615 B m e v  arsize_top=0 arsize_bot=0 is_shrink=n
3 0.004 8.45 2.56615 B m e v  arsize_top=0 arsize_bot=0 is_shrink=n
3 0.004 8.45 2.61615 B m e v  arsize_top=0 arsize_bot=0 is_shrink=n
3 0.004 8.45 2.66615 B m e v  arsize_top=0 arsize_bot=0 is_shrink=n
3 0.004 8.45 2.71615 B m e v  arsize_top=0 arsize_bot=0 is_shrink=n
3 0.004 8.45 2.76615 B m e v  arsize_top=0 arsize_bot=0 is_shrink=n
3 0.004 8.45 2.81615 B m e v  arsize_top=0 arsize_bot=0 is_shrink=n
3 0.004 8.45 2.86615 B m e v  arsize_top=0 arsize_bot=0 is_shrink=n
3 0.004 8.45 2.91615 B m e v  arsize_top=0 arsize_bot=0 is_shrink=n
3 0.004 8.45 2.96615 B m e v  arsize_top=0 arsize_bot=0 is_shrink=n
3 0.004 8.45 3.01615 B m e v  arsize_top=0 arsize_bot=0 is_shrink=n
3 0.004 8.45 3.06615 B m e v  arsize_top=0 arsize_bot=0 is_shrink=n
3 0.004 8.45 3.11615 B m e v  arsize_top=0 arsize_bot=0 is_shrink=n
3 0.004 8.45 3.16615 B m e v  arsize_top=0 arsize_bot=0 is_shrink=n
3 0.004 8.45 3.21615 B m e v  arsize_top=0 arsize_bot=0 is_shrink=n
3 0.004 8.45 3.36615 B m e v  arsize_top=0 arsize_bot=0 is_shrink=n
3 0.004 8.45 3.51615 B m e v  arsize_top=0 arsize_bot=0 is_shrink=n
3 0.004 8.45 3.56615 B m e v  arsize_top=0 arsize_bot=0 is_shrink=n
3 0.004 8.45 3.61615 B m e v  arsize_top=0 arsize_bot=0 is_shrink=n
3 0.004 8.45 3.76615 B m e v  arsize_top=0 arsize_bot=0 is_shrink=n
3 0.004 8.5 1.86615 B m e v  arsize_top=0 arsize_bot=0 is_shrink=n
3 0.004 8.5 1.91615 B m e v  arsize_top=0 arsize_bot=0 is_shrink=n
3 0.004 8.5 1.96615 B m e v  arsize_top=0 arsize_bot=0 is_shrink=n
3 0.004 8.5 2.01615 B m e v  arsize_top=0 arsize_bot=0 is_shrink=n
3 0.004 8.5 2.06615 B m e v  arsize_top=0 arsize_bot=0 is_shrink=n
3 0.004 8.5 2.11615 B m e v  arsize_top=0 arsize_bot=0 is_shrink=n
3 0.004 8.5 2.16615 B m e v  arsize_top=0 arsize_bot=0 is_shrink=n
3 0.004 8.5 2.21615 B m e v  arsize_top=0 arsize_bot=0 is_shrink=n
3 0.004 8.5 2.26615 B m e v  arsize_top=0 arsize_bot=0 is_shrink=n
3 0.004 8.5 2.31615 B m e v  arsize_top=0 arsize_bot=0 is_shrink=n
3 0.004 8.5 2.36615 B m e v  arsize_top=0 arsize_bot=0 is_shrink=n
3 0.004 8.5 2.41615 B m e v  arsize_top=0 arsize_bot=0 is_shrink=n
3 0.004 8.5 2.46615 B m e v  arsize_top=0 arsize_bot=0 is_shrink=n
3 0.004 8.5 2.51615 B m e v  arsize_top=0 arsize_bot=0 is_shrink=n
3 0.004 8.5 2.56615 B m e v  arsize_top=0 arsize_bot=0 is_shrink=n
3 0.004 8.5 2.61615 B m e v  arsize_top=0 arsize_bot=0 is_shrink=n
3 0.004 8.5 2.66615 B m e v  arsize_top=0 arsize_bot=0 is_shrink=n
3 0.004 8.5 2.71615 B m e v  arsize_top=0 arsize_bot=0 is_shrink=n
3 0.004 8.5 2.76615 B m e v  arsize_top=0 arsize_bot=0 is_shrink=n
3 0.004 8.5 2.81615 B m e v  arsize_top=0 arsize_bot=0 is_shrink=n
3 0.004 8.5 2.86615 B m e v  arsize_top=0 arsize_bot=0 is_shrink=n
3 0.004 8.5 2.91615 B m e v  arsize_top=0 arsize_bot=0 is_shrink=n
3 0.004 8.5 2.96615 B m e v  arsize_top=0 arsize_bot=0 is_shrink=n
3 0.004 8.5 3.01615 B m e v  arsize_top=0 arsize_bot=0 is_shrink=n
3 0.004 8.5 3.06615 B m e v  arsize_top=0 arsize_bot=0 is_shrink=n
3 0.004 8.5 3.11615 B m e v  arsize_top=0 arsize_bot=0 is_shrink=n
3 0.004 8.5 3.16615 B m e v  arsize_top=0 arsize_bot=0 is_shrink=n
3 0.004 8.5 3.21615 B m e v  arsize_top=0 arsize_bot=0 is_shrink=n
3 0.004 8.5 3.26615 B m e v  arsize_top=0 arsize_bot=0 is_shrink=n
3 0.004 8.5 3.41615 B m e v  arsize_top=0 arsize_bot=0 is_shrink=n
3 0.004 8.5 3.56615 B m e v  arsize_top=0 arsize_bot=0 is_shrink=n
3 0.004 8.5 3.71615 B m e v  arsize_top=0 arsize_bot=0 is_shrink=n
3 0.004 8.5 3.86615 B m e v  arsize_top=0 arsize_bot=0 is_shrink=n
3 0.005 6.6015 4.89736 B m e v  arsize_top=0 arsize_bot=0 is_shrink=n
3 0.005 6.6015 4.93674 B m e v  arsize_top=0 arsize_bot=0 is_shrink=n
3 0.005 6.62119 4.87768 B m e v  arsize_top=0 arsize_bot=0 is_shrink=n
3 0.005 6.62119 4.91705 B m e v  arsize_top=0 arsize_bot=0 is_shrink=n
3 0.005 6.62119 4.95642 B m e v  arsize_top=0 arsize_bot=0 is_shrink=n
3 0.005 6.64088 4.89736 B m e v  arsize_top=0 arsize_bot=0 is_shrink=n
3 0.005 6.64088 4.93674 B m e v  arsize_top=0 arsize_bot=0 is_shrink=n
3 0.005 10.00731 0.036 B m e v  arsize_top=0 arsize_bot=0 is_shrink=n
3 0.005 10.01 2.191 B m e v  arsize_top=0 arsize_bot=0 is_shrink=n
3 0.005 10.01 2.2481 B m e v  arsize_top=0 arsize_bot=0 is_shrink=n
3 0.005 10.01 2.32725 B m e v  arsize_top=0 arsize_bot=0 is_shrink=n
3 0.005 10.01 2.38435 B m e v  arsize_top=0 arsize_bot=0 is_shrink=n
3 0.005 10.01 2.46235 B m e v  arsize_top=0 arsize_bot=0 is_shrink=n
3 0.005 10.01 2.51945 B m e v  arsize_top=0 arsize_bot=0 is_shrink=n
3 0.005 10.01 2.6159 B m e v  arsize_top=0 arsize_bot=0 is_shrink=n
3 0.005 10.01 2.673 B m e v  arsize_top=0 arsize_bot=0 is_shrink=n
3 0.005 10.02901 5.98762 B m e v  arsize_top=0 arsize_bot=0 is_shrink=n
3 0.005 10.03 4.51 B m e v  arsize_top=0 arsize_bot=0 is_shrink=n
3 0.005 10.05731 0.036 B m e v  arsize_top=0 arsize_bot=0 is_shrink=n
3 0.005 10.07901 5.98762 B m e v  arsize_top=0 arsize_bot=0 is_shrink=n
3 0.005 10.10731 0.036 B m e v  arsize_top=0 arsize_bot=0 is_shrink=n
3 0.005 10.11779 2.78 B m e v  arsize_top=0 arsize_bot=0 is_shrink=n
3 0.005 10.125 2.008 B m e v  arsize_top=0 arsize_bot=0 is_shrink=n
3 0.005 10.125 2.0651 B m e v  arsize_top=0 arsize_bot=0 is_shrink=n
3 0.005 10.125 2.1224 B m e v  arsize_top=0 arsize_bot=0 is_shrink=n
3 0.005 10.125 2.1795 B m e v  arsize_top=0 arsize_bot=0 is_shrink=n
3 0.005 10.125 2.2597 B m e v  arsize_top=0 arsize_bot=0 is_shrink=n
3 0.005 10.125 2.3168 B m e v  arsize_top=0 arsize_bot=0 is_shrink=n
3 0.005 10.125 2.3948 B m e v  arsize_top=0 arsize_bot=0 is_shrink=n
3 0.005 10.125 2.4519 B m e v  arsize_top=0 arsize_bot=0 is_shrink=n
3 0.005 10.125 2.5299 B m e v  arsize_top=0 arsize_bot=0 is_shrink=n
3 0.005 10.125 2.587 B m e v  arsize_top=0 arsize_bot=0 is_shrink=n
3 0.005 10.125 2.688 B m e v  arsize_top=0 arsize_bot=0 is_shrink=n
3 0.005 10.125 2.7451 B m e v  arsize_top=0 arsize_bot=0 is_shrink=n
3 0.005 10.12901 5.98762 B m e v  arsize_top=0 arsize_bot=0 is_shrink=n
3 0.005 10.15731 0.036 B m e v  arsize_top=0 arsize_bot=0 is_shrink=n
3 0.005 10.16607 2.81 B m e v  arsize_top=0 arsize_bot=0 is_shrink=n
3 0.005 10.17901 5.98762 B m e v  arsize_top=0 arsize_bot=0 is_shrink=n
3 0.005 10.20731 0.036 B m e v  arsize_top=0 arsize_bot=0 is_shrink=n
3 0.005 10.22901 5.98762 B m e v  arsize_top=0 arsize_bot=0 is_shrink=n
3 0.005 10.25731 0.036 B m e v  arsize_top=0 arsize_bot=0 is_shrink=n
3 0.005 10.26 1.9179 B m e v  arsize_top=0 arsize_bot=0 is_shrink=n
3 0.005 10.26 1.975 B m e v  arsize_top=0 arsize_bot=0 is_shrink=n
3 0.005 10.26499 4.9431 B m e v  arsize_top=0 arsize_bot=0 is_shrink=n
3 0.005 10.26499 4.9831 B m e v  arsize_top=0 arsize_bot=0 is_shrink=n
3 0.005 10.26499 5.0281 B m e v  arsize_top=0 arsize_bot=0 is_shrink=n
3 0.005 10.26499 5.0731 B m e v  arsize_top=0 arsize_bot=0 is_shrink=n
3 0.005 10.26499 5.1181 B m e v  arsize_top=0 arsize_bot=0 is_shrink=n
3 0.005 10.27901 5.98762 B m e v  arsize_top=0 arsize_bot=0 is_shrink=n
3 0.005 1.02874 0.036 B m e v  arsize_top=0 arsize_bot=0 is_shrink=n
3 0.005 1.02901 5.98762 B m e v  arsize_top=0 arsize_bot=0 is_shrink=n
3 0.005 10.295 1.6559 B m e v  arsize_top=0 arsize_bot=0 is_shrink=n
3 0.005 10.295 1.713 B m e v  arsize_top=0 arsize_bot=0 is_shrink=n
3 0.005 10.29525 1.8199 B m e v  arsize_top=0 arsize_bot=0 is_shrink=n
3 0.005 10.29525 1.877 B m e v  arsize_top=0 arsize_bot=0 is_shrink=n
3 0.005 1.03 5.065 B m e v  arsize_top=0 arsize_bot=0 is_shrink=n
3 0.005 10.30499 4.9431 B m e v  arsize_top=0 arsize_bot=0 is_shrink=n
3 0.005 10.30499 4.9831 B m e v  arsize_top=0 arsize_bot=0 is_shrink=n
3 0.005 10.30499 5.0281 B m e v  arsize_top=0 arsize_bot=0 is_shrink=n
3 0.005 10.30499 5.0731 B m e v  arsize_top=0 arsize_bot=0 is_shrink=n
3 0.005 10.30499 5.1181 B m e v  arsize_top=0 arsize_bot=0 is_shrink=n
3 0.005 10.30731 0.036 B m e v  arsize_top=0 arsize_bot=0 is_shrink=n
3 0.005 10.32901 5.98762 B m e v  arsize_top=0 arsize_bot=0 is_shrink=n
3 0.005 10.33999 4.9231 B m e v  arsize_top=0 arsize_bot=0 is_shrink=n
3 0.005 10.34499 5.1181 B m e v  arsize_top=0 arsize_bot=0 is_shrink=n
3 0.005 10.35731 0.036 B m e v  arsize_top=0 arsize_bot=0 is_shrink=n
3 0.005 10.37314 1.55336 B m e v  arsize_top=0 arsize_bot=0 is_shrink=n
3 0.005 10.37901 5.98762 B m e v  arsize_top=0 arsize_bot=0 is_shrink=n
3 0.005 10.38499 5.1181 B m e v  arsize_top=0 arsize_bot=0 is_shrink=n
3 0.005 10.40731 0.036 B m e v  arsize_top=0 arsize_bot=0 is_shrink=n
3 0.005 10.41451 1.51198 B m e v  arsize_top=0 arsize_bot=0 is_shrink=n
3 0.005 10.4159 1.43 B m e v  arsize_top=0 arsize_bot=0 is_shrink=n
3 0.005 10.42499 4.9431 B m e v  arsize_top=0 arsize_bot=0 is_shrink=n
3 0.005 10.42499 4.9831 B m e v  arsize_top=0 arsize_bot=0 is_shrink=n
3 0.005 10.42499 5.0281 B m e v  arsize_top=0 arsize_bot=0 is_shrink=n
3 0.005 10.42499 5.0731 B m e v  arsize_top=0 arsize_bot=0 is_shrink=n
3 0.005 10.42499 5.1181 B m e v  arsize_top=0 arsize_bot=0 is_shrink=n
3 0.005 10.42901 5.98762 B m e v  arsize_top=0 arsize_bot=0 is_shrink=n
3 0.005 10.43 1.277 B m e v  arsize_top=0 arsize_bot=0 is_shrink=n
3 0.005 10.43 1.3341 B m e v  arsize_top=0 arsize_bot=0 is_shrink=n
3 0.005 10.45731 0.036 B m e v  arsize_top=0 arsize_bot=0 is_shrink=n
3 0.005 10.46499 4.9431 B m e v  arsize_top=0 arsize_bot=0 is_shrink=n
3 0.005 10.46499 4.9831 B m e v  arsize_top=0 arsize_bot=0 is_shrink=n
3 0.005 10.46499 5.0281 B m e v  arsize_top=0 arsize_bot=0 is_shrink=n
3 0.005 10.46499 5.0731 B m e v  arsize_top=0 arsize_bot=0 is_shrink=n
3 0.005 10.46499 5.1181 B m e v  arsize_top=0 arsize_bot=0 is_shrink=n
3 0.005 10.465 5.165 B m e v  arsize_top=0 arsize_bot=0 is_shrink=n
3 0.005 10.465 5.195 B m e v  arsize_top=0 arsize_bot=0 is_shrink=n
3 0.005 10.465 5.245 B m e v  arsize_top=0 arsize_bot=0 is_shrink=n
3 0.005 10.465 5.275 B m e v  arsize_top=0 arsize_bot=0 is_shrink=n
3 0.005 10.473 1.43 B m e v  arsize_top=0 arsize_bot=0 is_shrink=n
3 0.005 10.47901 5.98762 B m e v  arsize_top=0 arsize_bot=0 is_shrink=n
3 0.005 10.50731 0.036 B m e v  arsize_top=0 arsize_bot=0 is_shrink=n
3 0.005 10.515 5.32 B m e v  arsize_top=0 arsize_bot=0 is_shrink=n
3 0.005 10.52901 5.98762 B m e v  arsize_top=0 arsize_bot=0 is_shrink=n
3 0.005 10.55731 0.036 B m e v  arsize_top=0 arsize_bot=0 is_shrink=n
3 0.005 10.57901 5.98762 B m e v  arsize_top=0 arsize_bot=0 is_shrink=n
3 0.005 10.60731 0.036 B m e v  arsize_top=0 arsize_bot=0 is_shrink=n
3 0.005 10.62901 5.98762 B m e v  arsize_top=0 arsize_bot=0 is_shrink=n
3 0.005 10.65499 4.9431 B m e v  arsize_top=0 arsize_bot=0 is_shrink=n
3 0.005 10.65499 4.9831 B m e v  arsize_top=0 arsize_bot=0 is_shrink=n
3 0.005 10.65499 5.0281 B m e v  arsize_top=0 arsize_bot=0 is_shrink=n
3 0.005 10.65499 5.0731 B m e v  arsize_top=0 arsize_bot=0 is_shrink=n
3 0.005 10.65499 5.1181 B m e v  arsize_top=0 arsize_bot=0 is_shrink=n
3 0.005 10.65731 0.036 B m e v  arsize_top=0 arsize_bot=0 is_shrink=n
3 0.005 10.67901 5.98762 B m e v  arsize_top=0 arsize_bot=0 is_shrink=n
3 0.005 10.69499 4.9431 B m e v  arsize_top=0 arsize_bot=0 is_shrink=n
3 0.005 10.69499 4.9831 B m e v  arsize_top=0 arsize_bot=0 is_shrink=n
3 0.005 10.69499 5.0281 B m e v  arsize_top=0 arsize_bot=0 is_shrink=n
3 0.005 10.69499 5.0731 B m e v  arsize_top=0 arsize_bot=0 is_shrink=n
3 0.005 10.69499 5.1181 B m e v  arsize_top=0 arsize_bot=0 is_shrink=n
3 0.005 10.70731 0.036 B m e v  arsize_top=0 arsize_bot=0 is_shrink=n
3 0.005 10.72901 5.98762 B m e v  arsize_top=0 arsize_bot=0 is_shrink=n
3 0.005 10.72999 4.9231 B m e v  arsize_top=0 arsize_bot=0 is_shrink=n
3 0.005 10.73499 5.1181 B m e v  arsize_top=0 arsize_bot=0 is_shrink=n
3 0.005 10.75731 0.036 B m e v  arsize_top=0 arsize_bot=0 is_shrink=n
3 0.005 10.77499 4.9231 B m e v  arsize_top=0 arsize_bot=0 is_shrink=n
3 0.005 10.77499 5.1181 B m e v  arsize_top=0 arsize_bot=0 is_shrink=n
3 0.005 10.77901 5.98762 B m e v  arsize_top=0 arsize_bot=0 is_shrink=n
3 0.005 1.07874 0.036 B m e v  arsize_top=0 arsize_bot=0 is_shrink=n
3 0.005 1.07901 5.98762 B m e v  arsize_top=0 arsize_bot=0 is_shrink=n
3 0.005 10.80499 5.42656 B m e v  arsize_top=0 arsize_bot=0 is_shrink=n
3 0.005 10.80499 5.56656 B m e v  arsize_top=0 arsize_bot=0 is_shrink=n
3 0.005 10.80731 0.036 B m e v  arsize_top=0 arsize_bot=0 is_shrink=n
3 0.005 10.81499 4.9431 B m e v  arsize_top=0 arsize_bot=0 is_shrink=n
3 0.005 10.81499 4.9831 B m e v  arsize_top=0 arsize_bot=0 is_shrink=n
3 0.005 10.81499 5.0281 B m e v  arsize_top=0 arsize_bot=0 is_shrink=n
3 0.005 10.81499 5.0731 B m e v  arsize_top=0 arsize_bot=0 is_shrink=n
3 0.005 10.81499 5.1181 B m e v  arsize_top=0 arsize_bot=0 is_shrink=n
3 0.005 10.82901 5.98762 B m e v  arsize_top=0 arsize_bot=0 is_shrink=n
3 0.005 10.84499 5.42656 B m e v  arsize_top=0 arsize_bot=0 is_shrink=n
3 0.005 10.84499 5.56656 B m e v  arsize_top=0 arsize_bot=0 is_shrink=n
3 0.005 10.85499 4.9431 B m e v  arsize_top=0 arsize_bot=0 is_shrink=n
3 0.005 10.85499 4.9831 B m e v  arsize_top=0 arsize_bot=0 is_shrink=n
3 0.005 10.85499 5.0281 B m e v  arsize_top=0 arsize_bot=0 is_shrink=n
3 0.005 10.85499 5.0731 B m e v  arsize_top=0 arsize_bot=0 is_shrink=n
3 0.005 10.85499 5.1181 B m e v  arsize_top=0 arsize_bot=0 is_shrink=n
3 0.005 10.85731 0.036 B m e v  arsize_top=0 arsize_bot=0 is_shrink=n
3 0.005 10.87901 5.98762 B m e v  arsize_top=0 arsize_bot=0 is_shrink=n
3 0.005 10.90731 0.036 B m e v  arsize_top=0 arsize_bot=0 is_shrink=n
3 0.005 10.92901 5.98762 B m e v  arsize_top=0 arsize_bot=0 is_shrink=n
3 0.005 10.95731 0.036 B m e v  arsize_top=0 arsize_bot=0 is_shrink=n
3 0.005 10.97035 5.42656 B m e v  arsize_top=0 arsize_bot=0 is_shrink=n
3 0.005 10.97035 5.56656 B m e v  arsize_top=0 arsize_bot=0 is_shrink=n
3 0.005 10.97901 5.98762 B m e v  arsize_top=0 arsize_bot=0 is_shrink=n
3 0.005 11.00731 0.036 B m e v  arsize_top=0 arsize_bot=0 is_shrink=n
3 0.005 11.01035 5.42656 B m e v  arsize_top=0 arsize_bot=0 is_shrink=n
3 0.005 11.01035 5.56656 B m e v  arsize_top=0 arsize_bot=0 is_shrink=n
3 0.005 11.02901 5.98762 B m e v  arsize_top=0 arsize_bot=0 is_shrink=n
3 0.005 11.05731 0.036 B m e v  arsize_top=0 arsize_bot=0 is_shrink=n
3 0.005 11.07901 5.98762 B m e v  arsize_top=0 arsize_bot=0 is_shrink=n
3 0.005 11.10731 0.036 B m e v  arsize_top=0 arsize_bot=0 is_shrink=n
3 0.005 11.12901 5.98762 B m e v  arsize_top=0 arsize_bot=0 is_shrink=n
3 0.005 11.13571 5.42656 B m e v  arsize_top=0 arsize_bot=0 is_shrink=n
3 0.005 11.13571 5.56656 B m e v  arsize_top=0 arsize_bot=0 is_shrink=n
3 0.005 11.15731 0.036 B m e v  arsize_top=0 arsize_bot=0 is_shrink=n
3 0.005 11.17571 5.42656 B m e v  arsize_top=0 arsize_bot=0 is_shrink=n
3 0.005 11.17571 5.56656 B m e v  arsize_top=0 arsize_bot=0 is_shrink=n
3 0.005 11.17901 5.98762 B m e v  arsize_top=0 arsize_bot=0 is_shrink=n
3 0.005 11.20731 0.036 B m e v  arsize_top=0 arsize_bot=0 is_shrink=n
3 0.005 11.22901 5.98762 B m e v  arsize_top=0 arsize_bot=0 is_shrink=n
3 0.005 1.12303 5.46016 B m e v  arsize_top=0 arsize_bot=0 is_shrink=n
3 0.005 11.25731 0.036 B m e v  arsize_top=0 arsize_bot=0 is_shrink=n
3 0.005 11.27901 5.98762 B m e v  arsize_top=0 arsize_bot=0 is_shrink=n
3 0.005 1.12874 0.036 B m e v  arsize_top=0 arsize_bot=0 is_shrink=n
3 0.005 1.12901 5.98762 B m e v  arsize_top=0 arsize_bot=0 is_shrink=n
3 0.005 11.30107 5.42656 B m e v  arsize_top=0 arsize_bot=0 is_shrink=n
3 0.005 11.30107 5.56656 B m e v  arsize_top=0 arsize_bot=0 is_shrink=n
3 0.005 11.30731 0.036 B m e v  arsize_top=0 arsize_bot=0 is_shrink=n
3 0.005 11.32901 5.98762 B m e v  arsize_top=0 arsize_bot=0 is_shrink=n
3 0.005 11.34107 5.42656 B m e v  arsize_top=0 arsize_bot=0 is_shrink=n
3 0.005 11.34107 5.56656 B m e v  arsize_top=0 arsize_bot=0 is_shrink=n
3 0.005 11.35731 0.036 B m e v  arsize_top=0 arsize_bot=0 is_shrink=n
3 0.005 11.37901 5.98762 B m e v  arsize_top=0 arsize_bot=0 is_shrink=n
3 0.005 11.40731 0.036 B m e v  arsize_top=0 arsize_bot=0 is_shrink=n
3 0.005 11.42901 5.98762 B m e v  arsize_top=0 arsize_bot=0 is_shrink=n
3 0.005 11.45279 2.9414 B m e v  arsize_top=0 arsize_bot=0 is_shrink=n
3 0.005 11.45279 2.9764 B m e v  arsize_top=0 arsize_bot=0 is_shrink=n
3 0.005 11.45279 3.0214 B m e v  arsize_top=0 arsize_bot=0 is_shrink=n
3 0.005 11.45279 3.0564 B m e v  arsize_top=0 arsize_bot=0 is_shrink=n
3 0.005 11.45279 3.1014 B m e v  arsize_top=0 arsize_bot=0 is_shrink=n
3 0.005 11.45279 3.1364 B m e v  arsize_top=0 arsize_bot=0 is_shrink=n
3 0.005 11.45279 3.1814 B m e v  arsize_top=0 arsize_bot=0 is_shrink=n
3 0.005 11.45279 3.2164 B m e v  arsize_top=0 arsize_bot=0 is_shrink=n
3 0.005 11.45279 3.2614 B m e v  arsize_top=0 arsize_bot=0 is_shrink=n
3 0.005 11.45279 3.2964 B m e v  arsize_top=0 arsize_bot=0 is_shrink=n
3 0.005 11.45731 0.036 B m e v  arsize_top=0 arsize_bot=0 is_shrink=n
3 0.005 11.46643 5.42656 B m e v  arsize_top=0 arsize_bot=0 is_shrink=n
3 0.005 11.46643 5.56656 B m e v  arsize_top=0 arsize_bot=0 is_shrink=n
3 0.005 11.47901 5.98762 B m e v  arsize_top=0 arsize_bot=0 is_shrink=n
3 0.005 11.49316 1.4635 B m e v  arsize_top=0 arsize_bot=0 is_shrink=n
3 0.005 11.49316 1.5605 B m e v  arsize_top=0 arsize_bot=0 is_shrink=n
3 0.005 11.49316 1.6235 B m e v  arsize_top=0 arsize_bot=0 is_shrink=n
3 0.005 11.49316 1.7835 B m e v  arsize_top=0 arsize_bot=0 is_shrink=n
3 0.005 11.49316 1.8805 B m e v  arsize_top=0 arsize_bot=0 is_shrink=n
3 0.005 11.49316 1.9435 B m e v  arsize_top=0 arsize_bot=0 is_shrink=n
3 0.005 11.49316 2.0405 B m e v  arsize_top=0 arsize_bot=0 is_shrink=n
3 0.005 11.49316 2.1035 B m e v  arsize_top=0 arsize_bot=0 is_shrink=n
3 0.005 11.49316 2.3605 B m e v  arsize_top=0 arsize_bot=0 is_shrink=n
3 0.005 11.49316 2.4235 B m e v  arsize_top=0 arsize_bot=0 is_shrink=n
3 0.005 11.49316 2.5205 B m e v  arsize_top=0 arsize_bot=0 is_shrink=n
3 0.005 11.49316 2.5835 B m e v  arsize_top=0 arsize_bot=0 is_shrink=n
3 0.005 11.49366 1.401 B m e v  arsize_top=0 arsize_bot=0 is_shrink=n
3 0.005 11.49366 1.721 B m e v  arsize_top=0 arsize_bot=0 is_shrink=n
3 0.005 11.50362 2.73 B m e v  arsize_top=0 arsize_bot=0 is_shrink=n
3 0.005 11.50362 2.8 B m e v  arsize_top=0 arsize_bot=0 is_shrink=n
3 0.005 11.50643 5.42656 B m e v  arsize_top=0 arsize_bot=0 is_shrink=n
3 0.005 11.50643 5.56656 B m e v  arsize_top=0 arsize_bot=0 is_shrink=n
3 0.005 11.50731 0.036 B m e v  arsize_top=0 arsize_bot=0 is_shrink=n
3 0.005 11.52901 5.98762 B m e v  arsize_top=0 arsize_bot=0 is_shrink=n
3 0.005 11.55731 0.036 B m e v  arsize_top=0 arsize_bot=0 is_shrink=n
3 0.005 11.57901 5.98762 B m e v  arsize_top=0 arsize_bot=0 is_shrink=n
3 0.005 11.58613 2.855 B m e v  arsize_top=0 arsize_bot=0 is_shrink=n
3 0.005 11.60731 0.036 B m e v  arsize_top=0 arsize_bot=0 is_shrink=n
3 0.005 11.62901 5.98762 B m e v  arsize_top=0 arsize_bot=0 is_shrink=n
3 0.005 11.63179 5.42656 B m e v  arsize_top=0 arsize_bot=0 is_shrink=n
3 0.005 11.63179 5.56656 B m e v  arsize_top=0 arsize_bot=0 is_shrink=n
3 0.005 11.65731 0.036 B m e v  arsize_top=0 arsize_bot=0 is_shrink=n
3 0.005 11.67179 5.42656 B m e v  arsize_top=0 arsize_bot=0 is_shrink=n
3 0.005 11.67179 5.56656 B m e v  arsize_top=0 arsize_bot=0 is_shrink=n
3 0.005 11.67901 5.98762 B m e v  arsize_top=0 arsize_bot=0 is_shrink=n
3 0.005 11.69316 1.4805 B m e v  arsize_top=0 arsize_bot=0 is_shrink=n
3 0.005 11.69316 1.5435 B m e v  arsize_top=0 arsize_bot=0 is_shrink=n
3 0.005 11.69316 1.8005 B m e v  arsize_top=0 arsize_bot=0 is_shrink=n
3 0.005 11.69316 1.8635 B m e v  arsize_top=0 arsize_bot=0 is_shrink=n
3 0.005 11.69316 1.9605 B m e v  arsize_top=0 arsize_bot=0 is_shrink=n
3 0.005 11.69316 2.0235 B m e v  arsize_top=0 arsize_bot=0 is_shrink=n
3 0.005 11.69316 2.1205 B m e v  arsize_top=0 arsize_bot=0 is_shrink=n
3 0.005 11.69316 2.1835 B m e v  arsize_top=0 arsize_bot=0 is_shrink=n
3 0.005 11.69316 2.2805 B m e v  arsize_top=0 arsize_bot=0 is_shrink=n
3 0.005 11.69316 2.3435 B m e v  arsize_top=0 arsize_bot=0 is_shrink=n
3 0.005 11.69316 2.4405 B m e v  arsize_top=0 arsize_bot=0 is_shrink=n
3 0.005 11.69316 2.5035 B m e v  arsize_top=0 arsize_bot=0 is_shrink=n
3 0.005 11.69316 2.6005 B m e v  arsize_top=0 arsize_bot=0 is_shrink=n
3 0.005 11.69316 2.6635 B m e v  arsize_top=0 arsize_bot=0 is_shrink=n
3 0.005 11.70731 0.036 B m e v  arsize_top=0 arsize_bot=0 is_shrink=n
3 0.005 11.72901 5.98762 B m e v  arsize_top=0 arsize_bot=0 is_shrink=n
3 0.005 11.74316 1.6405 B m e v  arsize_top=0 arsize_bot=0 is_shrink=n
3 0.005 11.74316 1.7035 B m e v  arsize_top=0 arsize_bot=0 is_shrink=n
3 0.005 11.75731 0.036 B m e v  arsize_top=0 arsize_bot=0 is_shrink=n
3 0.005 11.7719 4.80999 B m e v  arsize_top=0 arsize_bot=0 is_shrink=n
3 0.005 11.7719 4.85499 B m e v  arsize_top=0 arsize_bot=0 is_shrink=n
3 0.005 11.7719 4.90499 B m e v  arsize_top=0 arsize_bot=0 is_shrink=n
3 0.005 11.7719 4.94999 B m e v  arsize_top=0 arsize_bot=0 is_shrink=n
3 0.005 11.77901 5.98762 B m e v  arsize_top=0 arsize_bot=0 is_shrink=n
3 0.005 1.17874 0.036 B m e v  arsize_top=0 arsize_bot=0 is_shrink=n
3 0.005 1.17901 5.98762 B m e v  arsize_top=0 arsize_bot=0 is_shrink=n
3 0.005 11.79316 2.2005 B m e v  arsize_top=0 arsize_bot=0 is_shrink=n
3 0.005 11.79316 2.2635 B m e v  arsize_top=0 arsize_bot=0 is_shrink=n
3 0.005 11.79715 5.42656 B m e v  arsize_top=0 arsize_bot=0 is_shrink=n
3 0.005 11.79715 5.56656 B m e v  arsize_top=0 arsize_bot=0 is_shrink=n
3 0.005 11.80731 0.036 B m e v  arsize_top=0 arsize_bot=0 is_shrink=n
3 0.005 11.8219 4.80999 B m e v  arsize_top=0 arsize_bot=0 is_shrink=n
3 0.005 11.8219 4.94999 B m e v  arsize_top=0 arsize_bot=0 is_shrink=n
3 0.005 11.82901 5.98762 B m e v  arsize_top=0 arsize_bot=0 is_shrink=n
3 0.005 11.83715 5.42656 B m e v  arsize_top=0 arsize_bot=0 is_shrink=n
3 0.005 11.83715 5.56656 B m e v  arsize_top=0 arsize_bot=0 is_shrink=n
3 0.005 11.845 2.85 B m e v  arsize_top=0 arsize_bot=0 is_shrink=n
3 0.005 11.85731 0.036 B m e v  arsize_top=0 arsize_bot=0 is_shrink=n
3 0.005 11.8719 4.80999 B m e v  arsize_top=0 arsize_bot=0 is_shrink=n
3 0.005 11.8719 4.94999 B m e v  arsize_top=0 arsize_bot=0 is_shrink=n
3 0.005 11.87901 5.98762 B m e v  arsize_top=0 arsize_bot=0 is_shrink=n
3 0.005 1.18906 5.04351 B m e v  arsize_top=0 arsize_bot=0 is_shrink=n
3 0.005 11.90731 0.036 B m e v  arsize_top=0 arsize_bot=0 is_shrink=n
3 0.005 11.9219 4.80999 B m e v  arsize_top=0 arsize_bot=0 is_shrink=n
3 0.005 11.9219 4.94999 B m e v  arsize_top=0 arsize_bot=0 is_shrink=n
3 0.005 11.92901 5.98762 B m e v  arsize_top=0 arsize_bot=0 is_shrink=n
3 0.005 11.95731 0.036 B m e v  arsize_top=0 arsize_bot=0 is_shrink=n
3 0.005 11.96251 5.42656 B m e v  arsize_top=0 arsize_bot=0 is_shrink=n
3 0.005 11.96251 5.56656 B m e v  arsize_top=0 arsize_bot=0 is_shrink=n
3 0.005 11.9719 4.80999 B m e v  arsize_top=0 arsize_bot=0 is_shrink=n
3 0.005 11.9719 4.85499 B m e v  arsize_top=0 arsize_bot=0 is_shrink=n
3 0.005 11.9719 4.90499 B m e v  arsize_top=0 arsize_bot=0 is_shrink=n
3 0.005 11.9719 4.94999 B m e v  arsize_top=0 arsize_bot=0 is_shrink=n
3 0.005 11.97901 5.98762 B m e v  arsize_top=0 arsize_bot=0 is_shrink=n
3 0.005 12.00251 5.42656 B m e v  arsize_top=0 arsize_bot=0 is_shrink=n
3 0.005 12.00251 5.56656 B m e v  arsize_top=0 arsize_bot=0 is_shrink=n
3 0.005 12.00731 0.036 B m e v  arsize_top=0 arsize_bot=0 is_shrink=n
3 0.005 1.20177 5.46016 B m e v  arsize_top=0 arsize_bot=0 is_shrink=n
3 0.005 1.20177 5.78 B m e v  arsize_top=0 arsize_bot=0 is_shrink=n
3 0.005 12.025 4.915 B m e v  arsize_top=0 arsize_bot=0 is_shrink=n
3 0.005 12.02901 5.98762 B m e v  arsize_top=0 arsize_bot=0 is_shrink=n
3 0.005 12.055 4.915 B m e v  arsize_top=0 arsize_bot=0 is_shrink=n
3 0.005 12.05731 0.036 B m e v  arsize_top=0 arsize_bot=0 is_shrink=n
3 0.005 12.07901 5.98762 B m e v  arsize_top=0 arsize_bot=0 is_shrink=n
3 0.005 12.10731 0.036 B m e v  arsize_top=0 arsize_bot=0 is_shrink=n
3 0.005 12.12 4.965 B m e v  arsize_top=0 arsize_bot=0 is_shrink=n
3 0.005 12.12787 5.42656 B m e v  arsize_top=0 arsize_bot=0 is_shrink=n
3 0.005 12.12787 5.56656 B m e v  arsize_top=0 arsize_bot=0 is_shrink=n
3 0.005 12.12901 5.98762 B m e v  arsize_top=0 arsize_bot=0 is_shrink=n
3 0.005 12.15731 0.036 B m e v  arsize_top=0 arsize_bot=0 is_shrink=n
3 0.005 12.16787 5.42656 B m e v  arsize_top=0 arsize_bot=0 is_shrink=n
3 0.005 12.16787 5.56656 B m e v  arsize_top=0 arsize_bot=0 is_shrink=n
3 0.005 12.17901 5.98762 B m e v  arsize_top=0 arsize_bot=0 is_shrink=n
3 0.005 12.185 4.915 B m e v  arsize_top=0 arsize_bot=0 is_shrink=n
3 0.005 12.20731 0.036 B m e v  arsize_top=0 arsize_bot=0 is_shrink=n
3 0.005 12.215 4.915 B m e v  arsize_top=0 arsize_bot=0 is_shrink=n
3 0.005 12.22901 5.98762 B m e v  arsize_top=0 arsize_bot=0 is_shrink=n
3 0.005 12.25731 0.036 B m e v  arsize_top=0 arsize_bot=0 is_shrink=n
3 0.005 12.27901 5.98762 B m e v  arsize_top=0 arsize_bot=0 is_shrink=n
3 0.005 1.22874 0.036 B m e v  arsize_top=0 arsize_bot=0 is_shrink=n
3 0.005 1.22901 5.98762 B m e v  arsize_top=0 arsize_bot=0 is_shrink=n
3 0.005 12.30731 0.036 B m e v  arsize_top=0 arsize_bot=0 is_shrink=n
3 0.005 12.32901 5.98762 B m e v  arsize_top=0 arsize_bot=0 is_shrink=n
3 0.005 12.34 2.19 B m e v  arsize_top=0 arsize_bot=0 is_shrink=n
3 0.005 12.35731 0.036 B m e v  arsize_top=0 arsize_bot=0 is_shrink=n
3 0.005 12.37901 5.98762 B m e v  arsize_top=0 arsize_bot=0 is_shrink=n
3 0.005 1.23906 4.60351 B m e v  arsize_top=0 arsize_bot=0 is_shrink=n
3 0.005 12.40731 0.036 B m e v  arsize_top=0 arsize_bot=0 is_shrink=n
3 0.005 12.42901 5.98762 B m e v  arsize_top=0 arsize_bot=0 is_shrink=n
3 0.005 12.45731 0.036 B m e v  arsize_top=0 arsize_bot=0 is_shrink=n
3 0.005 12.47901 5.98762 B m e v  arsize_top=0 arsize_bot=0 is_shrink=n
3 0.005 12.50731 0.036 B m e v  arsize_top=0 arsize_bot=0 is_shrink=n
3 0.005 12.52901 5.98762 B m e v  arsize_top=0 arsize_bot=0 is_shrink=n
3 0.005 12.55731 0.036 B m e v  arsize_top=0 arsize_bot=0 is_shrink=n
3 0.005 12.57901 5.98762 B m e v  arsize_top=0 arsize_bot=0 is_shrink=n
3 0.005 12.60731 0.036 B m e v  arsize_top=0 arsize_bot=0 is_shrink=n
3 0.005 12.62901 5.98762 B m e v  arsize_top=0 arsize_bot=0 is_shrink=n
3 0.005 12.65731 0.036 B m e v  arsize_top=0 arsize_bot=0 is_shrink=n
3 0.005 12.67901 5.98762 B m e v  arsize_top=0 arsize_bot=0 is_shrink=n
3 0.005 12.70731 0.036 B m e v  arsize_top=0 arsize_bot=0 is_shrink=n
3 0.005 12.72901 5.98762 B m e v  arsize_top=0 arsize_bot=0 is_shrink=n
3 0.005 12.75731 0.036 B m e v  arsize_top=0 arsize_bot=0 is_shrink=n
3 0.005 12.77901 5.98762 B m e v  arsize_top=0 arsize_bot=0 is_shrink=n
3 0.005 1.27874 0.036 B m e v  arsize_top=0 arsize_bot=0 is_shrink=n
3 0.005 1.27901 5.98762 B m e v  arsize_top=0 arsize_bot=0 is_shrink=n
3 0.005 0.12874 0.036 B m e v  arsize_top=0 arsize_bot=0 is_shrink=n
3 0.005 1.28051 5.46016 B m e v  arsize_top=0 arsize_bot=0 is_shrink=n
3 0.005 1.28051 5.78 B m e v  arsize_top=0 arsize_bot=0 is_shrink=n
3 0.005 12.80731 0.036 B m e v  arsize_top=0 arsize_bot=0 is_shrink=n
3 0.005 12.82901 5.98762 B m e v  arsize_top=0 arsize_bot=0 is_shrink=n
3 0.005 12.85729 0.03739 B m e v  arsize_top=0 arsize_bot=0 is_shrink=n
3 0.005 12.87726 5.97451 B m e v  arsize_top=0 arsize_bot=0 is_shrink=n
3 0.005 12.88911 0.07596 B m e v  arsize_top=0 arsize_bot=0 is_shrink=n
3 0.005 12.8892 1.02596 B m e v  arsize_top=0 arsize_bot=0 is_shrink=n
3 0.005 12.8892 1.07596 B m e v  arsize_top=0 arsize_bot=0 is_shrink=n
3 0.005 12.8892 1.12596 B m e v  arsize_top=0 arsize_bot=0 is_shrink=n
3 0.005 12.8892 1.17596 B m e v  arsize_top=0 arsize_bot=0 is_shrink=n
3 0.005 12.8892 1.22596 B m e v  arsize_top=0 arsize_bot=0 is_shrink=n
3 0.005 12.8892 0.12596 B m e v  arsize_top=0 arsize_bot=0 is_shrink=n
3 0.005 12.8892 1.27596 B m e v  arsize_top=0 arsize_bot=0 is_shrink=n
3 0.005 12.8892 1.32596 B m e v  arsize_top=0 arsize_bot=0 is_shrink=n
3 0.005 12.8892 1.37596 B m e v  arsize_top=0 arsize_bot=0 is_shrink=n
3 0.005 12.8892 1.42596 B m e v  arsize_top=0 arsize_bot=0 is_shrink=n
3 0.005 12.8892 1.47596 B m e v  arsize_top=0 arsize_bot=0 is_shrink=n
3 0.005 12.8892 1.52596 B m e v  arsize_top=0 arsize_bot=0 is_shrink=n
3 0.005 12.8892 1.57596 B m e v  arsize_top=0 arsize_bot=0 is_shrink=n
3 0.005 12.8892 1.62596 B m e v  arsize_top=0 arsize_bot=0 is_shrink=n
3 0.005 12.8892 1.67596 B m e v  arsize_top=0 arsize_bot=0 is_shrink=n
3 0.005 12.8892 1.72596 B m e v  arsize_top=0 arsize_bot=0 is_shrink=n
3 0.005 12.8892 0.17596 B m e v  arsize_top=0 arsize_bot=0 is_shrink=n
3 0.005 12.8892 1.77596 B m e v  arsize_top=0 arsize_bot=0 is_shrink=n
3 0.005 12.8892 1.82596 B m e v  arsize_top=0 arsize_bot=0 is_shrink=n
3 0.005 12.8892 1.87596 B m e v  arsize_top=0 arsize_bot=0 is_shrink=n
3 0.005 12.8892 1.92596 B m e v  arsize_top=0 arsize_bot=0 is_shrink=n
3 0.005 12.8892 1.97596 B m e v  arsize_top=0 arsize_bot=0 is_shrink=n
3 0.005 12.8892 2.02596 B m e v  arsize_top=0 arsize_bot=0 is_shrink=n
3 0.005 12.8892 2.07596 B m e v  arsize_top=0 arsize_bot=0 is_shrink=n
3 0.005 12.8892 2.17596 B m e v  arsize_top=0 arsize_bot=0 is_shrink=n
3 0.005 12.8892 2.22596 B m e v  arsize_top=0 arsize_bot=0 is_shrink=n
3 0.005 12.8892 0.22596 B m e v  arsize_top=0 arsize_bot=0 is_shrink=n
3 0.005 12.8892 2.27596 B m e v  arsize_top=0 arsize_bot=0 is_shrink=n
3 0.005 12.8892 2.32596 B m e v  arsize_top=0 arsize_bot=0 is_shrink=n
3 0.005 12.8892 2.37596 B m e v  arsize_top=0 arsize_bot=0 is_shrink=n
3 0.005 12.8892 2.42596 B m e v  arsize_top=0 arsize_bot=0 is_shrink=n
3 0.005 12.8892 2.47596 B m e v  arsize_top=0 arsize_bot=0 is_shrink=n
3 0.005 12.8892 2.52596 B m e v  arsize_top=0 arsize_bot=0 is_shrink=n
3 0.005 12.8892 2.57596 B m e v  arsize_top=0 arsize_bot=0 is_shrink=n
3 0.005 12.8892 2.62596 B m e v  arsize_top=0 arsize_bot=0 is_shrink=n
3 0.005 12.8892 2.67596 B m e v  arsize_top=0 arsize_bot=0 is_shrink=n
3 0.005 12.8892 2.72596 B m e v  arsize_top=0 arsize_bot=0 is_shrink=n
3 0.005 12.8892 0.27596 B m e v  arsize_top=0 arsize_bot=0 is_shrink=n
3 0.005 12.8892 2.77596 B m e v  arsize_top=0 arsize_bot=0 is_shrink=n
3 0.005 12.8892 2.82596 B m e v  arsize_top=0 arsize_bot=0 is_shrink=n
3 0.005 12.8892 2.87596 B m e v  arsize_top=0 arsize_bot=0 is_shrink=n
3 0.005 12.8892 2.92596 B m e v  arsize_top=0 arsize_bot=0 is_shrink=n
3 0.005 12.8892 2.97596 B m e v  arsize_top=0 arsize_bot=0 is_shrink=n
3 0.005 12.8892 3.02596 B m e v  arsize_top=0 arsize_bot=0 is_shrink=n
3 0.005 12.8892 3.07596 B m e v  arsize_top=0 arsize_bot=0 is_shrink=n
3 0.005 12.8892 3.12596 B m e v  arsize_top=0 arsize_bot=0 is_shrink=n
3 0.005 12.8892 3.17596 B m e v  arsize_top=0 arsize_bot=0 is_shrink=n
3 0.005 12.8892 3.22596 B m e v  arsize_top=0 arsize_bot=0 is_shrink=n
3 0.005 12.8892 0.32596 B m e v  arsize_top=0 arsize_bot=0 is_shrink=n
3 0.005 12.8892 3.27596 B m e v  arsize_top=0 arsize_bot=0 is_shrink=n
3 0.005 12.8892 3.32596 B m e v  arsize_top=0 arsize_bot=0 is_shrink=n
3 0.005 12.8892 3.37596 B m e v  arsize_top=0 arsize_bot=0 is_shrink=n
3 0.005 12.8892 3.42596 B m e v  arsize_top=0 arsize_bot=0 is_shrink=n
3 0.005 12.8892 3.47596 B m e v  arsize_top=0 arsize_bot=0 is_shrink=n
3 0.005 12.8892 3.52596 B m e v  arsize_top=0 arsize_bot=0 is_shrink=n
3 0.005 12.8892 3.57596 B m e v  arsize_top=0 arsize_bot=0 is_shrink=n
3 0.005 12.8892 3.62596 B m e v  arsize_top=0 arsize_bot=0 is_shrink=n
3 0.005 12.8892 3.67596 B m e v  arsize_top=0 arsize_bot=0 is_shrink=n
3 0.005 12.8892 3.72596 B m e v  arsize_top=0 arsize_bot=0 is_shrink=n
3 0.005 12.8892 0.37596 B m e v  arsize_top=0 arsize_bot=0 is_shrink=n
3 0.005 12.8892 3.77596 B m e v  arsize_top=0 arsize_bot=0 is_shrink=n
3 0.005 12.8892 3.82596 B m e v  arsize_top=0 arsize_bot=0 is_shrink=n
3 0.005 12.8892 3.87596 B m e v  arsize_top=0 arsize_bot=0 is_shrink=n
3 0.005 12.8892 3.92596 B m e v  arsize_top=0 arsize_bot=0 is_shrink=n
3 0.005 12.8892 3.97596 B m e v  arsize_top=0 arsize_bot=0 is_shrink=n
3 0.005 12.8892 4.02596 B m e v  arsize_top=0 arsize_bot=0 is_shrink=n
3 0.005 12.8892 4.07596 B m e v  arsize_top=0 arsize_bot=0 is_shrink=n
3 0.005 12.8892 4.12596 B m e v  arsize_top=0 arsize_bot=0 is_shrink=n
3 0.005 12.8892 4.17596 B m e v  arsize_top=0 arsize_bot=0 is_shrink=n
3 0.005 12.8892 4.22596 B m e v  arsize_top=0 arsize_bot=0 is_shrink=n
3 0.005 12.8892 0.42596 B m e v  arsize_top=0 arsize_bot=0 is_shrink=n
3 0.005 12.8892 4.27596 B m e v  arsize_top=0 arsize_bot=0 is_shrink=n
3 0.005 12.8892 4.32596 B m e v  arsize_top=0 arsize_bot=0 is_shrink=n
3 0.005 12.8892 4.37596 B m e v  arsize_top=0 arsize_bot=0 is_shrink=n
3 0.005 12.8892 4.42596 B m e v  arsize_top=0 arsize_bot=0 is_shrink=n
3 0.005 12.8892 4.47596 B m e v  arsize_top=0 arsize_bot=0 is_shrink=n
3 0.005 12.8892 4.52596 B m e v  arsize_top=0 arsize_bot=0 is_shrink=n
3 0.005 12.8892 4.57596 B m e v  arsize_top=0 arsize_bot=0 is_shrink=n
3 0.005 12.8892 4.62596 B m e v  arsize_top=0 arsize_bot=0 is_shrink=n
3 0.005 12.8892 4.67596 B m e v  arsize_top=0 arsize_bot=0 is_shrink=n
3 0.005 12.8892 4.72596 B m e v  arsize_top=0 arsize_bot=0 is_shrink=n
3 0.005 12.8892 0.47596 B m e v  arsize_top=0 arsize_bot=0 is_shrink=n
3 0.005 12.8892 4.77596 B m e v  arsize_top=0 arsize_bot=0 is_shrink=n
3 0.005 12.8892 4.82596 B m e v  arsize_top=0 arsize_bot=0 is_shrink=n
3 0.005 12.8892 0.52596 B m e v  arsize_top=0 arsize_bot=0 is_shrink=n
3 0.005 12.8892 5.27596 B m e v  arsize_top=0 arsize_bot=0 is_shrink=n
3 0.005 12.8892 5.32596 B m e v  arsize_top=0 arsize_bot=0 is_shrink=n
3 0.005 12.8892 5.37596 B m e v  arsize_top=0 arsize_bot=0 is_shrink=n
3 0.005 12.8892 5.42596 B m e v  arsize_top=0 arsize_bot=0 is_shrink=n
3 0.005 12.8892 5.47596 B m e v  arsize_top=0 arsize_bot=0 is_shrink=n
3 0.005 12.8892 5.52596 B m e v  arsize_top=0 arsize_bot=0 is_shrink=n
3 0.005 12.8892 5.57596 B m e v  arsize_top=0 arsize_bot=0 is_shrink=n
3 0.005 12.8892 5.62596 B m e v  arsize_top=0 arsize_bot=0 is_shrink=n
3 0.005 12.8892 5.67596 B m e v  arsize_top=0 arsize_bot=0 is_shrink=n
3 0.005 12.8892 5.72596 B m e v  arsize_top=0 arsize_bot=0 is_shrink=n
3 0.005 12.8892 0.57596 B m e v  arsize_top=0 arsize_bot=0 is_shrink=n
3 0.005 12.8892 5.77596 B m e v  arsize_top=0 arsize_bot=0 is_shrink=n
3 0.005 12.8892 5.82596 B m e v  arsize_top=0 arsize_bot=0 is_shrink=n
3 0.005 12.8892 5.87596 B m e v  arsize_top=0 arsize_bot=0 is_shrink=n
3 0.005 12.8892 5.92596 B m e v  arsize_top=0 arsize_bot=0 is_shrink=n
3 0.005 12.8892 0.62596 B m e v  arsize_top=0 arsize_bot=0 is_shrink=n
3 0.005 0.12901 5.98762 B m e v  arsize_top=0 arsize_bot=0 is_shrink=n
3 0.005 1.305 5.885 B m e v  arsize_top=0 arsize_bot=0 is_shrink=n
3 0.005 1.31 5.355 B m e v  arsize_top=0 arsize_bot=0 is_shrink=n
3 0.005 1.32874 0.036 B m e v  arsize_top=0 arsize_bot=0 is_shrink=n
3 0.005 1.32901 5.98762 B m e v  arsize_top=0 arsize_bot=0 is_shrink=n
3 0.005 1.33656 4.85601 B m e v  arsize_top=0 arsize_bot=0 is_shrink=n
3 0.005 1.355 5.885 B m e v  arsize_top=0 arsize_bot=0 is_shrink=n
3 0.005 1.36 5.355 B m e v  arsize_top=0 arsize_bot=0 is_shrink=n
3 0.005 1.37874 0.036 B m e v  arsize_top=0 arsize_bot=0 is_shrink=n
3 0.005 1.37901 5.98762 B m e v  arsize_top=0 arsize_bot=0 is_shrink=n
3 0.005 1.405 5.885 B m e v  arsize_top=0 arsize_bot=0 is_shrink=n
3 0.005 1.41 5.355 B m e v  arsize_top=0 arsize_bot=0 is_shrink=n
3 0.005 1.42874 0.036 B m e v  arsize_top=0 arsize_bot=0 is_shrink=n
3 0.005 1.42901 5.98762 B m e v  arsize_top=0 arsize_bot=0 is_shrink=n
3 0.005 1.455 5.885 B m e v  arsize_top=0 arsize_bot=0 is_shrink=n
3 0.005 1.46 5.355 B m e v  arsize_top=0 arsize_bot=0 is_shrink=n
3 0.005 1.47874 0.036 B m e v  arsize_top=0 arsize_bot=0 is_shrink=n
3 0.005 1.47901 5.98762 B m e v  arsize_top=0 arsize_bot=0 is_shrink=n
3 0.005 1.51673 5.46016 B m e v  arsize_top=0 arsize_bot=0 is_shrink=n
3 0.005 1.51673 5.78 B m e v  arsize_top=0 arsize_bot=0 is_shrink=n
3 0.005 1.52874 0.036 B m e v  arsize_top=0 arsize_bot=0 is_shrink=n
3 0.005 1.52901 5.98762 B m e v  arsize_top=0 arsize_bot=0 is_shrink=n
3 0.005 1.56221 4.81402 B m e v  arsize_top=0 arsize_bot=0 is_shrink=n
3 0.005 1.56221 5.023 B m e v  arsize_top=0 arsize_bot=0 is_shrink=n
3 0.005 1.56765 4.66826 B m e v  arsize_top=0 arsize_bot=0 is_shrink=n
3 0.005 1.56765 5.13026 B m e v  arsize_top=0 arsize_bot=0 is_shrink=n
3 0.005 1.57874 0.036 B m e v  arsize_top=0 arsize_bot=0 is_shrink=n
3 0.005 1.57901 5.98762 B m e v  arsize_top=0 arsize_bot=0 is_shrink=n
3 0.005 1.62765 4.66826 B m e v  arsize_top=0 arsize_bot=0 is_shrink=n
3 0.005 1.62765 5.13026 B m e v  arsize_top=0 arsize_bot=0 is_shrink=n
3 0.005 1.62874 0.036 B m e v  arsize_top=0 arsize_bot=0 is_shrink=n
3 0.005 1.62901 5.98762 B m e v  arsize_top=0 arsize_bot=0 is_shrink=n
3 0.005 1.63173 4.81527 B m e v  arsize_top=0 arsize_bot=0 is_shrink=n
3 0.005 1.63308 4.92 B m e v  arsize_top=0 arsize_bot=0 is_shrink=n
3 0.005 1.63308 5.023 B m e v  arsize_top=0 arsize_bot=0 is_shrink=n
3 0.005 1.6385 5.09224 B m e v  arsize_top=0 arsize_bot=0 is_shrink=n
3 0.005 1.63851 4.74418 B m e v  arsize_top=0 arsize_bot=0 is_shrink=n
3 0.005 1.67874 0.036 B m e v  arsize_top=0 arsize_bot=0 is_shrink=n
3 0.005 1.67901 5.98762 B m e v  arsize_top=0 arsize_bot=0 is_shrink=n
3 0.005 1.6985 5.09224 B m e v  arsize_top=0 arsize_bot=0 is_shrink=n
3 0.005 1.69851 4.74418 B m e v  arsize_top=0 arsize_bot=0 is_shrink=n
3 0.005 1.7 4.812 B m e v  arsize_top=0 arsize_bot=0 is_shrink=n
3 0.005 1.70395 4.92 B m e v  arsize_top=0 arsize_bot=0 is_shrink=n
3 0.005 1.70395 5.023 B m e v  arsize_top=0 arsize_bot=0 is_shrink=n
3 0.005 1.72874 0.036 B m e v  arsize_top=0 arsize_bot=0 is_shrink=n
3 0.005 1.72901 5.98762 B m e v  arsize_top=0 arsize_bot=0 is_shrink=n
3 0.005 1.77481 4.92 B m e v  arsize_top=0 arsize_bot=0 is_shrink=n
3 0.005 1.77481 5.023 B m e v  arsize_top=0 arsize_bot=0 is_shrink=n
3 0.005 1.776 4.812 B m e v  arsize_top=0 arsize_bot=0 is_shrink=n
3 0.005 1.77874 0.036 B m e v  arsize_top=0 arsize_bot=0 is_shrink=n
3 0.005 1.77901 5.98762 B m e v  arsize_top=0 arsize_bot=0 is_shrink=n
3 0.005 0.17874 0.036 B m e v  arsize_top=0 arsize_bot=0 is_shrink=n
3 0.005 1.78025 4.74418 B m e v  arsize_top=0 arsize_bot=0 is_shrink=n
3 0.005 0.17901 5.98762 B m e v  arsize_top=0 arsize_bot=0 is_shrink=n
3 0.005 1.792 2.4781 B m e v  arsize_top=0 arsize_bot=0 is_shrink=n
3 0.005 1.82874 0.036 B m e v  arsize_top=0 arsize_bot=0 is_shrink=n
3 0.005 1.82901 5.98762 B m e v  arsize_top=0 arsize_bot=0 is_shrink=n
3 0.005 1.84025 4.74418 B m e v  arsize_top=0 arsize_bot=0 is_shrink=n
3 0.005 1.84568 4.81 B m e v  arsize_top=0 arsize_bot=0 is_shrink=n
3 0.005 1.84568 4.92 B m e v  arsize_top=0 arsize_bot=0 is_shrink=n
3 0.005 1.84568 5.023 B m e v  arsize_top=0 arsize_bot=0 is_shrink=n
3 0.005 1.85111 4.61826 B m e v  arsize_top=0 arsize_bot=0 is_shrink=n
3 0.005 1.85111 5.13026 B m e v  arsize_top=0 arsize_bot=0 is_shrink=n
3 0.005 1.87874 0.036 B m e v  arsize_top=0 arsize_bot=0 is_shrink=n
3 0.005 1.87901 5.98762 B m e v  arsize_top=0 arsize_bot=0 is_shrink=n
3 0.005 1.91111 4.61826 B m e v  arsize_top=0 arsize_bot=0 is_shrink=n
3 0.005 1.91111 5.13026 B m e v  arsize_top=0 arsize_bot=0 is_shrink=n
3 0.005 1.91654 4.92 B m e v  arsize_top=0 arsize_bot=0 is_shrink=n
3 0.005 1.91654 5.023 B m e v  arsize_top=0 arsize_bot=0 is_shrink=n
3 0.005 1.92 4.81 B m e v  arsize_top=0 arsize_bot=0 is_shrink=n
3 0.005 1.92197 5.09224 B m e v  arsize_top=0 arsize_bot=0 is_shrink=n
3 0.005 1.92346 5.377 B m e v  arsize_top=0 arsize_bot=0 is_shrink=n
3 0.005 1.92874 0.036 B m e v  arsize_top=0 arsize_bot=0 is_shrink=n
3 0.005 1.92901 5.98762 B m e v  arsize_top=0 arsize_bot=0 is_shrink=n
3 0.005 1.97874 0.036 B m e v  arsize_top=0 arsize_bot=0 is_shrink=n
3 0.005 1.97901 5.98762 B m e v  arsize_top=0 arsize_bot=0 is_shrink=n
3 0.005 1.98197 5.09224 B m e v  arsize_top=0 arsize_bot=0 is_shrink=n
3 0.005 1.98741 4.92 B m e v  arsize_top=0 arsize_bot=0 is_shrink=n
3 0.005 1.98741 5.023 B m e v  arsize_top=0 arsize_bot=0 is_shrink=n
3 0.005 1.99 4.81 B m e v  arsize_top=0 arsize_bot=0 is_shrink=n
3 0.005 2.01853 4.62815 B m e v  arsize_top=0 arsize_bot=0 is_shrink=n
3 0.005 2.02874 0.036 B m e v  arsize_top=0 arsize_bot=0 is_shrink=n
3 0.005 2.02901 5.98762 B m e v  arsize_top=0 arsize_bot=0 is_shrink=n
3 0.005 2.05828 4.92 B m e v  arsize_top=0 arsize_bot=0 is_shrink=n
3 0.005 2.05828 5.023 B m e v  arsize_top=0 arsize_bot=0 is_shrink=n
3 0.005 2.06087 4.81 B m e v  arsize_top=0 arsize_bot=0 is_shrink=n
3 0.005 2.06371 4.74418 B m e v  arsize_top=0 arsize_bot=0 is_shrink=n
3 0.005 2.06371 5.13026 B m e v  arsize_top=0 arsize_bot=0 is_shrink=n
3 0.005 2.07853 4.62815 B m e v  arsize_top=0 arsize_bot=0 is_shrink=n
3 0.005 2.07874 0.036 B m e v  arsize_top=0 arsize_bot=0 is_shrink=n
3 0.005 2.07901 5.98762 B m e v  arsize_top=0 arsize_bot=0 is_shrink=n
3 0.005 2.12371 4.74418 B m e v  arsize_top=0 arsize_bot=0 is_shrink=n
3 0.005 2.12371 5.13026 B m e v  arsize_top=0 arsize_bot=0 is_shrink=n
3 0.005 2.12874 0.036 B m e v  arsize_top=0 arsize_bot=0 is_shrink=n
3 0.005 2.12901 5.98762 B m e v  arsize_top=0 arsize_bot=0 is_shrink=n
3 0.005 2.12914 4.81 B m e v  arsize_top=0 arsize_bot=0 is_shrink=n
3 0.005 2.12914 4.92 B m e v  arsize_top=0 arsize_bot=0 is_shrink=n
3 0.005 2.12914 5.023 B m e v  arsize_top=0 arsize_bot=0 is_shrink=n
3 0.005 2.13457 5.09224 B m e v  arsize_top=0 arsize_bot=0 is_shrink=n
3 0.005 2.14346 5.377 B m e v  arsize_top=0 arsize_bot=0 is_shrink=n
3 0.005 2.17874 0.036 B m e v  arsize_top=0 arsize_bot=0 is_shrink=n
3 0.005 2.17901 5.98762 B m e v  arsize_top=0 arsize_bot=0 is_shrink=n
3 0.005 2.19457 5.09224 B m e v  arsize_top=0 arsize_bot=0 is_shrink=n
3 0.005 2.20001 4.81 B m e v  arsize_top=0 arsize_bot=0 is_shrink=n
3 0.005 2.20001 4.926 B m e v  arsize_top=0 arsize_bot=0 is_shrink=n
3 0.005 2.20001 5.023 B m e v  arsize_top=0 arsize_bot=0 is_shrink=n
3 0.005 2.20544 4.74418 B m e v  arsize_top=0 arsize_bot=0 is_shrink=n
3 0.005 2.20855 4.62826 B m e v  arsize_top=0 arsize_bot=0 is_shrink=n
3 0.005 2.22874 0.036 B m e v  arsize_top=0 arsize_bot=0 is_shrink=n
3 0.005 2.22901 5.98762 B m e v  arsize_top=0 arsize_bot=0 is_shrink=n
3 0.005 2.26544 4.74418 B m e v  arsize_top=0 arsize_bot=0 is_shrink=n
3 0.005 2.26855 4.62826 B m e v  arsize_top=0 arsize_bot=0 is_shrink=n
3 0.005 2.27087 4.81 B m e v  arsize_top=0 arsize_bot=0 is_shrink=n
3 0.005 2.27087 4.92 B m e v  arsize_top=0 arsize_bot=0 is_shrink=n
3 0.005 2.27087 5.023 B m e v  arsize_top=0 arsize_bot=0 is_shrink=n
3 0.005 2.27874 0.036 B m e v  arsize_top=0 arsize_bot=0 is_shrink=n
3 0.005 2.27901 5.98762 B m e v  arsize_top=0 arsize_bot=0 is_shrink=n
3 0.005 0.22874 0.036 B m e v  arsize_top=0 arsize_bot=0 is_shrink=n
3 0.005 0.22901 5.98762 B m e v  arsize_top=0 arsize_bot=0 is_shrink=n
3 0.005 2.32874 0.036 B m e v  arsize_top=0 arsize_bot=0 is_shrink=n
3 0.005 2.32901 5.98762 B m e v  arsize_top=0 arsize_bot=0 is_shrink=n
3 0.005 2.34174 4.81 B m e v  arsize_top=0 arsize_bot=0 is_shrink=n
3 0.005 2.34174 4.92 B m e v  arsize_top=0 arsize_bot=0 is_shrink=n
3 0.005 2.34174 5.023 B m e v  arsize_top=0 arsize_bot=0 is_shrink=n
3 0.005 2.34717 4.70326 B m e v  arsize_top=0 arsize_bot=0 is_shrink=n
3 0.005 2.34717 5.15374 B m e v  arsize_top=0 arsize_bot=0 is_shrink=n
3 0.005 2.37874 0.036 B m e v  arsize_top=0 arsize_bot=0 is_shrink=n
3 0.005 2.37901 5.98762 B m e v  arsize_top=0 arsize_bot=0 is_shrink=n
3 0.005 2.40717 4.70326 B m e v  arsize_top=0 arsize_bot=0 is_shrink=n
3 0.005 2.40717 5.15374 B m e v  arsize_top=0 arsize_bot=0 is_shrink=n
3 0.005 2.41261 4.81402 B m e v  arsize_top=0 arsize_bot=0 is_shrink=n
3 0.005 2.41261 5.023 B m e v  arsize_top=0 arsize_bot=0 is_shrink=n
3 0.005 2.42874 0.036 B m e v  arsize_top=0 arsize_bot=0 is_shrink=n
3 0.005 2.42901 5.98762 B m e v  arsize_top=0 arsize_bot=0 is_shrink=n
3 0.005 2.47874 0.036 B m e v  arsize_top=0 arsize_bot=0 is_shrink=n
3 0.005 2.47901 5.98762 B m e v  arsize_top=0 arsize_bot=0 is_shrink=n
3 0.005 2.52874 0.036 B m e v  arsize_top=0 arsize_bot=0 is_shrink=n
3 0.005 2.52901 5.98762 B m e v  arsize_top=0 arsize_bot=0 is_shrink=n
3 0.005 2.57874 0.036 B m e v  arsize_top=0 arsize_bot=0 is_shrink=n
3 0.005 2.57901 5.98762 B m e v  arsize_top=0 arsize_bot=0 is_shrink=n
3 0.005 2.62874 0.036 B m e v  arsize_top=0 arsize_bot=0 is_shrink=n
3 0.005 2.62901 5.98762 B m e v  arsize_top=0 arsize_bot=0 is_shrink=n
3 0.005 2.67874 0.036 B m e v  arsize_top=0 arsize_bot=0 is_shrink=n
3 0.005 2.67901 5.98762 B m e v  arsize_top=0 arsize_bot=0 is_shrink=n
3 0.005 2.72681 4.81402 B m e v  arsize_top=0 arsize_bot=0 is_shrink=n
3 0.005 2.72681 5.023 B m e v  arsize_top=0 arsize_bot=0 is_shrink=n
3 0.005 2.72874 0.036 B m e v  arsize_top=0 arsize_bot=0 is_shrink=n
3 0.005 2.72901 5.98762 B m e v  arsize_top=0 arsize_bot=0 is_shrink=n
3 0.005 2.73225 4.70574 B m e v  arsize_top=0 arsize_bot=0 is_shrink=n
3 0.005 2.73225 5.17874 B m e v  arsize_top=0 arsize_bot=0 is_shrink=n
3 0.005 2.77874 0.036 B m e v  arsize_top=0 arsize_bot=0 is_shrink=n
3 0.005 2.77901 5.98762 B m e v  arsize_top=0 arsize_bot=0 is_shrink=n
3 0.005 0.27874 0.036 B m e v  arsize_top=0 arsize_bot=0 is_shrink=n
3 0.005 0.27901 5.98762 B m e v  arsize_top=0 arsize_bot=0 is_shrink=n
3 0.005 2.79225 4.70574 B m e v  arsize_top=0 arsize_bot=0 is_shrink=n
3 0.005 2.79225 5.17874 B m e v  arsize_top=0 arsize_bot=0 is_shrink=n
3 0.005 2.79768 4.81402 B m e v  arsize_top=0 arsize_bot=0 is_shrink=n
3 0.005 2.79768 4.92 B m e v  arsize_top=0 arsize_bot=0 is_shrink=n
3 0.005 2.79768 5.023 B m e v  arsize_top=0 arsize_bot=0 is_shrink=n
3 0.005 2.80311 4.74418 B m e v  arsize_top=0 arsize_bot=0 is_shrink=n
3 0.005 2.82874 0.036 B m e v  arsize_top=0 arsize_bot=0 is_shrink=n
3 0.005 2.82901 5.98762 B m e v  arsize_top=0 arsize_bot=0 is_shrink=n
3 0.005 2.86311 4.74418 B m e v  arsize_top=0 arsize_bot=0 is_shrink=n
3 0.005 2.86555 4.81402 B m e v  arsize_top=0 arsize_bot=0 is_shrink=n
3 0.005 2.86855 4.92 B m e v  arsize_top=0 arsize_bot=0 is_shrink=n
3 0.005 2.86855 5.023 B m e v  arsize_top=0 arsize_bot=0 is_shrink=n
3 0.005 2.87087 5.20876 B m e v  arsize_top=0 arsize_bot=0 is_shrink=n
3 0.005 2.87708 4.70574 B m e v  arsize_top=0 arsize_bot=0 is_shrink=n
3 0.005 2.87874 0.036 B m e v  arsize_top=0 arsize_bot=0 is_shrink=n
3 0.005 2.87901 5.98762 B m e v  arsize_top=0 arsize_bot=0 is_shrink=n
3 0.005 2.92874 0.036 B m e v  arsize_top=0 arsize_bot=0 is_shrink=n
3 0.005 2.92901 5.98762 B m e v  arsize_top=0 arsize_bot=0 is_shrink=n
3 0.005 2.93087 5.20876 B m e v  arsize_top=0 arsize_bot=0 is_shrink=n
3 0.005 2.93708 4.70574 B m e v  arsize_top=0 arsize_bot=0 is_shrink=n
3 0.005 2.93941 5.023 B m e v  arsize_top=0 arsize_bot=0 is_shrink=n
3 0.005 2.94141 4.81402 B m e v  arsize_top=0 arsize_bot=0 is_shrink=n
3 0.005 2.9422 2.925 B m e v  arsize_top=0 arsize_bot=0 is_shrink=n
3 0.005 2.945 4.92 B m e v  arsize_top=0 arsize_bot=0 is_shrink=n
3 0.005 2.97721 2.7861 B m e v  arsize_top=0 arsize_bot=0 is_shrink=n
3 0.005 2.97721 2.8989 B m e v  arsize_top=0 arsize_bot=0 is_shrink=n
3 0.005 2.97874 0.036 B m e v  arsize_top=0 arsize_bot=0 is_shrink=n
3 0.005 2.97901 5.98762 B m e v  arsize_top=0 arsize_bot=0 is_shrink=n
3 0.005 3.01028 4.81402 B m e v  arsize_top=0 arsize_bot=0 is_shrink=n
3 0.005 3.01028 4.92 B m e v  arsize_top=0 arsize_bot=0 is_shrink=n
3 0.005 3.01028 5.023 B m e v  arsize_top=0 arsize_bot=0 is_shrink=n
3 0.005 3.01571 4.70574 B m e v  arsize_top=0 arsize_bot=0 is_shrink=n
3 0.005 3.01571 5.20374 B m e v  arsize_top=0 arsize_bot=0 is_shrink=n
3 0.005 3.02874 0.036 B m e v  arsize_top=0 arsize_bot=0 is_shrink=n
3 0.005 3.02901 5.98762 B m e v  arsize_top=0 arsize_bot=0 is_shrink=n
3 0.005 3.06792 5.332 B m e v  arsize_top=0 arsize_bot=0 is_shrink=n
3 0.005 3.07571 4.70574 B m e v  arsize_top=0 arsize_bot=0 is_shrink=n
3 0.005 3.07571 5.20374 B m e v  arsize_top=0 arsize_bot=0 is_shrink=n
3 0.005 3.07691 4.81402 B m e v  arsize_top=0 arsize_bot=0 is_shrink=n
3 0.005 3.07874 0.036 B m e v  arsize_top=0 arsize_bot=0 is_shrink=n
3 0.005 3.07901 5.98762 B m e v  arsize_top=0 arsize_bot=0 is_shrink=n
3 0.005 3.08114 4.92 B m e v  arsize_top=0 arsize_bot=0 is_shrink=n
3 0.005 3.08114 5.023 B m e v  arsize_top=0 arsize_bot=0 is_shrink=n
3 0.005 3.08657 5.09224 B m e v  arsize_top=0 arsize_bot=0 is_shrink=n
3 0.005 3.12874 0.036 B m e v  arsize_top=0 arsize_bot=0 is_shrink=n
3 0.005 3.12901 5.98762 B m e v  arsize_top=0 arsize_bot=0 is_shrink=n
3 0.005 3.14 4.92 B m e v  arsize_top=0 arsize_bot=0 is_shrink=n
3 0.005 3.14657 5.09224 B m e v  arsize_top=0 arsize_bot=0 is_shrink=n
3 0.005 3.15201 5.023 B m e v  arsize_top=0 arsize_bot=0 is_shrink=n
3 0.005 3.15398 4.81402 B m e v  arsize_top=0 arsize_bot=0 is_shrink=n
3 0.005 3.15744 4.74418 B m e v  arsize_top=0 arsize_bot=0 is_shrink=n
3 0.005 3.17874 0.036 B m e v  arsize_top=0 arsize_bot=0 is_shrink=n
3 0.005 3.17901 5.98762 B m e v  arsize_top=0 arsize_bot=0 is_shrink=n
3 0.005 3.21744 4.74418 B m e v  arsize_top=0 arsize_bot=0 is_shrink=n
3 0.005 3.22288 4.81402 B m e v  arsize_top=0 arsize_bot=0 is_shrink=n
3 0.005 3.22288 4.92 B m e v  arsize_top=0 arsize_bot=0 is_shrink=n
3 0.005 3.22288 5.023 B m e v  arsize_top=0 arsize_bot=0 is_shrink=n
3 0.005 3.22831 4.68074 B m e v  arsize_top=0 arsize_bot=0 is_shrink=n
3 0.005 3.22831 5.18128 B m e v  arsize_top=0 arsize_bot=0 is_shrink=n
3 0.005 3.22874 0.036 B m e v  arsize_top=0 arsize_bot=0 is_shrink=n
3 0.005 3.22901 5.98762 B m e v  arsize_top=0 arsize_bot=0 is_shrink=n
3 0.005 3.26 5.332 B m e v  arsize_top=0 arsize_bot=0 is_shrink=n
3 0.005 3.275 4.92 B m e v  arsize_top=0 arsize_bot=0 is_shrink=n
3 0.005 3.27874 0.036 B m e v  arsize_top=0 arsize_bot=0 is_shrink=n
3 0.005 3.27901 5.98762 B m e v  arsize_top=0 arsize_bot=0 is_shrink=n
3 0.005 0.32874 0.036 B m e v  arsize_top=0 arsize_bot=0 is_shrink=n
3 0.005 3.28831 4.68074 B m e v  arsize_top=0 arsize_bot=0 is_shrink=n
3 0.005 3.28831 5.18128 B m e v  arsize_top=0 arsize_bot=0 is_shrink=n
3 0.005 0.32901 5.98762 B m e v  arsize_top=0 arsize_bot=0 is_shrink=n
3 0.005 3.29374 4.81402 B m e v  arsize_top=0 arsize_bot=0 is_shrink=n
3 0.005 3.29374 5.023 B m e v  arsize_top=0 arsize_bot=0 is_shrink=n
3 0.005 3.29917 5.14224 B m e v  arsize_top=0 arsize_bot=0 is_shrink=n
3 0.005 3.32874 0.036 B m e v  arsize_top=0 arsize_bot=0 is_shrink=n
3 0.005 3.32901 5.98762 B m e v  arsize_top=0 arsize_bot=0 is_shrink=n
3 0.005 3.35917 5.14224 B m e v  arsize_top=0 arsize_bot=0 is_shrink=n
3 0.005 3.36461 4.81402 B m e v  arsize_top=0 arsize_bot=0 is_shrink=n
3 0.005 3.36461 4.926 B m e v  arsize_top=0 arsize_bot=0 is_shrink=n
3 0.005 3.36461 5.023 B m e v  arsize_top=0 arsize_bot=0 is_shrink=n
3 0.005 3.37004 4.74418 B m e v  arsize_top=0 arsize_bot=0 is_shrink=n
3 0.005 3.37004 5.18128 B m e v  arsize_top=0 arsize_bot=0 is_shrink=n
3 0.005 3.37874 0.036 B m e v  arsize_top=0 arsize_bot=0 is_shrink=n
3 0.005 3.37901 5.98762 B m e v  arsize_top=0 arsize_bot=0 is_shrink=n
3 0.005 3.41 5.332 B m e v  arsize_top=0 arsize_bot=0 is_shrink=n
3 0.005 3.42874 0.036 B m e v  arsize_top=0 arsize_bot=0 is_shrink=n
3 0.005 3.42901 5.98762 B m e v  arsize_top=0 arsize_bot=0 is_shrink=n
3 0.005 3.43004 4.74418 B m e v  arsize_top=0 arsize_bot=0 is_shrink=n
3 0.005 3.43004 5.18128 B m e v  arsize_top=0 arsize_bot=0 is_shrink=n
3 0.005 3.43547 4.81402 B m e v  arsize_top=0 arsize_bot=0 is_shrink=n
3 0.005 3.43547 4.928 B m e v  arsize_top=0 arsize_bot=0 is_shrink=n
3 0.005 3.43547 5.023 B m e v  arsize_top=0 arsize_bot=0 is_shrink=n
3 0.005 3.44091 4.62574 B m e v  arsize_top=0 arsize_bot=0 is_shrink=n
3 0.005 3.47874 0.036 B m e v  arsize_top=0 arsize_bot=0 is_shrink=n
3 0.005 3.47901 5.98762 B m e v  arsize_top=0 arsize_bot=0 is_shrink=n
3 0.005 3.50091 4.62574 B m e v  arsize_top=0 arsize_bot=0 is_shrink=n
3 0.005 3.50634 4.81402 B m e v  arsize_top=0 arsize_bot=0 is_shrink=n
3 0.005 3.50634 4.92 B m e v  arsize_top=0 arsize_bot=0 is_shrink=n
3 0.005 3.50634 5.023 B m e v  arsize_top=0 arsize_bot=0 is_shrink=n
3 0.005 3.51177 4.68099 B m e v  arsize_top=0 arsize_bot=0 is_shrink=n
3 0.005 3.51177 5.17874 B m e v  arsize_top=0 arsize_bot=0 is_shrink=n
3 0.005 3.52874 0.036 B m e v  arsize_top=0 arsize_bot=0 is_shrink=n
3 0.005 3.52901 5.98762 B m e v  arsize_top=0 arsize_bot=0 is_shrink=n
3 0.005 3.57 4.45 B m e v  arsize_top=0 arsize_bot=0 is_shrink=n
3 0.005 3.57177 4.68099 B m e v  arsize_top=0 arsize_bot=0 is_shrink=n
3 0.005 3.57177 5.17874 B m e v  arsize_top=0 arsize_bot=0 is_shrink=n
3 0.005 3.57721 4.81402 B m e v  arsize_top=0 arsize_bot=0 is_shrink=n
3 0.005 3.57721 5.023 B m e v  arsize_top=0 arsize_bot=0 is_shrink=n
3 0.005 3.57874 0.036 B m e v  arsize_top=0 arsize_bot=0 is_shrink=n
3 0.005 3.57901 5.98762 B m e v  arsize_top=0 arsize_bot=0 is_shrink=n
3 0.005 0.036 1.00868 B m e v  arsize_top=0 arsize_bot=0 is_shrink=n
3 0.005 0.036 1.05868 B m e v  arsize_top=0 arsize_bot=0 is_shrink=n
3 0.005 0.036 0.10868 B m e v  arsize_top=0 arsize_bot=0 is_shrink=n
3 0.005 0.036 1.10868 B m e v  arsize_top=0 arsize_bot=0 is_shrink=n
3 0.005 0.036 1.15868 B m e v  arsize_top=0 arsize_bot=0 is_shrink=n
3 0.005 0.036 1.20868 B m e v  arsize_top=0 arsize_bot=0 is_shrink=n
3 0.005 0.036 1.25868 B m e v  arsize_top=0 arsize_bot=0 is_shrink=n
3 0.005 0.036 1.30868 B m e v  arsize_top=0 arsize_bot=0 is_shrink=n
3 0.005 0.036 1.35868 B m e v  arsize_top=0 arsize_bot=0 is_shrink=n
3 0.005 0.036 1.40868 B m e v  arsize_top=0 arsize_bot=0 is_shrink=n
3 0.005 0.036 1.45868 B m e v  arsize_top=0 arsize_bot=0 is_shrink=n
3 0.005 0.036 1.50868 B m e v  arsize_top=0 arsize_bot=0 is_shrink=n
3 0.005 0.036 1.55868 B m e v  arsize_top=0 arsize_bot=0 is_shrink=n
3 0.005 0.036 0.15868 B m e v  arsize_top=0 arsize_bot=0 is_shrink=n
3 0.005 0.036 1.60868 B m e v  arsize_top=0 arsize_bot=0 is_shrink=n
3 0.005 0.036 1.65868 B m e v  arsize_top=0 arsize_bot=0 is_shrink=n
3 0.005 0.036 1.70868 B m e v  arsize_top=0 arsize_bot=0 is_shrink=n
3 0.005 0.036 1.75868 B m e v  arsize_top=0 arsize_bot=0 is_shrink=n
3 0.005 0.036 1.80868 B m e v  arsize_top=0 arsize_bot=0 is_shrink=n
3 0.005 0.036 1.85868 B m e v  arsize_top=0 arsize_bot=0 is_shrink=n
3 0.005 0.036 1.90868 B m e v  arsize_top=0 arsize_bot=0 is_shrink=n
3 0.005 0.036 1.95868 B m e v  arsize_top=0 arsize_bot=0 is_shrink=n
3 0.005 0.036 2.00868 B m e v  arsize_top=0 arsize_bot=0 is_shrink=n
3 0.005 0.036 2.05868 B m e v  arsize_top=0 arsize_bot=0 is_shrink=n
3 0.005 0.036 0.20868 B m e v  arsize_top=0 arsize_bot=0 is_shrink=n
3 0.005 0.036 2.10868 B m e v  arsize_top=0 arsize_bot=0 is_shrink=n
3 0.005 0.036 2.15868 B m e v  arsize_top=0 arsize_bot=0 is_shrink=n
3 0.005 0.036 2.20868 B m e v  arsize_top=0 arsize_bot=0 is_shrink=n
3 0.005 0.036 2.25868 B m e v  arsize_top=0 arsize_bot=0 is_shrink=n
3 0.005 0.036 2.30868 B m e v  arsize_top=0 arsize_bot=0 is_shrink=n
3 0.005 0.036 2.35868 B m e v  arsize_top=0 arsize_bot=0 is_shrink=n
3 0.005 0.036 2.40868 B m e v  arsize_top=0 arsize_bot=0 is_shrink=n
3 0.005 0.036 2.45868 B m e v  arsize_top=0 arsize_bot=0 is_shrink=n
3 0.005 0.036 2.50868 B m e v  arsize_top=0 arsize_bot=0 is_shrink=n
3 0.005 0.036 2.55868 B m e v  arsize_top=0 arsize_bot=0 is_shrink=n
3 0.005 0.036 0.25868 B m e v  arsize_top=0 arsize_bot=0 is_shrink=n
3 0.005 0.036 2.60868 B m e v  arsize_top=0 arsize_bot=0 is_shrink=n
3 0.005 0.036 2.65868 B m e v  arsize_top=0 arsize_bot=0 is_shrink=n
3 0.005 0.036 2.70868 B m e v  arsize_top=0 arsize_bot=0 is_shrink=n
3 0.005 0.036 2.75868 B m e v  arsize_top=0 arsize_bot=0 is_shrink=n
3 0.005 0.036 2.80868 B m e v  arsize_top=0 arsize_bot=0 is_shrink=n
3 0.005 0.036 2.85868 B m e v  arsize_top=0 arsize_bot=0 is_shrink=n
3 0.005 0.036 2.90868 B m e v  arsize_top=0 arsize_bot=0 is_shrink=n
3 0.005 0.036 2.95868 B m e v  arsize_top=0 arsize_bot=0 is_shrink=n
3 0.005 0.036 3.00868 B m e v  arsize_top=0 arsize_bot=0 is_shrink=n
3 0.005 0.036 3.05868 B m e v  arsize_top=0 arsize_bot=0 is_shrink=n
3 0.005 0.036 0.30868 B m e v  arsize_top=0 arsize_bot=0 is_shrink=n
3 0.005 0.036 3.10868 B m e v  arsize_top=0 arsize_bot=0 is_shrink=n
3 0.005 0.036 3.15868 B m e v  arsize_top=0 arsize_bot=0 is_shrink=n
3 0.005 0.036 3.20868 B m e v  arsize_top=0 arsize_bot=0 is_shrink=n
3 0.005 0.036 3.25868 B m e v  arsize_top=0 arsize_bot=0 is_shrink=n
3 0.005 0.036 3.30868 B m e v  arsize_top=0 arsize_bot=0 is_shrink=n
3 0.005 0.036 3.35868 B m e v  arsize_top=0 arsize_bot=0 is_shrink=n
3 0.005 0.036 3.40868 B m e v  arsize_top=0 arsize_bot=0 is_shrink=n
3 0.005 0.036 3.45868 B m e v  arsize_top=0 arsize_bot=0 is_shrink=n
3 0.005 0.036 3.50868 B m e v  arsize_top=0 arsize_bot=0 is_shrink=n
3 0.005 0.036 3.55868 B m e v  arsize_top=0 arsize_bot=0 is_shrink=n
3 0.005 0.036 0.35868 B m e v  arsize_top=0 arsize_bot=0 is_shrink=n
3 0.005 0.036 3.60868 B m e v  arsize_top=0 arsize_bot=0 is_shrink=n
3 0.005 0.036 3.65868 B m e v  arsize_top=0 arsize_bot=0 is_shrink=n
3 0.005 0.036 3.70868 B m e v  arsize_top=0 arsize_bot=0 is_shrink=n
3 0.005 0.036 3.75868 B m e v  arsize_top=0 arsize_bot=0 is_shrink=n
3 0.005 0.036 3.80868 B m e v  arsize_top=0 arsize_bot=0 is_shrink=n
3 0.005 0.036 3.85868 B m e v  arsize_top=0 arsize_bot=0 is_shrink=n
3 0.005 0.036 3.90868 B m e v  arsize_top=0 arsize_bot=0 is_shrink=n
3 0.005 0.036 3.95868 B m e v  arsize_top=0 arsize_bot=0 is_shrink=n
3 0.005 0.036 4.00868 B m e v  arsize_top=0 arsize_bot=0 is_shrink=n
3 0.005 0.036 4.05868 B m e v  arsize_top=0 arsize_bot=0 is_shrink=n
3 0.005 0.036 0.40868 B m e v  arsize_top=0 arsize_bot=0 is_shrink=n
3 0.005 0.036 4.10868 B m e v  arsize_top=0 arsize_bot=0 is_shrink=n
3 0.005 0.036 4.15868 B m e v  arsize_top=0 arsize_bot=0 is_shrink=n
3 0.005 0.036 4.20868 B m e v  arsize_top=0 arsize_bot=0 is_shrink=n
3 0.005 0.036 4.25868 B m e v  arsize_top=0 arsize_bot=0 is_shrink=n
3 0.005 0.036 4.30868 B m e v  arsize_top=0 arsize_bot=0 is_shrink=n
3 0.005 0.036 4.35868 B m e v  arsize_top=0 arsize_bot=0 is_shrink=n
3 0.005 0.036 4.40868 B m e v  arsize_top=0 arsize_bot=0 is_shrink=n
3 0.005 0.036 4.45868 B m e v  arsize_top=0 arsize_bot=0 is_shrink=n
3 0.005 0.036 4.50868 B m e v  arsize_top=0 arsize_bot=0 is_shrink=n
3 0.005 0.036 4.55868 B m e v  arsize_top=0 arsize_bot=0 is_shrink=n
3 0.005 0.036 0.45868 B m e v  arsize_top=0 arsize_bot=0 is_shrink=n
3 0.005 0.036 4.60868 B m e v  arsize_top=0 arsize_bot=0 is_shrink=n
3 0.005 0.036 4.65868 B m e v  arsize_top=0 arsize_bot=0 is_shrink=n
3 0.005 0.036 4.70868 B m e v  arsize_top=0 arsize_bot=0 is_shrink=n
3 0.005 0.036 4.75868 B m e v  arsize_top=0 arsize_bot=0 is_shrink=n
3 0.005 0.036 0.50868 B m e v  arsize_top=0 arsize_bot=0 is_shrink=n
3 0.005 0.036 5.25868 B m e v  arsize_top=0 arsize_bot=0 is_shrink=n
3 0.005 0.036 5.30868 B m e v  arsize_top=0 arsize_bot=0 is_shrink=n
3 0.005 0.036 5.35868 B m e v  arsize_top=0 arsize_bot=0 is_shrink=n
3 0.005 0.036 5.40868 B m e v  arsize_top=0 arsize_bot=0 is_shrink=n
3 0.005 0.036 5.45868 B m e v  arsize_top=0 arsize_bot=0 is_shrink=n
3 0.005 0.036 5.50868 B m e v  arsize_top=0 arsize_bot=0 is_shrink=n
3 0.005 0.036 5.55868 B m e v  arsize_top=0 arsize_bot=0 is_shrink=n
3 0.005 0.036 0.55868 B m e v  arsize_top=0 arsize_bot=0 is_shrink=n
3 0.005 0.036 5.60868 B m e v  arsize_top=0 arsize_bot=0 is_shrink=n
3 0.005 0.036 5.65868 B m e v  arsize_top=0 arsize_bot=0 is_shrink=n
3 0.005 0.036 5.70868 B m e v  arsize_top=0 arsize_bot=0 is_shrink=n
3 0.005 0.036 5.75868 B m e v  arsize_top=0 arsize_bot=0 is_shrink=n
3 0.005 0.036 5.80868 B m e v  arsize_top=0 arsize_bot=0 is_shrink=n
3 0.005 0.036 5.85868 B m e v  arsize_top=0 arsize_bot=0 is_shrink=n
3 0.005 0.036 5.90868 B m e v  arsize_top=0 arsize_bot=0 is_shrink=n
3 0.005 3.60999 0.24 B m e v  arsize_top=0 arsize_bot=0 is_shrink=n
3 0.005 3.62874 0.036 B m e v  arsize_top=0 arsize_bot=0 is_shrink=n
3 0.005 3.62901 5.98762 B m e v  arsize_top=0 arsize_bot=0 is_shrink=n
3 0.005 3.65999 0.345 B m e v  arsize_top=0 arsize_bot=0 is_shrink=n
3 0.005 3.66 4.63 B m e v  arsize_top=0 arsize_bot=0 is_shrink=n
3 0.005 3.67874 0.036 B m e v  arsize_top=0 arsize_bot=0 is_shrink=n
3 0.005 3.67901 5.98762 B m e v  arsize_top=0 arsize_bot=0 is_shrink=n
3 0.005 3.72 4.45 B m e v  arsize_top=0 arsize_bot=0 is_shrink=n
3 0.005 3.72874 0.036 B m e v  arsize_top=0 arsize_bot=0 is_shrink=n
3 0.005 3.72901 5.98762 B m e v  arsize_top=0 arsize_bot=0 is_shrink=n
3 0.005 3.77 4.86 B m e v  arsize_top=0 arsize_bot=0 is_shrink=n
3 0.005 3.77874 0.036 B m e v  arsize_top=0 arsize_bot=0 is_shrink=n
3 0.005 3.77901 5.98762 B m e v  arsize_top=0 arsize_bot=0 is_shrink=n
3 0.005 0.37874 0.036 B m e v  arsize_top=0 arsize_bot=0 is_shrink=n
3 0.005 0.37901 5.98762 B m e v  arsize_top=0 arsize_bot=0 is_shrink=n
3 0.005 0.03827 5.95863 B m e v  arsize_top=0 arsize_bot=0 is_shrink=n
3 0.005 3.82874 0.036 B m e v  arsize_top=0 arsize_bot=0 is_shrink=n
3 0.005 3.82901 5.98762 B m e v  arsize_top=0 arsize_bot=0 is_shrink=n
3 0.005 3.835 4.6 B m e v  arsize_top=0 arsize_bot=0 is_shrink=n
3 0.005 3.86827 2.64559 B m e v  arsize_top=0 arsize_bot=0 is_shrink=n
3 0.005 3.87 5.125 B m e v  arsize_top=0 arsize_bot=0 is_shrink=n
3 0.005 3.87874 0.036 B m e v  arsize_top=0 arsize_bot=0 is_shrink=n
3 0.005 3.87901 5.98762 B m e v  arsize_top=0 arsize_bot=0 is_shrink=n
3 0.005 3.92874 0.036 B m e v  arsize_top=0 arsize_bot=0 is_shrink=n
3 0.005 3.92901 5.98762 B m e v  arsize_top=0 arsize_bot=0 is_shrink=n
3 0.005 3.97874 0.036 B m e v  arsize_top=0 arsize_bot=0 is_shrink=n
3 0.005 3.97901 5.98762 B m e v  arsize_top=0 arsize_bot=0 is_shrink=n
3 0.005 3.9865 4.635 B m e v  arsize_top=0 arsize_bot=0 is_shrink=n
3 0.005 4.02874 0.036 B m e v  arsize_top=0 arsize_bot=0 is_shrink=n
3 0.005 4.02901 5.98762 B m e v  arsize_top=0 arsize_bot=0 is_shrink=n
3 0.005 4.07386 2.55 B m e v  arsize_top=0 arsize_bot=0 is_shrink=n
3 0.005 4.07874 0.036 B m e v  arsize_top=0 arsize_bot=0 is_shrink=n
3 0.005 4.07901 5.98762 B m e v  arsize_top=0 arsize_bot=0 is_shrink=n
3 0.005 4.1049 4.7649 B m e v  arsize_top=0 arsize_bot=0 is_shrink=n
3 0.005 4.12874 0.036 B m e v  arsize_top=0 arsize_bot=0 is_shrink=n
3 0.005 4.12901 5.98762 B m e v  arsize_top=0 arsize_bot=0 is_shrink=n
3 0.005 4.14 4.655 B m e v  arsize_top=0 arsize_bot=0 is_shrink=n
3 0.005 4.15221 2.9281 B m e v  arsize_top=0 arsize_bot=0 is_shrink=n
3 0.005 4.17874 0.036 B m e v  arsize_top=0 arsize_bot=0 is_shrink=n
3 0.005 4.17901 5.98762 B m e v  arsize_top=0 arsize_bot=0 is_shrink=n
3 0.005 4.22874 0.036 B m e v  arsize_top=0 arsize_bot=0 is_shrink=n
3 0.005 4.22901 5.98762 B m e v  arsize_top=0 arsize_bot=0 is_shrink=n
3 0.005 4.26105 4.9431 B m e v  arsize_top=0 arsize_bot=0 is_shrink=n
3 0.005 4.26105 4.9831 B m e v  arsize_top=0 arsize_bot=0 is_shrink=n
3 0.005 4.26105 5.0281 B m e v  arsize_top=0 arsize_bot=0 is_shrink=n
3 0.005 4.26105 5.0731 B m e v  arsize_top=0 arsize_bot=0 is_shrink=n
3 0.005 4.26105 5.1181 B m e v  arsize_top=0 arsize_bot=0 is_shrink=n
3 0.005 4.27874 0.036 B m e v  arsize_top=0 arsize_bot=0 is_shrink=n
3 0.005 4.27901 5.98762 B m e v  arsize_top=0 arsize_bot=0 is_shrink=n
3 0.005 0.42874 0.036 B m e v  arsize_top=0 arsize_bot=0 is_shrink=n
3 0.005 0.42901 5.98762 B m e v  arsize_top=0 arsize_bot=0 is_shrink=n
3 0.005 4.30105 4.9431 B m e v  arsize_top=0 arsize_bot=0 is_shrink=n
3 0.005 4.30105 4.9831 B m e v  arsize_top=0 arsize_bot=0 is_shrink=n
3 0.005 4.30105 5.0281 B m e v  arsize_top=0 arsize_bot=0 is_shrink=n
3 0.005 4.30105 5.0731 B m e v  arsize_top=0 arsize_bot=0 is_shrink=n
3 0.005 4.30105 5.1181 B m e v  arsize_top=0 arsize_bot=0 is_shrink=n
3 0.005 4.32874 0.036 B m e v  arsize_top=0 arsize_bot=0 is_shrink=n
3 0.005 4.32901 5.98762 B m e v  arsize_top=0 arsize_bot=0 is_shrink=n
3 0.005 4.33605 4.9231 B m e v  arsize_top=0 arsize_bot=0 is_shrink=n
3 0.005 4.34105 5.1181 B m e v  arsize_top=0 arsize_bot=0 is_shrink=n
3 0.005 4.37874 0.036 B m e v  arsize_top=0 arsize_bot=0 is_shrink=n
3 0.005 4.37901 5.98762 B m e v  arsize_top=0 arsize_bot=0 is_shrink=n
3 0.005 4.38105 4.9231 B m e v  arsize_top=0 arsize_bot=0 is_shrink=n
3 0.005 4.38105 5.1181 B m e v  arsize_top=0 arsize_bot=0 is_shrink=n
3 0.005 4.42105 4.9431 B m e v  arsize_top=0 arsize_bot=0 is_shrink=n
3 0.005 4.42105 4.9831 B m e v  arsize_top=0 arsize_bot=0 is_shrink=n
3 0.005 4.42105 5.0281 B m e v  arsize_top=0 arsize_bot=0 is_shrink=n
3 0.005 4.42105 5.0731 B m e v  arsize_top=0 arsize_bot=0 is_shrink=n
3 0.005 4.42105 5.1181 B m e v  arsize_top=0 arsize_bot=0 is_shrink=n
3 0.005 4.42874 0.036 B m e v  arsize_top=0 arsize_bot=0 is_shrink=n
3 0.005 4.42901 5.98762 B m e v  arsize_top=0 arsize_bot=0 is_shrink=n
3 0.005 4.46105 4.9431 B m e v  arsize_top=0 arsize_bot=0 is_shrink=n
3 0.005 4.46105 4.9831 B m e v  arsize_top=0 arsize_bot=0 is_shrink=n
3 0.005 4.46105 5.0281 B m e v  arsize_top=0 arsize_bot=0 is_shrink=n
3 0.005 4.46105 5.0731 B m e v  arsize_top=0 arsize_bot=0 is_shrink=n
3 0.005 4.46105 5.1181 B m e v  arsize_top=0 arsize_bot=0 is_shrink=n
3 0.005 4.47874 0.036 B m e v  arsize_top=0 arsize_bot=0 is_shrink=n
3 0.005 4.47901 5.98762 B m e v  arsize_top=0 arsize_bot=0 is_shrink=n
3 0.005 4.52874 0.036 B m e v  arsize_top=0 arsize_bot=0 is_shrink=n
3 0.005 4.52901 5.98762 B m e v  arsize_top=0 arsize_bot=0 is_shrink=n
3 0.005 4.57874 0.036 B m e v  arsize_top=0 arsize_bot=0 is_shrink=n
3 0.005 4.57901 5.98762 B m e v  arsize_top=0 arsize_bot=0 is_shrink=n
3 0.005 4.62874 0.036 B m e v  arsize_top=0 arsize_bot=0 is_shrink=n
3 0.005 4.62901 5.98762 B m e v  arsize_top=0 arsize_bot=0 is_shrink=n
3 0.005 4.65105 4.9431 B m e v  arsize_top=0 arsize_bot=0 is_shrink=n
3 0.005 4.65105 4.9831 B m e v  arsize_top=0 arsize_bot=0 is_shrink=n
3 0.005 4.65105 5.0281 B m e v  arsize_top=0 arsize_bot=0 is_shrink=n
3 0.005 4.65105 5.0731 B m e v  arsize_top=0 arsize_bot=0 is_shrink=n
3 0.005 4.65105 5.1181 B m e v  arsize_top=0 arsize_bot=0 is_shrink=n
3 0.005 4.67874 0.036 B m e v  arsize_top=0 arsize_bot=0 is_shrink=n
3 0.005 4.67901 5.98762 B m e v  arsize_top=0 arsize_bot=0 is_shrink=n
3 0.005 4.69105 4.9431 B m e v  arsize_top=0 arsize_bot=0 is_shrink=n
3 0.005 4.69105 4.9831 B m e v  arsize_top=0 arsize_bot=0 is_shrink=n
3 0.005 4.69105 5.0281 B m e v  arsize_top=0 arsize_bot=0 is_shrink=n
3 0.005 4.69105 5.0731 B m e v  arsize_top=0 arsize_bot=0 is_shrink=n
3 0.005 4.69105 5.1181 B m e v  arsize_top=0 arsize_bot=0 is_shrink=n
3 0.005 4.7 5.54929 B m e v  arsize_top=0 arsize_bot=0 is_shrink=n
3 0.005 4.72605 4.9231 B m e v  arsize_top=0 arsize_bot=0 is_shrink=n
3 0.005 4.72874 0.036 B m e v  arsize_top=0 arsize_bot=0 is_shrink=n
3 0.005 4.72901 5.98762 B m e v  arsize_top=0 arsize_bot=0 is_shrink=n
3 0.005 4.73105 5.1181 B m e v  arsize_top=0 arsize_bot=0 is_shrink=n
3 0.005 4.77105 4.9231 B m e v  arsize_top=0 arsize_bot=0 is_shrink=n
3 0.005 4.77105 5.1181 B m e v  arsize_top=0 arsize_bot=0 is_shrink=n
3 0.005 4.77874 0.03612 B m e v  arsize_top=0 arsize_bot=0 is_shrink=n
3 0.005 4.77901 5.98762 B m e v  arsize_top=0 arsize_bot=0 is_shrink=n
3 0.005 0.47874 0.036 B m e v  arsize_top=0 arsize_bot=0 is_shrink=n
3 0.005 0.47901 5.98762 B m e v  arsize_top=0 arsize_bot=0 is_shrink=n
3 0.005 4.81 5.375 B m e v  arsize_top=0 arsize_bot=0 is_shrink=n
3 0.005 4.81105 4.9431 B m e v  arsize_top=0 arsize_bot=0 is_shrink=n
3 0.005 4.81105 4.9831 B m e v  arsize_top=0 arsize_bot=0 is_shrink=n
3 0.005 4.81105 5.0281 B m e v  arsize_top=0 arsize_bot=0 is_shrink=n
3 0.005 4.81105 5.0731 B m e v  arsize_top=0 arsize_bot=0 is_shrink=n
3 0.005 4.81105 5.1181 B m e v  arsize_top=0 arsize_bot=0 is_shrink=n
3 0.005 4.81704 0.06826 B m e v  arsize_top=0 arsize_bot=0 is_shrink=n
3 0.005 4.81834 0.11825 B m e v  arsize_top=0 arsize_bot=0 is_shrink=n
3 0.005 4.81834 0.16825 B m e v  arsize_top=0 arsize_bot=0 is_shrink=n
3 0.005 4.81834 0.21825 B m e v  arsize_top=0 arsize_bot=0 is_shrink=n
3 0.005 4.81834 0.26825 B m e v  arsize_top=0 arsize_bot=0 is_shrink=n
3 0.005 4.81834 0.31825 B m e v  arsize_top=0 arsize_bot=0 is_shrink=n
3 0.005 4.81919 0.36824 B m e v  arsize_top=0 arsize_bot=0 is_shrink=n
3 0.005 0.4826 5.8976 B m e v  arsize_top=0 arsize_bot=0 is_shrink=n
3 0.005 4.82901 5.98762 B m e v  arsize_top=0 arsize_bot=0 is_shrink=n
3 0.005 4.83591 0.41536 B m e v  arsize_top=0 arsize_bot=0 is_shrink=n
3 0.005 4.85105 4.9431 B m e v  arsize_top=0 arsize_bot=0 is_shrink=n
3 0.005 4.85105 4.9831 B m e v  arsize_top=0 arsize_bot=0 is_shrink=n
3 0.005 4.85105 5.0281 B m e v  arsize_top=0 arsize_bot=0 is_shrink=n
3 0.005 4.85105 5.0731 B m e v  arsize_top=0 arsize_bot=0 is_shrink=n
3 0.005 4.85105 5.1181 B m e v  arsize_top=0 arsize_bot=0 is_shrink=n
3 0.005 4.87109 0.45089 B m e v  arsize_top=0 arsize_bot=0 is_shrink=n
3 0.005 4.87901 5.98762 B m e v  arsize_top=0 arsize_bot=0 is_shrink=n
3 0.005 4.91805 0.46808 B m e v  arsize_top=0 arsize_bot=0 is_shrink=n
3 0.005 4.92 5.7 B m e v  arsize_top=0 arsize_bot=0 is_shrink=n
3 0.005 4.92901 5.98762 B m e v  arsize_top=0 arsize_bot=0 is_shrink=n
3 0.005 4.96 5.375 B m e v  arsize_top=0 arsize_bot=0 is_shrink=n
3 0.005 4.96804 0.46907 B m e v  arsize_top=0 arsize_bot=0 is_shrink=n
3 0.005 4.97901 5.98762 B m e v  arsize_top=0 arsize_bot=0 is_shrink=n
3 0.005 5.01804 0.46907 B m e v  arsize_top=0 arsize_bot=0 is_shrink=n
3 0.005 5.02901 5.98762 B m e v  arsize_top=0 arsize_bot=0 is_shrink=n
3 0.005 5.04441 5.605 B m e v  arsize_top=0 arsize_bot=0 is_shrink=n
3 0.005 5.06804 0.46907 B m e v  arsize_top=0 arsize_bot=0 is_shrink=n
3 0.005 5.07901 5.98762 B m e v  arsize_top=0 arsize_bot=0 is_shrink=n
3 0.005 5.11804 0.46907 B m e v  arsize_top=0 arsize_bot=0 is_shrink=n
3 0.005 5.12901 5.98762 B m e v  arsize_top=0 arsize_bot=0 is_shrink=n
3 0.005 5.16 5.645 B m e v  arsize_top=0 arsize_bot=0 is_shrink=n
3 0.005 5.16804 0.46907 B m e v  arsize_top=0 arsize_bot=0 is_shrink=n
3 0.005 5.17901 5.98762 B m e v  arsize_top=0 arsize_bot=0 is_shrink=n
3 0.005 5.21804 0.46907 B m e v  arsize_top=0 arsize_bot=0 is_shrink=n
3 0.005 5.22901 5.98762 B m e v  arsize_top=0 arsize_bot=0 is_shrink=n
3 0.005 5.26804 0.46907 B m e v  arsize_top=0 arsize_bot=0 is_shrink=n
3 0.005 5.27901 5.98762 B m e v  arsize_top=0 arsize_bot=0 is_shrink=n
3 0.005 0.52874 0.036 B m e v  arsize_top=0 arsize_bot=0 is_shrink=n
3 0.005 0.52901 5.98762 B m e v  arsize_top=0 arsize_bot=0 is_shrink=n
3 0.005 5.31804 0.46907 B m e v  arsize_top=0 arsize_bot=0 is_shrink=n
3 0.005 5.32901 5.98762 B m e v  arsize_top=0 arsize_bot=0 is_shrink=n
3 0.005 5.36804 0.46907 B m e v  arsize_top=0 arsize_bot=0 is_shrink=n
3 0.005 5.37901 5.98762 B m e v  arsize_top=0 arsize_bot=0 is_shrink=n
3 0.005 5.38048 1.5957 B m e v  arsize_top=0 arsize_bot=0 is_shrink=n
3 0.005 5.38048 1.6528 B m e v  arsize_top=0 arsize_bot=0 is_shrink=n
3 0.005 5.38048 1.732 B m e v  arsize_top=0 arsize_bot=0 is_shrink=n
3 0.005 5.38048 1.7891 B m e v  arsize_top=0 arsize_bot=0 is_shrink=n
3 0.005 5.38048 1.8717 B m e v  arsize_top=0 arsize_bot=0 is_shrink=n
3 0.005 5.38048 1.9288 B m e v  arsize_top=0 arsize_bot=0 is_shrink=n
3 0.005 5.38048 2.0071 B m e v  arsize_top=0 arsize_bot=0 is_shrink=n
3 0.005 5.38048 2.0642 B m e v  arsize_top=0 arsize_bot=0 is_shrink=n
3 0.005 5.38048 2.1478 B m e v  arsize_top=0 arsize_bot=0 is_shrink=n
3 0.005 5.38048 2.2049 B m e v  arsize_top=0 arsize_bot=0 is_shrink=n
3 0.005 5.38048 2.2832 B m e v  arsize_top=0 arsize_bot=0 is_shrink=n
3 0.005 5.38048 2.3403 B m e v  arsize_top=0 arsize_bot=0 is_shrink=n
3 0.005 5.38048 2.4186 B m e v  arsize_top=0 arsize_bot=0 is_shrink=n
3 0.005 5.38048 2.4757 B m e v  arsize_top=0 arsize_bot=0 is_shrink=n
3 0.005 5.38048 2.5578 B m e v  arsize_top=0 arsize_bot=0 is_shrink=n
3 0.005 5.38048 2.6149 B m e v  arsize_top=0 arsize_bot=0 is_shrink=n
3 0.005 5.41804 0.46907 B m e v  arsize_top=0 arsize_bot=0 is_shrink=n
3 0.005 5.42901 5.98762 B m e v  arsize_top=0 arsize_bot=0 is_shrink=n
3 0.005 5.44886 2.9414 B m e v  arsize_top=0 arsize_bot=0 is_shrink=n
3 0.005 5.44886 2.9764 B m e v  arsize_top=0 arsize_bot=0 is_shrink=n
3 0.005 5.44886 3.0214 B m e v  arsize_top=0 arsize_bot=0 is_shrink=n
3 0.005 5.44886 3.0564 B m e v  arsize_top=0 arsize_bot=0 is_shrink=n
3 0.005 5.44886 3.1014 B m e v  arsize_top=0 arsize_bot=0 is_shrink=n
3 0.005 5.44886 3.1364 B m e v  arsize_top=0 arsize_bot=0 is_shrink=n
3 0.005 5.44886 3.1814 B m e v  arsize_top=0 arsize_bot=0 is_shrink=n
3 0.005 5.44886 3.2164 B m e v  arsize_top=0 arsize_bot=0 is_shrink=n
3 0.005 5.44886 3.2614 B m e v  arsize_top=0 arsize_bot=0 is_shrink=n
3 0.005 5.44886 3.2964 B m e v  arsize_top=0 arsize_bot=0 is_shrink=n
3 0.005 5.46804 0.46907 B m e v  arsize_top=0 arsize_bot=0 is_shrink=n
3 0.005 5.47901 5.98762 B m e v  arsize_top=0 arsize_bot=0 is_shrink=n
3 0.005 5.49221 2.73 B m e v  arsize_top=0 arsize_bot=0 is_shrink=n
3 0.005 5.51804 0.46907 B m e v  arsize_top=0 arsize_bot=0 is_shrink=n
3 0.005 5.52901 5.98762 B m e v  arsize_top=0 arsize_bot=0 is_shrink=n
3 0.005 5.53531 1.6642 B m e v  arsize_top=0 arsize_bot=0 is_shrink=n
3 0.005 5.53531 1.7213 B m e v  arsize_top=0 arsize_bot=0 is_shrink=n
3 0.005 5.53531 1.8032 B m e v  arsize_top=0 arsize_bot=0 is_shrink=n
3 0.005 5.53531 1.8603 B m e v  arsize_top=0 arsize_bot=0 is_shrink=n
3 0.005 5.53531 1.9393 B m e v  arsize_top=0 arsize_bot=0 is_shrink=n
3 0.005 5.53531 1.9964 B m e v  arsize_top=0 arsize_bot=0 is_shrink=n
3 0.005 5.53531 2.0802 B m e v  arsize_top=0 arsize_bot=0 is_shrink=n
3 0.005 5.53531 2.1373 B m e v  arsize_top=0 arsize_bot=0 is_shrink=n
3 0.005 5.53531 2.2156 B m e v  arsize_top=0 arsize_bot=0 is_shrink=n
3 0.005 5.53531 2.2727 B m e v  arsize_top=0 arsize_bot=0 is_shrink=n
3 0.005 5.53531 2.351 B m e v  arsize_top=0 arsize_bot=0 is_shrink=n
3 0.005 5.53531 2.4081 B m e v  arsize_top=0 arsize_bot=0 is_shrink=n
3 0.005 5.53531 2.4902 B m e v  arsize_top=0 arsize_bot=0 is_shrink=n
3 0.005 5.53531 2.5473 B m e v  arsize_top=0 arsize_bot=0 is_shrink=n
3 0.005 5.53531 2.6254 B m e v  arsize_top=0 arsize_bot=0 is_shrink=n
3 0.005 5.53531 2.6825 B m e v  arsize_top=0 arsize_bot=0 is_shrink=n
3 0.005 5.53594 4.55505 B m e v  arsize_top=0 arsize_bot=0 is_shrink=n
3 0.005 5.56804 0.46907 B m e v  arsize_top=0 arsize_bot=0 is_shrink=n
3 0.005 5.5722 3 B m e v  arsize_top=0 arsize_bot=0 is_shrink=n
3 0.005 5.57709 4.5102 B m e v  arsize_top=0 arsize_bot=0 is_shrink=n
3 0.005 5.57901 5.98762 B m e v  arsize_top=0 arsize_bot=0 is_shrink=n
3 0.005 5.5822 2.855 B m e v  arsize_top=0 arsize_bot=0 is_shrink=n
3 0.005 5.61709 4.5102 B m e v  arsize_top=0 arsize_bot=0 is_shrink=n
3 0.005 5.61804 0.46907 B m e v  arsize_top=0 arsize_bot=0 is_shrink=n
3 0.005 5.62901 5.98762 B m e v  arsize_top=0 arsize_bot=0 is_shrink=n
3 0.005 5.65709 4.5102 B m e v  arsize_top=0 arsize_bot=0 is_shrink=n
3 0.005 5.66804 0.46907 B m e v  arsize_top=0 arsize_bot=0 is_shrink=n
3 0.005 5.67901 5.98762 B m e v  arsize_top=0 arsize_bot=0 is_shrink=n
3 0.005 5.69709 4.5102 B m e v  arsize_top=0 arsize_bot=0 is_shrink=n
3 0.005 5.71804 0.46907 B m e v  arsize_top=0 arsize_bot=0 is_shrink=n
3 0.005 5.72901 5.98762 B m e v  arsize_top=0 arsize_bot=0 is_shrink=n
3 0.005 5.73709 4.5102 B m e v  arsize_top=0 arsize_bot=0 is_shrink=n
3 0.005 5.75779 3.02559 B m e v  arsize_top=0 arsize_bot=0 is_shrink=n
3 0.005 5.76804 0.46907 B m e v  arsize_top=0 arsize_bot=0 is_shrink=n
3 0.005 5.77709 4.5102 B m e v  arsize_top=0 arsize_bot=0 is_shrink=n
3 0.005 5.77901 5.98762 B m e v  arsize_top=0 arsize_bot=0 is_shrink=n
3 0.005 0.57874 0.036 B m e v  arsize_top=0 arsize_bot=0 is_shrink=n
3 0.005 0.57901 5.98762 B m e v  arsize_top=0 arsize_bot=0 is_shrink=n
3 0.005 5.81709 4.5102 B m e v  arsize_top=0 arsize_bot=0 is_shrink=n
3 0.005 5.81804 0.46907 B m e v  arsize_top=0 arsize_bot=0 is_shrink=n
3 0.005 5.82901 5.98762 B m e v  arsize_top=0 arsize_bot=0 is_shrink=n
3 0.005 5.84969 2.85 B m e v  arsize_top=0 arsize_bot=0 is_shrink=n
3 0.005 5.85709 4.5102 B m e v  arsize_top=0 arsize_bot=0 is_shrink=n
3 0.005 5.86804 0.46907 B m e v  arsize_top=0 arsize_bot=0 is_shrink=n
3 0.005 5.87901 5.98762 B m e v  arsize_top=0 arsize_bot=0 is_shrink=n
3 0.005 5.89709 4.5102 B m e v  arsize_top=0 arsize_bot=0 is_shrink=n
3 0.005 5.91804 0.46907 B m e v  arsize_top=0 arsize_bot=0 is_shrink=n
3 0.005 5.9192 2.943 B m e v  arsize_top=0 arsize_bot=0 is_shrink=n
3 0.005 5.92901 5.98762 B m e v  arsize_top=0 arsize_bot=0 is_shrink=n
3 0.005 5.93709 4.5102 B m e v  arsize_top=0 arsize_bot=0 is_shrink=n
3 0.005 5.96804 0.46907 B m e v  arsize_top=0 arsize_bot=0 is_shrink=n
3 0.005 5.97709 4.5102 B m e v  arsize_top=0 arsize_bot=0 is_shrink=n
3 0.005 5.97901 5.98762 B m e v  arsize_top=0 arsize_bot=0 is_shrink=n
3 0.005 6.01709 4.5102 B m e v  arsize_top=0 arsize_bot=0 is_shrink=n
3 0.005 6.01804 0.46907 B m e v  arsize_top=0 arsize_bot=0 is_shrink=n
3 0.005 6.02901 5.98762 B m e v  arsize_top=0 arsize_bot=0 is_shrink=n
3 0.005 6.05709 4.5102 B m e v  arsize_top=0 arsize_bot=0 is_shrink=n
3 0.005 6.06804 0.46907 B m e v  arsize_top=0 arsize_bot=0 is_shrink=n
3 0.005 6.07901 5.98762 B m e v  arsize_top=0 arsize_bot=0 is_shrink=n
3 0.005 6.09709 4.5102 B m e v  arsize_top=0 arsize_bot=0 is_shrink=n
3 0.005 6.11804 0.46907 B m e v  arsize_top=0 arsize_bot=0 is_shrink=n
3 0.005 6.12901 5.98762 B m e v  arsize_top=0 arsize_bot=0 is_shrink=n
3 0.005 6.16804 0.46907 B m e v  arsize_top=0 arsize_bot=0 is_shrink=n
3 0.005 6.17901 5.98762 B m e v  arsize_top=0 arsize_bot=0 is_shrink=n
3 0.005 6.21804 0.46907 B m e v  arsize_top=0 arsize_bot=0 is_shrink=n
3 0.005 6.22901 5.98762 B m e v  arsize_top=0 arsize_bot=0 is_shrink=n
3 0.005 6.26804 0.46907 B m e v  arsize_top=0 arsize_bot=0 is_shrink=n
3 0.005 6.27901 5.98762 B m e v  arsize_top=0 arsize_bot=0 is_shrink=n
3 0.005 0.62874 0.036 B m e v  arsize_top=0 arsize_bot=0 is_shrink=n
3 0.005 0.62901 5.98762 B m e v  arsize_top=0 arsize_bot=0 is_shrink=n
3 0.005 6.31295 4.99705 B m e v  arsize_top=0 arsize_bot=0 is_shrink=n
3 0.005 6.315 4.625 B m e v  arsize_top=0 arsize_bot=0 is_shrink=n
3 0.005 6.315 4.66 B m e v  arsize_top=0 arsize_bot=0 is_shrink=n
3 0.005 6.315 4.705 B m e v  arsize_top=0 arsize_bot=0 is_shrink=n
3 0.005 6.315 4.74 B m e v  arsize_top=0 arsize_bot=0 is_shrink=n
3 0.005 6.315 4.785 B m e v  arsize_top=0 arsize_bot=0 is_shrink=n
3 0.005 6.315 4.82 B m e v  arsize_top=0 arsize_bot=0 is_shrink=n
3 0.005 6.315 4.865 B m e v  arsize_top=0 arsize_bot=0 is_shrink=n
3 0.005 6.315 4.9 B m e v  arsize_top=0 arsize_bot=0 is_shrink=n
3 0.005 6.31804 0.46907 B m e v  arsize_top=0 arsize_bot=0 is_shrink=n
3 0.005 6.32901 5.98762 B m e v  arsize_top=0 arsize_bot=0 is_shrink=n
3 0.005 6.36804 0.46907 B m e v  arsize_top=0 arsize_bot=0 is_shrink=n
3 0.005 6.37901 5.98762 B m e v  arsize_top=0 arsize_bot=0 is_shrink=n
3 0.005 6.385 5.07 B m e v  arsize_top=0 arsize_bot=0 is_shrink=n
3 0.005 6.41804 0.46907 B m e v  arsize_top=0 arsize_bot=0 is_shrink=n
3 0.005 6.42901 5.98762 B m e v  arsize_top=0 arsize_bot=0 is_shrink=n
3 0.005 6.46804 0.46907 B m e v  arsize_top=0 arsize_bot=0 is_shrink=n
3 0.005 6.47901 5.98762 B m e v  arsize_top=0 arsize_bot=0 is_shrink=n
3 0.005 6.51803 0.46862 B m e v  arsize_top=0 arsize_bot=0 is_shrink=n
3 0.005 6.52901 5.98762 B m e v  arsize_top=0 arsize_bot=0 is_shrink=n
3 0.005 0.65349 1.85609 B m e v  arsize_top=0 arsize_bot=0 is_shrink=n
3 0.005 0.65349 1.91629 B m e v  arsize_top=0 arsize_bot=0 is_shrink=n
3 0.005 6.56568 0.45345 B m e v  arsize_top=0 arsize_bot=0 is_shrink=n
3 0.005 6.57901 5.98762 B m e v  arsize_top=0 arsize_bot=0 is_shrink=n
3 0.005 6.59709 5.0502 B m e v  arsize_top=0 arsize_bot=0 is_shrink=n
3 0.005 6.60234 0.41946 B m e v  arsize_top=0 arsize_bot=0 is_shrink=n
3 0.005 6.605 4.77 B m e v  arsize_top=0 arsize_bot=0 is_shrink=n
3 0.005 6.62 4.61 B m e v  arsize_top=0 arsize_bot=0 is_shrink=n
3 0.005 6.62 4.645 B m e v  arsize_top=0 arsize_bot=0 is_shrink=n
3 0.005 6.62 4.69 B m e v  arsize_top=0 arsize_bot=0 is_shrink=n
3 0.005 6.62 4.725 B m e v  arsize_top=0 arsize_bot=0 is_shrink=n
3 0.005 6.62107 0.3731 B m e v  arsize_top=0 arsize_bot=0 is_shrink=n
3 0.005 6.62262 0.12312 B m e v  arsize_top=0 arsize_bot=0 is_shrink=n
3 0.005 6.62262 0.17312 B m e v  arsize_top=0 arsize_bot=0 is_shrink=n
3 0.005 6.62262 0.22312 B m e v  arsize_top=0 arsize_bot=0 is_shrink=n
3 0.005 6.62262 0.27312 B m e v  arsize_top=0 arsize_bot=0 is_shrink=n
3 0.005 6.62262 0.32312 B m e v  arsize_top=0 arsize_bot=0 is_shrink=n
3 0.005 6.62299 0.07312 B m e v  arsize_top=0 arsize_bot=0 is_shrink=n
3 0.005 6.62901 5.98762 B m e v  arsize_top=0 arsize_bot=0 is_shrink=n
3 0.005 6.65219 4.77 B m e v  arsize_top=0 arsize_bot=0 is_shrink=n
3 0.005 6.65731 0.03676 B m e v  arsize_top=0 arsize_bot=0 is_shrink=n
3 0.005 6.67901 5.98762 B m e v  arsize_top=0 arsize_bot=0 is_shrink=n
3 0.005 6.70731 0.036 B m e v  arsize_top=0 arsize_bot=0 is_shrink=n
3 0.005 6.72901 5.98762 B m e v  arsize_top=0 arsize_bot=0 is_shrink=n
3 0.005 6.75731 0.036 B m e v  arsize_top=0 arsize_bot=0 is_shrink=n
3 0.005 6.77901 5.98762 B m e v  arsize_top=0 arsize_bot=0 is_shrink=n
3 0.005 0.67874 0.036 B m e v  arsize_top=0 arsize_bot=0 is_shrink=n
3 0.005 0.67901 5.98762 B m e v  arsize_top=0 arsize_bot=0 is_shrink=n
3 0.005 6.80731 0.036 B m e v  arsize_top=0 arsize_bot=0 is_shrink=n
3 0.005 6.82901 5.98762 B m e v  arsize_top=0 arsize_bot=0 is_shrink=n
3 0.005 6.85731 0.036 B m e v  arsize_top=0 arsize_bot=0 is_shrink=n
3 0.005 6.87 5 B m e v  arsize_top=0 arsize_bot=0 is_shrink=n
3 0.005 6.87901 5.98762 B m e v  arsize_top=0 arsize_bot=0 is_shrink=n
3 0.005 6.905 4.88705 B m e v  arsize_top=0 arsize_bot=0 is_shrink=n
3 0.005 6.905 4.94705 B m e v  arsize_top=0 arsize_bot=0 is_shrink=n
3 0.005 6.90731 0.036 B m e v  arsize_top=0 arsize_bot=0 is_shrink=n
3 0.005 6.92901 5.98762 B m e v  arsize_top=0 arsize_bot=0 is_shrink=n
3 0.005 6.955 4.72 B m e v  arsize_top=0 arsize_bot=0 is_shrink=n
3 0.005 6.955 4.76 B m e v  arsize_top=0 arsize_bot=0 is_shrink=n
3 0.005 6.955 4.8 B m e v  arsize_top=0 arsize_bot=0 is_shrink=n
3 0.005 6.955 4.84 B m e v  arsize_top=0 arsize_bot=0 is_shrink=n
3 0.005 6.95731 0.036 B m e v  arsize_top=0 arsize_bot=0 is_shrink=n
3 0.005 6.97901 5.98762 B m e v  arsize_top=0 arsize_bot=0 is_shrink=n
3 0.005 7.00731 0.036 B m e v  arsize_top=0 arsize_bot=0 is_shrink=n
3 0.005 0.705 5.355 B m e v  arsize_top=0 arsize_bot=0 is_shrink=n
3 0.005 7.1926 5.04351 B m e v  arsize_top=0 arsize_bot=0 is_shrink=n
3 0.005 7.2426 4.60351 B m e v  arsize_top=0 arsize_bot=0 is_shrink=n
3 0.005 0.72874 0.036 B m e v  arsize_top=0 arsize_bot=0 is_shrink=n
3 0.005 0.72901 5.98762 B m e v  arsize_top=0 arsize_bot=0 is_shrink=n
3 0.005 0.73 5.175 B m e v  arsize_top=0 arsize_bot=0 is_shrink=n
3 0.005 7.3401 4.85601 B m e v  arsize_top=0 arsize_bot=0 is_shrink=n
3 0.005 7.35731 0.036 B m e v  arsize_top=0 arsize_bot=0 is_shrink=n
3 0.005 7.37901 5.98762 B m e v  arsize_top=0 arsize_bot=0 is_shrink=n
3 0.005 7.40731 0.036 B m e v  arsize_top=0 arsize_bot=0 is_shrink=n
3 0.005 7.42901 5.98762 B m e v  arsize_top=0 arsize_bot=0 is_shrink=n
3 0.005 7.45731 0.036 B m e v  arsize_top=0 arsize_bot=0 is_shrink=n
3 0.005 7.47901 5.98762 B m e v  arsize_top=0 arsize_bot=0 is_shrink=n
3 0.005 7.50731 0.036 B m e v  arsize_top=0 arsize_bot=0 is_shrink=n
3 0.005 7.52901 5.98762 B m e v  arsize_top=0 arsize_bot=0 is_shrink=n
3 0.005 7.55731 0.036 B m e v  arsize_top=0 arsize_bot=0 is_shrink=n
3 0.005 7.56575 4.81402 B m e v  arsize_top=0 arsize_bot=0 is_shrink=n
3 0.005 7.56575 5.023 B m e v  arsize_top=0 arsize_bot=0 is_shrink=n
3 0.005 7.57119 4.66826 B m e v  arsize_top=0 arsize_bot=0 is_shrink=n
3 0.005 7.57119 5.13026 B m e v  arsize_top=0 arsize_bot=0 is_shrink=n
3 0.005 7.57901 5.98762 B m e v  arsize_top=0 arsize_bot=0 is_shrink=n
3 0.005 7.60731 0.036 B m e v  arsize_top=0 arsize_bot=0 is_shrink=n
3 0.005 7.62901 5.98762 B m e v  arsize_top=0 arsize_bot=0 is_shrink=n
3 0.005 7.63119 4.66826 B m e v  arsize_top=0 arsize_bot=0 is_shrink=n
3 0.005 7.63119 5.13026 B m e v  arsize_top=0 arsize_bot=0 is_shrink=n
3 0.005 7.63527 4.81527 B m e v  arsize_top=0 arsize_bot=0 is_shrink=n
3 0.005 7.63662 4.92 B m e v  arsize_top=0 arsize_bot=0 is_shrink=n
3 0.005 7.63662 5.023 B m e v  arsize_top=0 arsize_bot=0 is_shrink=n
3 0.005 7.64204 5.09224 B m e v  arsize_top=0 arsize_bot=0 is_shrink=n
3 0.005 7.64205 4.74418 B m e v  arsize_top=0 arsize_bot=0 is_shrink=n
3 0.005 7.65731 0.036 B m e v  arsize_top=0 arsize_bot=0 is_shrink=n
3 0.005 7.67901 5.98762 B m e v  arsize_top=0 arsize_bot=0 is_shrink=n
3 0.005 7.70204 5.09224 B m e v  arsize_top=0 arsize_bot=0 is_shrink=n
3 0.005 7.70205 4.74418 B m e v  arsize_top=0 arsize_bot=0 is_shrink=n
3 0.005 7.70354 4.812 B m e v  arsize_top=0 arsize_bot=0 is_shrink=n
3 0.005 7.70731 0.036 B m e v  arsize_top=0 arsize_bot=0 is_shrink=n
3 0.005 7.70749 4.9207 B m e v  arsize_top=0 arsize_bot=0 is_shrink=n
3 0.005 7.70749 5.023 B m e v  arsize_top=0 arsize_bot=0 is_shrink=n
3 0.005 7.72901 5.98762 B m e v  arsize_top=0 arsize_bot=0 is_shrink=n
3 0.005 7.75731 0.036 B m e v  arsize_top=0 arsize_bot=0 is_shrink=n
3 0.005 7.77835 4.9207 B m e v  arsize_top=0 arsize_bot=0 is_shrink=n
3 0.005 7.77835 5.023 B m e v  arsize_top=0 arsize_bot=0 is_shrink=n
3 0.005 7.77901 5.98762 B m e v  arsize_top=0 arsize_bot=0 is_shrink=n
3 0.005 7.77954 4.812 B m e v  arsize_top=0 arsize_bot=0 is_shrink=n
3 0.005 0.77874 0.036 B m e v  arsize_top=0 arsize_bot=0 is_shrink=n
3 0.005 7.78379 4.74418 B m e v  arsize_top=0 arsize_bot=0 is_shrink=n
3 0.005 0.77901 5.98762 B m e v  arsize_top=0 arsize_bot=0 is_shrink=n
3 0.005 0.07874 0.036 B m e v  arsize_top=0 arsize_bot=0 is_shrink=n
3 0.005 7.80731 0.036 B m e v  arsize_top=0 arsize_bot=0 is_shrink=n
3 0.005 7.82901 5.98762 B m e v  arsize_top=0 arsize_bot=0 is_shrink=n
3 0.005 7.84379 4.74418 B m e v  arsize_top=0 arsize_bot=0 is_shrink=n
3 0.005 7.84922 4.81 B m e v  arsize_top=0 arsize_bot=0 is_shrink=n
3 0.005 7.84922 4.9207 B m e v  arsize_top=0 arsize_bot=0 is_shrink=n
3 0.005 7.84922 5.023 B m e v  arsize_top=0 arsize_bot=0 is_shrink=n
3 0.005 7.85465 4.61826 B m e v  arsize_top=0 arsize_bot=0 is_shrink=n
3 0.005 7.85465 5.13026 B m e v  arsize_top=0 arsize_bot=0 is_shrink=n
3 0.005 7.85731 0.036 B m e v  arsize_top=0 arsize_bot=0 is_shrink=n
3 0.005 7.87901 5.98762 B m e v  arsize_top=0 arsize_bot=0 is_shrink=n
3 0.005 0.07901 5.98762 B m e v  arsize_top=0 arsize_bot=0 is_shrink=n
3 0.005 7.90731 0.036 B m e v  arsize_top=0 arsize_bot=0 is_shrink=n
3 0.005 7.91465 4.61826 B m e v  arsize_top=0 arsize_bot=0 is_shrink=n
3 0.005 7.91465 5.13026 B m e v  arsize_top=0 arsize_bot=0 is_shrink=n
3 0.005 7.92008 4.9207 B m e v  arsize_top=0 arsize_bot=0 is_shrink=n
3 0.005 7.92008 5.023 B m e v  arsize_top=0 arsize_bot=0 is_shrink=n
3 0.005 7.92354 4.81 B m e v  arsize_top=0 arsize_bot=0 is_shrink=n
3 0.005 7.92551 5.09224 B m e v  arsize_top=0 arsize_bot=0 is_shrink=n
3 0.005 7.927 5.377 B m e v  arsize_top=0 arsize_bot=0 is_shrink=n
3 0.005 7.92901 5.98762 B m e v  arsize_top=0 arsize_bot=0 is_shrink=n
3 0.005 7.95731 0.036 B m e v  arsize_top=0 arsize_bot=0 is_shrink=n
3 0.005 7.97901 5.98762 B m e v  arsize_top=0 arsize_bot=0 is_shrink=n
3 0.005 7.98551 5.09224 B m e v  arsize_top=0 arsize_bot=0 is_shrink=n
3 0.005 7.99095 4.9207 B m e v  arsize_top=0 arsize_bot=0 is_shrink=n
3 0.005 7.99095 5.023 B m e v  arsize_top=0 arsize_bot=0 is_shrink=n
3 0.005 7.99354 4.81 B m e v  arsize_top=0 arsize_bot=0 is_shrink=n
3 0.005 8.00731 0.036 B m e v  arsize_top=0 arsize_bot=0 is_shrink=n
3 0.005 8.02207 4.62815 B m e v  arsize_top=0 arsize_bot=0 is_shrink=n
3 0.005 8.02901 5.98762 B m e v  arsize_top=0 arsize_bot=0 is_shrink=n
3 0.005 8.05731 0.036 B m e v  arsize_top=0 arsize_bot=0 is_shrink=n
3 0.005 8.06182 4.9207 B m e v  arsize_top=0 arsize_bot=0 is_shrink=n
3 0.005 8.06182 5.023 B m e v  arsize_top=0 arsize_bot=0 is_shrink=n
3 0.005 8.06441 4.81 B m e v  arsize_top=0 arsize_bot=0 is_shrink=n
3 0.005 8.06725 4.74418 B m e v  arsize_top=0 arsize_bot=0 is_shrink=n
3 0.005 8.06725 5.13026 B m e v  arsize_top=0 arsize_bot=0 is_shrink=n
3 0.005 8.07901 5.98762 B m e v  arsize_top=0 arsize_bot=0 is_shrink=n
3 0.005 8.08207 4.62815 B m e v  arsize_top=0 arsize_bot=0 is_shrink=n
3 0.005 8.10731 0.036 B m e v  arsize_top=0 arsize_bot=0 is_shrink=n
3 0.005 8.12725 4.74418 B m e v  arsize_top=0 arsize_bot=0 is_shrink=n
3 0.005 8.12725 5.13026 B m e v  arsize_top=0 arsize_bot=0 is_shrink=n
3 0.005 8.12901 5.98762 B m e v  arsize_top=0 arsize_bot=0 is_shrink=n
3 0.005 8.13268 4.81 B m e v  arsize_top=0 arsize_bot=0 is_shrink=n
3 0.005 8.13268 4.9207 B m e v  arsize_top=0 arsize_bot=0 is_shrink=n
3 0.005 8.13268 5.023 B m e v  arsize_top=0 arsize_bot=0 is_shrink=n
3 0.005 8.13811 5.09224 B m e v  arsize_top=0 arsize_bot=0 is_shrink=n
3 0.005 8.147 5.377 B m e v  arsize_top=0 arsize_bot=0 is_shrink=n
3 0.005 8.15731 0.036 B m e v  arsize_top=0 arsize_bot=0 is_shrink=n
3 0.005 8.17901 5.98762 B m e v  arsize_top=0 arsize_bot=0 is_shrink=n
3 0.005 8.19811 5.09224 B m e v  arsize_top=0 arsize_bot=0 is_shrink=n
3 0.005 8.20355 4.81 B m e v  arsize_top=0 arsize_bot=0 is_shrink=n
3 0.005 8.20355 4.9267 B m e v  arsize_top=0 arsize_bot=0 is_shrink=n
3 0.005 8.20355 5.023 B m e v  arsize_top=0 arsize_bot=0 is_shrink=n
3 0.005 8.20731 0.036 B m e v  arsize_top=0 arsize_bot=0 is_shrink=n
3 0.005 8.20898 4.74418 B m e v  arsize_top=0 arsize_bot=0 is_shrink=n
3 0.005 8.21209 4.62826 B m e v  arsize_top=0 arsize_bot=0 is_shrink=n
3 0.005 8.22901 5.98762 B m e v  arsize_top=0 arsize_bot=0 is_shrink=n
3 0.005 8.25731 0.036 B m e v  arsize_top=0 arsize_bot=0 is_shrink=n
3 0.005 8.26898 4.74418 B m e v  arsize_top=0 arsize_bot=0 is_shrink=n
3 0.005 8.27209 4.62826 B m e v  arsize_top=0 arsize_bot=0 is_shrink=n
3 0.005 8.27441 4.81 B m e v  arsize_top=0 arsize_bot=0 is_shrink=n
3 0.005 8.27441 4.9207 B m e v  arsize_top=0 arsize_bot=0 is_shrink=n
3 0.005 8.27441 5.023 B m e v  arsize_top=0 arsize_bot=0 is_shrink=n
3 0.005 8.27901 5.98762 B m e v  arsize_top=0 arsize_bot=0 is_shrink=n
3 0.005 0.82874 0.036 B m e v  arsize_top=0 arsize_bot=0 is_shrink=n
3 0.005 0.82901 5.98762 B m e v  arsize_top=0 arsize_bot=0 is_shrink=n
3 0.005 8.30731 0.036 B m e v  arsize_top=0 arsize_bot=0 is_shrink=n
3 0.005 8.32901 5.98762 B m e v  arsize_top=0 arsize_bot=0 is_shrink=n
3 0.005 8.34528 4.81 B m e v  arsize_top=0 arsize_bot=0 is_shrink=n
3 0.005 8.34528 4.9207 B m e v  arsize_top=0 arsize_bot=0 is_shrink=n
3 0.005 8.34528 5.023 B m e v  arsize_top=0 arsize_bot=0 is_shrink=n
3 0.005 8.35071 4.70326 B m e v  arsize_top=0 arsize_bot=0 is_shrink=n
3 0.005 8.35071 5.15374 B m e v  arsize_top=0 arsize_bot=0 is_shrink=n
3 0.005 8.35731 0.036 B m e v  arsize_top=0 arsize_bot=0 is_shrink=n
3 0.005 8.37901 5.98762 B m e v  arsize_top=0 arsize_bot=0 is_shrink=n
3 0.005 8.40731 0.036 B m e v  arsize_top=0 arsize_bot=0 is_shrink=n
3 0.005 8.41071 4.70326 B m e v  arsize_top=0 arsize_bot=0 is_shrink=n
3 0.005 8.41071 5.15374 B m e v  arsize_top=0 arsize_bot=0 is_shrink=n
3 0.005 8.41615 4.81402 B m e v  arsize_top=0 arsize_bot=0 is_shrink=n
3 0.005 8.41615 5.023 B m e v  arsize_top=0 arsize_bot=0 is_shrink=n
3 0.005 8.42901 5.98762 B m e v  arsize_top=0 arsize_bot=0 is_shrink=n
3 0.005 8.45731 0.036 B m e v  arsize_top=0 arsize_bot=0 is_shrink=n
3 0.005 8.47901 5.98762 B m e v  arsize_top=0 arsize_bot=0 is_shrink=n
3 0.005 0.84953 5.17 B m e v  arsize_top=0 arsize_bot=0 is_shrink=n
3 0.005 8.50731 0.036 B m e v  arsize_top=0 arsize_bot=0 is_shrink=n
3 0.005 8.52901 5.98762 B m e v  arsize_top=0 arsize_bot=0 is_shrink=n
3 0.005 8.55731 0.036 B m e v  arsize_top=0 arsize_bot=0 is_shrink=n
3 0.005 8.57901 5.98762 B m e v  arsize_top=0 arsize_bot=0 is_shrink=n
3 0.005 8.60731 0.036 B m e v  arsize_top=0 arsize_bot=0 is_shrink=n
3 0.005 8.62901 5.98762 B m e v  arsize_top=0 arsize_bot=0 is_shrink=n
3 0.005 8.65731 0.036 B m e v  arsize_top=0 arsize_bot=0 is_shrink=n
3 0.005 8.67901 5.98762 B m e v  arsize_top=0 arsize_bot=0 is_shrink=n
3 0.005 8.70731 0.036 B m e v  arsize_top=0 arsize_bot=0 is_shrink=n
3 0.005 8.72901 5.98762 B m e v  arsize_top=0 arsize_bot=0 is_shrink=n
3 0.005 8.73035 4.81402 B m e v  arsize_top=0 arsize_bot=0 is_shrink=n
3 0.005 8.73035 5.023 B m e v  arsize_top=0 arsize_bot=0 is_shrink=n
3 0.005 8.73579 4.70574 B m e v  arsize_top=0 arsize_bot=0 is_shrink=n
3 0.005 8.73579 5.17874 B m e v  arsize_top=0 arsize_bot=0 is_shrink=n
3 0.005 8.75731 0.036 B m e v  arsize_top=0 arsize_bot=0 is_shrink=n
3 0.005 8.77901 5.98762 B m e v  arsize_top=0 arsize_bot=0 is_shrink=n
3 0.005 0.87874 0.036 B m e v  arsize_top=0 arsize_bot=0 is_shrink=n
3 0.005 0.87901 5.98762 B m e v  arsize_top=0 arsize_bot=0 is_shrink=n
3 0.005 8.79579 4.70574 B m e v  arsize_top=0 arsize_bot=0 is_shrink=n
3 0.005 8.79579 5.17874 B m e v  arsize_top=0 arsize_bot=0 is_shrink=n
3 0.005 8.80122 4.81402 B m e v  arsize_top=0 arsize_bot=0 is_shrink=n
3 0.005 8.80122 4.92 B m e v  arsize_top=0 arsize_bot=0 is_shrink=n
3 0.005 8.80122 5.023 B m e v  arsize_top=0 arsize_bot=0 is_shrink=n
3 0.005 8.80665 4.74418 B m e v  arsize_top=0 arsize_bot=0 is_shrink=n
3 0.005 8.80731 0.036 B m e v  arsize_top=0 arsize_bot=0 is_shrink=n
3 0.005 8.82901 5.98762 B m e v  arsize_top=0 arsize_bot=0 is_shrink=n
3 0.005 8.85731 0.036 B m e v  arsize_top=0 arsize_bot=0 is_shrink=n
3 0.005 8.86665 4.74418 B m e v  arsize_top=0 arsize_bot=0 is_shrink=n
3 0.005 8.86909 4.81402 B m e v  arsize_top=0 arsize_bot=0 is_shrink=n
3 0.005 8.87209 4.92 B m e v  arsize_top=0 arsize_bot=0 is_shrink=n
3 0.005 8.87209 5.023 B m e v  arsize_top=0 arsize_bot=0 is_shrink=n
3 0.005 8.87441 5.20876 B m e v  arsize_top=0 arsize_bot=0 is_shrink=n
3 0.005 8.87901 5.98762 B m e v  arsize_top=0 arsize_bot=0 is_shrink=n
3 0.005 8.88062 4.70574 B m e v  arsize_top=0 arsize_bot=0 is_shrink=n
3 0.005 8.90731 0.036 B m e v  arsize_top=0 arsize_bot=0 is_shrink=n
3 0.005 8.92901 5.98762 B m e v  arsize_top=0 arsize_bot=0 is_shrink=n
3 0.005 8.93441 5.20876 B m e v  arsize_top=0 arsize_bot=0 is_shrink=n
3 0.005 8.94062 4.70574 B m e v  arsize_top=0 arsize_bot=0 is_shrink=n
3 0.005 8.94279 2.925 B m e v  arsize_top=0 arsize_bot=0 is_shrink=n
3 0.005 8.94295 5.023 B m e v  arsize_top=0 arsize_bot=0 is_shrink=n
3 0.005 8.94495 4.81402 B m e v  arsize_top=0 arsize_bot=0 is_shrink=n
3 0.005 8.94854 4.92 B m e v  arsize_top=0 arsize_bot=0 is_shrink=n
3 0.005 8.95731 0.036 B m e v  arsize_top=0 arsize_bot=0 is_shrink=n
3 0.005 8.97901 5.98762 B m e v  arsize_top=0 arsize_bot=0 is_shrink=n
3 0.005 8.98115 2.7861 B m e v  arsize_top=0 arsize_bot=0 is_shrink=n
3 0.005 8.98115 2.8989 B m e v  arsize_top=0 arsize_bot=0 is_shrink=n
3 0.005 9.00731 0.036 B m e v  arsize_top=0 arsize_bot=0 is_shrink=n
3 0.005 9.01382 4.81402 B m e v  arsize_top=0 arsize_bot=0 is_shrink=n
3 0.005 9.01382 4.92 B m e v  arsize_top=0 arsize_bot=0 is_shrink=n
3 0.005 9.01382 5.023 B m e v  arsize_top=0 arsize_bot=0 is_shrink=n
3 0.005 9.01925 4.70574 B m e v  arsize_top=0 arsize_bot=0 is_shrink=n
3 0.005 9.01925 5.20374 B m e v  arsize_top=0 arsize_bot=0 is_shrink=n
3 0.005 9.02901 5.98762 B m e v  arsize_top=0 arsize_bot=0 is_shrink=n
3 0.005 9.05731 0.036 B m e v  arsize_top=0 arsize_bot=0 is_shrink=n
3 0.005 9.07 5.332 B m e v  arsize_top=0 arsize_bot=0 is_shrink=n
3 0.005 9.07901 5.98762 B m e v  arsize_top=0 arsize_bot=0 is_shrink=n
3 0.005 9.07925 4.70574 B m e v  arsize_top=0 arsize_bot=0 is_shrink=n
3 0.005 9.07925 5.20374 B m e v  arsize_top=0 arsize_bot=0 is_shrink=n
3 0.005 9.08045 4.81402 B m e v  arsize_top=0 arsize_bot=0 is_shrink=n
3 0.005 9.08468 4.92 B m e v  arsize_top=0 arsize_bot=0 is_shrink=n
3 0.005 9.08468 5.023 B m e v  arsize_top=0 arsize_bot=0 is_shrink=n
3 0.005 9.09011 5.09224 B m e v  arsize_top=0 arsize_bot=0 is_shrink=n
3 0.005 9.10731 0.036 B m e v  arsize_top=0 arsize_bot=0 is_shrink=n
3 0.005 9.12901 5.98762 B m e v  arsize_top=0 arsize_bot=0 is_shrink=n
3 0.005 9.14354 4.92 B m e v  arsize_top=0 arsize_bot=0 is_shrink=n
3 0.005 9.15011 5.09224 B m e v  arsize_top=0 arsize_bot=0 is_shrink=n
3 0.005 9.15555 5.023 B m e v  arsize_top=0 arsize_bot=0 is_shrink=n
3 0.005 9.15731 0.036 B m e v  arsize_top=0 arsize_bot=0 is_shrink=n
3 0.005 9.15752 4.81402 B m e v  arsize_top=0 arsize_bot=0 is_shrink=n
3 0.005 9.16098 4.74418 B m e v  arsize_top=0 arsize_bot=0 is_shrink=n
3 0.005 9.17901 5.98762 B m e v  arsize_top=0 arsize_bot=0 is_shrink=n
3 0.005 9.20731 0.036 B m e v  arsize_top=0 arsize_bot=0 is_shrink=n
3 0.005 9.22098 4.74418 B m e v  arsize_top=0 arsize_bot=0 is_shrink=n
3 0.005 9.22642 4.81402 B m e v  arsize_top=0 arsize_bot=0 is_shrink=n
3 0.005 9.22642 4.92 B m e v  arsize_top=0 arsize_bot=0 is_shrink=n
3 0.005 9.22642 5.023 B m e v  arsize_top=0 arsize_bot=0 is_shrink=n
3 0.005 9.22901 5.98762 B m e v  arsize_top=0 arsize_bot=0 is_shrink=n
3 0.005 9.23185 4.68074 B m e v  arsize_top=0 arsize_bot=0 is_shrink=n
3 0.005 9.23185 5.18128 B m e v  arsize_top=0 arsize_bot=0 is_shrink=n
3 0.005 9.25731 0.036 B m e v  arsize_top=0 arsize_bot=0 is_shrink=n
3 0.005 9.265 5.332 B m e v  arsize_top=0 arsize_bot=0 is_shrink=n
3 0.005 9.27854 4.92 B m e v  arsize_top=0 arsize_bot=0 is_shrink=n
3 0.005 9.27901 5.98762 B m e v  arsize_top=0 arsize_bot=0 is_shrink=n
3 0.005 0.92874 0.036 B m e v  arsize_top=0 arsize_bot=0 is_shrink=n
3 0.005 0.92901 5.98762 B m e v  arsize_top=0 arsize_bot=0 is_shrink=n
3 0.005 9.29185 4.68074 B m e v  arsize_top=0 arsize_bot=0 is_shrink=n
3 0.005 9.29185 5.18128 B m e v  arsize_top=0 arsize_bot=0 is_shrink=n
3 0.005 9.29728 4.81402 B m e v  arsize_top=0 arsize_bot=0 is_shrink=n
3 0.005 9.29728 5.023 B m e v  arsize_top=0 arsize_bot=0 is_shrink=n
3 0.005 9.30271 5.14224 B m e v  arsize_top=0 arsize_bot=0 is_shrink=n
3 0.005 9.30731 0.036 B m e v  arsize_top=0 arsize_bot=0 is_shrink=n
3 0.005 9.32901 5.98762 B m e v  arsize_top=0 arsize_bot=0 is_shrink=n
3 0.005 9.35731 0.036 B m e v  arsize_top=0 arsize_bot=0 is_shrink=n
3 0.005 9.36271 5.14224 B m e v  arsize_top=0 arsize_bot=0 is_shrink=n
3 0.005 9.36815 4.81402 B m e v  arsize_top=0 arsize_bot=0 is_shrink=n
3 0.005 9.36815 4.926 B m e v  arsize_top=0 arsize_bot=0 is_shrink=n
3 0.005 9.36815 5.023 B m e v  arsize_top=0 arsize_bot=0 is_shrink=n
3 0.005 9.37358 4.74418 B m e v  arsize_top=0 arsize_bot=0 is_shrink=n
3 0.005 9.37358 5.18128 B m e v  arsize_top=0 arsize_bot=0 is_shrink=n
3 0.005 9.37901 5.98762 B m e v  arsize_top=0 arsize_bot=0 is_shrink=n
3 0.005 9.40731 0.036 B m e v  arsize_top=0 arsize_bot=0 is_shrink=n
3 0.005 9.40795 0.26133 B m e v  arsize_top=0 arsize_bot=0 is_shrink=n
3 0.005 9.415 5.332 B m e v  arsize_top=0 arsize_bot=0 is_shrink=n
3 0.005 9.42901 5.98762 B m e v  arsize_top=0 arsize_bot=0 is_shrink=n
3 0.005 9.43358 4.74418 B m e v  arsize_top=0 arsize_bot=0 is_shrink=n
3 0.005 9.43358 5.18128 B m e v  arsize_top=0 arsize_bot=0 is_shrink=n
3 0.005 9.43901 4.81402 B m e v  arsize_top=0 arsize_bot=0 is_shrink=n
3 0.005 9.43901 4.928 B m e v  arsize_top=0 arsize_bot=0 is_shrink=n
3 0.005 9.43901 5.023 B m e v  arsize_top=0 arsize_bot=0 is_shrink=n
3 0.005 9.44445 4.62574 B m e v  arsize_top=0 arsize_bot=0 is_shrink=n
3 0.005 9.45731 0.036 B m e v  arsize_top=0 arsize_bot=0 is_shrink=n
3 0.005 9.45795 0.36633 B m e v  arsize_top=0 arsize_bot=0 is_shrink=n
3 0.005 9.47901 5.98762 B m e v  arsize_top=0 arsize_bot=0 is_shrink=n
3 0.005 9.50445 4.62574 B m e v  arsize_top=0 arsize_bot=0 is_shrink=n
3 0.005 9.50731 0.036 B m e v  arsize_top=0 arsize_bot=0 is_shrink=n
3 0.005 9.50988 4.81402 B m e v  arsize_top=0 arsize_bot=0 is_shrink=n
3 0.005 9.50988 4.92 B m e v  arsize_top=0 arsize_bot=0 is_shrink=n
3 0.005 9.50988 5.023 B m e v  arsize_top=0 arsize_bot=0 is_shrink=n
3 0.005 9.51531 4.68099 B m e v  arsize_top=0 arsize_bot=0 is_shrink=n
3 0.005 9.51531 5.17874 B m e v  arsize_top=0 arsize_bot=0 is_shrink=n
3 0.005 9.52901 5.98762 B m e v  arsize_top=0 arsize_bot=0 is_shrink=n
3 0.005 0.955 5.325 B m e v  arsize_top=0 arsize_bot=0 is_shrink=n
3 0.005 9.55731 0.036 B m e v  arsize_top=0 arsize_bot=0 is_shrink=n
3 0.005 9.57531 4.68099 B m e v  arsize_top=0 arsize_bot=0 is_shrink=n
3 0.005 9.57531 5.17874 B m e v  arsize_top=0 arsize_bot=0 is_shrink=n
3 0.005 9.57901 5.98762 B m e v  arsize_top=0 arsize_bot=0 is_shrink=n
3 0.005 9.58075 4.81402 B m e v  arsize_top=0 arsize_bot=0 is_shrink=n
3 0.005 9.58075 5.023 B m e v  arsize_top=0 arsize_bot=0 is_shrink=n
3 0.005 9.60731 0.036 B m e v  arsize_top=0 arsize_bot=0 is_shrink=n
3 0.005 9.62901 5.98762 B m e v  arsize_top=0 arsize_bot=0 is_shrink=n
3 0.005 9.64796 0.79643 B m e v  arsize_top=0 arsize_bot=0 is_shrink=n
3 0.005 9.65731 0.036 B m e v  arsize_top=0 arsize_bot=0 is_shrink=n
3 0.005 9.67901 5.98762 B m e v  arsize_top=0 arsize_bot=0 is_shrink=n
3 0.005 9.70731 0.036 B m e v  arsize_top=0 arsize_bot=0 is_shrink=n
3 0.005 9.72901 5.98762 B m e v  arsize_top=0 arsize_bot=0 is_shrink=n
3 0.005 9.75731 0.036 B m e v  arsize_top=0 arsize_bot=0 is_shrink=n
3 0.005 9.77901 5.98762 B m e v  arsize_top=0 arsize_bot=0 is_shrink=n
3 0.005 0.97874 0.036 B m e v  arsize_top=0 arsize_bot=0 is_shrink=n
3 0.005 0.97901 5.98762 B m e v  arsize_top=0 arsize_bot=0 is_shrink=n
3 0.005 9.80731 0.036 B m e v  arsize_top=0 arsize_bot=0 is_shrink=n
3 0.005 9.82901 5.98762 B m e v  arsize_top=0 arsize_bot=0 is_shrink=n
3 0.005 9.85731 0.036 B m e v  arsize_top=0 arsize_bot=0 is_shrink=n
3 0.005 9.87901 5.98762 B m e v  arsize_top=0 arsize_bot=0 is_shrink=n
3 0.005 9.90731 0.036 B m e v  arsize_top=0 arsize_bot=0 is_shrink=n
3 0.005 9.91 4.7 B m e v  arsize_top=0 arsize_bot=0 is_shrink=n
3 0.005 9.92901 5.98762 B m e v  arsize_top=0 arsize_bot=0 is_shrink=n
3 0.005 9.95731 0.036 B m e v  arsize_top=0 arsize_bot=0 is_shrink=n
3 0.005 9.96 4.69 B m e v  arsize_top=0 arsize_bot=0 is_shrink=n
3 0.005 9.97901 5.98762 B m e v  arsize_top=0 arsize_bot=0 is_shrink=n
3 0.005 9.995 2.87559 B m e v  arsize_top=0 arsize_bot=0 is_shrink=n
4 0.0126 4.95768 1.99115 T e e  arsize_top=0 arsize_bot=0 is_shrink=n
4 0 5.30875 1.7821 D 0.02 0.02 e e staggered 0 0 0  is_shrink=n
4 0.004 4.98268 1.96615 B m e v  arsize_top=0 arsize_bot=0 is_shrink=n
5 0.01378 0.17323 2.51575 B e e  arsize_top=0 arsize_bot=0 is_shrink=n
5 0 5.34275 1.7821 D 0.02 0.02 e e staggered 0 0 0  is_shrink=n
5 0.004 5.42048 1.7796 B m e v  arsize_top=0 arsize_bot=0 is_shrink=n
6 0 0.52 5.591 T 0.03 0.03 e e staggered 0 0 0  is_shrink=n
6 0 4.9574 5.54685 T 0.02362 0.04134 e e staggered 0 0 0  is_shrink=n
6 0 4.86 5.767 T 0.02 0.02 e e staggered 0 0 0  is_shrink=n
6 0 4.76 5.408 T 0.02 0.02 e e staggered 0 0 0  is_shrink=n
6 0 3.94 4.627 T 0.02 0.02 e e staggered 0 0 0  is_shrink=n
6 0 1.03 4.993 T 0.02 0.02 e e staggered 0 0 0  is_shrink=n
6 0 5.06 5.767 T 0.02 0.02 e e staggered 0 0 0  is_shrink=n
6 0 1.044 5.417 T 0.02 0.02 e e staggered 0 0 0  is_shrink=n
6 0 1.12 5.857 T 0.02 0.02 e e staggered 0 0 0  is_shrink=n
6 0 1.04 5.857 T 0.02 0.02 e e staggered 0 0 0  is_shrink=n
6 0 1.094 5.383 T 0.02 0.02 e e staggered 0 0 0  is_shrink=n
6 0 0.948 5.383 T 0.02 0.02 e e staggered 0 0 0  is_shrink=n
6 0 0.9 5.383 T 0.02 0.02 e e staggered 0 0 0  is_shrink=n
6 0 0.83 5.383 T 0.02 0.02 e e staggered 0 0 0  is_shrink=n
6 0 3.94 4.683 T 0.02 0.02 e e staggered 0 0 0  is_shrink=n
6 0 0.97 5.857 T 0.02 0.02 e e staggered 0 0 0  is_shrink=n
6 0 0.89 5.857 T 0.02 0.02 e e staggered 0 0 0  is_shrink=n
6 0 0.81 5.857 T 0.02 0.02 e e staggered 0 0 0  is_shrink=n
6 0 0.73 5.857 T 0.02 0.02 e e staggered 0 0 0  is_shrink=n
6 0 0.91 5.113 T 0.02 0.02 e e staggered 0 0 0  is_shrink=n
6 0 7.2426 5.12551 T 0.02 0.02 e e staggered 0 0 0  is_shrink=n
6 0 7.2926 5.12551 T 0.02 0.02 e e staggered 0 0 0  is_shrink=n
6 0 7.3926 5.12551 T 0.02 0.02 e e staggered 0 0 0  is_shrink=n
6 0 1.23906 5.12551 T 0.02 0.02 e e staggered 0 0 0  is_shrink=n
6 0 1.28906 5.12551 T 0.02 0.02 e e staggered 0 0 0  is_shrink=n
6 0 1.38906 5.12551 T 0.02 0.02 e e staggered 0 0 0  is_shrink=n
6 0 0.755 5.383 T 0.02 0.02 e e staggered 0 0 0  is_shrink=n
6 0 5.16 5.583 T 0.02 0.02 e e staggered 0 0 0  is_shrink=n
6 0 4.96 5.442 T 0.02 0.02 e e staggered 0 0 0  is_shrink=n
6 0 4.14 4.717 T 0.02 0.02 e e staggered 0 0 0  is_shrink=n
6 0 1.31 5.417 T 0.02 0.02 e e staggered 0 0 0  is_shrink=n
6 0 1.46 5.417 T 0.02 0.02 e e staggered 0 0 0  is_shrink=n
6 0 1.41 5.417 T 0.02 0.02 e e staggered 0 0 0  is_shrink=n
6 0 0.73 5.233 T 0.02 0.02 e e staggered 0 0 0  is_shrink=n
6 0 3.77 4.793 T 0.02 0.02 e e staggered 0 0 0  is_shrink=n
6 0 7.1926 4.98151 T 0.02 0.02 e e staggered 0 0 0  is_shrink=n
6 0 1.18906 4.98151 T 0.02 0.02 e e staggered 0 0 0  is_shrink=n
6 0 1.36 5.417 T 0.02 0.02 e e staggered 0 0 0  is_shrink=n
6 0 1.03 5.127 T 0.02 0.02 e e staggered 0 0 0  is_shrink=n
6 0 5.09559 5.55965 T 0.01575 0.03543 e e staggered 0 0 0  is_shrink=n
6 0 4.08035 4.71559 T 0.03543 0.01575 e e staggered 0 0 0  is_shrink=n
6 0 1.02559 5.20965 T 0.01575 0.03543 e e staggered 0 0 0  is_shrink=n
6 0 3.77441 4.72035 T 0.01575 0.03543 e e staggered 0 0 0  is_shrink=n
6 0 0.81016 5.1239 T 0.01102 0.04331 e e staggered 0 0 0  is_shrink=n
6 0 0.81016 5.2361 T 0.01102 0.04331 e e staggered 0 0 0  is_shrink=n
6 0 0.79047 5.2361 T 0.01102 0.04331 e e staggered 0 0 0  is_shrink=n
6 0 1.25067 4.9602 T 0.01575 0.06693 e e staggered 0 0 0  is_shrink=n
6 0 7.25421 4.9602 T 0.01575 0.06693 e e staggered 0 0 0  is_shrink=n
6 0 1.35925 5.53642 T 0.03937 0.10827 e e staggered 0 0 0  is_shrink=n
6 0 1.43799 5.53642 T 0.03937 0.10827 e e staggered 0 0 0  is_shrink=n
6 0 1.825 4.562 D 0.02 0.02 e e staggered 0 0 0  is_shrink=n
6 0 7.88354 4.562 D 0.02 0.02 e e staggered 0 0 0  is_shrink=n
6 0 1.88 4.562 D 0.02 0.02 e e staggered 0 0 0  is_shrink=n
6 0 7.82854 4.562 D 0.02 0.02 e e staggered 0 0 0  is_shrink=n
6 0 5.883 3.07 D 0.02 0.02 e e staggered 0 0 0  is_shrink=n
6 0 9.145 5.332 D 0.02 0.02 e e staggered 0 0 0  is_shrink=n
6 0 9.19 5.332 D 0.02 0.02 e e staggered 0 0 0  is_shrink=n
6 0 9.34 5.332 D 0.02 0.02 e e staggered 0 0 0  is_shrink=n
6 0 3.33646 5.332 D 0.02 0.02 e e staggered 0 0 0  is_shrink=n
6 0 2.06646 5.377 D 0.02 0.02 e e staggered 0 0 0  is_shrink=n
6 0 8.07 5.377 D 0.02 0.02 e e staggered 0 0 0  is_shrink=n
6 0 8.005 5.377 D 0.02 0.02 e e staggered 0 0 0  is_shrink=n
6 0 3.18646 5.332 D 0.02 0.02 e e staggered 0 0 0  is_shrink=n
6 0 2.00146 5.377 D 0.02 0.02 e e staggered 0 0 0  is_shrink=n
6 0 3.14146 5.332 D 0.02 0.02 e e staggered 0 0 0  is_shrink=n
6 0 11.65062 2.855 D 0.02 0.02 e e staggered 0 0 0  is_shrink=n
6 0 5.64669 2.855 D 0.02 0.02 e e staggered 0 0 0  is_shrink=n
6 0 5.883 2.97 D 0.02 0.02 e e staggered 0 0 0  is_shrink=n
6 0 5.80255 2.97441 D 0.03543 0.01575 e e staggered 0 0 0  is_shrink=n
6 0 11.72031 2.85 D 0.03543 0.01575 e e staggered 0 0 0  is_shrink=n
6 0 5.71638 2.85 D 0.03543 0.01575 e e staggered 0 0 0  is_shrink=n
6 0.005 1.094 5.356 B m e v  arsize_top=0 arsize_bot=0 is_shrink=n
6 0.005 11.865 4.455 B m e v  arsize_top=0 arsize_bot=0 is_shrink=n
6 0.005 1.38906 5.15351 B m e v  arsize_top=0 arsize_bot=0 is_shrink=n
6 0.005 0.58 5.591 B m e v  arsize_top=0 arsize_bot=0 is_shrink=n
6 0.005 7.42604 5.15895 B m e v  arsize_top=0 arsize_bot=0 is_shrink=n
6 0.005 1.03 4.96 B m e v  arsize_top=0 arsize_bot=0 is_shrink=n
6 0.005 1.03 5.155 B m e v  arsize_top=0 arsize_bot=0 is_shrink=n
6 0.005 1.04 5.885 B m e v  arsize_top=0 arsize_bot=0 is_shrink=n
6 0.005 1.044 5.448 B m e v  arsize_top=0 arsize_bot=0 is_shrink=n
6 0.005 1.12 5.885 B m e v  arsize_top=0 arsize_bot=0 is_shrink=n
6 0.005 11.67762 2.85 B m e v  arsize_top=0 arsize_bot=0 is_shrink=n
6 0.005 1.18906 4.95351 B m e v  arsize_top=0 arsize_bot=0 is_shrink=n
6 0.005 1.23906 5.15351 B m e v  arsize_top=0 arsize_bot=0 is_shrink=n
6 0.005 1.28906 5.15351 B m e v  arsize_top=0 arsize_bot=0 is_shrink=n
6 0.005 1.32 5.46 B m e v  arsize_top=0 arsize_bot=0 is_shrink=n
6 0.005 1.35925 5.46016 B m e v  arsize_top=0 arsize_bot=0 is_shrink=n
6 0.005 1.4 5.46 B m e v  arsize_top=0 arsize_bot=0 is_shrink=n
6 0.005 1.43799 5.46016 B m e v  arsize_top=0 arsize_bot=0 is_shrink=n
6 0.005 3.77 4.765 B m e v  arsize_top=0 arsize_bot=0 is_shrink=n
6 0.005 3.94 4.655 B m e v  arsize_top=0 arsize_bot=0 is_shrink=n
6 0.005 4.14 4.745 B m e v  arsize_top=0 arsize_bot=0 is_shrink=n
6 0.005 4.76 5.375 B m e v  arsize_top=0 arsize_bot=0 is_shrink=n
6 0.005 4.892 5.767 B m e v  arsize_top=0 arsize_bot=0 is_shrink=n
6 0.005 4.96 5.5 B m e v  arsize_top=0 arsize_bot=0 is_shrink=n
6 0.005 5.088 5.767 B m e v  arsize_top=0 arsize_bot=0 is_shrink=n
6 0.005 5.16 5.555 B m e v  arsize_top=0 arsize_bot=0 is_shrink=n
6 0.005 5.67369 2.85 B m e v  arsize_top=0 arsize_bot=0 is_shrink=n
6 0.005 5.8522 2.97 B m e v  arsize_top=0 arsize_bot=0 is_shrink=n
6 0.005 5.855 3.07 B m e v  arsize_top=0 arsize_bot=0 is_shrink=n
6 0.005 7.1926 4.95351 B m e v  arsize_top=0 arsize_bot=0 is_shrink=n
6 0.005 7.2426 5.15351 B m e v  arsize_top=0 arsize_bot=0 is_shrink=n
6 0.005 7.2926 5.15351 B m e v  arsize_top=0 arsize_bot=0 is_shrink=n
6 0.005 0.73 5.205 B m e v  arsize_top=0 arsize_bot=0 is_shrink=n
6 0.005 0.73 5.885 B m e v  arsize_top=0 arsize_bot=0 is_shrink=n
6 0.005 0.755 5.355 B m e v  arsize_top=0 arsize_bot=0 is_shrink=n
6 0.005 0.81 5.885 B m e v  arsize_top=0 arsize_bot=0 is_shrink=n
6 0.005 0.81016 5.17 B m e v  arsize_top=0 arsize_bot=0 is_shrink=n
6 0.005 0.83 5.355 B m e v  arsize_top=0 arsize_bot=0 is_shrink=n
6 0.005 0.89 5.885 B m e v  arsize_top=0 arsize_bot=0 is_shrink=n
6 0.005 0.9 5.355 B m e v  arsize_top=0 arsize_bot=0 is_shrink=n
6 0.005 0.91 5.075 B m e v  arsize_top=0 arsize_bot=0 is_shrink=n
6 0.005 0.97 5.885 B m e v  arsize_top=0 arsize_bot=0 is_shrink=n
7 0 0.68 5.113 T 0.02 0.02 e e staggered 0 0 0  is_shrink=n
7 0 0.97 4.993 T 0.02 0.02 e e staggered 0 0 0  is_shrink=n
7 0 0.73 5.027 T 0.02 0.02 e e staggered 0 0 0  is_shrink=n
7 0 0.73 5.113 T 0.02 0.02 e e staggered 0 0 0  is_shrink=n
7 0 0.79047 5.1239 T 0.01102 0.04331 e e staggered 0 0 0  is_shrink=n
7 0.015 0.73 5.07 T m e v t  arsize_top=0 arsize_bot=0 is_shrink=n
8 0 4.03667 4.96077 T 0.01575 0.06693 e e staggered 0 0 0  is_shrink=n
8 0 5.125 5.433 T 0.02 0.02 e e staggered 0 0 0  is_shrink=n
8 0 3.89 4.683 T 0.02 0.02 e e staggered 0 0 0  is_shrink=n
8 0 3.91 5.477 T 0.02 0.02 e e staggered 0 0 0  is_shrink=n
8 0 9.98 4.543 T 0.02 0.02 e e staggered 0 0 0  is_shrink=n
8 0 3.67 4.483 T 0.02 0.02 e e staggered 0 0 0  is_shrink=n
8 0 4.0399 4.79499 T 0.02 0.02 e e staggered 0 0 0  is_shrink=n
8 0 3.9899 4.79499 T 0.02 0.02 e e staggered 0 0 0  is_shrink=n
8 0 4.0099 5.35899 T 0.02 0.02 e e staggered 0 0 0  is_shrink=n
8 0 4.0599 5.35899 T 0.02 0.02 e e staggered 0 0 0  is_shrink=n
8 0 3.66999 0.7751 T 0.02 0.02 e e staggered 0 0 0  is_shrink=n
8 0 3.60999 0.7751 T 0.02 0.02 e e staggered 0 0 0  is_shrink=n
8 0 3.75999 0.2711 T 0.02 0.02 e e staggered 0 0 0  is_shrink=n
8 0 9.55795 0.29243 T 0.02 0.02 e e staggered 0 0 0  is_shrink=n
8 0 9.40795 0.79643 T 0.02 0.02 e e staggered 0 0 0  is_shrink=n
8 0 9.46795 0.79643 T 0.02 0.02 e e staggered 0 0 0  is_shrink=n
8 0 7.3426 4.63151 T 0.02 0.02 e e staggered 0 0 0  is_shrink=n
8 0 7.2926 4.63151 T 0.02 0.02 e e staggered 0 0 0  is_shrink=n
8 0 1.33906 4.63151 T 0.02 0.02 e e staggered 0 0 0  is_shrink=n
8 0 1.28906 4.63151 T 0.02 0.02 e e staggered 0 0 0  is_shrink=n
8 0 3.72 4.517 T 0.02 0.02 e e staggered 0 0 0  is_shrink=n
8 0 10.03 4.577 T 0.02 0.02 e e staggered 0 0 0  is_shrink=n
8 0 4.1049 4.82899 T 0.02 0.02 e e staggered 0 0 0  is_shrink=n
8 0 1.405 5.823 T 0.02 0.02 e e staggered 0 0 0  is_shrink=n
8 0 1.305 5.823 T 0.02 0.02 e e staggered 0 0 0  is_shrink=n
8 0 7.2426 4.66551 T 0.02 0.02 e e staggered 0 0 0  is_shrink=n
8 0 1.23906 4.66551 T 0.02 0.02 e e staggered 0 0 0  is_shrink=n
8 0 1.455 5.823 T 0.02 0.02 e e staggered 0 0 0  is_shrink=n
8 0 1.355 5.823 T 0.02 0.02 e e staggered 0 0 0  is_shrink=n
8 0 10.02559 4.64965 T 0.01575 0.03543 e e staggered 0 0 0  is_shrink=n
8 0 3.69559 4.58965 T 0.01575 0.03543 e e staggered 0 0 0  is_shrink=n
8 0 1.25067 4.79682 T 0.01575 0.06693 e e staggered 0 0 0  is_shrink=n
8 0 7.25421 4.79682 T 0.01575 0.06693 e e staggered 0 0 0  is_shrink=n
8 0 3.70999 0.62932 T 0.0252 0.07244 e e staggered 0 0 0  is_shrink=n
8 0 9.50795 0.65065 T 0.0252 0.07244 e e staggered 0 0 0  is_shrink=n
8 0 1.35925 5.70374 T 0.03937 0.10827 e e staggered 0 0 0  is_shrink=n
8 0 1.43799 5.70374 T 0.03937 0.10827 e e staggered 0 0 0  is_shrink=n
8 0 11.35062 2.73 D 0.02 0.02 e e staggered 0 0 0  is_shrink=n
8 0 11.35062 2.8 D 0.02 0.02 e e staggered 0 0 0  is_shrink=n
8 0 11.61662 2.785 D 0.02 0.02 e e staggered 0 0 0  is_shrink=n
8 0 11.61662 2.905 D 0.02 0.02 e e staggered 0 0 0  is_shrink=n
8 0 5.34669 2.73 D 0.02 0.02 e e staggered 0 0 0  is_shrink=n
8 0 5.34669 2.8 D 0.02 0.02 e e staggered 0 0 0  is_shrink=n
8 0 5.61269 2.785 D 0.02 0.02 e e staggered 0 0 0  is_shrink=n
8 0 5.61269 2.905 D 0.02 0.02 e e staggered 0 0 0  is_shrink=n
8 0 4.09086 2.65 D 0.02 0.02 e e staggered 0 0 0  is_shrink=n
8 0 10.133 2.88 D 0.02 0.02 e e staggered 0 0 0  is_shrink=n
8 0 10.10079 2.82 D 0.02 0.02 e e staggered 0 0 0  is_shrink=n
8 0 4.05686 2.59 D 0.02 0.02 e e staggered 0 0 0  is_shrink=n
8 0 3.99421 2.59441 D 0.03543 0.01575 e e staggered 0 0 0  is_shrink=n
8 0 10.03814 2.82441 D 0.03543 0.01575 e e staggered 0 0 0  is_shrink=n
8 0.005 11.395 2.725 B m e v  arsize_top=0 arsize_bot=0 is_shrink=n
8 0.005 1.33906 4.60351 B m e v  arsize_top=0 arsize_bot=0 is_shrink=n
8 0.005 3.75999 0.24001 B m e v  arsize_top=0 arsize_bot=0 is_shrink=n
8 0.005 5.387 2.725 B m e v  arsize_top=0 arsize_bot=0 is_shrink=n
8 0.005 9.55795 0.26134 B m e v  arsize_top=0 arsize_bot=0 is_shrink=n
8 0.005 10.03 4.61 B m e v  arsize_top=0 arsize_bot=0 is_shrink=n
8 0.005 10.07286 2.82337 B m e v  arsize_top=0 arsize_bot=0 is_shrink=n
8 0.005 11.395 2.8 B m e v  arsize_top=0 arsize_bot=0 is_shrink=n
8 0.005 11.58613 2.785 B m e v  arsize_top=0 arsize_bot=0 is_shrink=n
8 0.005 11.58613 2.905 B m e v  arsize_top=0 arsize_bot=0 is_shrink=n
8 0.005 1.23906 4.69351 B m e v  arsize_top=0 arsize_bot=0 is_shrink=n
8 0.005 1.335 5.78 B m e v  arsize_top=0 arsize_bot=0 is_shrink=n
8 0.005 1.37925 5.78 B m e v  arsize_top=0 arsize_bot=0 is_shrink=n
8 0.005 1.42 5.78 B m e v  arsize_top=0 arsize_bot=0 is_shrink=n
8 0.005 1.45799 5.78 B m e v  arsize_top=0 arsize_bot=0 is_shrink=n
8 0.005 3.67 4.45 B m e v  arsize_top=0 arsize_bot=0 is_shrink=n
8 0.005 3.70999 0.7 B m e v  arsize_top=0 arsize_bot=0 is_shrink=n
8 0.005 3.71203 0.77535 B m e v  arsize_top=0 arsize_bot=0 is_shrink=n
8 0.005 3.72 4.545 B m e v  arsize_top=0 arsize_bot=0 is_shrink=n
8 0.005 3.89 4.655 B m e v  arsize_top=0 arsize_bot=0 is_shrink=n
8 0.005 3.91 5.51 B m e v  arsize_top=0 arsize_bot=0 is_shrink=n
8 0.005 3.9899 4.765 B m e v  arsize_top=0 arsize_bot=0 is_shrink=n
8 0.005 4.02893 2.59337 B m e v  arsize_top=0 arsize_bot=0 is_shrink=n
8 0.005 4.0599 5.395 B m e v  arsize_top=0 arsize_bot=0 is_shrink=n
8 0.005 4.1049 4.86 B m e v  arsize_top=0 arsize_bot=0 is_shrink=n
8 0.005 5.125 5.4 B m e v  arsize_top=0 arsize_bot=0 is_shrink=n
8 0.005 5.37969 2.8 B m e v  arsize_top=0 arsize_bot=0 is_shrink=n
8 0.005 5.5822 2.785 B m e v  arsize_top=0 arsize_bot=0 is_shrink=n
8 0.005 5.5822 2.905 B m e v  arsize_top=0 arsize_bot=0 is_shrink=n
8 0.005 7.2426 4.69351 B m e v  arsize_top=0 arsize_bot=0 is_shrink=n
8 0.005 7.2926 4.60351 B m e v  arsize_top=0 arsize_bot=0 is_shrink=n
8 0.005 9.46795 0.82632 B m e v  arsize_top=0 arsize_bot=0 is_shrink=n
8 0.005 9.50795 0.72133 B m e v  arsize_top=0 arsize_bot=0 is_shrink=n
8 0.005 9.98 4.51 B m e v  arsize_top=0 arsize_bot=0 is_shrink=n
9 0.0126 11.01161 2.49115 T e e  arsize_top=0 arsize_bot=0 is_shrink=n
9 0 11.42193 2.575 D 0.02 0.02 e e staggered 0 0 0  is_shrink=n
9 0.004 11.03661 2.51615 B m e v  arsize_top=0 arsize_bot=0 is_shrink=n
10 0.01378 12.55905 4.56299 B e e  arsize_top=0 arsize_bot=0 is_shrink=n
10 0 11.45593 2.575 D 0.02 0.02 e e staggered 0 0 0  is_shrink=n
10 0.004 11.53316 2.572 B m e v  arsize_top=0 arsize_bot=0 is_shrink=n
11 0.0126 11.01161 2.44115 T e e  arsize_top=0 arsize_bot=0 is_shrink=n
11 0 11.42193 2.53 D 0.02 0.02 e e staggered 0 0 0  is_shrink=n
11 0.004 11.03661 2.46615 B m e v  arsize_top=0 arsize_bot=0 is_shrink=n
12 0.01378 12.63779 4.60237 B e e  arsize_top=0 arsize_bot=0 is_shrink=n
12 0 11.45593 2.53 D 0.02 0.02 e e staggered 0 0 0  is_shrink=n
12 0.004 11.53316 2.532 B m e v  arsize_top=0 arsize_bot=0 is_shrink=n
13 0.0126 10.91161 2.49115 T e e  arsize_top=0 arsize_bot=0 is_shrink=n
13 0 11.62193 2.655 D 0.02 0.02 e e staggered 0 0 0  is_shrink=n
13 0.004 10.93661 2.46615 B m e v  arsize_top=0 arsize_bot=0 is_shrink=n
14 0.01378 12.55905 4.40551 B e e  arsize_top=0 arsize_bot=0 is_shrink=n
14 0 11.65593 2.655 D 0.02 0.02 e e staggered 0 0 0  is_shrink=n
14 0.004 11.73316 2.652 B m e v  arsize_top=0 arsize_bot=0 is_shrink=n
15 0.0126 10.91161 2.44115 T e e  arsize_top=0 arsize_bot=0 is_shrink=n
15 0 11.62193 2.61 D 0.02 0.02 e e staggered 0 0 0  is_shrink=n
15 0.004 10.93661 2.41615 B m e v  arsize_top=0 arsize_bot=0 is_shrink=n
16 0.01378 12.63779 4.44488 B e e  arsize_top=0 arsize_bot=0 is_shrink=n
16 0 11.65593 2.61 D 0.02 0.02 e e staggered 0 0 0  is_shrink=n
16 0.004 11.73316 2.612 B m e v  arsize_top=0 arsize_bot=0 is_shrink=n
17 0.0126 10.96161 2.44115 T e e  arsize_top=0 arsize_bot=0 is_shrink=n
17 0 11.62193 2.495 D 0.02 0.02 e e staggered 0 0 0  is_shrink=n
17 0.004 10.98661 2.41615 B m e v  arsize_top=0 arsize_bot=0 is_shrink=n
18 0.01378 12.55905 4.24803 B e e  arsize_top=0 arsize_bot=0 is_shrink=n
18 0 11.65593 2.495 D 0.02 0.02 e e staggered 0 0 0  is_shrink=n
18 0.004 11.73316 2.492 B m e v  arsize_top=0 arsize_bot=0 is_shrink=n
19 0.0126 10.96161 2.39115 T e e  arsize_top=0 arsize_bot=0 is_shrink=n
19 0 11.62193 2.45 D 0.02 0.02 e e staggered 0 0 0  is_shrink=n
19 0.004 10.98661 2.36615 B m e v  arsize_top=0 arsize_bot=0 is_shrink=n
20 0.01378 12.63779 4.2874 B e e  arsize_top=0 arsize_bot=0 is_shrink=n
20 0 11.65593 2.45 D 0.02 0.02 e e staggered 0 0 0  is_shrink=n
20 0.004 11.73316 2.452 B m e v  arsize_top=0 arsize_bot=0 is_shrink=n
21 0.0126 11.06161 2.44115 T e e  arsize_top=0 arsize_bot=0 is_shrink=n
21 0 11.42193 2.415 D 0.02 0.02 e e staggered 0 0 0  is_shrink=n
21 0.004 11.08661 2.41615 B m e v  arsize_top=0 arsize_bot=0 is_shrink=n
22 0.01378 12.55905 4.09055 B e e  arsize_top=0 arsize_bot=0 is_shrink=n
22 0 11.45593 2.415 D 0.02 0.02 e e staggered 0 0 0  is_shrink=n
22 0.004 11.53316 2.412 B m e v  arsize_top=0 arsize_bot=0 is_shrink=n
23 0.0126 11.06161 2.39115 T e e  arsize_top=0 arsize_bot=0 is_shrink=n
23 0 11.42193 2.37 D 0.02 0.02 e e staggered 0 0 0  is_shrink=n
23 0.004 11.08661 2.36615 B m e v  arsize_top=0 arsize_bot=0 is_shrink=n
24 0.01378 12.63779 4.12992 B e e  arsize_top=0 arsize_bot=0 is_shrink=n
24 0 11.45593 2.37 D 0.02 0.02 e e staggered 0 0 0  is_shrink=n
24 0.004 11.53316 2.372 B m e v  arsize_top=0 arsize_bot=0 is_shrink=n
25 0.0126 10.91161 2.34115 T e e  arsize_top=0 arsize_bot=0 is_shrink=n
25 0 11.62193 2.335 D 0.02 0.02 e e staggered 0 0 0  is_shrink=n
25 0.004 10.93661 2.31615 B m e v  arsize_top=0 arsize_bot=0 is_shrink=n
26 0.01378 12.55905 3.93307 B e e  arsize_top=0 arsize_bot=0 is_shrink=n
26 0 11.65593 2.335 D 0.02 0.02 e e staggered 0 0 0  is_shrink=n
26 0.004 11.73316 2.332 B m e v  arsize_top=0 arsize_bot=0 is_shrink=n
27 0.0126 10.91161 2.29115 T e e  arsize_top=0 arsize_bot=0 is_shrink=n
27 0 11.62193 2.29 D 0.02 0.02 e e staggered 0 0 0  is_shrink=n
27 0.004 10.93661 2.26615 B m e v  arsize_top=0 arsize_bot=0 is_shrink=n
28 0.01378 12.63779 3.97244 B e e  arsize_top=0 arsize_bot=0 is_shrink=n
28 0 11.65593 2.29 D 0.02 0.02 e e staggered 0 0 0  is_shrink=n
28 0.004 11.73316 2.292 B m e v  arsize_top=0 arsize_bot=0 is_shrink=n
29 0.0126 10.96161 2.29115 T e e  arsize_top=0 arsize_bot=0 is_shrink=n
29 0 11.42193 2.095 D 0.02 0.02 e e staggered 0 0 0  is_shrink=n
29 0.004 10.98661 2.26615 B m e v  arsize_top=0 arsize_bot=0 is_shrink=n
30 0.01378 12.55905 3.77559 B e e  arsize_top=0 arsize_bot=0 is_shrink=n
30 0 11.45593 2.095 D 0.02 0.02 e e staggered 0 0 0  is_shrink=n
30 0.004 11.53316 2.092 B m e v  arsize_top=0 arsize_bot=0 is_shrink=n
31 0.0126 10.96161 2.24115 T e e  arsize_top=0 arsize_bot=0 is_shrink=n
31 0 11.42193 2.05 D 0.02 0.02 e e staggered 0 0 0  is_shrink=n
31 0.004 10.98661 2.21615 B m e v  arsize_top=0 arsize_bot=0 is_shrink=n
32 0.01378 12.63779 3.81496 B e e  arsize_top=0 arsize_bot=0 is_shrink=n
32 0 11.45593 2.05 D 0.02 0.02 e e staggered 0 0 0  is_shrink=n
32 0.004 11.53316 2.052 B m e v  arsize_top=0 arsize_bot=0 is_shrink=n
33 0.0126 11.01161 2.34115 T e e  arsize_top=0 arsize_bot=0 is_shrink=n
33 0 11.42193 2.255 D 0.02 0.02 e e staggered 0 0 0  is_shrink=n
33 0.004 11.03661 2.31615 B m e v  arsize_top=0 arsize_bot=0 is_shrink=n
34 0.01378 12.55905 3.61811 B e e  arsize_top=0 arsize_bot=0 is_shrink=n
34 0 11.45593 2.255 D 0.02 0.02 e e staggered 0 0 0  is_shrink=n
34 0.004 11.83316 2.252 B m e v  arsize_top=0 arsize_bot=0 is_shrink=n
35 0.0126 11.01161 2.29115 T e e  arsize_top=0 arsize_bot=0 is_shrink=n
35 0 11.42193 2.21 D 0.02 0.02 e e staggered 0 0 0  is_shrink=n
35 0.004 11.03661 2.26615 B m e v  arsize_top=0 arsize_bot=0 is_shrink=n
36 0.01378 12.63779 3.65748 B e e  arsize_top=0 arsize_bot=0 is_shrink=n
36 0 11.45593 2.21 D 0.02 0.02 e e staggered 0 0 0  is_shrink=n
36 0.004 11.83316 2.212 B m e v  arsize_top=0 arsize_bot=0 is_shrink=n
37 0.0126 11.06161 2.29115 T e e  arsize_top=0 arsize_bot=0 is_shrink=n
37 0 11.62193 2.175 D 0.02 0.02 e e staggered 0 0 0  is_shrink=n
37 0.004 11.08661 2.26615 B m e v  arsize_top=0 arsize_bot=0 is_shrink=n
38 0.01378 12.55905 3.46063 B e e  arsize_top=0 arsize_bot=0 is_shrink=n
38 0 11.65593 2.175 D 0.02 0.02 e e staggered 0 0 0  is_shrink=n
38 0.004 11.73316 2.172 B m e v  arsize_top=0 arsize_bot=0 is_shrink=n
39 0.0126 11.06161 2.24115 T e e  arsize_top=0 arsize_bot=0 is_shrink=n
39 0 11.62193 2.13 D 0.02 0.02 e e staggered 0 0 0  is_shrink=n
39 0.004 11.08661 2.21615 B m e v  arsize_top=0 arsize_bot=0 is_shrink=n
40 0.01378 12.63779 3.5 B e e  arsize_top=0 arsize_bot=0 is_shrink=n
40 0 11.65593 2.13 D 0.02 0.02 e e staggered 0 0 0  is_shrink=n
40 0.004 11.73316 2.132 B m e v  arsize_top=0 arsize_bot=0 is_shrink=n
41 0.0126 11.06161 2.14115 T e e  arsize_top=0 arsize_bot=0 is_shrink=n
41 0 11.42193 1.935 D 0.02 0.02 e e staggered 0 0 0  is_shrink=n
41 0.004 11.08661 2.11615 B m e v  arsize_top=0 arsize_bot=0 is_shrink=n
42 0.01378 12.63779 3.26378 B e e  arsize_top=0 arsize_bot=0 is_shrink=n
42 0 11.45593 1.935 D 0.02 0.02 e e staggered 0 0 0  is_shrink=n
42 0.004 11.53316 1.932 B m e v  arsize_top=0 arsize_bot=0 is_shrink=n
43 0.0126 11.06161 2.09115 T e e  arsize_top=0 arsize_bot=0 is_shrink=n
43 0 11.42193 1.89 D 0.02 0.02 e e staggered 0 0 0  is_shrink=n
43 0.004 11.08661 2.06615 B m e v  arsize_top=0 arsize_bot=0 is_shrink=n
44 0.01378 12.55905 3.30315 B e e  arsize_top=0 arsize_bot=0 is_shrink=n
44 0 11.45593 1.89 D 0.02 0.02 e e staggered 0 0 0  is_shrink=n
44 0.004 11.53316 1.892 B m e v  arsize_top=0 arsize_bot=0 is_shrink=n
45 0.0126 10.96161 2.14115 T e e  arsize_top=0 arsize_bot=0 is_shrink=n
45 0 11.62193 2.015 D 0.02 0.02 e e staggered 0 0 0  is_shrink=n
45 0.004 10.98661 2.11615 B m e v  arsize_top=0 arsize_bot=0 is_shrink=n
46 0.01378 12.63779 3.1063 B e e  arsize_top=0 arsize_bot=0 is_shrink=n
46 0 11.65593 2.015 D 0.02 0.02 e e staggered 0 0 0  is_shrink=n
46 0.004 11.73316 2.012 B m e v  arsize_top=0 arsize_bot=0 is_shrink=n
47 0.0126 10.96161 2.09115 T e e  arsize_top=0 arsize_bot=0 is_shrink=n
47 0 11.62193 1.97 D 0.02 0.02 e e staggered 0 0 0  is_shrink=n
47 0.004 10.98661 2.06615 B m e v  arsize_top=0 arsize_bot=0 is_shrink=n
48 0.01378 12.55905 3.14567 B e e  arsize_top=0 arsize_bot=0 is_shrink=n
48 0 11.65593 1.97 D 0.02 0.02 e e staggered 0 0 0  is_shrink=n
48 0.004 11.73316 1.972 B m e v  arsize_top=0 arsize_bot=0 is_shrink=n
49 0.0126 10.91161 2.09115 T e e  arsize_top=0 arsize_bot=0 is_shrink=n
49 0 11.42193 1.775 D 0.02 0.02 e e staggered 0 0 0  is_shrink=n
49 0.004 10.93661 2.06615 B m e v  arsize_top=0 arsize_bot=0 is_shrink=n
50 0.01378 12.63779 2.94882 B e e  arsize_top=0 arsize_bot=0 is_shrink=n
50 0 11.45593 1.775 D 0.02 0.02 e e staggered 0 0 0  is_shrink=n
50 0.004 11.53316 1.772 B m e v  arsize_top=0 arsize_bot=0 is_shrink=n
51 0.0126 10.91161 2.04115 T e e  arsize_top=0 arsize_bot=0 is_shrink=n
51 0 11.42193 1.73 D 0.02 0.02 e e staggered 0 0 0  is_shrink=n
51 0.004 10.93661 2.01615 B m e v  arsize_top=0 arsize_bot=0 is_shrink=n
52 0.01378 12.55905 2.98819 B e e  arsize_top=0 arsize_bot=0 is_shrink=n
52 0 11.45593 1.73 D 0.02 0.02 e e staggered 0 0 0  is_shrink=n
52 0.004 11.53316 1.732 B m e v  arsize_top=0 arsize_bot=0 is_shrink=n
53 0.0126 11.01161 2.09115 T e e  arsize_top=0 arsize_bot=0 is_shrink=n
53 0 11.62193 1.855 D 0.02 0.02 e e staggered 0 0 0  is_shrink=n
53 0.004 11.03661 2.06615 B m e v  arsize_top=0 arsize_bot=0 is_shrink=n
54 0.01378 12.63779 2.79134 B e e  arsize_top=0 arsize_bot=0 is_shrink=n
54 0 11.65593 1.855 D 0.02 0.02 e e staggered 0 0 0  is_shrink=n
54 0.004 11.73316 1.852 B m e v  arsize_top=0 arsize_bot=0 is_shrink=n
55 0.0126 11.01161 2.04115 T e e  arsize_top=0 arsize_bot=0 is_shrink=n
55 0 11.62193 1.81 D 0.02 0.02 e e staggered 0 0 0  is_shrink=n
55 0.004 11.03661 2.01615 B m e v  arsize_top=0 arsize_bot=0 is_shrink=n
56 0.01378 12.55905 2.83071 B e e  arsize_top=0 arsize_bot=0 is_shrink=n
56 0 11.65593 1.81 D 0.02 0.02 e e staggered 0 0 0  is_shrink=n
56 0.004 11.73316 1.812 B m e v  arsize_top=0 arsize_bot=0 is_shrink=n
57 0.0126 10.96161 1.99115 T e e  arsize_top=0 arsize_bot=0 is_shrink=n
57 0 11.42193 1.615 D 0.02 0.02 e e staggered 0 0 0  is_shrink=n
57 0.004 10.98661 1.96615 B m e v  arsize_top=0 arsize_bot=0 is_shrink=n
58 0.01378 12.63779 2.55512 B e e  arsize_top=0 arsize_bot=0 is_shrink=n
58 0 11.45593 1.615 D 0.02 0.02 e e staggered 0 0 0  is_shrink=n
58 0.004 11.53316 1.612 B m e v  arsize_top=0 arsize_bot=0 is_shrink=n
59 0.0126 10.96161 1.94115 T e e  arsize_top=0 arsize_bot=0 is_shrink=n
59 0 11.42193 1.57 D 0.02 0.02 e e staggered 0 0 0  is_shrink=n
59 0.004 10.98661 1.91615 B m e v  arsize_top=0 arsize_bot=0 is_shrink=n
60 0.01378 12.55905 2.59449 B e e  arsize_top=0 arsize_bot=0 is_shrink=n
60 0 11.45593 1.57 D 0.02 0.02 e e staggered 0 0 0  is_shrink=n
60 0.004 11.53316 1.572 B m e v  arsize_top=0 arsize_bot=0 is_shrink=n
61 0.0126 10.91161 1.94115 T e e  arsize_top=0 arsize_bot=0 is_shrink=n
61 0 11.42193 1.41 D 0.02 0.02 e e staggered 0 0 0  is_shrink=n
61 0.004 10.93661 1.91615 B m e v  arsize_top=0 arsize_bot=0 is_shrink=n
62 0.01378 12.63779 2.39764 B e e  arsize_top=0 arsize_bot=0 is_shrink=n
62 0 11.45593 1.41 D 0.02 0.02 e e staggered 0 0 0  is_shrink=n
62 0.004 11.53316 1.412 B m e v  arsize_top=0 arsize_bot=0 is_shrink=n
63 0.0126 10.91161 1.89115 T e e  arsize_top=0 arsize_bot=0 is_shrink=n
63 0 11.42193 1.455 D 0.02 0.02 e e staggered 0 0 0  is_shrink=n
63 0.004 10.93661 1.86615 B m e v  arsize_top=0 arsize_bot=0 is_shrink=n
64 0.01378 12.55905 2.43701 B e e  arsize_top=0 arsize_bot=0 is_shrink=n
64 0 11.45593 1.455 D 0.02 0.02 e e staggered 0 0 0  is_shrink=n
64 0.004 11.53316 1.452 B m e v  arsize_top=0 arsize_bot=0 is_shrink=n
65 0.0126 11.01161 1.94115 T e e  arsize_top=0 arsize_bot=0 is_shrink=n
65 0 11.62193 1.49 D 0.02 0.02 e e staggered 0 0 0  is_shrink=n
65 0.004 11.03661 1.91615 B m e v  arsize_top=0 arsize_bot=0 is_shrink=n
66 0.01378 12.63779 2.24016 B e e  arsize_top=0 arsize_bot=0 is_shrink=n
66 0 11.65593 1.49 D 0.02 0.02 e e staggered 0 0 0  is_shrink=n
66 0.004 11.73316 1.492 B m e v  arsize_top=0 arsize_bot=0 is_shrink=n
67 0.0126 11.01161 1.89115 T e e  arsize_top=0 arsize_bot=0 is_shrink=n
67 0 11.62193 1.535 D 0.02 0.02 e e staggered 0 0 0  is_shrink=n
67 0.004 11.03661 1.86615 B m e v  arsize_top=0 arsize_bot=0 is_shrink=n
68 0.01378 12.55905 2.27953 B e e  arsize_top=0 arsize_bot=0 is_shrink=n
68 0 11.65593 1.535 D 0.02 0.02 e e staggered 0 0 0  is_shrink=n
68 0.004 11.73316 1.532 B m e v  arsize_top=0 arsize_bot=0 is_shrink=n
69 0.0126 11.06161 1.99115 T e e  arsize_top=0 arsize_bot=0 is_shrink=n
69 0 11.62193 1.695 D 0.02 0.02 e e staggered 0 0 0  is_shrink=n
69 0.004 11.08661 1.96615 B m e v  arsize_top=0 arsize_bot=0 is_shrink=n
70 0.01378 12.55905 2.04331 B e e  arsize_top=0 arsize_bot=0 is_shrink=n
70 0 11.65593 1.695 D 0.02 0.02 e e staggered 0 0 0  is_shrink=n
70 0.004 11.78316 1.692 B m e v  arsize_top=0 arsize_bot=0 is_shrink=n
71 0.0126 11.06161 1.94115 T e e  arsize_top=0 arsize_bot=0 is_shrink=n
71 0 11.62193 1.65 D 0.02 0.02 e e staggered 0 0 0  is_shrink=n
71 0.004 11.08661 1.91615 B m e v  arsize_top=0 arsize_bot=0 is_shrink=n
72 0.01378 12.63779 2.08268 B e e  arsize_top=0 arsize_bot=0 is_shrink=n
72 0 11.65593 1.65 D 0.02 0.02 e e staggered 0 0 0  is_shrink=n
72 0.004 11.78316 1.652 B m e v  arsize_top=0 arsize_bot=0 is_shrink=n
73 0.0126 5.00768 1.94115 T e e  arsize_top=0 arsize_bot=0 is_shrink=n
73 0 5.46358 1.6693 D 0.02 0.02 e e staggered 0 0 0  is_shrink=n
73 0.004 5.03268 1.91615 B m e v  arsize_top=0 arsize_bot=0 is_shrink=n
74 0.01378 0.17323 2.20079 B e e  arsize_top=0 arsize_bot=0 is_shrink=n
74 0 5.49758 1.6693 D 0.02 0.02 e e staggered 0 0 0  is_shrink=n
74 0.004 5.57531 1.6718 B m e v  arsize_top=0 arsize_bot=0 is_shrink=n
75 0 4.01677 5.78 T 0.07874 0.04331 e e staggered 0 0 0  is_shrink=n
75 0 3.62 4.517 T 0.02 0.02 e e staggered 0 0 0  is_shrink=n
75 0 3.67 4.517 T 0.02 0.02 e e staggered 0 0 0  is_shrink=n
75 0 3.57 4.517 T 0.02 0.02 e e staggered 0 0 0  is_shrink=n
75 0 3.64441 4.58965 T 0.01575 0.03543 e e staggered 0 0 0  is_shrink=n
75 0.015 3.925 5.78 T m e v t  arsize_top=0 arsize_bot=0 is_shrink=n
76 0 4.01677 5.68 T 0.07874 0.04331 e e staggered 0 0 0  is_shrink=n
76 0 9.91 4.577 T 0.02 0.02 e e staggered 0 0 0  is_shrink=n
76 0 9.98 4.577 T 0.02 0.02 e e staggered 0 0 0  is_shrink=n
76 0 9.91 4.633 T 0.02 0.02 e e staggered 0 0 0  is_shrink=n
76 0 9.97441 4.64965 T 0.01575 0.03543 e e staggered 0 0 0  is_shrink=n
76 0.015 9.865 4.635 T m e v t  arsize_top=0 arsize_bot=0 is_shrink=n
77 0 4.8826 5.54685 T 0.02362 0.04134 e e staggered 0 0 0  is_shrink=n
77 0 4.76 5.442 T 0.02 0.02 e e staggered 0 0 0  is_shrink=n
77 0 4.81 5.442 T 0.02 0.02 e e staggered 0 0 0  is_shrink=n
77 0.015 4.81 5.485 T m e v t  arsize_top=0 arsize_bot=0 is_shrink=n
78 0.0126 5.00768 2.04115 T e e  arsize_top=0 arsize_bot=0 is_shrink=n
78 0 5.46358 1.9444 D 0.02 0.02 e e staggered 0 0 0  is_shrink=n
78 0.004 5.03268 2.01615 B m e v  arsize_top=0 arsize_bot=0 is_shrink=n
79 0.01378 0.09449 2.79134 B e e  arsize_top=0 arsize_bot=0 is_shrink=n
79 0 5.49758 1.9444 D 0.02 0.02 e e staggered 0 0 0  is_shrink=n
79 0.004 5.57531 1.9469 B m e v  arsize_top=0 arsize_bot=0 is_shrink=n
80 0.0126 4.95768 2.14115 T e e  arsize_top=0 arsize_bot=0 is_shrink=n
80 0 5.46358 2.1303 D 0.02 0.02 e e staggered 0 0 0  is_shrink=n
80 0.004 4.98268 2.11615 B m e v  arsize_top=0 arsize_bot=0 is_shrink=n
81 0.01378 0.17323 3.06693 B e e  arsize_top=0 arsize_bot=0 is_shrink=n
81 0 5.49758 2.1303 D 0.02 0.02 e e staggered 0 0 0  is_shrink=n
81 0.004 5.57531 2.1278 B m e v  arsize_top=0 arsize_bot=0 is_shrink=n
82 0.0275599 12.14961 5.71339 B e e  arsize_top=0 arsize_bot=0 is_shrink=n
82 0.0275599 11.98425 5.71339 B e e  arsize_top=0 arsize_bot=0 is_shrink=n
82 0.0275599 11.8189 5.71339 B e e  arsize_top=0 arsize_bot=0 is_shrink=n
82 0.0275599 11.65354 5.71339 B e e  arsize_top=0 arsize_bot=0 is_shrink=n
82 0.0275599 11.48819 5.71339 B e e  arsize_top=0 arsize_bot=0 is_shrink=n
82 0.0275599 11.32284 5.71339 B e e  arsize_top=0 arsize_bot=0 is_shrink=n
82 0.0275599 11.15748 5.71339 B e e  arsize_top=0 arsize_bot=0 is_shrink=n
82 0.0275599 10.99213 5.71339 B e e  arsize_top=0 arsize_bot=0 is_shrink=n
82 0.0275599 10.82677 5.71339 B e e  arsize_top=0 arsize_bot=0 is_shrink=n
82 0 6.87619 4.61587 T 0.0748 0.06693 e e staggered 0 0 0  is_shrink=n
82 0 6.34949 4.99705 T 0.02 0.02 e e staggered 0 0 0  is_shrink=n
82 0 5.10605 5.03983 T 0.1 0.12598 e e staggered 0 0 0  is_shrink=n
82 0 11.10999 5.03983 T 0.1 0.12598 e e staggered 0 0 0  is_shrink=n
82 0 11.52874 4.88 T 0.16142 0.07874 e e staggered 0 0 0  is_shrink=n
82 0 6.74209 4.6252 T 0.05 0.05 e e staggered 0 0 0  is_shrink=n
82 0 12.04 5.04 T 0.05 0.05 e e staggered 0 0 0  is_shrink=n
82 0 12.2 5.04 T 0.05 0.05 e e staggered 0 0 0  is_shrink=n
82 0 10.59 5.18 T 0.05 0.05 e e staggered 0 0 0  is_shrink=n
82 0 10.59 5.26 T 0.05 0.05 e e staggered 0 0 0  is_shrink=n
82 0 12.12 5.027 T 0.02 0.02 e e staggered 0 0 0  is_shrink=n
82 0 10.577 5.32 T 0.02 0.02 e e staggered 0 0 0  is_shrink=n
82 0.015 11.295 4.88 D m e v t  arsize_top=0 arsize_bot=0 is_shrink=n
82 0.015 5.105 5.05 D m e v t  arsize_top=0 arsize_bot=0 is_shrink=n
82 0.015 5.205 5.205 T m e v t  arsize_top=0 arsize_bot=0 is_shrink=n
82 0.015 6.82978 4.53097 T m e v t  arsize_top=0 arsize_bot=0 is_shrink=n
82 0.005 6.83709 4.5652 B m e v  arsize_top=0 arsize_bot=0 is_shrink=n
82 0.005 10.80499 5.6431 B m e v  arsize_top=0 arsize_bot=0 is_shrink=n
82 0.005 10.80499 5.7831 B m e v  arsize_top=0 arsize_bot=0 is_shrink=n
82 0.005 10.84499 5.6431 B m e v  arsize_top=0 arsize_bot=0 is_shrink=n
82 0.005 10.84499 5.7831 B m e v  arsize_top=0 arsize_bot=0 is_shrink=n
82 0.005 10.97035 5.6431 B m e v  arsize_top=0 arsize_bot=0 is_shrink=n
82 0.005 10.97035 5.7831 B m e v  arsize_top=0 arsize_bot=0 is_shrink=n
82 0.005 10.99999 4.9131 B m e v  arsize_top=0 arsize_bot=0 is_shrink=n
82 0.005 10.99999 4.9531 B m e v  arsize_top=0 arsize_bot=0 is_shrink=n
82 0.005 10.99999 4.9931 B m e v  arsize_top=0 arsize_bot=0 is_shrink=n
82 0.005 10.99999 5.0381 B m e v  arsize_top=0 arsize_bot=0 is_shrink=n
82 0.005 10.99999 5.0831 B m e v  arsize_top=0 arsize_bot=0 is_shrink=n
82 0.005 10.99999 5.1231 B m e v  arsize_top=0 arsize_bot=0 is_shrink=n
82 0.005 10.99999 5.1631 B m e v  arsize_top=0 arsize_bot=0 is_shrink=n
82 0.005 11.01035 5.6431 B m e v  arsize_top=0 arsize_bot=0 is_shrink=n
82 0.005 11.01035 5.7831 B m e v  arsize_top=0 arsize_bot=0 is_shrink=n
82 0.005 11.03999 4.9131 B m e v  arsize_top=0 arsize_bot=0 is_shrink=n
82 0.005 11.03999 4.9531 B m e v  arsize_top=0 arsize_bot=0 is_shrink=n
82 0.005 11.03999 4.9931 B m e v  arsize_top=0 arsize_bot=0 is_shrink=n
82 0.005 11.03999 5.0381 B m e v  arsize_top=0 arsize_bot=0 is_shrink=n
82 0.005 11.03999 5.0831 B m e v  arsize_top=0 arsize_bot=0 is_shrink=n
82 0.005 11.03999 5.1231 B m e v  arsize_top=0 arsize_bot=0 is_shrink=n
82 0.005 11.03999 5.1631 B m e v  arsize_top=0 arsize_bot=0 is_shrink=n
82 0.005 11.08499 4.9131 B m e v  arsize_top=0 arsize_bot=0 is_shrink=n
82 0.005 11.08499 4.9531 B m e v  arsize_top=0 arsize_bot=0 is_shrink=n
82 0.005 11.08499 5.1231 B m e v  arsize_top=0 arsize_bot=0 is_shrink=n
82 0.005 11.08499 5.1631 B m e v  arsize_top=0 arsize_bot=0 is_shrink=n
82 0.005 11.13499 4.9131 B m e v  arsize_top=0 arsize_bot=0 is_shrink=n
82 0.005 11.13499 4.9531 B m e v  arsize_top=0 arsize_bot=0 is_shrink=n
82 0.005 11.13499 5.1231 B m e v  arsize_top=0 arsize_bot=0 is_shrink=n
82 0.005 11.13499 5.1631 B m e v  arsize_top=0 arsize_bot=0 is_shrink=n
82 0.005 11.13571 5.6431 B m e v  arsize_top=0 arsize_bot=0 is_shrink=n
82 0.005 11.13571 5.7831 B m e v  arsize_top=0 arsize_bot=0 is_shrink=n
82 0.005 11.17571 5.6431 B m e v  arsize_top=0 arsize_bot=0 is_shrink=n
82 0.005 11.17571 5.7831 B m e v  arsize_top=0 arsize_bot=0 is_shrink=n
82 0.005 11.17999 4.9131 B m e v  arsize_top=0 arsize_bot=0 is_shrink=n
82 0.005 11.17999 4.9531 B m e v  arsize_top=0 arsize_bot=0 is_shrink=n
82 0.005 11.17999 4.9931 B m e v  arsize_top=0 arsize_bot=0 is_shrink=n
82 0.005 11.17999 5.0381 B m e v  arsize_top=0 arsize_bot=0 is_shrink=n
82 0.005 11.17999 5.0831 B m e v  arsize_top=0 arsize_bot=0 is_shrink=n
82 0.005 11.17999 5.1231 B m e v  arsize_top=0 arsize_bot=0 is_shrink=n
82 0.005 11.17999 5.1631 B m e v  arsize_top=0 arsize_bot=0 is_shrink=n
82 0.005 11.21999 4.9131 B m e v  arsize_top=0 arsize_bot=0 is_shrink=n
82 0.005 11.21999 4.9531 B m e v  arsize_top=0 arsize_bot=0 is_shrink=n
82 0.005 11.21999 4.9931 B m e v  arsize_top=0 arsize_bot=0 is_shrink=n
82 0.005 11.21999 5.0381 B m e v  arsize_top=0 arsize_bot=0 is_shrink=n
82 0.005 11.21999 5.0831 B m e v  arsize_top=0 arsize_bot=0 is_shrink=n
82 0.005 11.21999 5.1231 B m e v  arsize_top=0 arsize_bot=0 is_shrink=n
82 0.005 11.21999 5.1631 B m e v  arsize_top=0 arsize_bot=0 is_shrink=n
82 0.005 11.30107 5.6431 B m e v  arsize_top=0 arsize_bot=0 is_shrink=n
82 0.005 11.30107 5.7831 B m e v  arsize_top=0 arsize_bot=0 is_shrink=n
82 0.005 11.34107 5.6431 B m e v  arsize_top=0 arsize_bot=0 is_shrink=n
82 0.005 11.34107 5.7831 B m e v  arsize_top=0 arsize_bot=0 is_shrink=n
82 0.005 11.4269 4.80999 B m e v  arsize_top=0 arsize_bot=0 is_shrink=n
82 0.005 11.4269 4.85499 B m e v  arsize_top=0 arsize_bot=0 is_shrink=n
82 0.005 11.4269 4.90499 B m e v  arsize_top=0 arsize_bot=0 is_shrink=n
82 0.005 11.4269 4.94999 B m e v  arsize_top=0 arsize_bot=0 is_shrink=n
82 0.005 11.46643 5.6431 B m e v  arsize_top=0 arsize_bot=0 is_shrink=n
82 0.005 11.46643 5.7831 B m e v  arsize_top=0 arsize_bot=0 is_shrink=n
82 0.005 11.4769 4.80999 B m e v  arsize_top=0 arsize_bot=0 is_shrink=n
82 0.005 11.4769 4.94999 B m e v  arsize_top=0 arsize_bot=0 is_shrink=n
82 0.005 11.50643 5.6431 B m e v  arsize_top=0 arsize_bot=0 is_shrink=n
82 0.005 11.50643 5.7831 B m e v  arsize_top=0 arsize_bot=0 is_shrink=n
82 0.005 11.5269 4.80999 B m e v  arsize_top=0 arsize_bot=0 is_shrink=n
82 0.005 11.5269 4.94999 B m e v  arsize_top=0 arsize_bot=0 is_shrink=n
82 0.005 11.5769 4.80999 B m e v  arsize_top=0 arsize_bot=0 is_shrink=n
82 0.005 11.5769 4.94999 B m e v  arsize_top=0 arsize_bot=0 is_shrink=n
82 0.005 11.6269 4.80999 B m e v  arsize_top=0 arsize_bot=0 is_shrink=n
82 0.005 11.6269 4.85499 B m e v  arsize_top=0 arsize_bot=0 is_shrink=n
82 0.005 11.6269 4.90499 B m e v  arsize_top=0 arsize_bot=0 is_shrink=n
82 0.005 11.6269 4.94999 B m e v  arsize_top=0 arsize_bot=0 is_shrink=n
82 0.005 11.63179 5.6431 B m e v  arsize_top=0 arsize_bot=0 is_shrink=n
82 0.005 11.63179 5.7831 B m e v  arsize_top=0 arsize_bot=0 is_shrink=n
82 0.005 11.67179 5.6431 B m e v  arsize_top=0 arsize_bot=0 is_shrink=n
82 0.005 11.67179 5.7831 B m e v  arsize_top=0 arsize_bot=0 is_shrink=n
82 0.005 11.79715 5.6431 B m e v  arsize_top=0 arsize_bot=0 is_shrink=n
82 0.005 11.79715 5.7831 B m e v  arsize_top=0 arsize_bot=0 is_shrink=n
82 0.005 11.83715 5.6431 B m e v  arsize_top=0 arsize_bot=0 is_shrink=n
82 0.005 11.83715 5.7831 B m e v  arsize_top=0 arsize_bot=0 is_shrink=n
82 0.005 11.96251 5.6431 B m e v  arsize_top=0 arsize_bot=0 is_shrink=n
82 0.005 11.96251 5.7831 B m e v  arsize_top=0 arsize_bot=0 is_shrink=n
82 0.005 12.00251 5.6431 B m e v  arsize_top=0 arsize_bot=0 is_shrink=n
82 0.005 12.00251 5.7831 B m e v  arsize_top=0 arsize_bot=0 is_shrink=n
82 0.005 12.12787 5.6431 B m e v  arsize_top=0 arsize_bot=0 is_shrink=n
82 0.005 12.12787 5.7831 B m e v  arsize_top=0 arsize_bot=0 is_shrink=n
82 0.005 12.16787 5.6431 B m e v  arsize_top=0 arsize_bot=0 is_shrink=n
82 0.005 12.16787 5.7831 B m e v  arsize_top=0 arsize_bot=0 is_shrink=n
82 0.005 4.99605 4.9131 B m e v  arsize_top=0 arsize_bot=0 is_shrink=n
82 0.005 4.99605 4.9531 B m e v  arsize_top=0 arsize_bot=0 is_shrink=n
82 0.005 4.99605 4.9931 B m e v  arsize_top=0 arsize_bot=0 is_shrink=n
82 0.005 4.99605 5.0381 B m e v  arsize_top=0 arsize_bot=0 is_shrink=n
82 0.005 4.99605 5.0831 B m e v  arsize_top=0 arsize_bot=0 is_shrink=n
82 0.005 4.99605 5.1231 B m e v  arsize_top=0 arsize_bot=0 is_shrink=n
82 0.005 4.99605 5.1631 B m e v  arsize_top=0 arsize_bot=0 is_shrink=n
82 0.005 5.03605 4.9131 B m e v  arsize_top=0 arsize_bot=0 is_shrink=n
82 0.005 5.03605 4.9531 B m e v  arsize_top=0 arsize_bot=0 is_shrink=n
82 0.005 5.03605 4.9931 B m e v  arsize_top=0 arsize_bot=0 is_shrink=n
82 0.005 5.03605 5.0381 B m e v  arsize_top=0 arsize_bot=0 is_shrink=n
82 0.005 5.03605 5.0831 B m e v  arsize_top=0 arsize_bot=0 is_shrink=n
82 0.005 5.03605 5.1231 B m e v  arsize_top=0 arsize_bot=0 is_shrink=n
82 0.005 5.03605 5.1631 B m e v  arsize_top=0 arsize_bot=0 is_shrink=n
82 0.005 5.08105 4.9131 B m e v  arsize_top=0 arsize_bot=0 is_shrink=n
82 0.005 5.08105 4.9531 B m e v  arsize_top=0 arsize_bot=0 is_shrink=n
82 0.005 5.08105 5.1231 B m e v  arsize_top=0 arsize_bot=0 is_shrink=n
82 0.005 5.08105 5.1631 B m e v  arsize_top=0 arsize_bot=0 is_shrink=n
82 0.005 5.13105 4.9131 B m e v  arsize_top=0 arsize_bot=0 is_shrink=n
82 0.005 5.13105 4.9531 B m e v  arsize_top=0 arsize_bot=0 is_shrink=n
82 0.005 5.13105 5.1231 B m e v  arsize_top=0 arsize_bot=0 is_shrink=n
82 0.005 5.13105 5.1631 B m e v  arsize_top=0 arsize_bot=0 is_shrink=n
82 0.005 5.17605 4.9131 B m e v  arsize_top=0 arsize_bot=0 is_shrink=n
82 0.005 5.17605 4.9531 B m e v  arsize_top=0 arsize_bot=0 is_shrink=n
82 0.005 5.17605 4.9931 B m e v  arsize_top=0 arsize_bot=0 is_shrink=n
82 0.005 5.17605 5.0381 B m e v  arsize_top=0 arsize_bot=0 is_shrink=n
82 0.005 5.17605 5.0831 B m e v  arsize_top=0 arsize_bot=0 is_shrink=n
82 0.005 5.17605 5.1231 B m e v  arsize_top=0 arsize_bot=0 is_shrink=n
82 0.005 5.17605 5.1631 B m e v  arsize_top=0 arsize_bot=0 is_shrink=n
82 0.005 5.21605 4.9131 B m e v  arsize_top=0 arsize_bot=0 is_shrink=n
82 0.005 5.21605 4.9531 B m e v  arsize_top=0 arsize_bot=0 is_shrink=n
82 0.005 5.21605 4.9931 B m e v  arsize_top=0 arsize_bot=0 is_shrink=n
82 0.005 5.21605 5.0381 B m e v  arsize_top=0 arsize_bot=0 is_shrink=n
82 0.005 5.21605 5.0831 B m e v  arsize_top=0 arsize_bot=0 is_shrink=n
82 0.005 5.21605 5.1231 B m e v  arsize_top=0 arsize_bot=0 is_shrink=n
82 0.005 5.21605 5.1631 B m e v  arsize_top=0 arsize_bot=0 is_shrink=n
82 0.005 6.34949 5.03 B m e v  arsize_top=0 arsize_bot=0 is_shrink=n
82 0.005 6.72709 4.5652 B m e v  arsize_top=0 arsize_bot=0 is_shrink=n
82 0.005 6.76209 4.5652 B m e v  arsize_top=0 arsize_bot=0 is_shrink=n
82 0.005 6.79709 4.5652 B m e v  arsize_top=0 arsize_bot=0 is_shrink=n
82 0.005 6.87209 4.5652 B m e v  arsize_top=0 arsize_bot=0 is_shrink=n
82 0.005 6.90209 4.5652 B m e v  arsize_top=0 arsize_bot=0 is_shrink=n
83 0.0126 5.05768 1.99115 T e e  arsize_top=0 arsize_bot=0 is_shrink=n
83 0 5.46358 1.8533 D 0.02 0.02 e e staggered 0 0 0  is_shrink=n
83 0.004 5.08268 1.96615 B m e v  arsize_top=0 arsize_bot=0 is_shrink=n
84 0.01378 0.09449 2.00394 B e e  arsize_top=0 arsize_bot=0 is_shrink=n
84 0 5.49758 1.8533 D 0.02 0.02 e e staggered 0 0 0  is_shrink=n
84 0.004 5.57531 1.8508 B m e v  arsize_top=0 arsize_bot=0 is_shrink=n
85 0.0126 5.05768 1.94115 T e e  arsize_top=0 arsize_bot=0 is_shrink=n
85 0 5.46358 1.8083 D 0.02 0.02 e e staggered 0 0 0  is_shrink=n
85 0.004 5.08268 1.91615 B m e v  arsize_top=0 arsize_bot=0 is_shrink=n
86 0.01378 0.17323 2.04331 B e e  arsize_top=0 arsize_bot=0 is_shrink=n
86 0 5.49758 1.8083 D 0.02 0.02 e e staggered 0 0 0  is_shrink=n
86 0.004 5.57531 1.8108 B m e v  arsize_top=0 arsize_bot=0 is_shrink=n
87 0.0126 5.00768 1.89115 T e e  arsize_top=0 arsize_bot=0 is_shrink=n
87 0 5.46358 1.7143 D 0.02 0.02 e e staggered 0 0 0  is_shrink=n
87 0.004 5.03268 1.86615 B m e v  arsize_top=0 arsize_bot=0 is_shrink=n
88 0.01378 0.09449 2.24016 B e e  arsize_top=0 arsize_bot=0 is_shrink=n
88 0 5.49758 1.7143 D 0.02 0.02 e e staggered 0 0 0  is_shrink=n
88 0.004 5.57531 1.7118 B m e v  arsize_top=0 arsize_bot=0 is_shrink=n
89 0.0126 4.90768 1.89115 T e e  arsize_top=0 arsize_bot=0 is_shrink=n
89 0 5.30875 1.6458 D 0.02 0.02 e e staggered 0 0 0  is_shrink=n
89 0.004 4.93268 1.86615 B m e v  arsize_top=0 arsize_bot=0 is_shrink=n
90 0.01378 0.09449 2.39764 B e e  arsize_top=0 arsize_bot=0 is_shrink=n
90 0 5.34275 1.6458 D 0.02 0.02 e e staggered 0 0 0  is_shrink=n
90 0.004 5.42048 1.6433 B m e v  arsize_top=0 arsize_bot=0 is_shrink=n
91 0.0126 4.95768 1.94115 T e e  arsize_top=0 arsize_bot=0 is_shrink=n
91 0 5.30875 1.7371 D 0.02 0.02 e e staggered 0 0 0  is_shrink=n
91 0.004 4.98268 1.91615 B m e v  arsize_top=0 arsize_bot=0 is_shrink=n
92 0.01378 0.09449 2.55512 B e e  arsize_top=0 arsize_bot=0 is_shrink=n
92 0 5.34275 1.7371 D 0.02 0.02 e e staggered 0 0 0  is_shrink=n
92 0.004 5.42048 1.7396 B m e v  arsize_top=0 arsize_bot=0 is_shrink=n
93 0.0126 5.00768 2.09115 T e e  arsize_top=0 arsize_bot=0 is_shrink=n
93 0 5.46358 1.9894 D 0.02 0.02 e e staggered 0 0 0  is_shrink=n
93 0.004 5.03268 2.06615 B m e v  arsize_top=0 arsize_bot=0 is_shrink=n
94 0.01378 0.17323 2.75197 B e e  arsize_top=0 arsize_bot=0 is_shrink=n
94 0 5.49758 1.9894 D 0.02 0.02 e e staggered 0 0 0  is_shrink=n
94 0.004 5.57531 1.9869 B m e v  arsize_top=0 arsize_bot=0 is_shrink=n
95 0.0126 4.90768 2.09115 T e e  arsize_top=0 arsize_bot=0 is_shrink=n
95 0 5.30875 1.9218 D 0.02 0.02 e e staggered 0 0 0  is_shrink=n
95 0.004 4.93268 2.06615 B m e v  arsize_top=0 arsize_bot=0 is_shrink=n
96 0.01378 0.17323 2.90945 B e e  arsize_top=0 arsize_bot=0 is_shrink=n
96 0 5.34275 1.9218 D 0.02 0.02 e e staggered 0 0 0  is_shrink=n
96 0.004 5.42048 1.91835 B m e v  arsize_top=0 arsize_bot=0 is_shrink=n
97 0.0126 4.90768 2.04115 T e e  arsize_top=0 arsize_bot=0 is_shrink=n
97 0 5.30875 1.8768 D 0.02 0.02 e e staggered 0 0 0  is_shrink=n
97 0.004 4.93268 2.01615 B m e v  arsize_top=0 arsize_bot=0 is_shrink=n
98 0.01378 0.09449 2.94882 B e e  arsize_top=0 arsize_bot=0 is_shrink=n
98 0 5.34275 1.8768 D 0.02 0.02 e e staggered 0 0 0  is_shrink=n
98 0.004 5.42048 1.87835 B m e v  arsize_top=0 arsize_bot=0 is_shrink=n
99 0.0126 4.95768 2.09115 T e e  arsize_top=0 arsize_bot=0 is_shrink=n
99 0 5.46358 2.0853 D 0.02 0.02 e e staggered 0 0 0  is_shrink=n
99 0.004 4.98268 2.06615 B m e v  arsize_top=0 arsize_bot=0 is_shrink=n
100 0.01378 0.09449 3.1063 B e e  arsize_top=0 arsize_bot=0 is_shrink=n
100 0 5.49758 2.0853 D 0.02 0.02 e e staggered 0 0 0  is_shrink=n
100 0.004 5.57531 2.0878 B m e v  arsize_top=0 arsize_bot=0 is_shrink=n
101 0.0126 5.05768 2.29115 T e e  arsize_top=0 arsize_bot=0 is_shrink=n
101 0 5.46358 2.2657 D 0.02 0.02 e e staggered 0 0 0  is_shrink=n
101 0.004 5.08268 2.26615 B m e v  arsize_top=0 arsize_bot=0 is_shrink=n
102 0.01378 0.09449 3.42126 B e e  arsize_top=0 arsize_bot=0 is_shrink=n
102 0 5.49758 2.2657 D 0.02 0.02 e e staggered 0 0 0  is_shrink=n
102 0.004 5.57531 2.2632 B m e v  arsize_top=0 arsize_bot=0 is_shrink=n
103 0.0126 5.05768 2.24115 T e e  arsize_top=0 arsize_bot=0 is_shrink=n
103 0 5.46358 2.2207 D 0.02 0.02 e e staggered 0 0 0  is_shrink=n
103 0.004 5.08268 2.21615 B m e v  arsize_top=0 arsize_bot=0 is_shrink=n
104 0.01378 0.17323 3.46063 B e e  arsize_top=0 arsize_bot=0 is_shrink=n
104 0 5.49758 2.2207 D 0.02 0.02 e e staggered 0 0 0  is_shrink=n
104 0.004 5.57531 2.2232 B m e v  arsize_top=0 arsize_bot=0 is_shrink=n
105 0.0126 5.00768 2.34115 T e e  arsize_top=0 arsize_bot=0 is_shrink=n
105 0 5.30875 2.3333 D 0.02 0.02 e e staggered 0 0 0  is_shrink=n
105 0.004 5.03268 2.31615 B m e v  arsize_top=0 arsize_bot=0 is_shrink=n
106 0.01378 0.09449 3.57874 B e e  arsize_top=0 arsize_bot=0 is_shrink=n
106 0 5.34275 2.3333 D 0.02 0.02 e e staggered 0 0 0  is_shrink=n
106 0.004 5.42048 2.3308 B m e v  arsize_top=0 arsize_bot=0 is_shrink=n
107 0.0126 5.00768 2.29115 T e e  arsize_top=0 arsize_bot=0 is_shrink=n
107 0 5.30875 2.2883 D 0.02 0.02 e e staggered 0 0 0  is_shrink=n
107 0.004 5.03268 2.26615 B m e v  arsize_top=0 arsize_bot=0 is_shrink=n
108 0.01378 0.17323 3.61811 B e e  arsize_top=0 arsize_bot=0 is_shrink=n
108 0 5.34275 2.2883 D 0.02 0.02 e e staggered 0 0 0  is_shrink=n
108 0.004 5.42048 2.2908 B m e v  arsize_top=0 arsize_bot=0 is_shrink=n
109 0.0126 4.95768 2.29115 T e e  arsize_top=0 arsize_bot=0 is_shrink=n
109 0 5.30875 2.1979 D 0.02 0.02 e e staggered 0 0 0  is_shrink=n
109 0.004 4.98268 2.26615 B m e v  arsize_top=0 arsize_bot=0 is_shrink=n
110 0.01378 0.09449 3.73622 B e e  arsize_top=0 arsize_bot=0 is_shrink=n
110 0 5.34275 2.1979 D 0.02 0.02 e e staggered 0 0 0  is_shrink=n
110 0.004 5.42048 2.1954 B m e v  arsize_top=0 arsize_bot=0 is_shrink=n
111 0.0126 4.95768 2.24115 T e e  arsize_top=0 arsize_bot=0 is_shrink=n
111 0 5.30875 2.1529 D 0.02 0.02 e e staggered 0 0 0  is_shrink=n
111 0.004 4.98268 2.21615 B m e v  arsize_top=0 arsize_bot=0 is_shrink=n
112 0.01378 0.17323 3.77559 B e e  arsize_top=0 arsize_bot=0 is_shrink=n
112 0 5.34275 2.1529 D 0.02 0.02 e e staggered 0 0 0  is_shrink=n
112 0.004 5.42048 2.1554 B m e v  arsize_top=0 arsize_bot=0 is_shrink=n
113 0.0126 4.90768 2.34115 T e e  arsize_top=0 arsize_bot=0 is_shrink=n
113 0 5.46358 2.4011 D 0.02 0.02 e e staggered 0 0 0  is_shrink=n
113 0.004 4.93268 2.31615 B m e v  arsize_top=0 arsize_bot=0 is_shrink=n
114 0.01378 0.09449 3.8937 B e e  arsize_top=0 arsize_bot=0 is_shrink=n
114 0 5.49758 2.4011 D 0.02 0.02 e e staggered 0 0 0  is_shrink=n
114 0.004 5.57531 2.3986 B m e v  arsize_top=0 arsize_bot=0 is_shrink=n
115 0.0126 4.90768 2.29115 T e e  arsize_top=0 arsize_bot=0 is_shrink=n
115 0 5.46358 2.3561 D 0.02 0.02 e e staggered 0 0 0  is_shrink=n
115 0.004 4.93268 2.26615 B m e v  arsize_top=0 arsize_bot=0 is_shrink=n
116 0.01378 0.17323 3.93307 B e e  arsize_top=0 arsize_bot=0 is_shrink=n
116 0 5.49758 2.3561 D 0.02 0.02 e e staggered 0 0 0  is_shrink=n
116 0.004 5.57531 2.3586 B m e v  arsize_top=0 arsize_bot=0 is_shrink=n
117 0.0126 5.05768 2.44115 T e e  arsize_top=0 arsize_bot=0 is_shrink=n
117 0 5.30875 2.4687 D 0.02 0.02 e e staggered 0 0 0  is_shrink=n
117 0.004 5.08268 2.41615 B m e v  arsize_top=0 arsize_bot=0 is_shrink=n
118 0.01378 0.09449 4.05118 B e e  arsize_top=0 arsize_bot=0 is_shrink=n
118 0 5.34275 2.4687 D 0.02 0.02 e e staggered 0 0 0  is_shrink=n
118 0.004 5.42048 2.4662 B m e v  arsize_top=0 arsize_bot=0 is_shrink=n
119 0.0126 5.05768 2.39115 T e e  arsize_top=0 arsize_bot=0 is_shrink=n
119 0 5.30875 2.4237 D 0.02 0.02 e e staggered 0 0 0  is_shrink=n
119 0.004 5.08268 2.36615 B m e v  arsize_top=0 arsize_bot=0 is_shrink=n
120 0.01378 0.17323 4.09055 B e e  arsize_top=0 arsize_bot=0 is_shrink=n
120 0 5.34275 2.4237 D 0.02 0.02 e e staggered 0 0 0  is_shrink=n
120 0.004 5.42048 2.4262 B m e v  arsize_top=0 arsize_bot=0 is_shrink=n
121 0.0126 4.95768 2.44115 T e e  arsize_top=0 arsize_bot=0 is_shrink=n
121 0 5.46358 2.5403 D 0.02 0.02 e e staggered 0 0 0  is_shrink=n
121 0.004 4.98268 2.41615 B m e v  arsize_top=0 arsize_bot=0 is_shrink=n
122 0.01378 0.09449 4.20866 B e e  arsize_top=0 arsize_bot=0 is_shrink=n
122 0 5.49758 2.5403 D 0.02 0.02 e e staggered 0 0 0  is_shrink=n
122 0.004 5.57531 2.5378 B m e v  arsize_top=0 arsize_bot=0 is_shrink=n
123 0.0126 4.95768 2.39115 T e e  arsize_top=0 arsize_bot=0 is_shrink=n
123 0 5.46358 2.4953 D 0.02 0.02 e e staggered 0 0 0  is_shrink=n
123 0.004 4.98268 2.36615 B m e v  arsize_top=0 arsize_bot=0 is_shrink=n
124 0.01378 0.17323 4.24803 B e e  arsize_top=0 arsize_bot=0 is_shrink=n
124 0 5.49758 2.4953 D 0.02 0.02 e e staggered 0 0 0  is_shrink=n
124 0.004 5.57531 2.4978 B m e v  arsize_top=0 arsize_bot=0 is_shrink=n
125 0.0126 4.90768 2.49115 T e e  arsize_top=0 arsize_bot=0 is_shrink=n
125 0 5.46358 2.6755 D 0.02 0.02 e e staggered 0 0 0  is_shrink=n
125 0.004 4.93268 2.46615 B m e v  arsize_top=0 arsize_bot=0 is_shrink=n
126 0.01378 0.09449 4.36614 B e e  arsize_top=0 arsize_bot=0 is_shrink=n
126 0 5.49758 2.6755 D 0.02 0.02 e e staggered 0 0 0  is_shrink=n
126 0.004 5.57531 2.673 B m e v  arsize_top=0 arsize_bot=0 is_shrink=n
127 0.0126 4.90768 2.44115 T e e  arsize_top=0 arsize_bot=0 is_shrink=n
127 0 5.46358 2.6305 D 0.02 0.02 e e staggered 0 0 0  is_shrink=n
127 0.004 4.93268 2.41615 B m e v  arsize_top=0 arsize_bot=0 is_shrink=n
128 0.01378 0.17323 4.40551 B e e  arsize_top=0 arsize_bot=0 is_shrink=n
128 0 5.49758 2.6305 D 0.02 0.02 e e staggered 0 0 0  is_shrink=n
128 0.004 5.57531 2.633 B m e v  arsize_top=0 arsize_bot=0 is_shrink=n
129 0.0126 5.00768 2.49115 T e e  arsize_top=0 arsize_bot=0 is_shrink=n
129 0 5.30875 2.6079 D 0.02 0.02 e e staggered 0 0 0  is_shrink=n
129 0.004 5.03268 2.51615 B m e v  arsize_top=0 arsize_bot=0 is_shrink=n
130 0.01378 0.09449 4.52362 B e e  arsize_top=0 arsize_bot=0 is_shrink=n
130 0 5.34275 2.6079 D 0.02 0.02 e e staggered 0 0 0  is_shrink=n
130 0.004 5.42048 2.6054 B m e v  arsize_top=0 arsize_bot=0 is_shrink=n
131 0.0126 5.00768 2.44115 T e e  arsize_top=0 arsize_bot=0 is_shrink=n
131 0 5.30875 2.5629 D 0.02 0.02 e e staggered 0 0 0  is_shrink=n
131 0.004 5.03268 2.46615 B m e v  arsize_top=0 arsize_bot=0 is_shrink=n
132 0.01378 0.17323 4.563 B e e  arsize_top=0 arsize_bot=0 is_shrink=n
132 0 5.34275 2.5629 D 0.02 0.02 e e staggered 0 0 0  is_shrink=n
132 0.004 5.42048 2.5654 B m e v  arsize_top=0 arsize_bot=0 is_shrink=n
133 0.0126 5.05768 2.14115 T e e  arsize_top=0 arsize_bot=0 is_shrink=n
133 0 5.30875 2.0572 D 0.02 0.02 e e staggered 0 0 0  is_shrink=n
133 0.004 5.08268 2.11615 B m e v  arsize_top=0 arsize_bot=0 is_shrink=n
134 0.01378 0.17323 3.22441 B e e  arsize_top=0 arsize_bot=0 is_shrink=n
134 0 5.34275 2.0572 D 0.02 0.02 e e staggered 0 0 0  is_shrink=n
134 0.004 5.42048 2.0547 B m e v  arsize_top=0 arsize_bot=0 is_shrink=n
135 0.0126 5.05768 2.09115 T e e  arsize_top=0 arsize_bot=0 is_shrink=n
135 0 5.30875 2.0122 D 0.02 0.02 e e staggered 0 0 0  is_shrink=n
135 0.004 5.08268 2.06615 B m e v  arsize_top=0 arsize_bot=0 is_shrink=n
136 0.01378 0.09449 3.26378 B e e  arsize_top=0 arsize_bot=0 is_shrink=n
136 0 5.34275 2.0122 D 0.02 0.02 e e staggered 0 0 0  is_shrink=n
136 0.004 5.42048 2.0147 B m e v  arsize_top=0 arsize_bot=0 is_shrink=n
137 0 5.10605 4.75637 T 0.1 0.12598 e e staggered 0 0 0  is_shrink=n
137 0 4.75305 4.74134 T 0.07874 0.15748 e e staggered 0 0 0  is_shrink=n
137 0 4.36305 4.74134 T 0.07874 0.15748 e e staggered 0 0 0  is_shrink=n
137 0.0126 4.60768 2.94115 T e e  arsize_top=0 arsize_bot=0 is_shrink=n
137 0.0126 4.60768 2.99115 T e e  arsize_top=0 arsize_bot=0 is_shrink=n
137 0.0126 4.60768 3.09115 T e e  arsize_top=0 arsize_bot=0 is_shrink=n
137 0.0126 4.60768 3.14115 T e e  arsize_top=0 arsize_bot=0 is_shrink=n
137 0.0126 4.60768 3.24115 T e e  arsize_top=0 arsize_bot=0 is_shrink=n
137 0.0126 4.60768 3.29115 T e e  arsize_top=0 arsize_bot=0 is_shrink=n
137 0.0126 4.60768 3.39115 T e e  arsize_top=0 arsize_bot=0 is_shrink=n
137 0.0126 4.60768 3.44115 T e e  arsize_top=0 arsize_bot=0 is_shrink=n
137 0.0126 4.60768 3.54115 T e e  arsize_top=0 arsize_bot=0 is_shrink=n
137 0.0126 4.60768 3.59115 T e e  arsize_top=0 arsize_bot=0 is_shrink=n
137 0.0126 4.60768 3.69115 T e e  arsize_top=0 arsize_bot=0 is_shrink=n
137 0.0126 4.60768 3.74115 T e e  arsize_top=0 arsize_bot=0 is_shrink=n
137 0.0126 4.60768 3.84115 T e e  arsize_top=0 arsize_bot=0 is_shrink=n
137 0.0126 4.65768 2.94115 T e e  arsize_top=0 arsize_bot=0 is_shrink=n
137 0.0126 4.65768 2.99115 T e e  arsize_top=0 arsize_bot=0 is_shrink=n
137 0.0126 4.65768 3.09115 T e e  arsize_top=0 arsize_bot=0 is_shrink=n
137 0.0126 4.65768 3.14115 T e e  arsize_top=0 arsize_bot=0 is_shrink=n
137 0.0126 4.65768 3.24115 T e e  arsize_top=0 arsize_bot=0 is_shrink=n
137 0.0126 4.65768 3.29115 T e e  arsize_top=0 arsize_bot=0 is_shrink=n
137 0.0126 4.65768 3.39115 T e e  arsize_top=0 arsize_bot=0 is_shrink=n
137 0.0126 4.65768 3.44115 T e e  arsize_top=0 arsize_bot=0 is_shrink=n
137 0.0126 4.65768 3.54115 T e e  arsize_top=0 arsize_bot=0 is_shrink=n
137 0.0126 4.65768 3.59115 T e e  arsize_top=0 arsize_bot=0 is_shrink=n
137 0.0126 4.65768 3.69115 T e e  arsize_top=0 arsize_bot=0 is_shrink=n
137 0.0126 4.65768 3.74115 T e e  arsize_top=0 arsize_bot=0 is_shrink=n
137 0.0126 4.65768 3.84115 T e e  arsize_top=0 arsize_bot=0 is_shrink=n
137 0.0126 4.70768 2.94115 T e e  arsize_top=0 arsize_bot=0 is_shrink=n
137 0.0126 4.70768 2.99115 T e e  arsize_top=0 arsize_bot=0 is_shrink=n
137 0.0126 4.70768 3.09115 T e e  arsize_top=0 arsize_bot=0 is_shrink=n
137 0.0126 4.70768 3.14115 T e e  arsize_top=0 arsize_bot=0 is_shrink=n
137 0.0126 4.70768 3.24115 T e e  arsize_top=0 arsize_bot=0 is_shrink=n
137 0.0126 4.70768 3.29115 T e e  arsize_top=0 arsize_bot=0 is_shrink=n
137 0.0126 4.70768 3.39115 T e e  arsize_top=0 arsize_bot=0 is_shrink=n
137 0.0126 4.70768 3.44115 T e e  arsize_top=0 arsize_bot=0 is_shrink=n
137 0.0126 4.70768 3.54115 T e e  arsize_top=0 arsize_bot=0 is_shrink=n
137 0.0126 4.70768 3.59115 T e e  arsize_top=0 arsize_bot=0 is_shrink=n
137 0.0126 4.70768 3.69115 T e e  arsize_top=0 arsize_bot=0 is_shrink=n
137 0.0126 4.70768 3.74115 T e e  arsize_top=0 arsize_bot=0 is_shrink=n
137 0.0126 4.70768 3.84115 T e e  arsize_top=0 arsize_bot=0 is_shrink=n
137 0.0126 4.75768 2.94115 T e e  arsize_top=0 arsize_bot=0 is_shrink=n
137 0.0126 4.75768 2.99115 T e e  arsize_top=0 arsize_bot=0 is_shrink=n
137 0.0126 4.75768 3.09115 T e e  arsize_top=0 arsize_bot=0 is_shrink=n
137 0.0126 4.75768 3.14115 T e e  arsize_top=0 arsize_bot=0 is_shrink=n
137 0.0126 4.75768 3.24115 T e e  arsize_top=0 arsize_bot=0 is_shrink=n
137 0.0126 4.75768 3.29115 T e e  arsize_top=0 arsize_bot=0 is_shrink=n
137 0.0126 4.75768 3.39115 T e e  arsize_top=0 arsize_bot=0 is_shrink=n
137 0.0126 4.75768 3.44115 T e e  arsize_top=0 arsize_bot=0 is_shrink=n
137 0.0126 4.75768 3.54115 T e e  arsize_top=0 arsize_bot=0 is_shrink=n
137 0.0126 4.75768 3.59115 T e e  arsize_top=0 arsize_bot=0 is_shrink=n
137 0.0126 4.75768 3.69115 T e e  arsize_top=0 arsize_bot=0 is_shrink=n
137 0.0126 4.75768 3.74115 T e e  arsize_top=0 arsize_bot=0 is_shrink=n
137 0.0126 4.75768 3.84115 T e e  arsize_top=0 arsize_bot=0 is_shrink=n
137 0.0126 4.80768 2.94115 T e e  arsize_top=0 arsize_bot=0 is_shrink=n
137 0.0126 4.80768 2.99115 T e e  arsize_top=0 arsize_bot=0 is_shrink=n
137 0.0126 4.80768 3.09115 T e e  arsize_top=0 arsize_bot=0 is_shrink=n
137 0.0126 4.80768 3.14115 T e e  arsize_top=0 arsize_bot=0 is_shrink=n
137 0.0126 4.80768 3.24115 T e e  arsize_top=0 arsize_bot=0 is_shrink=n
137 0.0126 4.80768 3.29115 T e e  arsize_top=0 arsize_bot=0 is_shrink=n
137 0.0126 4.80768 3.39115 T e e  arsize_top=0 arsize_bot=0 is_shrink=n
137 0.0126 4.80768 3.44115 T e e  arsize_top=0 arsize_bot=0 is_shrink=n
137 0.0126 4.80768 3.54115 T e e  arsize_top=0 arsize_bot=0 is_shrink=n
137 0.0126 4.80768 3.59115 T e e  arsize_top=0 arsize_bot=0 is_shrink=n
137 0.0126 4.80768 3.69115 T e e  arsize_top=0 arsize_bot=0 is_shrink=n
137 0.0126 4.80768 3.74115 T e e  arsize_top=0 arsize_bot=0 is_shrink=n
137 0.0126 4.80768 3.84115 T e e  arsize_top=0 arsize_bot=0 is_shrink=n
137 0.0126 4.85768 2.94115 T e e  arsize_top=0 arsize_bot=0 is_shrink=n
137 0.0126 4.85768 2.99115 T e e  arsize_top=0 arsize_bot=0 is_shrink=n
137 0.0126 4.85768 3.09115 T e e  arsize_top=0 arsize_bot=0 is_shrink=n
137 0.0126 4.85768 3.14115 T e e  arsize_top=0 arsize_bot=0 is_shrink=n
137 0.0126 4.85768 3.24115 T e e  arsize_top=0 arsize_bot=0 is_shrink=n
137 0.0126 4.85768 3.29115 T e e  arsize_top=0 arsize_bot=0 is_shrink=n
137 0.0126 4.85768 3.39115 T e e  arsize_top=0 arsize_bot=0 is_shrink=n
137 0.0126 4.85768 3.44115 T e e  arsize_top=0 arsize_bot=0 is_shrink=n
137 0.0126 4.85768 3.54115 T e e  arsize_top=0 arsize_bot=0 is_shrink=n
137 0.0126 4.85768 3.59115 T e e  arsize_top=0 arsize_bot=0 is_shrink=n
137 0.0126 4.85768 3.69115 T e e  arsize_top=0 arsize_bot=0 is_shrink=n
137 0.0126 4.85768 3.74115 T e e  arsize_top=0 arsize_bot=0 is_shrink=n
137 0.0126 4.85768 3.84115 T e e  arsize_top=0 arsize_bot=0 is_shrink=n
137 0.0126 4.90768 2.94115 T e e  arsize_top=0 arsize_bot=0 is_shrink=n
137 0.0126 4.90768 2.99115 T e e  arsize_top=0 arsize_bot=0 is_shrink=n
137 0.0126 4.90768 3.09115 T e e  arsize_top=0 arsize_bot=0 is_shrink=n
137 0.0126 4.90768 3.14115 T e e  arsize_top=0 arsize_bot=0 is_shrink=n
137 0.0126 4.90768 3.24115 T e e  arsize_top=0 arsize_bot=0 is_shrink=n
137 0.0126 4.90768 3.29115 T e e  arsize_top=0 arsize_bot=0 is_shrink=n
137 0.0126 4.90768 3.39115 T e e  arsize_top=0 arsize_bot=0 is_shrink=n
137 0.0126 4.90768 3.44115 T e e  arsize_top=0 arsize_bot=0 is_shrink=n
137 0.0126 4.90768 3.54115 T e e  arsize_top=0 arsize_bot=0 is_shrink=n
137 0.0126 4.90768 3.59115 T e e  arsize_top=0 arsize_bot=0 is_shrink=n
137 0.0126 4.90768 3.69115 T e e  arsize_top=0 arsize_bot=0 is_shrink=n
137 0.0126 4.90768 3.74115 T e e  arsize_top=0 arsize_bot=0 is_shrink=n
137 0.0126 4.90768 3.84115 T e e  arsize_top=0 arsize_bot=0 is_shrink=n
137 0.0126 4.95768 2.94115 T e e  arsize_top=0 arsize_bot=0 is_shrink=n
137 0.0126 4.95768 2.99115 T e e  arsize_top=0 arsize_bot=0 is_shrink=n
137 0.0126 4.95768 3.09115 T e e  arsize_top=0 arsize_bot=0 is_shrink=n
137 0.0126 4.95768 3.14115 T e e  arsize_top=0 arsize_bot=0 is_shrink=n
137 0.0126 4.95768 3.24115 T e e  arsize_top=0 arsize_bot=0 is_shrink=n
137 0.0126 4.95768 3.29115 T e e  arsize_top=0 arsize_bot=0 is_shrink=n
137 0.0126 4.95768 3.39115 T e e  arsize_top=0 arsize_bot=0 is_shrink=n
137 0.0126 4.95768 3.44115 T e e  arsize_top=0 arsize_bot=0 is_shrink=n
137 0.0126 4.95768 3.54115 T e e  arsize_top=0 arsize_bot=0 is_shrink=n
137 0.0126 4.95768 3.59115 T e e  arsize_top=0 arsize_bot=0 is_shrink=n
137 0.0126 4.95768 3.69115 T e e  arsize_top=0 arsize_bot=0 is_shrink=n
137 0.0126 4.95768 3.74115 T e e  arsize_top=0 arsize_bot=0 is_shrink=n
137 0.0126 4.95768 3.84115 T e e  arsize_top=0 arsize_bot=0 is_shrink=n
137 0.0126 5.00768 2.94115 T e e  arsize_top=0 arsize_bot=0 is_shrink=n
137 0.0126 5.00768 2.99115 T e e  arsize_top=0 arsize_bot=0 is_shrink=n
137 0.0126 5.00768 3.09115 T e e  arsize_top=0 arsize_bot=0 is_shrink=n
137 0.0126 5.00768 3.14115 T e e  arsize_top=0 arsize_bot=0 is_shrink=n
137 0.0126 5.00768 3.24115 T e e  arsize_top=0 arsize_bot=0 is_shrink=n
137 0.0126 5.00768 3.29115 T e e  arsize_top=0 arsize_bot=0 is_shrink=n
137 0.0126 5.00768 3.39115 T e e  arsize_top=0 arsize_bot=0 is_shrink=n
137 0.0126 5.00768 3.44115 T e e  arsize_top=0 arsize_bot=0 is_shrink=n
137 0.0126 5.00768 3.54115 T e e  arsize_top=0 arsize_bot=0 is_shrink=n
137 0.0126 5.00768 3.59115 T e e  arsize_top=0 arsize_bot=0 is_shrink=n
137 0.0126 5.00768 3.69115 T e e  arsize_top=0 arsize_bot=0 is_shrink=n
137 0.0126 5.00768 3.74115 T e e  arsize_top=0 arsize_bot=0 is_shrink=n
137 0.0126 5.00768 3.84115 T e e  arsize_top=0 arsize_bot=0 is_shrink=n
137 0.0126 5.05768 2.94115 T e e  arsize_top=0 arsize_bot=0 is_shrink=n
137 0.0126 5.05768 2.99115 T e e  arsize_top=0 arsize_bot=0 is_shrink=n
137 0.0126 5.05768 3.09115 T e e  arsize_top=0 arsize_bot=0 is_shrink=n
137 0.0126 5.05768 3.14115 T e e  arsize_top=0 arsize_bot=0 is_shrink=n
137 0.0126 5.05768 3.24115 T e e  arsize_top=0 arsize_bot=0 is_shrink=n
137 0.0126 5.05768 3.29115 T e e  arsize_top=0 arsize_bot=0 is_shrink=n
137 0.0126 5.05768 3.39115 T e e  arsize_top=0 arsize_bot=0 is_shrink=n
137 0.0126 5.05768 3.44115 T e e  arsize_top=0 arsize_bot=0 is_shrink=n
137 0.0126 5.05768 3.54115 T e e  arsize_top=0 arsize_bot=0 is_shrink=n
137 0.0126 5.05768 3.59115 T e e  arsize_top=0 arsize_bot=0 is_shrink=n
137 0.0126 5.05768 3.69115 T e e  arsize_top=0 arsize_bot=0 is_shrink=n
137 0.0126 5.05768 3.74115 T e e  arsize_top=0 arsize_bot=0 is_shrink=n
137 0.0126 5.05768 3.84115 T e e  arsize_top=0 arsize_bot=0 is_shrink=n
137 0.015 4.41 4.21 D m e v t  arsize_top=0 arsize_bot=0 is_shrink=n
137 0.004 4.58268 2.96615 B m e v  arsize_top=0 arsize_bot=0 is_shrink=n
137 0.004 4.58268 3.01615 B m e v  arsize_top=0 arsize_bot=0 is_shrink=n
137 0.004 4.58268 3.11615 B m e v  arsize_top=0 arsize_bot=0 is_shrink=n
137 0.004 4.58268 3.16615 B m e v  arsize_top=0 arsize_bot=0 is_shrink=n
137 0.004 4.58268 3.26615 B m e v  arsize_top=0 arsize_bot=0 is_shrink=n
137 0.004 4.58268 3.31615 B m e v  arsize_top=0 arsize_bot=0 is_shrink=n
137 0.004 4.58268 3.41615 B m e v  arsize_top=0 arsize_bot=0 is_shrink=n
137 0.004 4.58268 3.46615 B m e v  arsize_top=0 arsize_bot=0 is_shrink=n
137 0.004 4.58268 3.56615 B m e v  arsize_top=0 arsize_bot=0 is_shrink=n
137 0.004 4.58268 3.61615 B m e v  arsize_top=0 arsize_bot=0 is_shrink=n
137 0.004 4.58268 3.71615 B m e v  arsize_top=0 arsize_bot=0 is_shrink=n
137 0.004 4.58268 3.76615 B m e v  arsize_top=0 arsize_bot=0 is_shrink=n
137 0.004 4.58268 3.86615 B m e v  arsize_top=0 arsize_bot=0 is_shrink=n
137 0.004 4.63268 2.96615 B m e v  arsize_top=0 arsize_bot=0 is_shrink=n
137 0.004 4.63268 3.01615 B m e v  arsize_top=0 arsize_bot=0 is_shrink=n
137 0.004 4.63268 3.11615 B m e v  arsize_top=0 arsize_bot=0 is_shrink=n
137 0.004 4.63268 3.16615 B m e v  arsize_top=0 arsize_bot=0 is_shrink=n
137 0.004 4.63268 3.26615 B m e v  arsize_top=0 arsize_bot=0 is_shrink=n
137 0.004 4.63268 3.31615 B m e v  arsize_top=0 arsize_bot=0 is_shrink=n
137 0.004 4.63268 3.41615 B m e v  arsize_top=0 arsize_bot=0 is_shrink=n
137 0.004 4.63268 3.46615 B m e v  arsize_top=0 arsize_bot=0 is_shrink=n
137 0.004 4.63268 3.56615 B m e v  arsize_top=0 arsize_bot=0 is_shrink=n
137 0.004 4.63268 3.61615 B m e v  arsize_top=0 arsize_bot=0 is_shrink=n
137 0.004 4.63268 3.71615 B m e v  arsize_top=0 arsize_bot=0 is_shrink=n
137 0.004 4.63268 3.76615 B m e v  arsize_top=0 arsize_bot=0 is_shrink=n
137 0.004 4.63268 3.86615 B m e v  arsize_top=0 arsize_bot=0 is_shrink=n
137 0.004 4.68268 2.96615 B m e v  arsize_top=0 arsize_bot=0 is_shrink=n
137 0.004 4.68268 3.01615 B m e v  arsize_top=0 arsize_bot=0 is_shrink=n
137 0.004 4.68268 3.11615 B m e v  arsize_top=0 arsize_bot=0 is_shrink=n
137 0.004 4.68268 3.16615 B m e v  arsize_top=0 arsize_bot=0 is_shrink=n
137 0.004 4.68268 3.26615 B m e v  arsize_top=0 arsize_bot=0 is_shrink=n
137 0.004 4.68268 3.31615 B m e v  arsize_top=0 arsize_bot=0 is_shrink=n
137 0.004 4.68268 3.41615 B m e v  arsize_top=0 arsize_bot=0 is_shrink=n
137 0.004 4.68268 3.46615 B m e v  arsize_top=0 arsize_bot=0 is_shrink=n
137 0.004 4.68268 3.56615 B m e v  arsize_top=0 arsize_bot=0 is_shrink=n
137 0.004 4.68268 3.61615 B m e v  arsize_top=0 arsize_bot=0 is_shrink=n
137 0.004 4.68268 3.71615 B m e v  arsize_top=0 arsize_bot=0 is_shrink=n
137 0.004 4.68268 3.76615 B m e v  arsize_top=0 arsize_bot=0 is_shrink=n
137 0.004 4.68268 3.86615 B m e v  arsize_top=0 arsize_bot=0 is_shrink=n
137 0.004 4.73268 2.96615 B m e v  arsize_top=0 arsize_bot=0 is_shrink=n
137 0.004 4.73268 3.01615 B m e v  arsize_top=0 arsize_bot=0 is_shrink=n
137 0.004 4.73268 3.11615 B m e v  arsize_top=0 arsize_bot=0 is_shrink=n
137 0.004 4.73268 3.16615 B m e v  arsize_top=0 arsize_bot=0 is_shrink=n
137 0.004 4.73268 3.26615 B m e v  arsize_top=0 arsize_bot=0 is_shrink=n
137 0.004 4.73268 3.31615 B m e v  arsize_top=0 arsize_bot=0 is_shrink=n
137 0.004 4.73268 3.41615 B m e v  arsize_top=0 arsize_bot=0 is_shrink=n
137 0.004 4.73268 3.46615 B m e v  arsize_top=0 arsize_bot=0 is_shrink=n
137 0.004 4.73268 3.56615 B m e v  arsize_top=0 arsize_bot=0 is_shrink=n
137 0.004 4.73268 3.61615 B m e v  arsize_top=0 arsize_bot=0 is_shrink=n
137 0.004 4.73268 3.71615 B m e v  arsize_top=0 arsize_bot=0 is_shrink=n
137 0.004 4.73268 3.76615 B m e v  arsize_top=0 arsize_bot=0 is_shrink=n
137 0.004 4.73268 3.86615 B m e v  arsize_top=0 arsize_bot=0 is_shrink=n
137 0.004 4.78268 2.96615 B m e v  arsize_top=0 arsize_bot=0 is_shrink=n
137 0.004 4.78268 3.01615 B m e v  arsize_top=0 arsize_bot=0 is_shrink=n
137 0.004 4.78268 3.11615 B m e v  arsize_top=0 arsize_bot=0 is_shrink=n
137 0.004 4.78268 3.16615 B m e v  arsize_top=0 arsize_bot=0 is_shrink=n
137 0.004 4.78268 3.26615 B m e v  arsize_top=0 arsize_bot=0 is_shrink=n
137 0.004 4.78268 3.31615 B m e v  arsize_top=0 arsize_bot=0 is_shrink=n
137 0.004 4.78268 3.41615 B m e v  arsize_top=0 arsize_bot=0 is_shrink=n
137 0.004 4.78268 3.46615 B m e v  arsize_top=0 arsize_bot=0 is_shrink=n
137 0.004 4.78268 3.56615 B m e v  arsize_top=0 arsize_bot=0 is_shrink=n
137 0.004 4.78268 3.61615 B m e v  arsize_top=0 arsize_bot=0 is_shrink=n
137 0.004 4.78268 3.71615 B m e v  arsize_top=0 arsize_bot=0 is_shrink=n
137 0.004 4.78268 3.76615 B m e v  arsize_top=0 arsize_bot=0 is_shrink=n
137 0.004 4.78268 3.86615 B m e v  arsize_top=0 arsize_bot=0 is_shrink=n
137 0.004 4.83268 2.96615 B m e v  arsize_top=0 arsize_bot=0 is_shrink=n
137 0.004 4.83268 3.01615 B m e v  arsize_top=0 arsize_bot=0 is_shrink=n
137 0.004 4.83268 3.11615 B m e v  arsize_top=0 arsize_bot=0 is_shrink=n
137 0.004 4.83268 3.16615 B m e v  arsize_top=0 arsize_bot=0 is_shrink=n
137 0.004 4.83268 3.26615 B m e v  arsize_top=0 arsize_bot=0 is_shrink=n
137 0.004 4.83268 3.31615 B m e v  arsize_top=0 arsize_bot=0 is_shrink=n
137 0.004 4.83268 3.41615 B m e v  arsize_top=0 arsize_bot=0 is_shrink=n
137 0.004 4.83268 3.46615 B m e v  arsize_top=0 arsize_bot=0 is_shrink=n
137 0.004 4.83268 3.56615 B m e v  arsize_top=0 arsize_bot=0 is_shrink=n
137 0.004 4.83268 3.61615 B m e v  arsize_top=0 arsize_bot=0 is_shrink=n
137 0.004 4.83268 3.71615 B m e v  arsize_top=0 arsize_bot=0 is_shrink=n
137 0.004 4.83268 3.76615 B m e v  arsize_top=0 arsize_bot=0 is_shrink=n
137 0.004 4.83268 3.86615 B m e v  arsize_top=0 arsize_bot=0 is_shrink=n
137 0.004 4.88268 2.96615 B m e v  arsize_top=0 arsize_bot=0 is_shrink=n
137 0.004 4.88268 3.01615 B m e v  arsize_top=0 arsize_bot=0 is_shrink=n
137 0.004 4.88268 3.11615 B m e v  arsize_top=0 arsize_bot=0 is_shrink=n
137 0.004 4.88268 3.16615 B m e v  arsize_top=0 arsize_bot=0 is_shrink=n
137 0.004 4.88268 3.26615 B m e v  arsize_top=0 arsize_bot=0 is_shrink=n
137 0.004 4.88268 3.31615 B m e v  arsize_top=0 arsize_bot=0 is_shrink=n
137 0.004 4.88268 3.41615 B m e v  arsize_top=0 arsize_bot=0 is_shrink=n
137 0.004 4.88268 3.46615 B m e v  arsize_top=0 arsize_bot=0 is_shrink=n
137 0.004 4.88268 3.56615 B m e v  arsize_top=0 arsize_bot=0 is_shrink=n
137 0.004 4.88268 3.61615 B m e v  arsize_top=0 arsize_bot=0 is_shrink=n
137 0.004 4.88268 3.71615 B m e v  arsize_top=0 arsize_bot=0 is_shrink=n
137 0.004 4.88268 3.76615 B m e v  arsize_top=0 arsize_bot=0 is_shrink=n
137 0.004 4.88268 3.86615 B m e v  arsize_top=0 arsize_bot=0 is_shrink=n
137 0.004 4.93268 2.96615 B m e v  arsize_top=0 arsize_bot=0 is_shrink=n
137 0.004 4.93268 3.01615 B m e v  arsize_top=0 arsize_bot=0 is_shrink=n
137 0.004 4.93268 3.11615 B m e v  arsize_top=0 arsize_bot=0 is_shrink=n
137 0.004 4.93268 3.16615 B m e v  arsize_top=0 arsize_bot=0 is_shrink=n
137 0.004 4.93268 3.26615 B m e v  arsize_top=0 arsize_bot=0 is_shrink=n
137 0.004 4.93268 3.31615 B m e v  arsize_top=0 arsize_bot=0 is_shrink=n
137 0.004 4.93268 3.41615 B m e v  arsize_top=0 arsize_bot=0 is_shrink=n
137 0.004 4.93268 3.46615 B m e v  arsize_top=0 arsize_bot=0 is_shrink=n
137 0.004 4.93268 3.56615 B m e v  arsize_top=0 arsize_bot=0 is_shrink=n
137 0.004 4.93268 3.61615 B m e v  arsize_top=0 arsize_bot=0 is_shrink=n
137 0.004 4.93268 3.71615 B m e v  arsize_top=0 arsize_bot=0 is_shrink=n
137 0.004 4.93268 3.76615 B m e v  arsize_top=0 arsize_bot=0 is_shrink=n
137 0.004 4.93268 3.86615 B m e v  arsize_top=0 arsize_bot=0 is_shrink=n
137 0.004 4.98268 2.96615 B m e v  arsize_top=0 arsize_bot=0 is_shrink=n
137 0.004 4.98268 3.01615 B m e v  arsize_top=0 arsize_bot=0 is_shrink=n
137 0.004 4.98268 3.11615 B m e v  arsize_top=0 arsize_bot=0 is_shrink=n
137 0.004 4.98268 3.16615 B m e v  arsize_top=0 arsize_bot=0 is_shrink=n
137 0.004 4.98268 3.26615 B m e v  arsize_top=0 arsize_bot=0 is_shrink=n
137 0.004 4.98268 3.31615 B m e v  arsize_top=0 arsize_bot=0 is_shrink=n
137 0.004 4.98268 3.41615 B m e v  arsize_top=0 arsize_bot=0 is_shrink=n
137 0.004 4.98268 3.46615 B m e v  arsize_top=0 arsize_bot=0 is_shrink=n
137 0.004 4.98268 3.56615 B m e v  arsize_top=0 arsize_bot=0 is_shrink=n
137 0.004 4.98268 3.61615 B m e v  arsize_top=0 arsize_bot=0 is_shrink=n
137 0.004 4.98268 3.71615 B m e v  arsize_top=0 arsize_bot=0 is_shrink=n
137 0.004 4.98268 3.76615 B m e v  arsize_top=0 arsize_bot=0 is_shrink=n
137 0.004 4.98268 3.86615 B m e v  arsize_top=0 arsize_bot=0 is_shrink=n
137 0.004 5.03268 2.96615 B m e v  arsize_top=0 arsize_bot=0 is_shrink=n
137 0.004 5.03268 3.01615 B m e v  arsize_top=0 arsize_bot=0 is_shrink=n
137 0.004 5.03268 3.11615 B m e v  arsize_top=0 arsize_bot=0 is_shrink=n
137 0.004 5.03268 3.16615 B m e v  arsize_top=0 arsize_bot=0 is_shrink=n
137 0.004 5.03268 3.26615 B m e v  arsize_top=0 arsize_bot=0 is_shrink=n
137 0.004 5.03268 3.31615 B m e v  arsize_top=0 arsize_bot=0 is_shrink=n
137 0.004 5.03268 3.41615 B m e v  arsize_top=0 arsize_bot=0 is_shrink=n
137 0.004 5.03268 3.46615 B m e v  arsize_top=0 arsize_bot=0 is_shrink=n
137 0.004 5.03268 3.56615 B m e v  arsize_top=0 arsize_bot=0 is_shrink=n
137 0.004 5.03268 3.61615 B m e v  arsize_top=0 arsize_bot=0 is_shrink=n
137 0.004 5.03268 3.71615 B m e v  arsize_top=0 arsize_bot=0 is_shrink=n
137 0.004 5.03268 3.76615 B m e v  arsize_top=0 arsize_bot=0 is_shrink=n
137 0.004 5.03268 3.86615 B m e v  arsize_top=0 arsize_bot=0 is_shrink=n
137 0.005 4.26605 4.6631 B m e v  arsize_top=0 arsize_bot=0 is_shrink=n
137 0.005 4.26605 4.7031 B m e v  arsize_top=0 arsize_bot=0 is_shrink=n
137 0.005 4.26605 4.7481 B m e v  arsize_top=0 arsize_bot=0 is_shrink=n
137 0.005 4.26605 4.7931 B m e v  arsize_top=0 arsize_bot=0 is_shrink=n
137 0.005 4.26605 4.8381 B m e v  arsize_top=0 arsize_bot=0 is_shrink=n
137 0.005 4.30605 4.6631 B m e v  arsize_top=0 arsize_bot=0 is_shrink=n
137 0.005 4.30605 4.7031 B m e v  arsize_top=0 arsize_bot=0 is_shrink=n
137 0.005 4.30605 4.7481 B m e v  arsize_top=0 arsize_bot=0 is_shrink=n
137 0.005 4.30605 4.7931 B m e v  arsize_top=0 arsize_bot=0 is_shrink=n
137 0.005 4.30605 4.8381 B m e v  arsize_top=0 arsize_bot=0 is_shrink=n
137 0.005 4.34105 4.6431 B m e v  arsize_top=0 arsize_bot=0 is_shrink=n
137 0.005 4.34605 4.8381 B m e v  arsize_top=0 arsize_bot=0 is_shrink=n
137 0.005 4.38605 4.6431 B m e v  arsize_top=0 arsize_bot=0 is_shrink=n
137 0.005 4.38605 4.8381 B m e v  arsize_top=0 arsize_bot=0 is_shrink=n
137 0.005 4.42605 4.6631 B m e v  arsize_top=0 arsize_bot=0 is_shrink=n
137 0.005 4.42605 4.7031 B m e v  arsize_top=0 arsize_bot=0 is_shrink=n
137 0.005 4.42605 4.7481 B m e v  arsize_top=0 arsize_bot=0 is_shrink=n
137 0.005 4.42605 4.7931 B m e v  arsize_top=0 arsize_bot=0 is_shrink=n
137 0.005 4.42605 4.8381 B m e v  arsize_top=0 arsize_bot=0 is_shrink=n
137 0.005 4.46605 4.6631 B m e v  arsize_top=0 arsize_bot=0 is_shrink=n
137 0.005 4.46605 4.7031 B m e v  arsize_top=0 arsize_bot=0 is_shrink=n
137 0.005 4.46605 4.7481 B m e v  arsize_top=0 arsize_bot=0 is_shrink=n
137 0.005 4.46605 4.7931 B m e v  arsize_top=0 arsize_bot=0 is_shrink=n
137 0.005 4.46605 4.8381 B m e v  arsize_top=0 arsize_bot=0 is_shrink=n
137 0.005 4.65605 4.6631 B m e v  arsize_top=0 arsize_bot=0 is_shrink=n
137 0.005 4.65605 4.7031 B m e v  arsize_top=0 arsize_bot=0 is_shrink=n
137 0.005 4.65605 4.7481 B m e v  arsize_top=0 arsize_bot=0 is_shrink=n
137 0.005 4.65605 4.7931 B m e v  arsize_top=0 arsize_bot=0 is_shrink=n
137 0.005 4.65605 4.8381 B m e v  arsize_top=0 arsize_bot=0 is_shrink=n
137 0.005 4.69605 4.6631 B m e v  arsize_top=0 arsize_bot=0 is_shrink=n
137 0.005 4.69605 4.7031 B m e v  arsize_top=0 arsize_bot=0 is_shrink=n
137 0.005 4.69605 4.7481 B m e v  arsize_top=0 arsize_bot=0 is_shrink=n
137 0.005 4.69605 4.7931 B m e v  arsize_top=0 arsize_bot=0 is_shrink=n
137 0.005 4.69605 4.8381 B m e v  arsize_top=0 arsize_bot=0 is_shrink=n
137 0.005 4.73105 4.6431 B m e v  arsize_top=0 arsize_bot=0 is_shrink=n
137 0.005 4.73605 4.8381 B m e v  arsize_top=0 arsize_bot=0 is_shrink=n
137 0.005 4.77605 4.6431 B m e v  arsize_top=0 arsize_bot=0 is_shrink=n
137 0.005 4.77605 4.8381 B m e v  arsize_top=0 arsize_bot=0 is_shrink=n
137 0.005 4.81605 4.6631 B m e v  arsize_top=0 arsize_bot=0 is_shrink=n
137 0.005 4.81605 4.7031 B m e v  arsize_top=0 arsize_bot=0 is_shrink=n
137 0.005 4.81605 4.7481 B m e v  arsize_top=0 arsize_bot=0 is_shrink=n
137 0.005 4.81605 4.7931 B m e v  arsize_top=0 arsize_bot=0 is_shrink=n
137 0.005 4.81605 4.8381 B m e v  arsize_top=0 arsize_bot=0 is_shrink=n
137 0.005 4.85605 4.6631 B m e v  arsize_top=0 arsize_bot=0 is_shrink=n
137 0.005 4.85605 4.7031 B m e v  arsize_top=0 arsize_bot=0 is_shrink=n
137 0.005 4.85605 4.7481 B m e v  arsize_top=0 arsize_bot=0 is_shrink=n
137 0.005 4.85605 4.7931 B m e v  arsize_top=0 arsize_bot=0 is_shrink=n
137 0.005 4.85605 4.8381 B m e v  arsize_top=0 arsize_bot=0 is_shrink=n
137 0.005 5.03605 4.6731 B m e v  arsize_top=0 arsize_bot=0 is_shrink=n
137 0.005 5.03605 4.7131 B m e v  arsize_top=0 arsize_bot=0 is_shrink=n
137 0.005 5.03605 4.7581 B m e v  arsize_top=0 arsize_bot=0 is_shrink=n
137 0.005 5.03605 4.8031 B m e v  arsize_top=0 arsize_bot=0 is_shrink=n
137 0.005 5.03605 4.8431 B m e v  arsize_top=0 arsize_bot=0 is_shrink=n
137 0.005 5.08105 4.6731 B m e v  arsize_top=0 arsize_bot=0 is_shrink=n
137 0.005 5.08105 4.8431 B m e v  arsize_top=0 arsize_bot=0 is_shrink=n
137 0.005 5.13105 4.6731 B m e v  arsize_top=0 arsize_bot=0 is_shrink=n
137 0.005 5.13105 4.8431 B m e v  arsize_top=0 arsize_bot=0 is_shrink=n
137 0.005 5.17605 4.6731 B m e v  arsize_top=0 arsize_bot=0 is_shrink=n
137 0.005 5.17605 4.7131 B m e v  arsize_top=0 arsize_bot=0 is_shrink=n
137 0.005 5.17605 4.7581 B m e v  arsize_top=0 arsize_bot=0 is_shrink=n
137 0.005 5.17605 4.8031 B m e v  arsize_top=0 arsize_bot=0 is_shrink=n
137 0.005 5.17605 4.8431 B m e v  arsize_top=0 arsize_bot=0 is_shrink=n
138 0 11.10999 4.75637 T 0.1 0.12598 e e staggered 0 0 0  is_shrink=n
138 0 10.36699 4.74134 T 0.07874 0.15748 e e staggered 0 0 0  is_shrink=n
138 0 10.75699 4.74134 T 0.07874 0.15748 e e staggered 0 0 0  is_shrink=n
138 0.0126 10.61161 2.94115 T e e  arsize_top=0 arsize_bot=0 is_shrink=n
138 0.0126 10.61161 2.99115 T e e  arsize_top=0 arsize_bot=0 is_shrink=n
138 0.0126 10.61161 3.09115 T e e  arsize_top=0 arsize_bot=0 is_shrink=n
138 0.0126 10.61161 3.14115 T e e  arsize_top=0 arsize_bot=0 is_shrink=n
138 0.0126 10.61161 3.24115 T e e  arsize_top=0 arsize_bot=0 is_shrink=n
138 0.0126 10.61161 3.29115 T e e  arsize_top=0 arsize_bot=0 is_shrink=n
138 0.0126 10.61161 3.39115 T e e  arsize_top=0 arsize_bot=0 is_shrink=n
138 0.0126 10.61161 3.44115 T e e  arsize_top=0 arsize_bot=0 is_shrink=n
138 0.0126 10.61161 3.54115 T e e  arsize_top=0 arsize_bot=0 is_shrink=n
138 0.0126 10.61161 3.59115 T e e  arsize_top=0 arsize_bot=0 is_shrink=n
138 0.0126 10.61161 3.69115 T e e  arsize_top=0 arsize_bot=0 is_shrink=n
138 0.0126 10.61161 3.74115 T e e  arsize_top=0 arsize_bot=0 is_shrink=n
138 0.0126 10.61161 3.84115 T e e  arsize_top=0 arsize_bot=0 is_shrink=n
138 0.0126 10.66161 2.94115 T e e  arsize_top=0 arsize_bot=0 is_shrink=n
138 0.0126 10.66161 2.99115 T e e  arsize_top=0 arsize_bot=0 is_shrink=n
138 0.0126 10.66161 3.09115 T e e  arsize_top=0 arsize_bot=0 is_shrink=n
138 0.0126 10.66161 3.14115 T e e  arsize_top=0 arsize_bot=0 is_shrink=n
138 0.0126 10.66161 3.24115 T e e  arsize_top=0 arsize_bot=0 is_shrink=n
138 0.0126 10.66161 3.29115 T e e  arsize_top=0 arsize_bot=0 is_shrink=n
138 0.0126 10.66161 3.39115 T e e  arsize_top=0 arsize_bot=0 is_shrink=n
138 0.0126 10.66161 3.44115 T e e  arsize_top=0 arsize_bot=0 is_shrink=n
138 0.0126 10.66161 3.54115 T e e  arsize_top=0 arsize_bot=0 is_shrink=n
138 0.0126 10.66161 3.59115 T e e  arsize_top=0 arsize_bot=0 is_shrink=n
138 0.0126 10.66161 3.69115 T e e  arsize_top=0 arsize_bot=0 is_shrink=n
138 0.0126 10.66161 3.74115 T e e  arsize_top=0 arsize_bot=0 is_shrink=n
138 0.0126 10.66161 3.84115 T e e  arsize_top=0 arsize_bot=0 is_shrink=n
138 0.0126 10.71161 2.94115 T e e  arsize_top=0 arsize_bot=0 is_shrink=n
138 0.0126 10.71161 2.99115 T e e  arsize_top=0 arsize_bot=0 is_shrink=n
138 0.0126 10.71161 3.09115 T e e  arsize_top=0 arsize_bot=0 is_shrink=n
138 0.0126 10.71161 3.14115 T e e  arsize_top=0 arsize_bot=0 is_shrink=n
138 0.0126 10.71161 3.24115 T e e  arsize_top=0 arsize_bot=0 is_shrink=n
138 0.0126 10.71161 3.29115 T e e  arsize_top=0 arsize_bot=0 is_shrink=n
138 0.0126 10.71161 3.39115 T e e  arsize_top=0 arsize_bot=0 is_shrink=n
138 0.0126 10.71161 3.44115 T e e  arsize_top=0 arsize_bot=0 is_shrink=n
138 0.0126 10.71161 3.54115 T e e  arsize_top=0 arsize_bot=0 is_shrink=n
138 0.0126 10.71161 3.59115 T e e  arsize_top=0 arsize_bot=0 is_shrink=n
138 0.0126 10.71161 3.69115 T e e  arsize_top=0 arsize_bot=0 is_shrink=n
138 0.0126 10.71161 3.74115 T e e  arsize_top=0 arsize_bot=0 is_shrink=n
138 0.0126 10.71161 3.84115 T e e  arsize_top=0 arsize_bot=0 is_shrink=n
138 0.0126 10.76161 2.94115 T e e  arsize_top=0 arsize_bot=0 is_shrink=n
138 0.0126 10.76161 2.99115 T e e  arsize_top=0 arsize_bot=0 is_shrink=n
138 0.0126 10.76161 3.09115 T e e  arsize_top=0 arsize_bot=0 is_shrink=n
138 0.0126 10.76161 3.14115 T e e  arsize_top=0 arsize_bot=0 is_shrink=n
138 0.0126 10.76161 3.24115 T e e  arsize_top=0 arsize_bot=0 is_shrink=n
138 0.0126 10.76161 3.29115 T e e  arsize_top=0 arsize_bot=0 is_shrink=n
138 0.0126 10.76161 3.39115 T e e  arsize_top=0 arsize_bot=0 is_shrink=n
138 0.0126 10.76161 3.44115 T e e  arsize_top=0 arsize_bot=0 is_shrink=n
138 0.0126 10.76161 3.54115 T e e  arsize_top=0 arsize_bot=0 is_shrink=n
138 0.0126 10.76161 3.59115 T e e  arsize_top=0 arsize_bot=0 is_shrink=n
138 0.0126 10.76161 3.69115 T e e  arsize_top=0 arsize_bot=0 is_shrink=n
138 0.0126 10.76161 3.74115 T e e  arsize_top=0 arsize_bot=0 is_shrink=n
138 0.0126 10.76161 3.84115 T e e  arsize_top=0 arsize_bot=0 is_shrink=n
138 0.0126 10.81161 2.94115 T e e  arsize_top=0 arsize_bot=0 is_shrink=n
138 0.0126 10.81161 2.99115 T e e  arsize_top=0 arsize_bot=0 is_shrink=n
138 0.0126 10.81161 3.09115 T e e  arsize_top=0 arsize_bot=0 is_shrink=n
138 0.0126 10.81161 3.14115 T e e  arsize_top=0 arsize_bot=0 is_shrink=n
138 0.0126 10.81161 3.24115 T e e  arsize_top=0 arsize_bot=0 is_shrink=n
138 0.0126 10.81161 3.29115 T e e  arsize_top=0 arsize_bot=0 is_shrink=n
138 0.0126 10.81161 3.39115 T e e  arsize_top=0 arsize_bot=0 is_shrink=n
138 0.0126 10.81161 3.44115 T e e  arsize_top=0 arsize_bot=0 is_shrink=n
138 0.0126 10.81161 3.54115 T e e  arsize_top=0 arsize_bot=0 is_shrink=n
138 0.0126 10.81161 3.59115 T e e  arsize_top=0 arsize_bot=0 is_shrink=n
138 0.0126 10.81161 3.69115 T e e  arsize_top=0 arsize_bot=0 is_shrink=n
138 0.0126 10.81161 3.74115 T e e  arsize_top=0 arsize_bot=0 is_shrink=n
138 0.0126 10.81161 3.84115 T e e  arsize_top=0 arsize_bot=0 is_shrink=n
138 0.0126 10.86161 2.94115 T e e  arsize_top=0 arsize_bot=0 is_shrink=n
138 0.0126 10.86161 2.99115 T e e  arsize_top=0 arsize_bot=0 is_shrink=n
138 0.0126 10.86161 3.09115 T e e  arsize_top=0 arsize_bot=0 is_shrink=n
138 0.0126 10.86161 3.14115 T e e  arsize_top=0 arsize_bot=0 is_shrink=n
138 0.0126 10.86161 3.24115 T e e  arsize_top=0 arsize_bot=0 is_shrink=n
138 0.0126 10.86161 3.29115 T e e  arsize_top=0 arsize_bot=0 is_shrink=n
138 0.0126 10.86161 3.39115 T e e  arsize_top=0 arsize_bot=0 is_shrink=n
138 0.0126 10.86161 3.44115 T e e  arsize_top=0 arsize_bot=0 is_shrink=n
138 0.0126 10.86161 3.54115 T e e  arsize_top=0 arsize_bot=0 is_shrink=n
138 0.0126 10.86161 3.59115 T e e  arsize_top=0 arsize_bot=0 is_shrink=n
138 0.0126 10.86161 3.69115 T e e  arsize_top=0 arsize_bot=0 is_shrink=n
138 0.0126 10.86161 3.74115 T e e  arsize_top=0 arsize_bot=0 is_shrink=n
138 0.0126 10.86161 3.84115 T e e  arsize_top=0 arsize_bot=0 is_shrink=n
138 0.0126 10.91161 2.94115 T e e  arsize_top=0 arsize_bot=0 is_shrink=n
138 0.0126 10.91161 2.99115 T e e  arsize_top=0 arsize_bot=0 is_shrink=n
138 0.0126 10.91161 3.09115 T e e  arsize_top=0 arsize_bot=0 is_shrink=n
138 0.0126 10.91161 3.14115 T e e  arsize_top=0 arsize_bot=0 is_shrink=n
138 0.0126 10.91161 3.24115 T e e  arsize_top=0 arsize_bot=0 is_shrink=n
138 0.0126 10.91161 3.29115 T e e  arsize_top=0 arsize_bot=0 is_shrink=n
138 0.0126 10.91161 3.39115 T e e  arsize_top=0 arsize_bot=0 is_shrink=n
138 0.0126 10.91161 3.44115 T e e  arsize_top=0 arsize_bot=0 is_shrink=n
138 0.0126 10.91161 3.54115 T e e  arsize_top=0 arsize_bot=0 is_shrink=n
138 0.0126 10.91161 3.59115 T e e  arsize_top=0 arsize_bot=0 is_shrink=n
138 0.0126 10.91161 3.69115 T e e  arsize_top=0 arsize_bot=0 is_shrink=n
138 0.0126 10.91161 3.74115 T e e  arsize_top=0 arsize_bot=0 is_shrink=n
138 0.0126 10.91161 3.84115 T e e  arsize_top=0 arsize_bot=0 is_shrink=n
138 0.0126 10.96161 2.94115 T e e  arsize_top=0 arsize_bot=0 is_shrink=n
138 0.0126 10.96161 2.99115 T e e  arsize_top=0 arsize_bot=0 is_shrink=n
138 0.0126 10.96161 3.09115 T e e  arsize_top=0 arsize_bot=0 is_shrink=n
138 0.0126 10.96161 3.14115 T e e  arsize_top=0 arsize_bot=0 is_shrink=n
138 0.0126 10.96161 3.24115 T e e  arsize_top=0 arsize_bot=0 is_shrink=n
138 0.0126 10.96161 3.29115 T e e  arsize_top=0 arsize_bot=0 is_shrink=n
138 0.0126 10.96161 3.39115 T e e  arsize_top=0 arsize_bot=0 is_shrink=n
138 0.0126 10.96161 3.44115 T e e  arsize_top=0 arsize_bot=0 is_shrink=n
138 0.0126 10.96161 3.54115 T e e  arsize_top=0 arsize_bot=0 is_shrink=n
138 0.0126 10.96161 3.59115 T e e  arsize_top=0 arsize_bot=0 is_shrink=n
138 0.0126 10.96161 3.69115 T e e  arsize_top=0 arsize_bot=0 is_shrink=n
138 0.0126 10.96161 3.74115 T e e  arsize_top=0 arsize_bot=0 is_shrink=n
138 0.0126 10.96161 3.84115 T e e  arsize_top=0 arsize_bot=0 is_shrink=n
138 0.0126 11.01161 2.94115 T e e  arsize_top=0 arsize_bot=0 is_shrink=n
138 0.0126 11.01161 2.99115 T e e  arsize_top=0 arsize_bot=0 is_shrink=n
138 0.0126 11.01161 3.09115 T e e  arsize_top=0 arsize_bot=0 is_shrink=n
138 0.0126 11.01161 3.14115 T e e  arsize_top=0 arsize_bot=0 is_shrink=n
138 0.0126 11.01161 3.24115 T e e  arsize_top=0 arsize_bot=0 is_shrink=n
138 0.0126 11.01161 3.29115 T e e  arsize_top=0 arsize_bot=0 is_shrink=n
138 0.0126 11.01161 3.39115 T e e  arsize_top=0 arsize_bot=0 is_shrink=n
138 0.0126 11.01161 3.44115 T e e  arsize_top=0 arsize_bot=0 is_shrink=n
138 0.0126 11.01161 3.54115 T e e  arsize_top=0 arsize_bot=0 is_shrink=n
138 0.0126 11.01161 3.59115 T e e  arsize_top=0 arsize_bot=0 is_shrink=n
138 0.0126 11.01161 3.69115 T e e  arsize_top=0 arsize_bot=0 is_shrink=n
138 0.0126 11.01161 3.74115 T e e  arsize_top=0 arsize_bot=0 is_shrink=n
138 0.0126 11.01161 3.84115 T e e  arsize_top=0 arsize_bot=0 is_shrink=n
138 0.0126 11.06161 2.94115 T e e  arsize_top=0 arsize_bot=0 is_shrink=n
138 0.0126 11.06161 2.99115 T e e  arsize_top=0 arsize_bot=0 is_shrink=n
138 0.0126 11.06161 3.09115 T e e  arsize_top=0 arsize_bot=0 is_shrink=n
138 0.0126 11.06161 3.14115 T e e  arsize_top=0 arsize_bot=0 is_shrink=n
138 0.0126 11.06161 3.24115 T e e  arsize_top=0 arsize_bot=0 is_shrink=n
138 0.0126 11.06161 3.29115 T e e  arsize_top=0 arsize_bot=0 is_shrink=n
138 0.0126 11.06161 3.39115 T e e  arsize_top=0 arsize_bot=0 is_shrink=n
138 0.0126 11.06161 3.44115 T e e  arsize_top=0 arsize_bot=0 is_shrink=n
138 0.0126 11.06161 3.54115 T e e  arsize_top=0 arsize_bot=0 is_shrink=n
138 0.0126 11.06161 3.59115 T e e  arsize_top=0 arsize_bot=0 is_shrink=n
138 0.0126 11.06161 3.69115 T e e  arsize_top=0 arsize_bot=0 is_shrink=n
138 0.0126 11.06161 3.74115 T e e  arsize_top=0 arsize_bot=0 is_shrink=n
138 0.0126 11.06161 3.84115 T e e  arsize_top=0 arsize_bot=0 is_shrink=n
138 0.015 10.41394 4.21 D m e v t  arsize_top=0 arsize_bot=0 is_shrink=n
138 0.004 10.58661 2.96615 B m e v  arsize_top=0 arsize_bot=0 is_shrink=n
138 0.004 10.58661 3.01615 B m e v  arsize_top=0 arsize_bot=0 is_shrink=n
138 0.004 10.58661 3.11615 B m e v  arsize_top=0 arsize_bot=0 is_shrink=n
138 0.004 10.58661 3.16615 B m e v  arsize_top=0 arsize_bot=0 is_shrink=n
138 0.004 10.58661 3.26615 B m e v  arsize_top=0 arsize_bot=0 is_shrink=n
138 0.004 10.58661 3.31615 B m e v  arsize_top=0 arsize_bot=0 is_shrink=n
138 0.004 10.58661 3.41615 B m e v  arsize_top=0 arsize_bot=0 is_shrink=n
138 0.004 10.58661 3.46615 B m e v  arsize_top=0 arsize_bot=0 is_shrink=n
138 0.004 10.58661 3.56615 B m e v  arsize_top=0 arsize_bot=0 is_shrink=n
138 0.004 10.58661 3.61615 B m e v  arsize_top=0 arsize_bot=0 is_shrink=n
138 0.004 10.58661 3.71615 B m e v  arsize_top=0 arsize_bot=0 is_shrink=n
138 0.004 10.58661 3.76615 B m e v  arsize_top=0 arsize_bot=0 is_shrink=n
138 0.004 10.58661 3.86615 B m e v  arsize_top=0 arsize_bot=0 is_shrink=n
138 0.004 10.63661 2.96615 B m e v  arsize_top=0 arsize_bot=0 is_shrink=n
138 0.004 10.63661 3.01615 B m e v  arsize_top=0 arsize_bot=0 is_shrink=n
138 0.004 10.63661 3.11615 B m e v  arsize_top=0 arsize_bot=0 is_shrink=n
138 0.004 10.63661 3.16615 B m e v  arsize_top=0 arsize_bot=0 is_shrink=n
138 0.004 10.63661 3.26615 B m e v  arsize_top=0 arsize_bot=0 is_shrink=n
138 0.004 10.63661 3.31615 B m e v  arsize_top=0 arsize_bot=0 is_shrink=n
138 0.004 10.63661 3.41615 B m e v  arsize_top=0 arsize_bot=0 is_shrink=n
138 0.004 10.63661 3.46615 B m e v  arsize_top=0 arsize_bot=0 is_shrink=n
138 0.004 10.63661 3.56615 B m e v  arsize_top=0 arsize_bot=0 is_shrink=n
138 0.004 10.63661 3.61615 B m e v  arsize_top=0 arsize_bot=0 is_shrink=n
138 0.004 10.63661 3.71615 B m e v  arsize_top=0 arsize_bot=0 is_shrink=n
138 0.004 10.63661 3.76615 B m e v  arsize_top=0 arsize_bot=0 is_shrink=n
138 0.004 10.63661 3.86615 B m e v  arsize_top=0 arsize_bot=0 is_shrink=n
138 0.004 10.68661 2.96615 B m e v  arsize_top=0 arsize_bot=0 is_shrink=n
138 0.004 10.68661 3.01615 B m e v  arsize_top=0 arsize_bot=0 is_shrink=n
138 0.004 10.68661 3.11615 B m e v  arsize_top=0 arsize_bot=0 is_shrink=n
138 0.004 10.68661 3.16615 B m e v  arsize_top=0 arsize_bot=0 is_shrink=n
138 0.004 10.68661 3.26615 B m e v  arsize_top=0 arsize_bot=0 is_shrink=n
138 0.004 10.68661 3.31615 B m e v  arsize_top=0 arsize_bot=0 is_shrink=n
138 0.004 10.68661 3.41615 B m e v  arsize_top=0 arsize_bot=0 is_shrink=n
138 0.004 10.68661 3.46615 B m e v  arsize_top=0 arsize_bot=0 is_shrink=n
138 0.004 10.68661 3.56615 B m e v  arsize_top=0 arsize_bot=0 is_shrink=n
138 0.004 10.68661 3.61615 B m e v  arsize_top=0 arsize_bot=0 is_shrink=n
138 0.004 10.68661 3.71615 B m e v  arsize_top=0 arsize_bot=0 is_shrink=n
138 0.004 10.68661 3.76615 B m e v  arsize_top=0 arsize_bot=0 is_shrink=n
138 0.004 10.68661 3.86615 B m e v  arsize_top=0 arsize_bot=0 is_shrink=n
138 0.004 10.73661 2.96615 B m e v  arsize_top=0 arsize_bot=0 is_shrink=n
138 0.004 10.73661 3.01615 B m e v  arsize_top=0 arsize_bot=0 is_shrink=n
138 0.004 10.73661 3.11615 B m e v  arsize_top=0 arsize_bot=0 is_shrink=n
138 0.004 10.73661 3.16615 B m e v  arsize_top=0 arsize_bot=0 is_shrink=n
138 0.004 10.73661 3.26615 B m e v  arsize_top=0 arsize_bot=0 is_shrink=n
138 0.004 10.73661 3.31615 B m e v  arsize_top=0 arsize_bot=0 is_shrink=n
138 0.004 10.73661 3.41615 B m e v  arsize_top=0 arsize_bot=0 is_shrink=n
138 0.004 10.73661 3.46615 B m e v  arsize_top=0 arsize_bot=0 is_shrink=n
138 0.004 10.73661 3.56615 B m e v  arsize_top=0 arsize_bot=0 is_shrink=n
138 0.004 10.73661 3.61615 B m e v  arsize_top=0 arsize_bot=0 is_shrink=n
138 0.004 10.73661 3.71615 B m e v  arsize_top=0 arsize_bot=0 is_shrink=n
138 0.004 10.73661 3.76615 B m e v  arsize_top=0 arsize_bot=0 is_shrink=n
138 0.004 10.73661 3.86615 B m e v  arsize_top=0 arsize_bot=0 is_shrink=n
138 0.004 10.78661 2.96615 B m e v  arsize_top=0 arsize_bot=0 is_shrink=n
138 0.004 10.78661 3.01615 B m e v  arsize_top=0 arsize_bot=0 is_shrink=n
138 0.004 10.78661 3.11615 B m e v  arsize_top=0 arsize_bot=0 is_shrink=n
138 0.004 10.78661 3.16615 B m e v  arsize_top=0 arsize_bot=0 is_shrink=n
138 0.004 10.78661 3.26615 B m e v  arsize_top=0 arsize_bot=0 is_shrink=n
138 0.004 10.78661 3.31615 B m e v  arsize_top=0 arsize_bot=0 is_shrink=n
138 0.004 10.78661 3.41615 B m e v  arsize_top=0 arsize_bot=0 is_shrink=n
138 0.004 10.78661 3.46615 B m e v  arsize_top=0 arsize_bot=0 is_shrink=n
138 0.004 10.78661 3.56615 B m e v  arsize_top=0 arsize_bot=0 is_shrink=n
138 0.004 10.78661 3.61615 B m e v  arsize_top=0 arsize_bot=0 is_shrink=n
138 0.004 10.78661 3.71615 B m e v  arsize_top=0 arsize_bot=0 is_shrink=n
138 0.004 10.78661 3.76615 B m e v  arsize_top=0 arsize_bot=0 is_shrink=n
138 0.004 10.78661 3.86615 B m e v  arsize_top=0 arsize_bot=0 is_shrink=n
138 0.004 10.83661 2.96615 B m e v  arsize_top=0 arsize_bot=0 is_shrink=n
138 0.004 10.83661 3.01615 B m e v  arsize_top=0 arsize_bot=0 is_shrink=n
138 0.004 10.83661 3.11615 B m e v  arsize_top=0 arsize_bot=0 is_shrink=n
138 0.004 10.83661 3.16615 B m e v  arsize_top=0 arsize_bot=0 is_shrink=n
138 0.004 10.83661 3.26615 B m e v  arsize_top=0 arsize_bot=0 is_shrink=n
138 0.004 10.83661 3.31615 B m e v  arsize_top=0 arsize_bot=0 is_shrink=n
138 0.004 10.83661 3.41615 B m e v  arsize_top=0 arsize_bot=0 is_shrink=n
138 0.004 10.83661 3.46615 B m e v  arsize_top=0 arsize_bot=0 is_shrink=n
138 0.004 10.83661 3.56615 B m e v  arsize_top=0 arsize_bot=0 is_shrink=n
138 0.004 10.83661 3.61615 B m e v  arsize_top=0 arsize_bot=0 is_shrink=n
138 0.004 10.83661 3.71615 B m e v  arsize_top=0 arsize_bot=0 is_shrink=n
138 0.004 10.83661 3.76615 B m e v  arsize_top=0 arsize_bot=0 is_shrink=n
138 0.004 10.83661 3.86615 B m e v  arsize_top=0 arsize_bot=0 is_shrink=n
138 0.004 10.88661 2.96615 B m e v  arsize_top=0 arsize_bot=0 is_shrink=n
138 0.004 10.88661 3.01615 B m e v  arsize_top=0 arsize_bot=0 is_shrink=n
138 0.004 10.88661 3.11615 B m e v  arsize_top=0 arsize_bot=0 is_shrink=n
138 0.004 10.88661 3.16615 B m e v  arsize_top=0 arsize_bot=0 is_shrink=n
138 0.004 10.88661 3.26615 B m e v  arsize_top=0 arsize_bot=0 is_shrink=n
138 0.004 10.88661 3.31615 B m e v  arsize_top=0 arsize_bot=0 is_shrink=n
138 0.004 10.88661 3.41615 B m e v  arsize_top=0 arsize_bot=0 is_shrink=n
138 0.004 10.88661 3.46615 B m e v  arsize_top=0 arsize_bot=0 is_shrink=n
138 0.004 10.88661 3.56615 B m e v  arsize_top=0 arsize_bot=0 is_shrink=n
138 0.004 10.88661 3.61615 B m e v  arsize_top=0 arsize_bot=0 is_shrink=n
138 0.004 10.88661 3.71615 B m e v  arsize_top=0 arsize_bot=0 is_shrink=n
138 0.004 10.88661 3.76615 B m e v  arsize_top=0 arsize_bot=0 is_shrink=n
138 0.004 10.88661 3.86615 B m e v  arsize_top=0 arsize_bot=0 is_shrink=n
138 0.004 10.93661 2.96615 B m e v  arsize_top=0 arsize_bot=0 is_shrink=n
138 0.004 10.93661 3.01615 B m e v  arsize_top=0 arsize_bot=0 is_shrink=n
138 0.004 10.93661 3.11615 B m e v  arsize_top=0 arsize_bot=0 is_shrink=n
138 0.004 10.93661 3.16615 B m e v  arsize_top=0 arsize_bot=0 is_shrink=n
138 0.004 10.93661 3.26615 B m e v  arsize_top=0 arsize_bot=0 is_shrink=n
138 0.004 10.93661 3.31615 B m e v  arsize_top=0 arsize_bot=0 is_shrink=n
138 0.004 10.93661 3.41615 B m e v  arsize_top=0 arsize_bot=0 is_shrink=n
138 0.004 10.93661 3.46615 B m e v  arsize_top=0 arsize_bot=0 is_shrink=n
138 0.004 10.93661 3.56615 B m e v  arsize_top=0 arsize_bot=0 is_shrink=n
138 0.004 10.93661 3.61615 B m e v  arsize_top=0 arsize_bot=0 is_shrink=n
138 0.004 10.93661 3.71615 B m e v  arsize_top=0 arsize_bot=0 is_shrink=n
138 0.004 10.93661 3.76615 B m e v  arsize_top=0 arsize_bot=0 is_shrink=n
138 0.004 10.93661 3.86615 B m e v  arsize_top=0 arsize_bot=0 is_shrink=n
138 0.004 10.98661 2.96615 B m e v  arsize_top=0 arsize_bot=0 is_shrink=n
138 0.004 10.98661 3.01615 B m e v  arsize_top=0 arsize_bot=0 is_shrink=n
138 0.004 10.98661 3.11615 B m e v  arsize_top=0 arsize_bot=0 is_shrink=n
138 0.004 10.98661 3.16615 B m e v  arsize_top=0 arsize_bot=0 is_shrink=n
138 0.004 10.98661 3.26615 B m e v  arsize_top=0 arsize_bot=0 is_shrink=n
138 0.004 10.98661 3.31615 B m e v  arsize_top=0 arsize_bot=0 is_shrink=n
138 0.004 10.98661 3.41615 B m e v  arsize_top=0 arsize_bot=0 is_shrink=n
138 0.004 10.98661 3.46615 B m e v  arsize_top=0 arsize_bot=0 is_shrink=n
138 0.004 10.98661 3.56615 B m e v  arsize_top=0 arsize_bot=0 is_shrink=n
138 0.004 10.98661 3.61615 B m e v  arsize_top=0 arsize_bot=0 is_shrink=n
138 0.004 10.98661 3.71615 B m e v  arsize_top=0 arsize_bot=0 is_shrink=n
138 0.004 10.98661 3.76615 B m e v  arsize_top=0 arsize_bot=0 is_shrink=n
138 0.004 10.98661 3.86615 B m e v  arsize_top=0 arsize_bot=0 is_shrink=n
138 0.004 11.03661 2.96615 B m e v  arsize_top=0 arsize_bot=0 is_shrink=n
138 0.004 11.03661 3.01615 B m e v  arsize_top=0 arsize_bot=0 is_shrink=n
138 0.004 11.03661 3.11615 B m e v  arsize_top=0 arsize_bot=0 is_shrink=n
138 0.004 11.03661 3.16615 B m e v  arsize_top=0 arsize_bot=0 is_shrink=n
138 0.004 11.03661 3.26615 B m e v  arsize_top=0 arsize_bot=0 is_shrink=n
138 0.004 11.03661 3.31615 B m e v  arsize_top=0 arsize_bot=0 is_shrink=n
138 0.004 11.03661 3.41615 B m e v  arsize_top=0 arsize_bot=0 is_shrink=n
138 0.004 11.03661 3.46615 B m e v  arsize_top=0 arsize_bot=0 is_shrink=n
138 0.004 11.03661 3.56615 B m e v  arsize_top=0 arsize_bot=0 is_shrink=n
138 0.004 11.03661 3.61615 B m e v  arsize_top=0 arsize_bot=0 is_shrink=n
138 0.004 11.03661 3.71615 B m e v  arsize_top=0 arsize_bot=0 is_shrink=n
138 0.004 11.03661 3.76615 B m e v  arsize_top=0 arsize_bot=0 is_shrink=n
138 0.004 11.03661 3.86615 B m e v  arsize_top=0 arsize_bot=0 is_shrink=n
138 0.005 10.26999 4.6631 B m e v  arsize_top=0 arsize_bot=0 is_shrink=n
138 0.005 10.26999 4.7031 B m e v  arsize_top=0 arsize_bot=0 is_shrink=n
138 0.005 10.26999 4.7481 B m e v  arsize_top=0 arsize_bot=0 is_shrink=n
138 0.005 10.26999 4.7931 B m e v  arsize_top=0 arsize_bot=0 is_shrink=n
138 0.005 10.26999 4.8381 B m e v  arsize_top=0 arsize_bot=0 is_shrink=n
138 0.005 10.30999 4.6631 B m e v  arsize_top=0 arsize_bot=0 is_shrink=n
138 0.005 10.30999 4.7031 B m e v  arsize_top=0 arsize_bot=0 is_shrink=n
138 0.005 10.30999 4.7481 B m e v  arsize_top=0 arsize_bot=0 is_shrink=n
138 0.005 10.30999 4.7931 B m e v  arsize_top=0 arsize_bot=0 is_shrink=n
138 0.005 10.30999 4.8381 B m e v  arsize_top=0 arsize_bot=0 is_shrink=n
138 0.005 10.34499 4.6431 B m e v  arsize_top=0 arsize_bot=0 is_shrink=n
138 0.005 10.34999 4.8381 B m e v  arsize_top=0 arsize_bot=0 is_shrink=n
138 0.005 10.38999 4.6431 B m e v  arsize_top=0 arsize_bot=0 is_shrink=n
138 0.005 10.38999 4.8381 B m e v  arsize_top=0 arsize_bot=0 is_shrink=n
138 0.005 10.42999 4.6631 B m e v  arsize_top=0 arsize_bot=0 is_shrink=n
138 0.005 10.42999 4.7031 B m e v  arsize_top=0 arsize_bot=0 is_shrink=n
138 0.005 10.42999 4.7481 B m e v  arsize_top=0 arsize_bot=0 is_shrink=n
138 0.005 10.42999 4.7931 B m e v  arsize_top=0 arsize_bot=0 is_shrink=n
138 0.005 10.42999 4.8381 B m e v  arsize_top=0 arsize_bot=0 is_shrink=n
138 0.005 10.46999 4.6631 B m e v  arsize_top=0 arsize_bot=0 is_shrink=n
138 0.005 10.46999 4.7031 B m e v  arsize_top=0 arsize_bot=0 is_shrink=n
138 0.005 10.46999 4.7481 B m e v  arsize_top=0 arsize_bot=0 is_shrink=n
138 0.005 10.46999 4.7931 B m e v  arsize_top=0 arsize_bot=0 is_shrink=n
138 0.005 10.46999 4.8381 B m e v  arsize_top=0 arsize_bot=0 is_shrink=n
138 0.005 10.65999 4.6631 B m e v  arsize_top=0 arsize_bot=0 is_shrink=n
138 0.005 10.65999 4.7031 B m e v  arsize_top=0 arsize_bot=0 is_shrink=n
138 0.005 10.65999 4.7481 B m e v  arsize_top=0 arsize_bot=0 is_shrink=n
138 0.005 10.65999 4.7931 B m e v  arsize_top=0 arsize_bot=0 is_shrink=n
138 0.005 10.65999 4.8381 B m e v  arsize_top=0 arsize_bot=0 is_shrink=n
138 0.005 10.69999 4.6631 B m e v  arsize_top=0 arsize_bot=0 is_shrink=n
138 0.005 10.69999 4.7031 B m e v  arsize_top=0 arsize_bot=0 is_shrink=n
138 0.005 10.69999 4.7481 B m e v  arsize_top=0 arsize_bot=0 is_shrink=n
138 0.005 10.69999 4.7931 B m e v  arsize_top=0 arsize_bot=0 is_shrink=n
138 0.005 10.69999 4.8381 B m e v  arsize_top=0 arsize_bot=0 is_shrink=n
138 0.005 10.73499 4.6431 B m e v  arsize_top=0 arsize_bot=0 is_shrink=n
138 0.005 10.73999 4.8381 B m e v  arsize_top=0 arsize_bot=0 is_shrink=n
138 0.005 10.77999 4.6431 B m e v  arsize_top=0 arsize_bot=0 is_shrink=n
138 0.005 10.77999 4.8381 B m e v  arsize_top=0 arsize_bot=0 is_shrink=n
138 0.005 10.81999 4.6631 B m e v  arsize_top=0 arsize_bot=0 is_shrink=n
138 0.005 10.81999 4.7031 B m e v  arsize_top=0 arsize_bot=0 is_shrink=n
138 0.005 10.81999 4.7481 B m e v  arsize_top=0 arsize_bot=0 is_shrink=n
138 0.005 10.81999 4.7931 B m e v  arsize_top=0 arsize_bot=0 is_shrink=n
138 0.005 10.81999 4.8381 B m e v  arsize_top=0 arsize_bot=0 is_shrink=n
138 0.005 10.85999 4.6631 B m e v  arsize_top=0 arsize_bot=0 is_shrink=n
138 0.005 10.85999 4.7031 B m e v  arsize_top=0 arsize_bot=0 is_shrink=n
138 0.005 10.85999 4.7481 B m e v  arsize_top=0 arsize_bot=0 is_shrink=n
138 0.005 10.85999 4.7931 B m e v  arsize_top=0 arsize_bot=0 is_shrink=n
138 0.005 10.85999 4.8381 B m e v  arsize_top=0 arsize_bot=0 is_shrink=n
138 0.005 11.03999 4.6731 B m e v  arsize_top=0 arsize_bot=0 is_shrink=n
138 0.005 11.03999 4.7131 B m e v  arsize_top=0 arsize_bot=0 is_shrink=n
138 0.005 11.03999 4.7581 B m e v  arsize_top=0 arsize_bot=0 is_shrink=n
138 0.005 11.03999 4.8031 B m e v  arsize_top=0 arsize_bot=0 is_shrink=n
138 0.005 11.03999 4.8431 B m e v  arsize_top=0 arsize_bot=0 is_shrink=n
138 0.005 11.08499 4.6731 B m e v  arsize_top=0 arsize_bot=0 is_shrink=n
138 0.005 11.08499 4.8431 B m e v  arsize_top=0 arsize_bot=0 is_shrink=n
138 0.005 11.13499 4.6731 B m e v  arsize_top=0 arsize_bot=0 is_shrink=n
138 0.005 11.13499 4.8431 B m e v  arsize_top=0 arsize_bot=0 is_shrink=n
138 0.005 11.17999 4.6731 B m e v  arsize_top=0 arsize_bot=0 is_shrink=n
138 0.005 11.17999 4.7131 B m e v  arsize_top=0 arsize_bot=0 is_shrink=n
138 0.005 11.17999 4.7581 B m e v  arsize_top=0 arsize_bot=0 is_shrink=n
138 0.005 11.17999 4.8031 B m e v  arsize_top=0 arsize_bot=0 is_shrink=n
138 0.005 11.17999 4.8431 B m e v  arsize_top=0 arsize_bot=0 is_shrink=n
139 0 3.60999 0.7411 T 0.02 0.02 e e staggered 0 0 0  is_shrink=n
139 0 3.60999 0.62932 T 0.0252 0.07244 e e staggered 0 0 0  is_shrink=n
139 0.0126 4.65768 2.84115 T e e  arsize_top=0 arsize_bot=0 is_shrink=n
139 0.005 3.635 0.715 B m e v  arsize_top=0 arsize_bot=0 is_shrink=n
139 0.004 4.63268 2.81615 B m e v  arsize_top=0 arsize_bot=0 is_shrink=n
140 0 3.60999 0.3051 T 0.02 0.02 e e staggered 0 0 0  is_shrink=n
140 0 3.60999 0.40688 T 0.0252 0.07244 e e staggered 0 0 0  is_shrink=n
140 0.0126 4.60768 2.84115 T e e  arsize_top=0 arsize_bot=0 is_shrink=n
140 0.005 3.635 0.49 B m e v  arsize_top=0 arsize_bot=0 is_shrink=n
140 0.004 4.58268 2.81615 B m e v  arsize_top=0 arsize_bot=0 is_shrink=n
141 0 3.66999 0.7411 T 0.02 0.02 e e staggered 0 0 0  is_shrink=n
141 0 3.65999 0.62932 T 0.0252 0.07244 e e staggered 0 0 0  is_shrink=n
141 0.0126 4.80768 2.84115 T e e  arsize_top=0 arsize_bot=0 is_shrink=n
141 0.005 3.785 0.69 B m e v  arsize_top=0 arsize_bot=0 is_shrink=n
141 0.004 4.78268 2.81615 B m e v  arsize_top=0 arsize_bot=0 is_shrink=n
142 0 3.75999 0.62932 T 0.0252 0.07244 e e staggered 0 0 0  is_shrink=n
142 0.0126 4.75768 2.84115 T e e  arsize_top=0 arsize_bot=0 is_shrink=n
142 0.005 3.56 0.49 B m e v  arsize_top=0 arsize_bot=0 is_shrink=n
142 0.004 4.73268 2.81615 B m e v  arsize_top=0 arsize_bot=0 is_shrink=n
143 0 3.75999 0.3051 T 0.02 0.02 e e staggered 0 0 0  is_shrink=n
143 0 3.75999 0.40688 T 0.0252 0.07244 e e staggered 0 0 0  is_shrink=n
143 0.0126 4.70768 2.84115 T e e  arsize_top=0 arsize_bot=0 is_shrink=n
143 0.005 3.75999 0.345 B m e v  arsize_top=0 arsize_bot=0 is_shrink=n
143 0.004 4.68268 2.81615 B m e v  arsize_top=0 arsize_bot=0 is_shrink=n
144 0 3.81999 0.7411 T 0.02 0.02 e e staggered 0 0 0  is_shrink=n
144 0 3.80999 0.62932 T 0.0252 0.07244 e e staggered 0 0 0  is_shrink=n
144 0.0126 4.70768 2.79115 T e e  arsize_top=0 arsize_bot=0 is_shrink=n
144 0.005 3.84 0.69 B m e v  arsize_top=0 arsize_bot=0 is_shrink=n
144 0.004 4.68268 2.76615 B m e v  arsize_top=0 arsize_bot=0 is_shrink=n
145 0 9.40795 0.76243 T 0.02 0.02 e e staggered 0 0 0  is_shrink=n
145 0 9.40795 0.65065 T 0.0252 0.07244 e e staggered 0 0 0  is_shrink=n
145 0.0126 10.66161 2.84115 T e e  arsize_top=0 arsize_bot=0 is_shrink=n
145 0.005 9.43296 0.73633 B m e v  arsize_top=0 arsize_bot=0 is_shrink=n
145 0.004 10.63661 2.81615 B m e v  arsize_top=0 arsize_bot=0 is_shrink=n
146 0 9.40795 0.32643 T 0.02 0.02 e e staggered 0 0 0  is_shrink=n
146 0 9.40795 0.42821 T 0.0252 0.07244 e e staggered 0 0 0  is_shrink=n
146 0.0126 10.61161 2.84115 T e e  arsize_top=0 arsize_bot=0 is_shrink=n
146 0.005 9.43296 0.49133 B m e v  arsize_top=0 arsize_bot=0 is_shrink=n
146 0.004 10.58661 2.81615 B m e v  arsize_top=0 arsize_bot=0 is_shrink=n
147 0 9.46795 0.76243 T 0.02 0.02 e e staggered 0 0 0  is_shrink=n
147 0 9.45795 0.65065 T 0.0252 0.07244 e e staggered 0 0 0  is_shrink=n
147 0.0126 10.81161 2.84115 T e e  arsize_top=0 arsize_bot=0 is_shrink=n
147 0.005 9.58296 0.71133 B m e v  arsize_top=0 arsize_bot=0 is_shrink=n
147 0.004 10.78661 2.81615 B m e v  arsize_top=0 arsize_bot=0 is_shrink=n
148 0 9.55795 0.65065 T 0.0252 0.07244 e e staggered 0 0 0  is_shrink=n
148 0.0126 10.76161 2.84115 T e e  arsize_top=0 arsize_bot=0 is_shrink=n
148 0.005 9.35796 0.49133 B m e v  arsize_top=0 arsize_bot=0 is_shrink=n
148 0.004 10.73661 2.81615 B m e v  arsize_top=0 arsize_bot=0 is_shrink=n
149 0 9.55795 0.32643 T 0.02 0.02 e e staggered 0 0 0  is_shrink=n
149 0 9.55795 0.42821 T 0.0252 0.07244 e e staggered 0 0 0  is_shrink=n
149 0.0126 10.71161 2.84115 T e e  arsize_top=0 arsize_bot=0 is_shrink=n
149 0.005 9.55795 0.36633 B m e v  arsize_top=0 arsize_bot=0 is_shrink=n
149 0.004 10.68661 2.81615 B m e v  arsize_top=0 arsize_bot=0 is_shrink=n
150 0 9.61795 0.76243 T 0.02 0.02 e e staggered 0 0 0  is_shrink=n
150 0 9.60795 0.65065 T 0.0252 0.07244 e e staggered 0 0 0  is_shrink=n
150 0.0126 10.71161 2.79115 T e e  arsize_top=0 arsize_bot=0 is_shrink=n
150 0.005 9.64 0.71 B m e v  arsize_top=0 arsize_bot=0 is_shrink=n
150 0.004 10.68661 2.76615 B m e v  arsize_top=0 arsize_bot=0 is_shrink=n
151 0 2.75044 4.85788 T 0.01378 0.05118 e e staggered 0 0 0  is_shrink=n
151 0.0126 2.07106 3.64115 T e e  arsize_top=0 arsize_bot=0 is_shrink=n
151 0.004 2.09606 3.66615 B m e v  arsize_top=0 arsize_bot=0 is_shrink=n
151 0.004 2.74225 4.667 B m e v  arsize_top=0 arsize_bot=0 is_shrink=n
152 0 2.77406 4.85788 T 0.01378 0.05118 e e staggered 0 0 0  is_shrink=n
152 0.0126 2.07106 3.69115 T e e  arsize_top=0 arsize_bot=0 is_shrink=n
152 0.004 2.09606 3.71615 B m e v  arsize_top=0 arsize_bot=0 is_shrink=n
152 0.004 2.78225 4.667 B m e v  arsize_top=0 arsize_bot=0 is_shrink=n
153 0 2.8213 4.85788 T 0.01378 0.05118 e e staggered 0 0 0  is_shrink=n
153 0.0126 2.17106 3.64115 T e e  arsize_top=0 arsize_bot=0 is_shrink=n
153 0.004 2.19606 3.66615 B m e v  arsize_top=0 arsize_bot=0 is_shrink=n
153 0.004 2.81311 4.78292 B m e v  arsize_top=0 arsize_bot=0 is_shrink=n
154 0 2.84492 4.85788 T 0.01378 0.05118 e e staggered 0 0 0  is_shrink=n
154 0.0126 2.17106 3.69115 T e e  arsize_top=0 arsize_bot=0 is_shrink=n
154 0.004 2.19606 3.71615 B m e v  arsize_top=0 arsize_bot=0 is_shrink=n
154 0.004 2.85311 4.78292 B m e v  arsize_top=0 arsize_bot=0 is_shrink=n
155 0 2.96303 4.85788 T 0.01378 0.05118 e e staggered 0 0 0  is_shrink=n
155 0.0126 2.02106 3.74115 T e e  arsize_top=0 arsize_bot=0 is_shrink=n
155 0.004 2.04606 3.76615 B m e v  arsize_top=0 arsize_bot=0 is_shrink=n
155 0.004 2.88708 4.667 B m e v  arsize_top=0 arsize_bot=0 is_shrink=n
156 0 2.98666 4.85788 T 0.01378 0.05118 e e staggered 0 0 0  is_shrink=n
156 0.0126 2.02106 3.79115 T e e  arsize_top=0 arsize_bot=0 is_shrink=n
156 0.004 2.04606 3.81615 B m e v  arsize_top=0 arsize_bot=0 is_shrink=n
156 0.004 2.92708 4.667 B m e v  arsize_top=0 arsize_bot=0 is_shrink=n
157 0 3.0339 4.85788 T 0.01378 0.05118 e e staggered 0 0 0  is_shrink=n
157 0.0126 2.17106 3.79115 T e e  arsize_top=0 arsize_bot=0 is_shrink=n
157 0.004 2.19606 3.81615 B m e v  arsize_top=0 arsize_bot=0 is_shrink=n
157 0.004 3.02571 4.667 B m e v  arsize_top=0 arsize_bot=0 is_shrink=n
158 0 3.05752 4.85788 T 0.01378 0.05118 e e staggered 0 0 0  is_shrink=n
158 0.0126 2.17106 3.84115 T e e  arsize_top=0 arsize_bot=0 is_shrink=n
158 0.004 2.19606 3.86615 B m e v  arsize_top=0 arsize_bot=0 is_shrink=n
158 0.004 3.06571 4.667 B m e v  arsize_top=0 arsize_bot=0 is_shrink=n
159 0 3.10477 4.85788 T 0.01378 0.05118 e e staggered 0 0 0  is_shrink=n
159 0 1.18906 5.12551 T 0.02 0.02 e e staggered 0 0 0  is_shrink=n
159 0 3.16 4.508 D 0.02 0.02 e e staggered 0 0 0  is_shrink=n
159 0.005 1.18906 5.15351 B m e v  arsize_top=0 arsize_bot=0 is_shrink=n
159 0.005 3.07 4.42 B m e v  arsize_top=0 arsize_bot=0 is_shrink=n
160 0 3.12839 4.85788 T 0.01378 0.05118 e e staggered 0 0 0  is_shrink=n
160 0 1.33906 5.12551 T 0.02 0.02 e e staggered 0 0 0  is_shrink=n
160 0 3.11 4.508 D 0.02 0.02 e e staggered 0 0 0  is_shrink=n
160 0.005 1.33906 5.15351 B m e v  arsize_top=0 arsize_bot=0 is_shrink=n
160 0.005 3.105 4.47 B m e v  arsize_top=0 arsize_bot=0 is_shrink=n
161 0 3.17563 4.85788 T 0.01378 0.05118 e e staggered 0 0 0  is_shrink=n
161 0.0126 2.42106 3.84115 T e e  arsize_top=0 arsize_bot=0 is_shrink=n
161 0.004 2.44606 3.86615 B m e v  arsize_top=0 arsize_bot=0 is_shrink=n
161 0.004 3.16744 4.78292 B m e v  arsize_top=0 arsize_bot=0 is_shrink=n
162 0 3.19925 4.85788 T 0.01378 0.05118 e e staggered 0 0 0  is_shrink=n
162 0.0126 2.42106 3.79115 T e e  arsize_top=0 arsize_bot=0 is_shrink=n
162 0.004 2.44606 3.81615 B m e v  arsize_top=0 arsize_bot=0 is_shrink=n
162 0.004 3.20744 4.78292 B m e v  arsize_top=0 arsize_bot=0 is_shrink=n
163 0 3.2465 4.85788 T 0.01378 0.05118 e e staggered 0 0 0  is_shrink=n
163 0.0126 2.37106 3.79115 T e e  arsize_top=0 arsize_bot=0 is_shrink=n
163 0.004 2.39606 3.81615 B m e v  arsize_top=0 arsize_bot=0 is_shrink=n
163 0.004 3.23831 4.642 B m e v  arsize_top=0 arsize_bot=0 is_shrink=n
164 0 3.27012 4.85788 T 0.01378 0.05118 e e staggered 0 0 0  is_shrink=n
164 0.0126 2.37106 3.74115 T e e  arsize_top=0 arsize_bot=0 is_shrink=n
164 0.004 2.39606 3.76615 B m e v  arsize_top=0 arsize_bot=0 is_shrink=n
164 0.004 3.27831 4.642 B m e v  arsize_top=0 arsize_bot=0 is_shrink=n
165 0 3.38823 4.85788 T 0.01378 0.05118 e e staggered 0 0 0  is_shrink=n
165 0.0126 2.42106 3.69115 T e e  arsize_top=0 arsize_bot=0 is_shrink=n
165 0.004 2.44606 3.71615 B m e v  arsize_top=0 arsize_bot=0 is_shrink=n
165 0.004 3.38004 4.78292 B m e v  arsize_top=0 arsize_bot=0 is_shrink=n
166 0 3.41185 4.85788 T 0.01378 0.05118 e e staggered 0 0 0  is_shrink=n
166 0.0126 2.42106 3.64115 T e e  arsize_top=0 arsize_bot=0 is_shrink=n
166 0.004 2.44606 3.66615 B m e v  arsize_top=0 arsize_bot=0 is_shrink=n
166 0.004 3.42004 4.78292 B m e v  arsize_top=0 arsize_bot=0 is_shrink=n
167 0 3.4591 4.85788 T 0.01378 0.05118 e e staggered 0 0 0  is_shrink=n
167 0.0126 2.37106 3.64115 T e e  arsize_top=0 arsize_bot=0 is_shrink=n
167 0.004 2.39606 3.66615 B m e v  arsize_top=0 arsize_bot=0 is_shrink=n
167 0.004 3.45091 4.587 B m e v  arsize_top=0 arsize_bot=0 is_shrink=n
168 0 3.48272 4.85788 T 0.01378 0.05118 e e staggered 0 0 0  is_shrink=n
168 0.0126 2.37106 3.59115 T e e  arsize_top=0 arsize_bot=0 is_shrink=n
168 0.004 2.39606 3.61615 B m e v  arsize_top=0 arsize_bot=0 is_shrink=n
168 0.004 3.49091 4.587 B m e v  arsize_top=0 arsize_bot=0 is_shrink=n
169 0 3.52996 4.85788 T 0.01378 0.05118 e e staggered 0 0 0  is_shrink=n
169 0.0126 2.32106 3.69115 T e e  arsize_top=0 arsize_bot=0 is_shrink=n
169 0.004 2.34606 3.71615 B m e v  arsize_top=0 arsize_bot=0 is_shrink=n
169 0.004 3.52177 4.71973 B m e v  arsize_top=0 arsize_bot=0 is_shrink=n
170 0 3.55358 4.85788 T 0.01378 0.05118 e e staggered 0 0 0  is_shrink=n
170 0.0126 2.32106 3.64115 T e e  arsize_top=0 arsize_bot=0 is_shrink=n
170 0.004 2.34606 3.66615 B m e v  arsize_top=0 arsize_bot=0 is_shrink=n
170 0.004 3.56177 4.71973 B m e v  arsize_top=0 arsize_bot=0 is_shrink=n
171 0 2.75044 4.97914 T 0.01378 0.05118 e e staggered 0 0 0  is_shrink=n
171 0.0126 2.02106 3.59115 T e e  arsize_top=0 arsize_bot=0 is_shrink=n
171 0.004 2.04606 3.61615 B m e v  arsize_top=0 arsize_bot=0 is_shrink=n
171 0.004 2.74225 5.14 B m e v  arsize_top=0 arsize_bot=0 is_shrink=n
172 0 2.77406 4.97914 T 0.01378 0.05118 e e staggered 0 0 0  is_shrink=n
172 0.0126 2.02106 3.64115 T e e  arsize_top=0 arsize_bot=0 is_shrink=n
172 0.004 2.04606 3.66615 B m e v  arsize_top=0 arsize_bot=0 is_shrink=n
172 0.004 2.78225 5.14 B m e v  arsize_top=0 arsize_bot=0 is_shrink=n
173 0 2.8213 4.97914 T 0.01378 0.05118 e e staggered 0 0 0  is_shrink=n
173 0.0126 2.12106 3.59115 T e e  arsize_top=0 arsize_bot=0 is_shrink=n
173 0.004 2.14606 3.61615 B m e v  arsize_top=0 arsize_bot=0 is_shrink=n
173 0.004 2.88087 5.17002 B m e v  arsize_top=0 arsize_bot=0 is_shrink=n
174 0 2.84492 4.97914 T 0.01378 0.05118 e e staggered 0 0 0  is_shrink=n
174 0.0126 2.12106 3.64115 T e e  arsize_top=0 arsize_bot=0 is_shrink=n
174 0.004 2.14606 3.66615 B m e v  arsize_top=0 arsize_bot=0 is_shrink=n
174 0.004 2.92087 5.17002 B m e v  arsize_top=0 arsize_bot=0 is_shrink=n
175 0 3.0339 4.97914 T 0.01378 0.05118 e e staggered 0 0 0  is_shrink=n
175 0.0126 2.12106 3.74115 T e e  arsize_top=0 arsize_bot=0 is_shrink=n
175 0.004 2.14606 3.76615 B m e v  arsize_top=0 arsize_bot=0 is_shrink=n
175 0.004 3.02571 5.165 B m e v  arsize_top=0 arsize_bot=0 is_shrink=n
176 0 3.05752 4.97914 T 0.01378 0.05118 e e staggered 0 0 0  is_shrink=n
176 0.0126 2.12106 3.79115 T e e  arsize_top=0 arsize_bot=0 is_shrink=n
176 0.004 2.14606 3.81615 B m e v  arsize_top=0 arsize_bot=0 is_shrink=n
176 0.004 3.06571 5.165 B m e v  arsize_top=0 arsize_bot=0 is_shrink=n
177 0 3.10477 4.97914 T 0.01378 0.05118 e e staggered 0 0 0  is_shrink=n
177 0.0126 2.07106 3.79115 T e e  arsize_top=0 arsize_bot=0 is_shrink=n
177 0.004 2.09606 3.81615 B m e v  arsize_top=0 arsize_bot=0 is_shrink=n
177 0.004 3.09657 5.0535 B m e v  arsize_top=0 arsize_bot=0 is_shrink=n
178 0 3.12839 4.97914 T 0.01378 0.05118 e e staggered 0 0 0  is_shrink=n
178 0.0126 2.07106 3.84115 T e e  arsize_top=0 arsize_bot=0 is_shrink=n
178 0.004 2.09606 3.86615 B m e v  arsize_top=0 arsize_bot=0 is_shrink=n
178 0.004 3.13657 5.0535 B m e v  arsize_top=0 arsize_bot=0 is_shrink=n
179 0 3.17563 4.97914 T 0.01378 0.05118 e e staggered 0 0 0  is_shrink=n
179 0 3.09646 5.298 D 0.02 0.02 e e staggered 0 0 0  is_shrink=n
179 0 3.14146 5.298 D 0.02 0.02 e e staggered 0 0 0  is_shrink=n
179 0.005 3.115 5.255 B m e v  arsize_top=0 arsize_bot=0 is_shrink=n
180 0 3.19925 4.97914 T 0.01378 0.05118 e e staggered 0 0 0  is_shrink=n
180 0 3.23146 5.298 D 0.02 0.02 e e staggered 0 0 0  is_shrink=n
180 0 3.18646 5.298 D 0.02 0.02 e e staggered 0 0 0  is_shrink=n
180 0.005 3.17146 5.255 B m e v  arsize_top=0 arsize_bot=0 is_shrink=n
181 0 3.2465 4.97914 T 0.01378 0.05118 e e staggered 0 0 0  is_shrink=n
181 0.0126 2.32106 3.84115 T e e  arsize_top=0 arsize_bot=0 is_shrink=n
181 0.004 2.34606 3.86615 B m e v  arsize_top=0 arsize_bot=0 is_shrink=n
181 0.004 3.23831 5.22002 B m e v  arsize_top=0 arsize_bot=0 is_shrink=n
182 0 3.27012 4.97914 T 0.01378 0.05118 e e staggered 0 0 0  is_shrink=n
182 0.0126 2.32106 3.79115 T e e  arsize_top=0 arsize_bot=0 is_shrink=n
182 0.004 2.34606 3.81615 B m e v  arsize_top=0 arsize_bot=0 is_shrink=n
182 0.004 3.27831 5.22002 B m e v  arsize_top=0 arsize_bot=0 is_shrink=n
183 0 3.31736 4.97914 T 0.01378 0.05118 e e staggered 0 0 0  is_shrink=n
183 0.0126 2.47106 3.79115 T e e  arsize_top=0 arsize_bot=0 is_shrink=n
183 0.004 2.49606 3.81615 B m e v  arsize_top=0 arsize_bot=0 is_shrink=n
183 0.004 3.30917 5.1035 B m e v  arsize_top=0 arsize_bot=0 is_shrink=n
184 0 3.34099 4.97914 T 0.01378 0.05118 e e staggered 0 0 0  is_shrink=n
184 0.0126 2.47106 3.74115 T e e  arsize_top=0 arsize_bot=0 is_shrink=n
184 0.004 2.49606 3.76615 B m e v  arsize_top=0 arsize_bot=0 is_shrink=n
184 0.004 3.34917 5.1035 B m e v  arsize_top=0 arsize_bot=0 is_shrink=n
185 0 3.38823 4.97914 T 0.01378 0.05118 e e staggered 0 0 0  is_shrink=n
185 0 2.67085 2.87 D 0.02 0.02 e e staggered 0 0 0  is_shrink=n
185 0.004 3.38004 5.22002 B m e v  arsize_top=0 arsize_bot=0 is_shrink=n
185 0.004 2.97721 2.865 B m e v  arsize_top=0 arsize_bot=0 is_shrink=n
186 0 3.41185 4.97914 T 0.01378 0.05118 e e staggered 0 0 0  is_shrink=n
186 0 2.67085 2.82 D 0.02 0.02 e e staggered 0 0 0  is_shrink=n
186 0.004 3.42004 5.22002 B m e v  arsize_top=0 arsize_bot=0 is_shrink=n
186 0.004 2.97721 2.825 B m e v  arsize_top=0 arsize_bot=0 is_shrink=n
187 0 3.4591 4.97914 T 0.01378 0.05118 e e staggered 0 0 0  is_shrink=n
187 0 3.38146 5.298 D 0.02 0.02 e e staggered 0 0 0  is_shrink=n
187 0 3.33646 5.298 D 0.02 0.02 e e staggered 0 0 0  is_shrink=n
187 0.005 3.45646 5.3 B m e v  arsize_top=0 arsize_bot=0 is_shrink=n
188 0 3.52996 4.97914 T 0.01378 0.05118 e e staggered 0 0 0  is_shrink=n
188 0.0126 2.47106 3.64115 T e e  arsize_top=0 arsize_bot=0 is_shrink=n
188 0.004 2.49606 3.66615 B m e v  arsize_top=0 arsize_bot=0 is_shrink=n
188 0.004 3.52177 5.14 B m e v  arsize_top=0 arsize_bot=0 is_shrink=n
189 0 3.55358 4.97914 T 0.01378 0.05118 e e staggered 0 0 0  is_shrink=n
189 0.0126 2.47106 3.59115 T e e  arsize_top=0 arsize_bot=0 is_shrink=n
189 0.004 2.49606 3.61615 B m e v  arsize_top=0 arsize_bot=0 is_shrink=n
189 0.004 3.56177 5.14 B m e v  arsize_top=0 arsize_bot=0 is_shrink=n
190 0 1.58584 4.85788 T 0.01378 0.05118 e e staggered 0 0 0  is_shrink=n
190 0.0126 2.07106 3.24115 T e e  arsize_top=0 arsize_bot=0 is_shrink=n
190 0.004 1.57765 4.707 B m e v  arsize_top=0 arsize_bot=0 is_shrink=n
190 0.004 2.09606 3.26615 B m e v  arsize_top=0 arsize_bot=0 is_shrink=n
191 0 1.60946 4.85788 T 0.01378 0.05118 e e staggered 0 0 0  is_shrink=n
191 0.0126 2.07106 3.29115 T e e  arsize_top=0 arsize_bot=0 is_shrink=n
191 0.004 1.61765 4.707 B m e v  arsize_top=0 arsize_bot=0 is_shrink=n
191 0.004 2.09606 3.31615 B m e v  arsize_top=0 arsize_bot=0 is_shrink=n
192 0 1.6567 4.85788 T 0.01378 0.05118 e e staggered 0 0 0  is_shrink=n
192 0.0126 2.12106 3.29115 T e e  arsize_top=0 arsize_bot=0 is_shrink=n
192 0.004 1.64851 4.78292 B m e v  arsize_top=0 arsize_bot=0 is_shrink=n
192 0.004 2.14606 3.31615 B m e v  arsize_top=0 arsize_bot=0 is_shrink=n
193 0 1.68032 4.85788 T 0.01378 0.05118 e e staggered 0 0 0  is_shrink=n
193 0.0126 2.12106 3.34115 T e e  arsize_top=0 arsize_bot=0 is_shrink=n
193 0.004 1.68851 4.78292 B m e v  arsize_top=0 arsize_bot=0 is_shrink=n
193 0.004 2.14606 3.36615 B m e v  arsize_top=0 arsize_bot=0 is_shrink=n
194 0 1.79843 4.85788 T 0.01378 0.05118 e e staggered 0 0 0  is_shrink=n
194 0.0126 2.07106 3.39115 T e e  arsize_top=0 arsize_bot=0 is_shrink=n
194 0.004 1.79025 4.78292 B m e v  arsize_top=0 arsize_bot=0 is_shrink=n
194 0.004 2.09606 3.41615 B m e v  arsize_top=0 arsize_bot=0 is_shrink=n
195 0 1.82206 4.85788 T 0.01378 0.05118 e e staggered 0 0 0  is_shrink=n
195 0.0126 2.07106 3.44115 T e e  arsize_top=0 arsize_bot=0 is_shrink=n
195 0.004 1.83025 4.78292 B m e v  arsize_top=0 arsize_bot=0 is_shrink=n
195 0.004 2.09606 3.46615 B m e v  arsize_top=0 arsize_bot=0 is_shrink=n
196 0 1.8693 4.85788 T 0.01378 0.05118 e e staggered 0 0 0  is_shrink=n
196 0.0126 2.12106 3.44115 T e e  arsize_top=0 arsize_bot=0 is_shrink=n
196 0.004 1.86111 4.657 B m e v  arsize_top=0 arsize_bot=0 is_shrink=n
196 0.004 2.14606 3.46615 B m e v  arsize_top=0 arsize_bot=0 is_shrink=n
197 0 1.89292 4.85788 T 0.01378 0.05118 e e staggered 0 0 0  is_shrink=n
197 0.0126 2.12106 3.49115 T e e  arsize_top=0 arsize_bot=0 is_shrink=n
197 0.004 1.90111 4.657 B m e v  arsize_top=0 arsize_bot=0 is_shrink=n
197 0.004 2.14606 3.51615 B m e v  arsize_top=0 arsize_bot=0 is_shrink=n
198 0 1.94017 4.85788 T 0.01378 0.05118 e e staggered 0 0 0  is_shrink=n
198 0 3.16 4.542 D 0.02 0.02 e e staggered 0 0 0  is_shrink=n
198 0 1.88 4.528 D 0.02 0.02 e e staggered 0 0 0  is_shrink=n
198 0.005 1.86 4.485 B m e v  arsize_top=0 arsize_bot=0 is_shrink=n
199 0 1.96379 4.85788 T 0.01378 0.05118 e e staggered 0 0 0  is_shrink=n
199 0 3.11 4.542 D 0.02 0.02 e e staggered 0 0 0  is_shrink=n
199 0 1.825 4.528 D 0.02 0.02 e e staggered 0 0 0  is_shrink=n
199 0.005 1.8 4.485 B m e v  arsize_top=0 arsize_bot=0 is_shrink=n
200 0 2.01103 4.85788 T 0.01378 0.05118 e e staggered 0 0 0  is_shrink=n
200 0.0126 2.47106 3.49115 T e e  arsize_top=0 arsize_bot=0 is_shrink=n
200 0.004 2.02853 4.66689 B m e v  arsize_top=0 arsize_bot=0 is_shrink=n
200 0.004 2.49606 3.51615 B m e v  arsize_top=0 arsize_bot=0 is_shrink=n
201 0 2.03465 4.85788 T 0.01378 0.05118 e e staggered 0 0 0  is_shrink=n
201 0.0126 2.47106 3.44115 T e e  arsize_top=0 arsize_bot=0 is_shrink=n
201 0.004 2.06853 4.66689 B m e v  arsize_top=0 arsize_bot=0 is_shrink=n
201 0.004 2.49606 3.46615 B m e v  arsize_top=0 arsize_bot=0 is_shrink=n
202 0 2.0819 4.85788 T 0.01378 0.05118 e e staggered 0 0 0  is_shrink=n
202 0.0126 2.32106 3.44115 T e e  arsize_top=0 arsize_bot=0 is_shrink=n
202 0.004 2.07371 4.78292 B m e v  arsize_top=0 arsize_bot=0 is_shrink=n
202 0.004 2.34606 3.46615 B m e v  arsize_top=0 arsize_bot=0 is_shrink=n
203 0 2.10552 4.85788 T 0.01378 0.05118 e e staggered 0 0 0  is_shrink=n
203 0.0126 2.32106 3.39115 T e e  arsize_top=0 arsize_bot=0 is_shrink=n
203 0.004 2.11371 4.78292 B m e v  arsize_top=0 arsize_bot=0 is_shrink=n
203 0.004 2.34606 3.41615 B m e v  arsize_top=0 arsize_bot=0 is_shrink=n
204 0 2.22363 4.85788 T 0.01378 0.05118 e e staggered 0 0 0  is_shrink=n
204 0.0126 2.47106 3.34115 T e e  arsize_top=0 arsize_bot=0 is_shrink=n
204 0.004 2.21544 4.78292 B m e v  arsize_top=0 arsize_bot=0 is_shrink=n
204 0.004 2.49606 3.36615 B m e v  arsize_top=0 arsize_bot=0 is_shrink=n
205 0 2.24725 4.85788 T 0.01378 0.05118 e e staggered 0 0 0  is_shrink=n
205 0.0126 2.47106 3.29115 T e e  arsize_top=0 arsize_bot=0 is_shrink=n
205 0.004 2.25544 4.78292 B m e v  arsize_top=0 arsize_bot=0 is_shrink=n
205 0.004 2.49606 3.31615 B m e v  arsize_top=0 arsize_bot=0 is_shrink=n
206 0 2.2945 4.85788 T 0.01378 0.05118 e e staggered 0 0 0  is_shrink=n
206 0.0126 2.37106 3.34115 T e e  arsize_top=0 arsize_bot=0 is_shrink=n
206 0.004 2.21855 4.667 B m e v  arsize_top=0 arsize_bot=0 is_shrink=n
206 0.004 2.39606 3.36615 B m e v  arsize_top=0 arsize_bot=0 is_shrink=n
207 0 2.31812 4.85788 T 0.01378 0.05118 e e staggered 0 0 0  is_shrink=n
207 0.0126 2.37106 3.29115 T e e  arsize_top=0 arsize_bot=0 is_shrink=n
207 0.004 2.25855 4.667 B m e v  arsize_top=0 arsize_bot=0 is_shrink=n
207 0.004 2.39606 3.31615 B m e v  arsize_top=0 arsize_bot=0 is_shrink=n
208 0 2.36536 4.85788 T 0.01378 0.05118 e e staggered 0 0 0  is_shrink=n
208 0.0126 2.32106 3.29115 T e e  arsize_top=0 arsize_bot=0 is_shrink=n
208 0.004 2.34606 3.31615 B m e v  arsize_top=0 arsize_bot=0 is_shrink=n
208 0.004 2.35717 4.742 B m e v  arsize_top=0 arsize_bot=0 is_shrink=n
209 0 2.38898 4.85788 T 0.01378 0.05118 e e staggered 0 0 0  is_shrink=n
209 0.0126 2.32106 3.24115 T e e  arsize_top=0 arsize_bot=0 is_shrink=n
209 0.004 2.34606 3.26615 B m e v  arsize_top=0 arsize_bot=0 is_shrink=n
209 0.004 2.39717 4.742 B m e v  arsize_top=0 arsize_bot=0 is_shrink=n
210 0 1.58584 4.97914 T 0.01378 0.05118 e e staggered 0 0 0  is_shrink=n
210 0.0126 2.02106 3.29115 T e e  arsize_top=0 arsize_bot=0 is_shrink=n
210 0.004 1.57765 5.169 B m e v  arsize_top=0 arsize_bot=0 is_shrink=n
210 0.004 2.04606 3.31615 B m e v  arsize_top=0 arsize_bot=0 is_shrink=n
211 0 1.60946 4.97914 T 0.01378 0.05118 e e staggered 0 0 0  is_shrink=n
211 0.0126 2.02106 3.34115 T e e  arsize_top=0 arsize_bot=0 is_shrink=n
211 0.004 1.61765 5.169 B m e v  arsize_top=0 arsize_bot=0 is_shrink=n
211 0.004 2.04606 3.36615 B m e v  arsize_top=0 arsize_bot=0 is_shrink=n
212 0 1.6567 4.97914 T 0.01378 0.05118 e e staggered 0 0 0  is_shrink=n
212 0.0126 2.17106 3.24115 T e e  arsize_top=0 arsize_bot=0 is_shrink=n
212 0.004 1.6485 5.0535 B m e v  arsize_top=0 arsize_bot=0 is_shrink=n
212 0.004 2.19606 3.26615 B m e v  arsize_top=0 arsize_bot=0 is_shrink=n
213 0 1.68032 4.97914 T 0.01378 0.05118 e e staggered 0 0 0  is_shrink=n
213 0.0126 2.17106 3.29115 T e e  arsize_top=0 arsize_bot=0 is_shrink=n
213 0.004 1.6885 5.0535 B m e v  arsize_top=0 arsize_bot=0 is_shrink=n
213 0.004 2.19606 3.31615 B m e v  arsize_top=0 arsize_bot=0 is_shrink=n
214 0 1.8693 4.97914 T 0.01378 0.05118 e e staggered 0 0 0  is_shrink=n
214 0.0126 2.17106 3.39115 T e e  arsize_top=0 arsize_bot=0 is_shrink=n
214 0.004 1.86111 5.169 B m e v  arsize_top=0 arsize_bot=0 is_shrink=n
214 0.004 2.19606 3.41615 B m e v  arsize_top=0 arsize_bot=0 is_shrink=n
215 0 1.89292 4.97914 T 0.01378 0.05118 e e staggered 0 0 0  is_shrink=n
215 0.0126 2.17106 3.44115 T e e  arsize_top=0 arsize_bot=0 is_shrink=n
215 0.004 1.90111 5.169 B m e v  arsize_top=0 arsize_bot=0 is_shrink=n
215 0.004 2.19606 3.46615 B m e v  arsize_top=0 arsize_bot=0 is_shrink=n
216 0 1.94017 4.97914 T 0.01378 0.05118 e e staggered 0 0 0  is_shrink=n
216 0.0126 2.02106 3.44115 T e e  arsize_top=0 arsize_bot=0 is_shrink=n
216 0.004 1.93197 5.0535 B m e v  arsize_top=0 arsize_bot=0 is_shrink=n
216 0.004 1.99606 3.46615 B m e v  arsize_top=0 arsize_bot=0 is_shrink=n
217 0 1.96379 4.97914 T 0.01378 0.05118 e e staggered 0 0 0  is_shrink=n
217 0.0126 2.02106 3.49115 T e e  arsize_top=0 arsize_bot=0 is_shrink=n
217 0.004 1.97197 5.0535 B m e v  arsize_top=0 arsize_bot=0 is_shrink=n
217 0.004 1.99606 3.51615 B m e v  arsize_top=0 arsize_bot=0 is_shrink=n
218 0 2.01103 4.97914 T 0.01378 0.05118 e e staggered 0 0 0  is_shrink=n
218 0 2.00146 5.343 D 0.02 0.02 e e staggered 0 0 0  is_shrink=n
218 0 1.95146 5.343 D 0.02 0.02 e e staggered 0 0 0  is_shrink=n
218 0.005 2.00146 5.29 B m e v  arsize_top=0 arsize_bot=0 is_shrink=n
219 0 2.03465 4.97914 T 0.01378 0.05118 e e staggered 0 0 0  is_shrink=n
219 0 2.06646 5.343 D 0.02 0.02 e e staggered 0 0 0  is_shrink=n
219 0 2.11646 5.343 D 0.02 0.02 e e staggered 0 0 0  is_shrink=n
219 0.005 2.06646 5.29 B m e v  arsize_top=0 arsize_bot=0 is_shrink=n
220 0 2.0819 4.97914 T 0.01378 0.05118 e e staggered 0 0 0  is_shrink=n
220 0.0126 2.37106 3.49115 T e e  arsize_top=0 arsize_bot=0 is_shrink=n
220 0.004 2.07371 5.169 B m e v  arsize_top=0 arsize_bot=0 is_shrink=n
220 0.004 2.39606 3.51615 B m e v  arsize_top=0 arsize_bot=0 is_shrink=n
221 0 2.10552 4.97914 T 0.01378 0.05118 e e staggered 0 0 0  is_shrink=n
221 0.0126 2.37106 3.44115 T e e  arsize_top=0 arsize_bot=0 is_shrink=n
221 0.004 2.11371 5.169 B m e v  arsize_top=0 arsize_bot=0 is_shrink=n
221 0.004 2.39606 3.46615 B m e v  arsize_top=0 arsize_bot=0 is_shrink=n
222 0 2.15276 4.97914 T 0.01378 0.05118 e e staggered 0 0 0  is_shrink=n
222 0.0126 2.42106 3.44115 T e e  arsize_top=0 arsize_bot=0 is_shrink=n
222 0.004 2.14457 5.0535 B m e v  arsize_top=0 arsize_bot=0 is_shrink=n
222 0.004 2.44606 3.46615 B m e v  arsize_top=0 arsize_bot=0 is_shrink=n
223 0 2.17639 4.97914 T 0.01378 0.05118 e e staggered 0 0 0  is_shrink=n
223 0.0126 2.42106 3.39115 T e e  arsize_top=0 arsize_bot=0 is_shrink=n
223 0.004 2.18457 5.0535 B m e v  arsize_top=0 arsize_bot=0 is_shrink=n
223 0.004 2.44606 3.41615 B m e v  arsize_top=0 arsize_bot=0 is_shrink=n
224 0 2.36536 4.97914 T 0.01378 0.05118 e e staggered 0 0 0  is_shrink=n
224 0.0126 2.42106 3.29115 T e e  arsize_top=0 arsize_bot=0 is_shrink=n
224 0.004 2.35717 5.115 B m e v  arsize_top=0 arsize_bot=0 is_shrink=n
224 0.004 2.44606 3.31615 B m e v  arsize_top=0 arsize_bot=0 is_shrink=n
225 0 2.38898 4.97914 T 0.01378 0.05118 e e staggered 0 0 0  is_shrink=n
225 0.0126 2.42106 3.24115 T e e  arsize_top=0 arsize_bot=0 is_shrink=n
225 0.004 2.39717 5.115 B m e v  arsize_top=0 arsize_bot=0 is_shrink=n
225 0.004 2.44606 3.26615 B m e v  arsize_top=0 arsize_bot=0 is_shrink=n
226 0 8.75398 4.85788 T 0.01378 0.05118 e e staggered 0 0 0  is_shrink=n
226 0.0126 8.075 3.64115 T e e  arsize_top=0 arsize_bot=0 is_shrink=n
226 0.004 8.1 3.66615 B m e v  arsize_top=0 arsize_bot=0 is_shrink=n
226 0.004 8.74579 4.667 B m e v  arsize_top=0 arsize_bot=0 is_shrink=n
227 0 8.7776 4.85788 T 0.01378 0.05118 e e staggered 0 0 0  is_shrink=n
227 0.0126 8.075 3.69115 T e e  arsize_top=0 arsize_bot=0 is_shrink=n
227 0.004 8.1 3.71615 B m e v  arsize_top=0 arsize_bot=0 is_shrink=n
227 0.004 8.78579 4.667 B m e v  arsize_top=0 arsize_bot=0 is_shrink=n
228 0 8.82484 4.85788 T 0.01378 0.05118 e e staggered 0 0 0  is_shrink=n
228 0.0126 8.175 3.64115 T e e  arsize_top=0 arsize_bot=0 is_shrink=n
228 0.004 8.2 3.66615 B m e v  arsize_top=0 arsize_bot=0 is_shrink=n
228 0.004 8.81665 4.78292 B m e v  arsize_top=0 arsize_bot=0 is_shrink=n
229 0 8.84846 4.85788 T 0.01378 0.05118 e e staggered 0 0 0  is_shrink=n
229 0.0126 8.175 3.69115 T e e  arsize_top=0 arsize_bot=0 is_shrink=n
229 0.004 8.2 3.71615 B m e v  arsize_top=0 arsize_bot=0 is_shrink=n
229 0.004 8.85665 4.78292 B m e v  arsize_top=0 arsize_bot=0 is_shrink=n
230 0 8.96657 4.85788 T 0.01378 0.05118 e e staggered 0 0 0  is_shrink=n
230 0.0126 8.025 3.74115 T e e  arsize_top=0 arsize_bot=0 is_shrink=n
230 0.004 8.05 3.76615 B m e v  arsize_top=0 arsize_bot=0 is_shrink=n
230 0.004 8.89062 4.667 B m e v  arsize_top=0 arsize_bot=0 is_shrink=n
231 0 8.9902 4.85788 T 0.01378 0.05118 e e staggered 0 0 0  is_shrink=n
231 0.0126 8.025 3.79115 T e e  arsize_top=0 arsize_bot=0 is_shrink=n
231 0.004 8.05 3.81615 B m e v  arsize_top=0 arsize_bot=0 is_shrink=n
231 0.004 8.93062 4.667 B m e v  arsize_top=0 arsize_bot=0 is_shrink=n
232 0 9.03744 4.85788 T 0.01378 0.05118 e e staggered 0 0 0  is_shrink=n
232 0.0126 8.175 3.79115 T e e  arsize_top=0 arsize_bot=0 is_shrink=n
232 0.004 8.2 3.81615 B m e v  arsize_top=0 arsize_bot=0 is_shrink=n
232 0.004 9.02925 4.667 B m e v  arsize_top=0 arsize_bot=0 is_shrink=n
233 0 9.06106 4.85788 T 0.01378 0.05118 e e staggered 0 0 0  is_shrink=n
233 0.0126 8.175 3.84115 T e e  arsize_top=0 arsize_bot=0 is_shrink=n
233 0.004 8.2 3.86615 B m e v  arsize_top=0 arsize_bot=0 is_shrink=n
233 0.004 9.06925 4.667 B m e v  arsize_top=0 arsize_bot=0 is_shrink=n
234 0 9.10831 4.85788 T 0.01378 0.05118 e e staggered 0 0 0  is_shrink=n
234 0 7.1926 5.12551 T 0.02 0.02 e e staggered 0 0 0  is_shrink=n
234 0 9.16354 4.508 D 0.02 0.02 e e staggered 0 0 0  is_shrink=n
234 0.005 7.1926 5.15351 B m e v  arsize_top=0 arsize_bot=0 is_shrink=n
234 0.005 9.07354 4.42 B m e v  arsize_top=0 arsize_bot=0 is_shrink=n
235 0 9.13193 4.85788 T 0.01378 0.05118 e e staggered 0 0 0  is_shrink=n
235 0 7.3426 5.12551 T 0.02 0.02 e e staggered 0 0 0  is_shrink=n
235 0 9.11354 4.508 D 0.02 0.02 e e staggered 0 0 0  is_shrink=n
235 0.005 7.3426 5.15351 B m e v  arsize_top=0 arsize_bot=0 is_shrink=n
235 0.005 9.10854 4.47 B m e v  arsize_top=0 arsize_bot=0 is_shrink=n
236 0 9.17917 4.85788 T 0.01378 0.05118 e e staggered 0 0 0  is_shrink=n
236 0.0126 8.425 3.84115 T e e  arsize_top=0 arsize_bot=0 is_shrink=n
236 0.004 8.45 3.86615 B m e v  arsize_top=0 arsize_bot=0 is_shrink=n
236 0.004 9.17098 4.78292 B m e v  arsize_top=0 arsize_bot=0 is_shrink=n
237 0 9.20279 4.85788 T 0.01378 0.05118 e e staggered 0 0 0  is_shrink=n
237 0.0126 8.425 3.79115 T e e  arsize_top=0 arsize_bot=0 is_shrink=n
237 0.004 8.45 3.81615 B m e v  arsize_top=0 arsize_bot=0 is_shrink=n
237 0.004 9.21098 4.78292 B m e v  arsize_top=0 arsize_bot=0 is_shrink=n
238 0 9.25004 4.85788 T 0.01378 0.05118 e e staggered 0 0 0  is_shrink=n
238 0.0126 8.375 3.79115 T e e  arsize_top=0 arsize_bot=0 is_shrink=n
238 0.004 8.4 3.81615 B m e v  arsize_top=0 arsize_bot=0 is_shrink=n
238 0.004 9.24185 4.642 B m e v  arsize_top=0 arsize_bot=0 is_shrink=n
239 0 9.27366 4.85788 T 0.01378 0.05118 e e staggered 0 0 0  is_shrink=n
239 0.0126 8.375 3.74115 T e e  arsize_top=0 arsize_bot=0 is_shrink=n
239 0.004 8.4 3.76615 B m e v  arsize_top=0 arsize_bot=0 is_shrink=n
239 0.004 9.28185 4.642 B m e v  arsize_top=0 arsize_bot=0 is_shrink=n
240 0 9.39177 4.85788 T 0.01378 0.05118 e e staggered 0 0 0  is_shrink=n
240 0.0126 8.425 3.69115 T e e  arsize_top=0 arsize_bot=0 is_shrink=n
240 0.004 8.45 3.71615 B m e v  arsize_top=0 arsize_bot=0 is_shrink=n
240 0.004 9.38358 4.78292 B m e v  arsize_top=0 arsize_bot=0 is_shrink=n
241 0 9.41539 4.85788 T 0.01378 0.05118 e e staggered 0 0 0  is_shrink=n
241 0.0126 8.425 3.64115 T e e  arsize_top=0 arsize_bot=0 is_shrink=n
241 0.004 8.45 3.66615 B m e v  arsize_top=0 arsize_bot=0 is_shrink=n
241 0.004 9.42358 4.78292 B m e v  arsize_top=0 arsize_bot=0 is_shrink=n
242 0 9.46264 4.85788 T 0.01378 0.05118 e e staggered 0 0 0  is_shrink=n
242 0.0126 8.375 3.64115 T e e  arsize_top=0 arsize_bot=0 is_shrink=n
242 0.004 8.4 3.66615 B m e v  arsize_top=0 arsize_bot=0 is_shrink=n
242 0.004 9.45445 4.587 B m e v  arsize_top=0 arsize_bot=0 is_shrink=n
243 0 9.48626 4.85788 T 0.01378 0.05118 e e staggered 0 0 0  is_shrink=n
243 0.0126 8.375 3.59115 T e e  arsize_top=0 arsize_bot=0 is_shrink=n
243 0.004 8.4 3.61615 B m e v  arsize_top=0 arsize_bot=0 is_shrink=n
243 0.004 9.49445 4.587 B m e v  arsize_top=0 arsize_bot=0 is_shrink=n
244 0 9.5335 4.85788 T 0.01378 0.05118 e e staggered 0 0 0  is_shrink=n
244 0.0126 8.325 3.69115 T e e  arsize_top=0 arsize_bot=0 is_shrink=n
244 0.004 8.35 3.71615 B m e v  arsize_top=0 arsize_bot=0 is_shrink=n
244 0.004 9.52531 4.71973 B m e v  arsize_top=0 arsize_bot=0 is_shrink=n
245 0 9.55712 4.85788 T 0.01378 0.05118 e e staggered 0 0 0  is_shrink=n
245 0.0126 8.325 3.64115 T e e  arsize_top=0 arsize_bot=0 is_shrink=n
245 0.004 8.35 3.66615 B m e v  arsize_top=0 arsize_bot=0 is_shrink=n
245 0.004 9.56531 4.71973 B m e v  arsize_top=0 arsize_bot=0 is_shrink=n
246 0 8.75398 4.97914 T 0.01378 0.05118 e e staggered 0 0 0  is_shrink=n
246 0.0126 8.025 3.59115 T e e  arsize_top=0 arsize_bot=0 is_shrink=n
246 0.004 8.05 3.61615 B m e v  arsize_top=0 arsize_bot=0 is_shrink=n
246 0.004 8.74579 5.14 B m e v  arsize_top=0 arsize_bot=0 is_shrink=n
247 0 8.7776 4.97914 T 0.01378 0.05118 e e staggered 0 0 0  is_shrink=n
247 0.0126 8.025 3.64115 T e e  arsize_top=0 arsize_bot=0 is_shrink=n
247 0.004 8.05 3.66615 B m e v  arsize_top=0 arsize_bot=0 is_shrink=n
247 0.004 8.78579 5.14 B m e v  arsize_top=0 arsize_bot=0 is_shrink=n
248 0 8.82484 4.97914 T 0.01378 0.05118 e e staggered 0 0 0  is_shrink=n
248 0.0126 8.125 3.59115 T e e  arsize_top=0 arsize_bot=0 is_shrink=n
248 0.004 8.15 3.61615 B m e v  arsize_top=0 arsize_bot=0 is_shrink=n
248 0.004 8.88441 5.17002 B m e v  arsize_top=0 arsize_bot=0 is_shrink=n
249 0 8.84846 4.97914 T 0.01378 0.05118 e e staggered 0 0 0  is_shrink=n
249 0.0126 8.125 3.64115 T e e  arsize_top=0 arsize_bot=0 is_shrink=n
249 0.004 8.15 3.66615 B m e v  arsize_top=0 arsize_bot=0 is_shrink=n
249 0.004 8.92441 5.17002 B m e v  arsize_top=0 arsize_bot=0 is_shrink=n
250 0 9.03744 4.97914 T 0.01378 0.05118 e e staggered 0 0 0  is_shrink=n
250 0.0126 8.125 3.74115 T e e  arsize_top=0 arsize_bot=0 is_shrink=n
250 0.004 8.15 3.76615 B m e v  arsize_top=0 arsize_bot=0 is_shrink=n
250 0.004 9.02925 5.165 B m e v  arsize_top=0 arsize_bot=0 is_shrink=n
251 0 9.06106 4.97914 T 0.01378 0.05118 e e staggered 0 0 0  is_shrink=n
251 0.0126 8.125 3.79115 T e e  arsize_top=0 arsize_bot=0 is_shrink=n
251 0.004 8.15 3.81615 B m e v  arsize_top=0 arsize_bot=0 is_shrink=n
251 0.004 9.06925 5.165 B m e v  arsize_top=0 arsize_bot=0 is_shrink=n
252 0 9.10831 4.97914 T 0.01378 0.05118 e e staggered 0 0 0  is_shrink=n
252 0.0126 8.075 3.79115 T e e  arsize_top=0 arsize_bot=0 is_shrink=n
252 0.004 8.1 3.81615 B m e v  arsize_top=0 arsize_bot=0 is_shrink=n
252 0.004 9.10011 5.0535 B m e v  arsize_top=0 arsize_bot=0 is_shrink=n
253 0 9.13193 4.97914 T 0.01378 0.05118 e e staggered 0 0 0  is_shrink=n
253 0.0126 8.075 3.84115 T e e  arsize_top=0 arsize_bot=0 is_shrink=n
253 0.004 8.1 3.86615 B m e v  arsize_top=0 arsize_bot=0 is_shrink=n
253 0.004 9.14011 5.0535 B m e v  arsize_top=0 arsize_bot=0 is_shrink=n
254 0 9.17917 4.97914 T 0.01378 0.05118 e e staggered 0 0 0  is_shrink=n
254 0 9.1 5.298 D 0.02 0.02 e e staggered 0 0 0  is_shrink=n
254 0 9.145 5.298 D 0.02 0.02 e e staggered 0 0 0  is_shrink=n
254 0.005 9.11854 5.255 B m e v  arsize_top=0 arsize_bot=0 is_shrink=n
255 0 9.20279 4.97914 T 0.01378 0.05118 e e staggered 0 0 0  is_shrink=n
255 0 9.235 5.298 D 0.02 0.02 e e staggered 0 0 0  is_shrink=n
255 0 9.19 5.298 D 0.02 0.02 e e staggered 0 0 0  is_shrink=n
255 0.005 9.175 5.255 B m e v  arsize_top=0 arsize_bot=0 is_shrink=n
256 0 9.25004 4.97914 T 0.01378 0.05118 e e staggered 0 0 0  is_shrink=n
256 0.0126 8.325 3.84115 T e e  arsize_top=0 arsize_bot=0 is_shrink=n
256 0.004 8.35 3.86615 B m e v  arsize_top=0 arsize_bot=0 is_shrink=n
256 0.004 9.24185 5.22002 B m e v  arsize_top=0 arsize_bot=0 is_shrink=n
257 0 9.27366 4.97914 T 0.01378 0.05118 e e staggered 0 0 0  is_shrink=n
257 0.0126 8.325 3.79115 T e e  arsize_top=0 arsize_bot=0 is_shrink=n
257 0.004 8.35 3.81615 B m e v  arsize_top=0 arsize_bot=0 is_shrink=n
257 0.004 9.28185 5.22002 B m e v  arsize_top=0 arsize_bot=0 is_shrink=n
258 0 9.3209 4.97914 T 0.01378 0.05118 e e staggered 0 0 0  is_shrink=n
258 0.0126 8.475 3.79115 T e e  arsize_top=0 arsize_bot=0 is_shrink=n
258 0.004 8.5 3.81615 B m e v  arsize_top=0 arsize_bot=0 is_shrink=n
258 0.004 9.31271 5.1035 B m e v  arsize_top=0 arsize_bot=0 is_shrink=n
259 0 9.34453 4.97914 T 0.01378 0.05118 e e staggered 0 0 0  is_shrink=n
259 0.0126 8.475 3.74115 T e e  arsize_top=0 arsize_bot=0 is_shrink=n
259 0.004 8.5 3.76615 B m e v  arsize_top=0 arsize_bot=0 is_shrink=n
259 0.004 9.35271 5.1035 B m e v  arsize_top=0 arsize_bot=0 is_shrink=n
260 0 9.39177 4.97914 T 0.01378 0.05118 e e staggered 0 0 0  is_shrink=n
260 0 8.67479 2.87 D 0.02 0.02 e e staggered 0 0 0  is_shrink=n
260 0.004 9.38358 5.22002 B m e v  arsize_top=0 arsize_bot=0 is_shrink=n
260 0.004 8.98115 2.865 B m e v  arsize_top=0 arsize_bot=0 is_shrink=n
261 0 9.41539 4.97914 T 0.01378 0.05118 e e staggered 0 0 0  is_shrink=n
261 0 8.67479 2.82 D 0.02 0.02 e e staggered 0 0 0  is_shrink=n
261 0.004 9.42358 5.22002 B m e v  arsize_top=0 arsize_bot=0 is_shrink=n
261 0.004 8.98115 2.825 B m e v  arsize_top=0 arsize_bot=0 is_shrink=n
262 0 9.46264 4.97914 T 0.01378 0.05118 e e staggered 0 0 0  is_shrink=n
262 0 9.385 5.298 D 0.02 0.02 e e staggered 0 0 0  is_shrink=n
262 0 9.34 5.298 D 0.02 0.02 e e staggered 0 0 0  is_shrink=n
262 0.005 9.46 5.3 B m e v  arsize_top=0 arsize_bot=0 is_shrink=n
263 0 9.5335 4.97914 T 0.01378 0.05118 e e staggered 0 0 0  is_shrink=n
263 0.0126 8.475 3.64115 T e e  arsize_top=0 arsize_bot=0 is_shrink=n
263 0.004 8.5 3.66615 B m e v  arsize_top=0 arsize_bot=0 is_shrink=n
263 0.004 9.52531 5.14 B m e v  arsize_top=0 arsize_bot=0 is_shrink=n
264 0 9.55712 4.97914 T 0.01378 0.05118 e e staggered 0 0 0  is_shrink=n
264 0.0126 8.475 3.59115 T e e  arsize_top=0 arsize_bot=0 is_shrink=n
264 0.004 8.5 3.61615 B m e v  arsize_top=0 arsize_bot=0 is_shrink=n
264 0.004 9.56531 5.14 B m e v  arsize_top=0 arsize_bot=0 is_shrink=n
265 0 7.58938 4.85788 T 0.01378 0.05118 e e staggered 0 0 0  is_shrink=n
265 0.0126 8.075 3.24115 T e e  arsize_top=0 arsize_bot=0 is_shrink=n
265 0.004 7.58119 4.707 B m e v  arsize_top=0 arsize_bot=0 is_shrink=n
265 0.004 8.1 3.26615 B m e v  arsize_top=0 arsize_bot=0 is_shrink=n
266 0 7.613 4.85788 T 0.01378 0.05118 e e staggered 0 0 0  is_shrink=n
266 0.0126 8.075 3.29115 T e e  arsize_top=0 arsize_bot=0 is_shrink=n
266 0.004 7.62119 4.707 B m e v  arsize_top=0 arsize_bot=0 is_shrink=n
266 0.004 8.1 3.31615 B m e v  arsize_top=0 arsize_bot=0 is_shrink=n
267 0 7.66024 4.85788 T 0.01378 0.05118 e e staggered 0 0 0  is_shrink=n
267 0.0126 8.125 3.29115 T e e  arsize_top=0 arsize_bot=0 is_shrink=n
267 0.004 7.65205 4.78292 B m e v  arsize_top=0 arsize_bot=0 is_shrink=n
267 0.004 8.15 3.31615 B m e v  arsize_top=0 arsize_bot=0 is_shrink=n
268 0 7.68386 4.85788 T 0.01378 0.05118 e e staggered 0 0 0  is_shrink=n
268 0.0126 8.125 3.34115 T e e  arsize_top=0 arsize_bot=0 is_shrink=n
268 0.004 7.69205 4.78292 B m e v  arsize_top=0 arsize_bot=0 is_shrink=n
268 0.004 8.15 3.36615 B m e v  arsize_top=0 arsize_bot=0 is_shrink=n
269 0 7.80197 4.85788 T 0.01378 0.05118 e e staggered 0 0 0  is_shrink=n
269 0.0126 8.075 3.39115 T e e  arsize_top=0 arsize_bot=0 is_shrink=n
269 0.004 7.79379 4.78292 B m e v  arsize_top=0 arsize_bot=0 is_shrink=n
269 0.004 8.1 3.41615 B m e v  arsize_top=0 arsize_bot=0 is_shrink=n
270 0 7.8256 4.85788 T 0.01378 0.05118 e e staggered 0 0 0  is_shrink=n
270 0.0126 8.075 3.44115 T e e  arsize_top=0 arsize_bot=0 is_shrink=n
270 0.004 7.83379 4.78292 B m e v  arsize_top=0 arsize_bot=0 is_shrink=n
270 0.004 8.1 3.46615 B m e v  arsize_top=0 arsize_bot=0 is_shrink=n
271 0 7.87284 4.85788 T 0.01378 0.05118 e e staggered 0 0 0  is_shrink=n
271 0.0126 8.125 3.44115 T e e  arsize_top=0 arsize_bot=0 is_shrink=n
271 0.004 7.86465 4.657 B m e v  arsize_top=0 arsize_bot=0 is_shrink=n
271 0.004 8.15 3.46615 B m e v  arsize_top=0 arsize_bot=0 is_shrink=n
272 0 7.89646 4.85788 T 0.01378 0.05118 e e staggered 0 0 0  is_shrink=n
272 0.0126 8.125 3.49115 T e e  arsize_top=0 arsize_bot=0 is_shrink=n
272 0.004 7.90465 4.657 B m e v  arsize_top=0 arsize_bot=0 is_shrink=n
272 0.004 8.15 3.51615 B m e v  arsize_top=0 arsize_bot=0 is_shrink=n
273 0 7.94371 4.85788 T 0.01378 0.05118 e e staggered 0 0 0  is_shrink=n
273 0 9.16354 4.542 D 0.02 0.02 e e staggered 0 0 0  is_shrink=n
273 0 7.88354 4.528 D 0.02 0.02 e e staggered 0 0 0  is_shrink=n
273 0.005 7.835 4.45 B m e v  arsize_top=0 arsize_bot=0 is_shrink=n
274 0 7.96733 4.85788 T 0.01378 0.05118 e e staggered 0 0 0  is_shrink=n
274 0 9.11354 4.542 D 0.02 0.02 e e staggered 0 0 0  is_shrink=n
274 0 7.82854 4.528 D 0.02 0.02 e e staggered 0 0 0  is_shrink=n
274 0.005 7.785 4.45 B m e v  arsize_top=0 arsize_bot=0 is_shrink=n
275 0 8.01457 4.85788 T 0.01378 0.05118 e e staggered 0 0 0  is_shrink=n
275 0.0126 8.475 3.49115 T e e  arsize_top=0 arsize_bot=0 is_shrink=n
275 0.004 8.03207 4.66689 B m e v  arsize_top=0 arsize_bot=0 is_shrink=n
275 0.004 8.5 3.51615 B m e v  arsize_top=0 arsize_bot=0 is_shrink=n
276 0 8.03819 4.85788 T 0.01378 0.05118 e e staggered 0 0 0  is_shrink=n
276 0.0126 8.475 3.44115 T e e  arsize_top=0 arsize_bot=0 is_shrink=n
276 0.004 8.07207 4.66689 B m e v  arsize_top=0 arsize_bot=0 is_shrink=n
276 0.004 8.5 3.46615 B m e v  arsize_top=0 arsize_bot=0 is_shrink=n
277 0 8.08544 4.85788 T 0.01378 0.05118 e e staggered 0 0 0  is_shrink=n
277 0.0126 8.325 3.44115 T e e  arsize_top=0 arsize_bot=0 is_shrink=n
277 0.004 8.07725 4.78292 B m e v  arsize_top=0 arsize_bot=0 is_shrink=n
277 0.004 8.35 3.46615 B m e v  arsize_top=0 arsize_bot=0 is_shrink=n
278 0 8.10906 4.85788 T 0.01378 0.05118 e e staggered 0 0 0  is_shrink=n
278 0.0126 8.325 3.39115 T e e  arsize_top=0 arsize_bot=0 is_shrink=n
278 0.004 8.11725 4.78292 B m e v  arsize_top=0 arsize_bot=0 is_shrink=n
278 0.004 8.35 3.41615 B m e v  arsize_top=0 arsize_bot=0 is_shrink=n
279 0 8.22717 4.85788 T 0.01378 0.05118 e e staggered 0 0 0  is_shrink=n
279 0.0126 8.475 3.34115 T e e  arsize_top=0 arsize_bot=0 is_shrink=n
279 0.004 8.21898 4.78292 B m e v  arsize_top=0 arsize_bot=0 is_shrink=n
279 0.004 8.5 3.36615 B m e v  arsize_top=0 arsize_bot=0 is_shrink=n
280 0 8.25079 4.85788 T 0.01378 0.05118 e e staggered 0 0 0  is_shrink=n
280 0.0126 8.475 3.29115 T e e  arsize_top=0 arsize_bot=0 is_shrink=n
280 0.004 8.25898 4.78292 B m e v  arsize_top=0 arsize_bot=0 is_shrink=n
280 0.004 8.5 3.31615 B m e v  arsize_top=0 arsize_bot=0 is_shrink=n
281 0 8.29804 4.85788 T 0.01378 0.05118 e e staggered 0 0 0  is_shrink=n
281 0.0126 8.375 3.34115 T e e  arsize_top=0 arsize_bot=0 is_shrink=n
281 0.004 8.22209 4.667 B m e v  arsize_top=0 arsize_bot=0 is_shrink=n
281 0.004 8.4 3.36615 B m e v  arsize_top=0 arsize_bot=0 is_shrink=n
282 0 8.32166 4.85788 T 0.01378 0.05118 e e staggered 0 0 0  is_shrink=n
282 0.0126 8.375 3.29115 T e e  arsize_top=0 arsize_bot=0 is_shrink=n
282 0.004 8.26209 4.667 B m e v  arsize_top=0 arsize_bot=0 is_shrink=n
282 0.004 8.4 3.31615 B m e v  arsize_top=0 arsize_bot=0 is_shrink=n
283 0 8.3689 4.85788 T 0.01378 0.05118 e e staggered 0 0 0  is_shrink=n
283 0.0126 8.325 3.29115 T e e  arsize_top=0 arsize_bot=0 is_shrink=n
283 0.004 8.35 3.31615 B m e v  arsize_top=0 arsize_bot=0 is_shrink=n
283 0.004 8.36071 4.742 B m e v  arsize_top=0 arsize_bot=0 is_shrink=n
284 0 8.39252 4.85788 T 0.01378 0.05118 e e staggered 0 0 0  is_shrink=n
284 0.0126 8.325 3.24115 T e e  arsize_top=0 arsize_bot=0 is_shrink=n
284 0.004 8.35 3.26615 B m e v  arsize_top=0 arsize_bot=0 is_shrink=n
284 0.004 8.40071 4.742 B m e v  arsize_top=0 arsize_bot=0 is_shrink=n
285 0 7.58938 4.97914 T 0.01378 0.05118 e e staggered 0 0 0  is_shrink=n
285 0.0126 8.025 3.29115 T e e  arsize_top=0 arsize_bot=0 is_shrink=n
285 0.004 7.58119 5.169 B m e v  arsize_top=0 arsize_bot=0 is_shrink=n
285 0.004 8.05 3.31615 B m e v  arsize_top=0 arsize_bot=0 is_shrink=n
286 0 7.613 4.97914 T 0.01378 0.05118 e e staggered 0 0 0  is_shrink=n
286 0.0126 8.025 3.34115 T e e  arsize_top=0 arsize_bot=0 is_shrink=n
286 0.004 7.62119 5.169 B m e v  arsize_top=0 arsize_bot=0 is_shrink=n
286 0.004 8.05 3.36615 B m e v  arsize_top=0 arsize_bot=0 is_shrink=n
287 0 7.66024 4.97914 T 0.01378 0.05118 e e staggered 0 0 0  is_shrink=n
287 0.0126 8.175 3.24115 T e e  arsize_top=0 arsize_bot=0 is_shrink=n
287 0.004 7.65204 5.0535 B m e v  arsize_top=0 arsize_bot=0 is_shrink=n
287 0.004 8.2 3.26615 B m e v  arsize_top=0 arsize_bot=0 is_shrink=n
288 0 7.68386 4.97914 T 0.01378 0.05118 e e staggered 0 0 0  is_shrink=n
288 0.0126 8.175 3.29115 T e e  arsize_top=0 arsize_bot=0 is_shrink=n
288 0.004 7.69204 5.0535 B m e v  arsize_top=0 arsize_bot=0 is_shrink=n
288 0.004 8.2 3.31615 B m e v  arsize_top=0 arsize_bot=0 is_shrink=n
289 0 7.87284 4.97914 T 0.01378 0.05118 e e staggered 0 0 0  is_shrink=n
289 0.0126 8.175 3.39115 T e e  arsize_top=0 arsize_bot=0 is_shrink=n
289 0.004 7.86465 5.169 B m e v  arsize_top=0 arsize_bot=0 is_shrink=n
289 0.004 8.2 3.41615 B m e v  arsize_top=0 arsize_bot=0 is_shrink=n
290 0 7.89646 4.97914 T 0.01378 0.05118 e e staggered 0 0 0  is_shrink=n
290 0.0126 8.175 3.44115 T e e  arsize_top=0 arsize_bot=0 is_shrink=n
290 0.004 7.90465 5.169 B m e v  arsize_top=0 arsize_bot=0 is_shrink=n
290 0.004 8.2 3.46615 B m e v  arsize_top=0 arsize_bot=0 is_shrink=n
291 0 7.94371 4.97914 T 0.01378 0.05118 e e staggered 0 0 0  is_shrink=n
291 0.0126 8.025 3.44115 T e e  arsize_top=0 arsize_bot=0 is_shrink=n
291 0.004 7.93551 5.0535 B m e v  arsize_top=0 arsize_bot=0 is_shrink=n
291 0.004 8 3.46615 B m e v  arsize_top=0 arsize_bot=0 is_shrink=n
292 0 7.96733 4.97914 T 0.01378 0.05118 e e staggered 0 0 0  is_shrink=n
292 0.0126 8.025 3.49115 T e e  arsize_top=0 arsize_bot=0 is_shrink=n
292 0.004 7.97551 5.0535 B m e v  arsize_top=0 arsize_bot=0 is_shrink=n
292 0.004 8 3.51615 B m e v  arsize_top=0 arsize_bot=0 is_shrink=n
293 0 8.01457 4.97914 T 0.01378 0.05118 e e staggered 0 0 0  is_shrink=n
293 0 8.005 5.343 D 0.02 0.02 e e staggered 0 0 0  is_shrink=n
293 0 7.955 5.343 D 0.02 0.02 e e staggered 0 0 0  is_shrink=n
293 0.005 8.005 5.29 B m e v  arsize_top=0 arsize_bot=0 is_shrink=n
294 0 8.03819 4.97914 T 0.01378 0.05118 e e staggered 0 0 0  is_shrink=n
294 0 8.12 5.343 D 0.02 0.02 e e staggered 0 0 0  is_shrink=n
294 0 8.07 5.343 D 0.02 0.02 e e staggered 0 0 0  is_shrink=n
294 0.005 8.07 5.29 B m e v  arsize_top=0 arsize_bot=0 is_shrink=n
295 0 8.08544 4.97914 T 0.01378 0.05118 e e staggered 0 0 0  is_shrink=n
295 0.0126 8.375 3.49115 T e e  arsize_top=0 arsize_bot=0 is_shrink=n
295 0.004 8.07725 5.169 B m e v  arsize_top=0 arsize_bot=0 is_shrink=n
295 0.004 8.4 3.51615 B m e v  arsize_top=0 arsize_bot=0 is_shrink=n
296 0 8.10906 4.97914 T 0.01378 0.05118 e e staggered 0 0 0  is_shrink=n
296 0.0126 8.375 3.44115 T e e  arsize_top=0 arsize_bot=0 is_shrink=n
296 0.004 8.11725 5.169 B m e v  arsize_top=0 arsize_bot=0 is_shrink=n
296 0.004 8.4 3.46615 B m e v  arsize_top=0 arsize_bot=0 is_shrink=n
297 0 8.1563 4.97914 T 0.01378 0.05118 e e staggered 0 0 0  is_shrink=n
297 0.0126 8.425 3.44115 T e e  arsize_top=0 arsize_bot=0 is_shrink=n
297 0.004 8.14811 5.0535 B m e v  arsize_top=0 arsize_bot=0 is_shrink=n
297 0.004 8.45 3.46615 B m e v  arsize_top=0 arsize_bot=0 is_shrink=n
298 0 8.17993 4.97914 T 0.01378 0.05118 e e staggered 0 0 0  is_shrink=n
298 0.0126 8.425 3.39115 T e e  arsize_top=0 arsize_bot=0 is_shrink=n
298 0.004 8.18811 5.0535 B m e v  arsize_top=0 arsize_bot=0 is_shrink=n
298 0.004 8.45 3.41615 B m e v  arsize_top=0 arsize_bot=0 is_shrink=n
299 0 8.3689 4.97914 T 0.01378 0.05118 e e staggered 0 0 0  is_shrink=n
299 0.0126 8.425 3.29115 T e e  arsize_top=0 arsize_bot=0 is_shrink=n
299 0.004 8.36071 5.115 B m e v  arsize_top=0 arsize_bot=0 is_shrink=n
299 0.004 8.45 3.31615 B m e v  arsize_top=0 arsize_bot=0 is_shrink=n
300 0 8.39252 4.97914 T 0.01378 0.05118 e e staggered 0 0 0  is_shrink=n
300 0.0126 8.425 3.24115 T e e  arsize_top=0 arsize_bot=0 is_shrink=n
300 0.004 8.40071 5.115 B m e v  arsize_top=0 arsize_bot=0 is_shrink=n
300 0.004 8.45 3.26615 B m e v  arsize_top=0 arsize_bot=0 is_shrink=n
301 0.0126 2.07106 3.54115 T e e  arsize_top=0 arsize_bot=0 is_shrink=n
301 0 1.857 3.61 D 0.02 0.02 e e staggered 0 0 0  is_shrink=n
301 0.015 1.9 3.61 D m e v t  arsize_top=0 arsize_bot=0 is_shrink=n
301 0.004 2.09606 3.56615 B m e v  arsize_top=0 arsize_bot=0 is_shrink=n
302 0.0126 2.12106 2.49115 T e e  arsize_top=0 arsize_bot=0 is_shrink=n
302 0 1.85421 2.4781 D 0.02 0.02 e e staggered 0 0 0  is_shrink=n
302 0.015 1.9 2.48 D m e v t  arsize_top=0 arsize_bot=0 is_shrink=n
302 0.004 2.14606 2.51615 B m e v  arsize_top=0 arsize_bot=0 is_shrink=n
303 0.0126 2.22106 2.84115 T e e  arsize_top=0 arsize_bot=0 is_shrink=n
303 0 2.63685 2.82 D 0.02 0.02 e e staggered 0 0 0  is_shrink=n
303 0.004 2.24606 2.86615 B m e v  arsize_top=0 arsize_bot=0 is_shrink=n
304 0.0126 2.22106 3.54115 T e e  arsize_top=0 arsize_bot=0 is_shrink=n
304 0 1.857 3.56 D 0.02 0.02 e e staggered 0 0 0  is_shrink=n
304 0.015 1.9 3.56 D m e v t  arsize_top=0 arsize_bot=0 is_shrink=n
304 0.004 2.24606 3.56615 B m e v  arsize_top=0 arsize_bot=0 is_shrink=n
305 0.0126 2.27106 2.84115 T e e  arsize_top=0 arsize_bot=0 is_shrink=n
305 0 2.63685 2.87 D 0.02 0.02 e e staggered 0 0 0  is_shrink=n
305 0.004 2.29606 2.86615 B m e v  arsize_top=0 arsize_bot=0 is_shrink=n
306 0.0126 2.27106 3.54115 T e e  arsize_top=0 arsize_bot=0 is_shrink=n
306 0 1.857 3.51 D 0.02 0.02 e e staggered 0 0 0  is_shrink=n
306 0.015 1.9 3.51 D m e v t  arsize_top=0 arsize_bot=0 is_shrink=n
306 0.004 2.29606 3.56615 B m e v  arsize_top=0 arsize_bot=0 is_shrink=n
307 0.0126 8.075 3.54115 T e e  arsize_top=0 arsize_bot=0 is_shrink=n
307 0 7.86094 3.61 D 0.02 0.02 e e staggered 0 0 0  is_shrink=n
307 0.015 7.90394 3.61 D m e v t  arsize_top=0 arsize_bot=0 is_shrink=n
307 0.004 8.1 3.56615 B m e v  arsize_top=0 arsize_bot=0 is_shrink=n
308 0.0126 8.125 2.49115 T e e  arsize_top=0 arsize_bot=0 is_shrink=n
308 0 7.85815 2.4781 D 0.02 0.02 e e staggered 0 0 0  is_shrink=n
308 0.015 7.90394 2.48 D m e v t  arsize_top=0 arsize_bot=0 is_shrink=n
308 0.004 8.15 2.51615 B m e v  arsize_top=0 arsize_bot=0 is_shrink=n
309 0.0126 8.225 2.84115 T e e  arsize_top=0 arsize_bot=0 is_shrink=n
309 0 8.64079 2.82 D 0.02 0.02 e e staggered 0 0 0  is_shrink=n
309 0.004 8.25 2.86615 B m e v  arsize_top=0 arsize_bot=0 is_shrink=n
310 0.0126 8.225 3.54115 T e e  arsize_top=0 arsize_bot=0 is_shrink=n
310 0 7.86094 3.56 D 0.02 0.02 e e staggered 0 0 0  is_shrink=n
310 0.015 7.90394 3.56 D m e v t  arsize_top=0 arsize_bot=0 is_shrink=n
310 0.004 8.25 3.56615 B m e v  arsize_top=0 arsize_bot=0 is_shrink=n
311 0.0126 8.275 2.84115 T e e  arsize_top=0 arsize_bot=0 is_shrink=n
311 0 8.64079 2.87 D 0.02 0.02 e e staggered 0 0 0  is_shrink=n
311 0.004 8.3 2.86615 B m e v  arsize_top=0 arsize_bot=0 is_shrink=n
312 0.0126 8.275 3.54115 T e e  arsize_top=0 arsize_bot=0 is_shrink=n
312 0 7.86094 3.51 D 0.02 0.02 e e staggered 0 0 0  is_shrink=n
312 0.015 7.90394 3.51 D m e v t  arsize_top=0 arsize_bot=0 is_shrink=n
312 0.004 8.3 3.56615 B m e v  arsize_top=0 arsize_bot=0 is_shrink=n
313 0.01378 0.17323 1.33465 B e e  arsize_top=0 arsize_bot=0 is_shrink=n
313 0 0.58299 1.3381 D 0.02 0.02 e e staggered 0 0 0  is_shrink=n
314 0.01378 0.17323 1.72835 B e e  arsize_top=0 arsize_bot=0 is_shrink=n
314 0 0.58298 1.655 D 0.02 0.02 e e staggered 0 0 0  is_shrink=n
315 0.01378 0.17323 1.88583 B e e  arsize_top=0 arsize_bot=0 is_shrink=n
315 0 0.58299 1.86182 D 0.02 0.02 e e staggered 0 0 0  is_shrink=n
316 0.01378 0.09449 1.9252 B e e  arsize_top=0 arsize_bot=0 is_shrink=n
316 0 0.58299 1.91182 D 0.02 0.02 e e staggered 0 0 0  is_shrink=n
317 0.01378 0.17323 2.12205 B e e  arsize_top=0 arsize_bot=0 is_shrink=n
318 0.01378 0.09449 3.34252 B e e  arsize_top=0 arsize_bot=0 is_shrink=n
319 0.01378 0.27165 1.72835 B e e  arsize_top=0 arsize_bot=0 is_shrink=n
320 0.01378 0.35039 1.84646 B e e  arsize_top=0 arsize_bot=0 is_shrink=n
321 0.01378 0.35039 1.9252 B e e  arsize_top=0 arsize_bot=0 is_shrink=n
321 0.0126 4.75768 1.94115 T e e  arsize_top=0 arsize_bot=0 is_shrink=n
321 0.004 4.73268 1.91615 B m e v  arsize_top=0 arsize_bot=0 is_shrink=n
322 0.01378 0.27165 1.96457 B e e  arsize_top=0 arsize_bot=0 is_shrink=n
322 0.0126 4.75768 1.89115 T e e  arsize_top=0 arsize_bot=0 is_shrink=n
322 0.004 4.73268 1.86615 B m e v  arsize_top=0 arsize_bot=0 is_shrink=n
323 0.01378 0.27165 2.04331 B e e  arsize_top=0 arsize_bot=0 is_shrink=n
323 0.01378 0.27165 2.59449 B e e  arsize_top=0 arsize_bot=0 is_shrink=n
323 0.01378 0.35039 3.26378 B e e  arsize_top=0 arsize_bot=0 is_shrink=n
323 0.01378 0.27165 4.563 B e e  arsize_top=0 arsize_bot=0 is_shrink=n
323 0 0.61699 1.3381 D 0.02 0.02 e e staggered 0 0 0  is_shrink=n
323 0 0.58298 2.045 D 0.02 0.02 e e staggered 0 0 0  is_shrink=n
324 0.01378 0.27165 2.12205 B e e  arsize_top=0 arsize_bot=0 is_shrink=n
324 0.0126 4.70768 1.99115 T e e  arsize_top=0 arsize_bot=0 is_shrink=n
324 0.004 4.68268 1.96615 B m e v  arsize_top=0 arsize_bot=0 is_shrink=n
325 0.01378 0.35039 2.16142 B e e  arsize_top=0 arsize_bot=0 is_shrink=n
325 0.0126 4.70768 1.94115 T e e  arsize_top=0 arsize_bot=0 is_shrink=n
325 0.004 4.68268 1.91615 B m e v  arsize_top=0 arsize_bot=0 is_shrink=n
326 0.01378 0.27165 2.27953 B e e  arsize_top=0 arsize_bot=0 is_shrink=n
326 0.0126 4.65768 1.94115 T e e  arsize_top=0 arsize_bot=0 is_shrink=n
326 0.004 4.63268 1.91615 B m e v  arsize_top=0 arsize_bot=0 is_shrink=n
327 0.01378 0.35039 2.3189 B e e  arsize_top=0 arsize_bot=0 is_shrink=n
327 0.0126 4.65768 1.89115 T e e  arsize_top=0 arsize_bot=0 is_shrink=n
327 0.004 4.63268 1.86615 B m e v  arsize_top=0 arsize_bot=0 is_shrink=n
328 0.01378 0.27165 2.43701 B e e  arsize_top=0 arsize_bot=0 is_shrink=n
328 0.0126 4.60768 1.99115 T e e  arsize_top=0 arsize_bot=0 is_shrink=n
328 0.004 4.58268 1.96615 B m e v  arsize_top=0 arsize_bot=0 is_shrink=n
329 0.01378 0.35039 2.47638 B e e  arsize_top=0 arsize_bot=0 is_shrink=n
329 0.0126 4.60768 1.94115 T e e  arsize_top=0 arsize_bot=0 is_shrink=n
329 0.004 4.58268 1.91615 B m e v  arsize_top=0 arsize_bot=0 is_shrink=n
330 0.01378 0.35039 2.55512 B e e  arsize_top=0 arsize_bot=0 is_shrink=n
331 0.01378 0.27165 2.67323 B e e  arsize_top=0 arsize_bot=0 is_shrink=n
331 0.0126 4.75768 2.09115 T e e  arsize_top=0 arsize_bot=0 is_shrink=n
331 0.004 4.73268 2.06615 B m e v  arsize_top=0 arsize_bot=0 is_shrink=n
332 0.01378 0.35039 2.7126 B e e  arsize_top=0 arsize_bot=0 is_shrink=n
332 0.0126 4.75768 2.04115 T e e  arsize_top=0 arsize_bot=0 is_shrink=n
332 0.004 4.73268 2.01615 B m e v  arsize_top=0 arsize_bot=0 is_shrink=n
333 0.01378 0.27165 2.83071 B e e  arsize_top=0 arsize_bot=0 is_shrink=n
333 0.0126 4.65768 2.09115 T e e  arsize_top=0 arsize_bot=0 is_shrink=n
333 0.004 4.63268 2.06615 B m e v  arsize_top=0 arsize_bot=0 is_shrink=n
334 0.01378 0.35039 2.87008 B e e  arsize_top=0 arsize_bot=0 is_shrink=n
334 0.0126 4.65768 2.04115 T e e  arsize_top=0 arsize_bot=0 is_shrink=n
334 0.004 4.63268 2.01615 B m e v  arsize_top=0 arsize_bot=0 is_shrink=n
335 0.01378 0.27165 2.98819 B e e  arsize_top=0 arsize_bot=0 is_shrink=n
335 0.0126 4.60768 2.14115 T e e  arsize_top=0 arsize_bot=0 is_shrink=n
335 0.004 4.58268 2.11615 B m e v  arsize_top=0 arsize_bot=0 is_shrink=n
336 0.01378 0.35039 3.02756 B e e  arsize_top=0 arsize_bot=0 is_shrink=n
336 0.0126 4.60768 2.09115 T e e  arsize_top=0 arsize_bot=0 is_shrink=n
336 0.004 4.58268 2.06615 B m e v  arsize_top=0 arsize_bot=0 is_shrink=n
337 0.01378 0.27165 3.14567 B e e  arsize_top=0 arsize_bot=0 is_shrink=n
337 0.0126 4.70768 2.14115 T e e  arsize_top=0 arsize_bot=0 is_shrink=n
337 0.004 4.68268 2.11615 B m e v  arsize_top=0 arsize_bot=0 is_shrink=n
338 0.01378 0.35039 3.18504 B e e  arsize_top=0 arsize_bot=0 is_shrink=n
338 0.0126 4.70768 2.09115 T e e  arsize_top=0 arsize_bot=0 is_shrink=n
338 0.004 4.68268 2.06615 B m e v  arsize_top=0 arsize_bot=0 is_shrink=n
339 0.01378 0.35039 3.34252 B e e  arsize_top=0 arsize_bot=0 is_shrink=n
339 0.0126 4.75768 2.34115 T e e  arsize_top=0 arsize_bot=0 is_shrink=n
339 0.004 4.73268 2.31615 B m e v  arsize_top=0 arsize_bot=0 is_shrink=n
340 0.01378 0.27165 3.38189 B e e  arsize_top=0 arsize_bot=0 is_shrink=n
340 0.0126 4.75768 2.29115 T e e  arsize_top=0 arsize_bot=0 is_shrink=n
340 0.004 4.73268 2.26615 B m e v  arsize_top=0 arsize_bot=0 is_shrink=n
341 0.01378 0.35039 3.5 B e e  arsize_top=0 arsize_bot=0 is_shrink=n
341 0.0126 4.70768 2.29115 T e e  arsize_top=0 arsize_bot=0 is_shrink=n
341 0.004 4.68268 2.26615 B m e v  arsize_top=0 arsize_bot=0 is_shrink=n
342 0.01378 0.27165 3.53937 B e e  arsize_top=0 arsize_bot=0 is_shrink=n
342 0.0126 4.70768 2.24115 T e e  arsize_top=0 arsize_bot=0 is_shrink=n
342 0.004 4.68268 2.21615 B m e v  arsize_top=0 arsize_bot=0 is_shrink=n
343 0.01378 0.35039 3.65748 B e e  arsize_top=0 arsize_bot=0 is_shrink=n
343 0.0126 4.60768 2.29115 T e e  arsize_top=0 arsize_bot=0 is_shrink=n
343 0.004 4.58268 2.26615 B m e v  arsize_top=0 arsize_bot=0 is_shrink=n
344 0.01378 0.27165 3.69685 B e e  arsize_top=0 arsize_bot=0 is_shrink=n
344 0.0126 4.60768 2.24115 T e e  arsize_top=0 arsize_bot=0 is_shrink=n
344 0.004 4.58268 2.21615 B m e v  arsize_top=0 arsize_bot=0 is_shrink=n
345 0.01378 0.35039 3.81496 B e e  arsize_top=0 arsize_bot=0 is_shrink=n
345 0.0126 4.65768 2.34115 T e e  arsize_top=0 arsize_bot=0 is_shrink=n
345 0.004 4.63268 2.31615 B m e v  arsize_top=0 arsize_bot=0 is_shrink=n
346 0.01378 0.27165 3.85433 B e e  arsize_top=0 arsize_bot=0 is_shrink=n
346 0.0126 4.65768 2.29115 T e e  arsize_top=0 arsize_bot=0 is_shrink=n
346 0.004 4.63268 2.26615 B m e v  arsize_top=0 arsize_bot=0 is_shrink=n
347 0.01378 0.35039 3.97244 B e e  arsize_top=0 arsize_bot=0 is_shrink=n
347 0.0126 4.70768 2.44115 T e e  arsize_top=0 arsize_bot=0 is_shrink=n
347 0.004 4.68268 2.41615 B m e v  arsize_top=0 arsize_bot=0 is_shrink=n
348 0.01378 0.27165 4.01181 B e e  arsize_top=0 arsize_bot=0 is_shrink=n
348 0.0126 4.70768 2.39115 T e e  arsize_top=0 arsize_bot=0 is_shrink=n
348 0.004 4.68268 2.36615 B m e v  arsize_top=0 arsize_bot=0 is_shrink=n
349 0.01378 0.35039 4.12992 B e e  arsize_top=0 arsize_bot=0 is_shrink=n
349 0.0126 4.60768 2.44115 T e e  arsize_top=0 arsize_bot=0 is_shrink=n
349 0.004 4.58268 2.41615 B m e v  arsize_top=0 arsize_bot=0 is_shrink=n
350 0.01378 0.27165 4.16929 B e e  arsize_top=0 arsize_bot=0 is_shrink=n
350 0.0126 4.60768 2.39115 T e e  arsize_top=0 arsize_bot=0 is_shrink=n
350 0.004 4.58268 2.36615 B m e v  arsize_top=0 arsize_bot=0 is_shrink=n
351 0.01378 0.35039 4.2874 B e e  arsize_top=0 arsize_bot=0 is_shrink=n
351 0.0126 4.65768 2.49115 T e e  arsize_top=0 arsize_bot=0 is_shrink=n
351 0.004 4.63268 2.46615 B m e v  arsize_top=0 arsize_bot=0 is_shrink=n
352 0.01378 0.27165 4.32677 B e e  arsize_top=0 arsize_bot=0 is_shrink=n
352 0.0126 4.65768 2.44115 T e e  arsize_top=0 arsize_bot=0 is_shrink=n
352 0.004 4.63268 2.41615 B m e v  arsize_top=0 arsize_bot=0 is_shrink=n
353 0.01378 0.35039 4.44488 B e e  arsize_top=0 arsize_bot=0 is_shrink=n
353 0.0126 4.75768 2.49115 T e e  arsize_top=0 arsize_bot=0 is_shrink=n
353 0.004 4.73268 2.46615 B m e v  arsize_top=0 arsize_bot=0 is_shrink=n
354 0.01378 0.27165 4.48425 B e e  arsize_top=0 arsize_bot=0 is_shrink=n
354 0.0126 4.75768 2.44115 T e e  arsize_top=0 arsize_bot=0 is_shrink=n
354 0.004 4.73268 2.41615 B m e v  arsize_top=0 arsize_bot=0 is_shrink=n
355 0.01378 0.35039 4.60237 B e e  arsize_top=0 arsize_bot=0 is_shrink=n
356 0.01378 12.63779 1.37402 B e e  arsize_top=0 arsize_bot=0 is_shrink=n
356 0 12.33999 1.3061 D 0.02 0.02 e e staggered 0 0 0  is_shrink=n
357 0.01378 12.63779 1.76772 B e e  arsize_top=0 arsize_bot=0 is_shrink=n
357 0 12.342 2.11 D 0.02 0.02 e e staggered 0 0 0  is_shrink=n
358 0.01378 12.63779 1.9252 B e e  arsize_top=0 arsize_bot=0 is_shrink=n
358 0 12.33901 1.98959 D 0.02 0.02 e e staggered 0 0 0  is_shrink=n
359 0.01378 12.55905 1.96457 B e e  arsize_top=0 arsize_bot=0 is_shrink=n
359 0 12.33901 1.93959 D 0.02 0.02 e e staggered 0 0 0  is_shrink=n
360 0.01378 12.63779 2.16142 B e e  arsize_top=0 arsize_bot=0 is_shrink=n
361 0.01378 12.55905 3.38189 B e e  arsize_top=0 arsize_bot=0 is_shrink=n
362 0.01378 12.73621 1.76772 B e e  arsize_top=0 arsize_bot=0 is_shrink=n
363 0.01378 12.81495 1.88583 B e e  arsize_top=0 arsize_bot=0 is_shrink=n
364 0.01378 12.81495 1.96457 B e e  arsize_top=0 arsize_bot=0 is_shrink=n
364 0.0126 10.76161 1.94115 T e e  arsize_top=0 arsize_bot=0 is_shrink=n
364 0.004 10.73661 1.91615 B m e v  arsize_top=0 arsize_bot=0 is_shrink=n
364 0.004 10.395 1.28555 B m e v  arsize_top=0 arsize_bot=0 is_shrink=n
365 0.01378 12.73621 2.00394 B e e  arsize_top=0 arsize_bot=0 is_shrink=n
365 0.0126 10.76161 1.89115 T e e  arsize_top=0 arsize_bot=0 is_shrink=n
365 0.004 10.73661 1.86615 B m e v  arsize_top=0 arsize_bot=0 is_shrink=n
365 0.004 10.395 1.32555 B m e v  arsize_top=0 arsize_bot=0 is_shrink=n
366 0.01378 12.73621 2.08268 B e e  arsize_top=0 arsize_bot=0 is_shrink=n
366 0.01378 12.73621 2.63386 B e e  arsize_top=0 arsize_bot=0 is_shrink=n
366 0.01378 12.81495 3.30315 B e e  arsize_top=0 arsize_bot=0 is_shrink=n
366 0.01378 12.73621 4.60237 B e e  arsize_top=0 arsize_bot=0 is_shrink=n
366 0 12.33999 1.3401 D 0.02 0.02 e e staggered 0 0 0  is_shrink=n
366 0 12.34198 2.155 D 0.02 0.02 e e staggered 0 0 0  is_shrink=n
367 0.01378 12.73621 2.16142 B e e  arsize_top=0 arsize_bot=0 is_shrink=n
367 0.0126 10.71161 1.99115 T e e  arsize_top=0 arsize_bot=0 is_shrink=n
367 0.004 10.68661 1.96615 B m e v  arsize_top=0 arsize_bot=0 is_shrink=n
367 0.004 10.46445 1.395 B m e v  arsize_top=0 arsize_bot=0 is_shrink=n
368 0.01378 12.81495 2.20079 B e e  arsize_top=0 arsize_bot=0 is_shrink=n
368 0.0126 10.71161 1.94115 T e e  arsize_top=0 arsize_bot=0 is_shrink=n
368 0.004 10.68661 1.91615 B m e v  arsize_top=0 arsize_bot=0 is_shrink=n
368 0.004 10.42445 1.395 B m e v  arsize_top=0 arsize_bot=0 is_shrink=n
369 0.01378 12.73621 2.3189 B e e  arsize_top=0 arsize_bot=0 is_shrink=n
369 0.0126 10.66161 1.94115 T e e  arsize_top=0 arsize_bot=0 is_shrink=n
369 0.004 10.63661 1.91615 B m e v  arsize_top=0 arsize_bot=0 is_shrink=n
369 0.004 10.38372 1.49328 B m e v  arsize_top=0 arsize_bot=0 is_shrink=n
370 0.01378 12.81495 2.35827 B e e  arsize_top=0 arsize_bot=0 is_shrink=n
370 0.0126 10.66161 1.89115 T e e  arsize_top=0 arsize_bot=0 is_shrink=n
370 0.004 10.63661 1.86615 B m e v  arsize_top=0 arsize_bot=0 is_shrink=n
370 0.004 10.35543 1.52157 B m e v  arsize_top=0 arsize_bot=0 is_shrink=n
371 0.01378 12.73621 2.47638 B e e  arsize_top=0 arsize_bot=0 is_shrink=n
371 0.0126 10.61161 1.99115 T e e  arsize_top=0 arsize_bot=0 is_shrink=n
371 0.004 10.58661 1.96615 B m e v  arsize_top=0 arsize_bot=0 is_shrink=n
371 0.004 10.26 1.70445 B m e v  arsize_top=0 arsize_bot=0 is_shrink=n
372 0.01378 12.81495 2.51575 B e e  arsize_top=0 arsize_bot=0 is_shrink=n
372 0.0126 10.61161 1.94115 T e e  arsize_top=0 arsize_bot=0 is_shrink=n
372 0.004 10.58661 1.91615 B m e v  arsize_top=0 arsize_bot=0 is_shrink=n
372 0.004 10.26 1.66445 B m e v  arsize_top=0 arsize_bot=0 is_shrink=n
373 0.01378 12.81495 2.59449 B e e  arsize_top=0 arsize_bot=0 is_shrink=n
374 0.01378 12.73621 2.7126 B e e  arsize_top=0 arsize_bot=0 is_shrink=n
374 0.0126 10.76161 2.09115 T e e  arsize_top=0 arsize_bot=0 is_shrink=n
374 0.004 10.73661 2.06615 B m e v  arsize_top=0 arsize_bot=0 is_shrink=n
374 0.004 10.26025 1.86845 B m e v  arsize_top=0 arsize_bot=0 is_shrink=n
375 0.01378 12.81495 2.75197 B e e  arsize_top=0 arsize_bot=0 is_shrink=n
375 0.0126 10.76161 2.04115 T e e  arsize_top=0 arsize_bot=0 is_shrink=n
375 0.004 10.73661 2.01615 B m e v  arsize_top=0 arsize_bot=0 is_shrink=n
375 0.004 10.26025 1.82845 B m e v  arsize_top=0 arsize_bot=0 is_shrink=n
376 0.01378 12.73621 2.87008 B e e  arsize_top=0 arsize_bot=0 is_shrink=n
376 0.0126 10.66161 2.09115 T e e  arsize_top=0 arsize_bot=0 is_shrink=n
376 0.004 10.63661 2.06615 B m e v  arsize_top=0 arsize_bot=0 is_shrink=n
376 0.004 10.225 1.96645 B m e v  arsize_top=0 arsize_bot=0 is_shrink=n
377 0.01378 12.81495 2.90945 B e e  arsize_top=0 arsize_bot=0 is_shrink=n
377 0.0126 10.66161 2.04115 T e e  arsize_top=0 arsize_bot=0 is_shrink=n
377 0.004 10.63661 2.01615 B m e v  arsize_top=0 arsize_bot=0 is_shrink=n
377 0.004 10.225 1.92645 B m e v  arsize_top=0 arsize_bot=0 is_shrink=n
378 0.01378 12.73621 3.02756 B e e  arsize_top=0 arsize_bot=0 is_shrink=n
378 0.0126 10.61161 2.14115 T e e  arsize_top=0 arsize_bot=0 is_shrink=n
378 0.004 10.58661 2.11615 B m e v  arsize_top=0 arsize_bot=0 is_shrink=n
378 0.004 10.09 2.05655 B m e v  arsize_top=0 arsize_bot=0 is_shrink=n
379 0.01378 12.81495 3.06693 B e e  arsize_top=0 arsize_bot=0 is_shrink=n
379 0.0126 10.61161 2.09115 T e e  arsize_top=0 arsize_bot=0 is_shrink=n
379 0.004 10.58661 2.06615 B m e v  arsize_top=0 arsize_bot=0 is_shrink=n
379 0.004 10.09 2.01655 B m e v  arsize_top=0 arsize_bot=0 is_shrink=n
380 0.01378 12.73621 3.18504 B e e  arsize_top=0 arsize_bot=0 is_shrink=n
380 0.0126 10.71161 2.14115 T e e  arsize_top=0 arsize_bot=0 is_shrink=n
380 0.004 10.68661 2.11615 B m e v  arsize_top=0 arsize_bot=0 is_shrink=n
380 0.004 10.09 2.17095 B m e v  arsize_top=0 arsize_bot=0 is_shrink=n
381 0.01378 12.81495 3.22441 B e e  arsize_top=0 arsize_bot=0 is_shrink=n
381 0.0126 10.71161 2.09115 T e e  arsize_top=0 arsize_bot=0 is_shrink=n
381 0.004 10.68661 2.06615 B m e v  arsize_top=0 arsize_bot=0 is_shrink=n
381 0.004 10.09 2.13095 B m e v  arsize_top=0 arsize_bot=0 is_shrink=n
382 0.01378 12.81495 3.38189 B e e  arsize_top=0 arsize_bot=0 is_shrink=n
382 0.0126 10.76161 2.34115 T e e  arsize_top=0 arsize_bot=0 is_shrink=n
382 0.004 10.73661 2.31615 B m e v  arsize_top=0 arsize_bot=0 is_shrink=n
382 0.004 9.975 2.23955 B m e v  arsize_top=0 arsize_bot=0 is_shrink=n
383 0.01378 12.73621 3.42126 B e e  arsize_top=0 arsize_bot=0 is_shrink=n
383 0.0126 10.76161 2.29115 T e e  arsize_top=0 arsize_bot=0 is_shrink=n
383 0.004 10.73661 2.26615 B m e v  arsize_top=0 arsize_bot=0 is_shrink=n
383 0.004 9.975 2.19955 B m e v  arsize_top=0 arsize_bot=0 is_shrink=n
384 0.01378 12.81495 3.53937 B e e  arsize_top=0 arsize_bot=0 is_shrink=n
384 0.0126 10.71161 2.29115 T e e  arsize_top=0 arsize_bot=0 is_shrink=n
384 0.004 10.68661 2.26615 B m e v  arsize_top=0 arsize_bot=0 is_shrink=n
384 0.004 9.975 2.3758 B m e v  arsize_top=0 arsize_bot=0 is_shrink=n
385 0.01378 12.73621 3.57874 B e e  arsize_top=0 arsize_bot=0 is_shrink=n
385 0.0126 10.71161 2.24115 T e e  arsize_top=0 arsize_bot=0 is_shrink=n
385 0.004 10.68661 2.21615 B m e v  arsize_top=0 arsize_bot=0 is_shrink=n
385 0.004 9.975 2.3358 B m e v  arsize_top=0 arsize_bot=0 is_shrink=n
386 0.01378 12.81495 3.69685 B e e  arsize_top=0 arsize_bot=0 is_shrink=n
386 0.0126 10.61161 2.29115 T e e  arsize_top=0 arsize_bot=0 is_shrink=n
386 0.004 10.58661 2.26615 B m e v  arsize_top=0 arsize_bot=0 is_shrink=n
386 0.004 10.09 2.30825 B m e v  arsize_top=0 arsize_bot=0 is_shrink=n
387 0.01378 12.73621 3.73622 B e e  arsize_top=0 arsize_bot=0 is_shrink=n
387 0.0126 10.61161 2.24115 T e e  arsize_top=0 arsize_bot=0 is_shrink=n
387 0.004 10.58661 2.21615 B m e v  arsize_top=0 arsize_bot=0 is_shrink=n
387 0.004 10.09 2.26825 B m e v  arsize_top=0 arsize_bot=0 is_shrink=n
388 0.01378 12.81495 3.85433 B e e  arsize_top=0 arsize_bot=0 is_shrink=n
388 0.0126 10.66161 2.34115 T e e  arsize_top=0 arsize_bot=0 is_shrink=n
388 0.004 10.63661 2.31615 B m e v  arsize_top=0 arsize_bot=0 is_shrink=n
388 0.004 10.09 2.40335 B m e v  arsize_top=0 arsize_bot=0 is_shrink=n
389 0.01378 12.73621 3.8937 B e e  arsize_top=0 arsize_bot=0 is_shrink=n
389 0.0126 10.66161 2.29115 T e e  arsize_top=0 arsize_bot=0 is_shrink=n
389 0.004 10.63661 2.26615 B m e v  arsize_top=0 arsize_bot=0 is_shrink=n
389 0.004 10.09 2.44335 B m e v  arsize_top=0 arsize_bot=0 is_shrink=n
390 0.01378 12.81495 4.01181 B e e  arsize_top=0 arsize_bot=0 is_shrink=n
390 0.0126 10.71161 2.44115 T e e  arsize_top=0 arsize_bot=0 is_shrink=n
390 0.004 10.68661 2.41615 B m e v  arsize_top=0 arsize_bot=0 is_shrink=n
390 0.004 10.09 2.57845 B m e v  arsize_top=0 arsize_bot=0 is_shrink=n
391 0.01378 12.73621 4.05118 B e e  arsize_top=0 arsize_bot=0 is_shrink=n
391 0.0126 10.71161 2.39115 T e e  arsize_top=0 arsize_bot=0 is_shrink=n
391 0.004 10.68661 2.36615 B m e v  arsize_top=0 arsize_bot=0 is_shrink=n
391 0.004 10.09 2.53845 B m e v  arsize_top=0 arsize_bot=0 is_shrink=n
392 0.01378 12.81495 4.16929 B e e  arsize_top=0 arsize_bot=0 is_shrink=n
392 0.0126 10.61161 2.44115 T e e  arsize_top=0 arsize_bot=0 is_shrink=n
392 0.004 10.58661 2.41615 B m e v  arsize_top=0 arsize_bot=0 is_shrink=n
392 0.004 9.975 2.5109 B m e v  arsize_top=0 arsize_bot=0 is_shrink=n
393 0.01378 12.73621 4.20866 B e e  arsize_top=0 arsize_bot=0 is_shrink=n
393 0.0126 10.61161 2.39115 T e e  arsize_top=0 arsize_bot=0 is_shrink=n
393 0.004 10.58661 2.36615 B m e v  arsize_top=0 arsize_bot=0 is_shrink=n
393 0.004 9.975 2.4709 B m e v  arsize_top=0 arsize_bot=0 is_shrink=n
394 0.01378 12.81495 4.32677 B e e  arsize_top=0 arsize_bot=0 is_shrink=n
394 0.0126 10.66161 2.49115 T e e  arsize_top=0 arsize_bot=0 is_shrink=n
394 0.004 10.63661 2.46615 B m e v  arsize_top=0 arsize_bot=0 is_shrink=n
394 0.004 9.975 2.62445 B m e v  arsize_top=0 arsize_bot=0 is_shrink=n
395 0.01378 12.73621 4.36614 B e e  arsize_top=0 arsize_bot=0 is_shrink=n
395 0.0126 10.66161 2.44115 T e e  arsize_top=0 arsize_bot=0 is_shrink=n
395 0.004 10.63661 2.41615 B m e v  arsize_top=0 arsize_bot=0 is_shrink=n
395 0.004 9.975 2.66445 B m e v  arsize_top=0 arsize_bot=0 is_shrink=n
396 0.01378 12.81495 4.48425 B e e  arsize_top=0 arsize_bot=0 is_shrink=n
396 0.0126 10.76161 2.49115 T e e  arsize_top=0 arsize_bot=0 is_shrink=n
396 0.004 10.73661 2.46615 B m e v  arsize_top=0 arsize_bot=0 is_shrink=n
396 0.004 10.09 2.73655 B m e v  arsize_top=0 arsize_bot=0 is_shrink=n
397 0.01378 12.73621 4.52362 B e e  arsize_top=0 arsize_bot=0 is_shrink=n
397 0.0126 10.76161 2.44115 T e e  arsize_top=0 arsize_bot=0 is_shrink=n
397 0.004 10.73661 2.41615 B m e v  arsize_top=0 arsize_bot=0 is_shrink=n
397 0.004 10.09 2.69655 B m e v  arsize_top=0 arsize_bot=0 is_shrink=n
398 0.01378 12.81495 4.64174 B e e  arsize_top=0 arsize_bot=0 is_shrink=n
399 0.0126 4.60768 2.59115 T e e  arsize_top=0 arsize_bot=0 is_shrink=n
399 0.004 4.58268 2.56615 B m e v  arsize_top=0 arsize_bot=0 is_shrink=n
400 0.0126 4.60768 2.64115 T e e  arsize_top=0 arsize_bot=0 is_shrink=n
400 0.004 4.58268 2.61615 B m e v  arsize_top=0 arsize_bot=0 is_shrink=n
401 0 4.585 5.48 T 0.02992 0.05 e e staggered 0 0 0  is_shrink=n
401 0 4.36323 5.58 T 0.07874 0.04331 e e staggered 0 0 0  is_shrink=n
401 0 4.36323 5.78 T 0.07874 0.04331 e e staggered 0 0 0  is_shrink=n
401 0 5.025 5.433 T 0.02 0.02 e e staggered 0 0 0  is_shrink=n
401 0 3.62 4.483 T 0.02 0.02 e e staggered 0 0 0  is_shrink=n
401 0.0126 4.60768 2.74115 T e e  arsize_top=0 arsize_bot=0 is_shrink=n
401 0 4.091 2.7 D 0.02 0.02 e e staggered 0 0 0  is_shrink=n
401 0.005 3.94 4.42 B m e v  arsize_top=0 arsize_bot=0 is_shrink=n
401 0.004 4.58268 2.71615 B m e v  arsize_top=0 arsize_bot=0 is_shrink=n
401 0.005 4.125 2.682 B m e v  arsize_top=0 arsize_bot=0 is_shrink=n
401 0.005 5.03 5.4 B m e v  arsize_top=0 arsize_bot=0 is_shrink=n
402 0 4.03667 5.18321 T 0.01575 0.06693 e e staggered 0 0 0  is_shrink=n
402 0 4.0599 5.32499 T 0.02 0.02 e e staggered 0 0 0  is_shrink=n
402 0.0126 4.60768 2.79115 T e e  arsize_top=0 arsize_bot=0 is_shrink=n
402 0.005 4.02 4.42 B m e v  arsize_top=0 arsize_bot=0 is_shrink=n
402 0.004 4.58268 2.76615 B m e v  arsize_top=0 arsize_bot=0 is_shrink=n
403 0.0126 4.65768 2.64115 T e e  arsize_top=0 arsize_bot=0 is_shrink=n
403 0.004 4.63268 2.61615 B m e v  arsize_top=0 arsize_bot=0 is_shrink=n
404 0.0126 4.65768 2.69115 T e e  arsize_top=0 arsize_bot=0 is_shrink=n
404 0.004 4.63268 2.66615 B m e v  arsize_top=0 arsize_bot=0 is_shrink=n
405 0.0126 4.70768 2.59115 T e e  arsize_top=0 arsize_bot=0 is_shrink=n
405 0.004 4.68268 2.56615 B m e v  arsize_top=0 arsize_bot=0 is_shrink=n
406 0.0126 4.70768 2.64115 T e e  arsize_top=0 arsize_bot=0 is_shrink=n
406 0.004 4.68268 2.61615 B m e v  arsize_top=0 arsize_bot=0 is_shrink=n
407 0.0126 4.70768 2.74115 T e e  arsize_top=0 arsize_bot=0 is_shrink=n
407 0 5.31269 2.73 D 0.02 0.02 e e staggered 0 0 0  is_shrink=n
407 0 5.42769 2.73 D 0.02 0.02 e e staggered 0 0 0  is_shrink=n
407 0.015 5.27 2.73 D m e v t  arsize_top=0 arsize_bot=0 is_shrink=n
407 0.004 4.68268 2.71615 B m e v  arsize_top=0 arsize_bot=0 is_shrink=n
408 0.0126 4.75768 2.64115 T e e  arsize_top=0 arsize_bot=0 is_shrink=n
408 0.004 4.73268 2.61615 B m e v  arsize_top=0 arsize_bot=0 is_shrink=n
409 0.0126 4.75768 2.69115 T e e  arsize_top=0 arsize_bot=0 is_shrink=n
409 0.004 4.73268 2.66615 B m e v  arsize_top=0 arsize_bot=0 is_shrink=n
410 0.0126 4.80768 2.19115 T e e  arsize_top=0 arsize_bot=0 is_shrink=n
410 0 0.61699 1.91182 D 0.02 0.02 e e staggered 0 0 0  is_shrink=n
410 0.004 4.83268 2.16615 B m e v  arsize_top=0 arsize_bot=0 is_shrink=n
410 0.004 0.69349 1.90612 B m e v  arsize_top=0 arsize_bot=0 is_shrink=n
411 0.0126 4.80768 2.74115 T e e  arsize_top=0 arsize_bot=0 is_shrink=n
411 0 5.64669 2.785 D 0.02 0.02 e e staggered 0 0 0  is_shrink=n
411 0 5.71638 2.82441 D 0.03543 0.01575 e e staggered 0 0 0  is_shrink=n
411 0.015 5.56 2.82 D m e v t  arsize_top=0 arsize_bot=0 is_shrink=n
411 0.004 4.78268 2.71615 B m e v  arsize_top=0 arsize_bot=0 is_shrink=n
412 0.0126 4.85768 2.19115 T e e  arsize_top=0 arsize_bot=0 is_shrink=n
412 0 0.61699 1.86182 D 0.02 0.02 e e staggered 0 0 0  is_shrink=n
412 0.004 4.88268 2.16615 B m e v  arsize_top=0 arsize_bot=0 is_shrink=n
412 0.004 0.69349 1.86612 B m e v  arsize_top=0 arsize_bot=0 is_shrink=n
413 0.0126 4.85768 2.74115 T e e  arsize_top=0 arsize_bot=0 is_shrink=n
413 0 5.64669 2.905 D 0.02 0.02 e e staggered 0 0 0  is_shrink=n
413 0 5.71638 2.87559 D 0.03543 0.01575 e e staggered 0 0 0  is_shrink=n
413 0.015 5.56 2.955 D m e v t  arsize_top=0 arsize_bot=0 is_shrink=n
413 0.004 4.88268 2.71615 B m e v  arsize_top=0 arsize_bot=0 is_shrink=n
414 0.0126 4.90768 2.64115 T e e  arsize_top=0 arsize_bot=0 is_shrink=n
414 0.004 4.93268 2.61615 B m e v  arsize_top=0 arsize_bot=0 is_shrink=n
415 0.0126 4.90768 2.69115 T e e  arsize_top=0 arsize_bot=0 is_shrink=n
415 0.004 4.93268 2.66615 B m e v  arsize_top=0 arsize_bot=0 is_shrink=n
416 0.0126 4.95768 2.59115 T e e  arsize_top=0 arsize_bot=0 is_shrink=n
416 0.004 4.98268 2.56615 B m e v  arsize_top=0 arsize_bot=0 is_shrink=n
417 0.0126 4.95768 2.64115 T e e  arsize_top=0 arsize_bot=0 is_shrink=n
417 0.004 4.98268 2.61615 B m e v  arsize_top=0 arsize_bot=0 is_shrink=n
418 0.0126 4.95768 2.74115 T e e  arsize_top=0 arsize_bot=0 is_shrink=n
418 0 5.31269 2.8 D 0.02 0.02 e e staggered 0 0 0  is_shrink=n
418 0 5.42769 2.8 D 0.02 0.02 e e staggered 0 0 0  is_shrink=n
418 0.015 5.27 2.8 D m e v t  arsize_top=0 arsize_bot=0 is_shrink=n
418 0.004 4.98268 2.71615 B m e v  arsize_top=0 arsize_bot=0 is_shrink=n
419 0 3.91 5.443 T 0.02 0.02 e e staggered 0 0 0  is_shrink=n
419 0 3.9099 5.35899 T 0.02 0.02 e e staggered 0 0 0  is_shrink=n
419 0.0126 5.00768 2.19115 T e e  arsize_top=0 arsize_bot=0 is_shrink=n
419 0.005 3.9099 5.395 B m e v  arsize_top=0 arsize_bot=0 is_shrink=n
419 0.004 5.03268 2.16615 B m e v  arsize_top=0 arsize_bot=0 is_shrink=n
420 0.0126 5.00768 2.64115 T e e  arsize_top=0 arsize_bot=0 is_shrink=n
420 0.004 5.03268 2.61615 B m e v  arsize_top=0 arsize_bot=0 is_shrink=n
421 0.0126 5.00768 2.69115 T e e  arsize_top=0 arsize_bot=0 is_shrink=n
421 0.004 5.03268 2.66615 B m e v  arsize_top=0 arsize_bot=0 is_shrink=n
422 0.0126 5.05768 2.59115 T e e  arsize_top=0 arsize_bot=0 is_shrink=n
422 0.004 5.08268 2.56615 B m e v  arsize_top=0 arsize_bot=0 is_shrink=n
423 0.0126 5.05768 2.64115 T e e  arsize_top=0 arsize_bot=0 is_shrink=n
423 0.004 5.08268 2.61615 B m e v  arsize_top=0 arsize_bot=0 is_shrink=n
424 0 4.01108 4.96077 T 0.01575 0.06693 e e staggered 0 0 0  is_shrink=n
424 0 4.0399 4.82899 T 0.02 0.02 e e staggered 0 0 0  is_shrink=n
424 0.0126 5.05768 2.74115 T e e  arsize_top=0 arsize_bot=0 is_shrink=n
424 0.005 4.06 4.86 B m e v  arsize_top=0 arsize_bot=0 is_shrink=n
424 0.004 5.08268 2.71615 B m e v  arsize_top=0 arsize_bot=0 is_shrink=n
425 0.0126 5.05768 3.79115 T e e  arsize_top=0 arsize_bot=0 is_shrink=n
425 0 1.823 3.61 D 0.02 0.02 e e staggered 0 0 0  is_shrink=n
425 0.005 4.07408 4.01979 B m e v  arsize_top=0 arsize_bot=0 is_shrink=n
425 0.004 5.03268 3.81615 B m e v  arsize_top=0 arsize_bot=0 is_shrink=n
426 0.0126 10.61161 2.59115 T e e  arsize_top=0 arsize_bot=0 is_shrink=n
426 0.004 10.58661 2.56615 B m e v  arsize_top=0 arsize_bot=0 is_shrink=n
427 0.0126 10.61161 2.64115 T e e  arsize_top=0 arsize_bot=0 is_shrink=n
427 0.004 10.58661 2.61615 B m e v  arsize_top=0 arsize_bot=0 is_shrink=n
428 0 4.535 5.48 T 0.02992 0.05 e e staggered 0 0 0  is_shrink=n
428 0 4.36323 5.48 T 0.07874 0.04331 e e staggered 0 0 0  is_shrink=n
428 0 4.36323 5.68 T 0.07874 0.04331 e e staggered 0 0 0  is_shrink=n
428 0 5.075 5.433 T 0.02 0.02 e e staggered 0 0 0  is_shrink=n
428 0 9.91 4.543 T 0.02 0.02 e e staggered 0 0 0  is_shrink=n
428 0.0126 10.61161 2.74115 T e e  arsize_top=0 arsize_bot=0 is_shrink=n
428 0 10.133 2.928 D 0.02 0.02 e e staggered 0 0 0  is_shrink=n
428 0.005 9.91 4.433 B m e v  arsize_top=0 arsize_bot=0 is_shrink=n
428 0.004 10.58661 2.71615 B m e v  arsize_top=0 arsize_bot=0 is_shrink=n
428 0.005 9.995 2.936 B m e v  arsize_top=0 arsize_bot=0 is_shrink=n
429 0 3.98549 5.18321 T 0.01575 0.06693 e e staggered 0 0 0  is_shrink=n
429 0 4.0099 5.32499 T 0.02 0.02 e e staggered 0 0 0  is_shrink=n
429 0.0126 10.61161 2.79115 T e e  arsize_top=0 arsize_bot=0 is_shrink=n
429 0.005 4 5.29 B m e v  arsize_top=0 arsize_bot=0 is_shrink=n
429 0.004 10.58661 2.76615 B m e v  arsize_top=0 arsize_bot=0 is_shrink=n
430 0.0126 10.66161 2.64115 T e e  arsize_top=0 arsize_bot=0 is_shrink=n
430 0.004 10.63661 2.61615 B m e v  arsize_top=0 arsize_bot=0 is_shrink=n
431 0.0126 10.66161 2.69115 T e e  arsize_top=0 arsize_bot=0 is_shrink=n
431 0.004 10.63661 2.66615 B m e v  arsize_top=0 arsize_bot=0 is_shrink=n
432 0.0126 10.71161 2.59115 T e e  arsize_top=0 arsize_bot=0 is_shrink=n
432 0.004 10.68661 2.56615 B m e v  arsize_top=0 arsize_bot=0 is_shrink=n
433 0.0126 10.71161 2.64115 T e e  arsize_top=0 arsize_bot=0 is_shrink=n
433 0.004 10.68661 2.61615 B m e v  arsize_top=0 arsize_bot=0 is_shrink=n
434 0.0126 10.71161 2.74115 T e e  arsize_top=0 arsize_bot=0 is_shrink=n
434 0 11.31662 2.73 D 0.02 0.02 e e staggered 0 0 0  is_shrink=n
434 0 11.43662 2.73 D 0.02 0.02 e e staggered 0 0 0  is_shrink=n
434 0.015 11.27 2.73 D m e v t  arsize_top=0 arsize_bot=0 is_shrink=n
434 0.004 10.68661 2.71615 B m e v  arsize_top=0 arsize_bot=0 is_shrink=n
435 0.0126 10.76161 2.64115 T e e  arsize_top=0 arsize_bot=0 is_shrink=n
435 0.004 10.73661 2.61615 B m e v  arsize_top=0 arsize_bot=0 is_shrink=n
436 0.0126 10.76161 2.69115 T e e  arsize_top=0 arsize_bot=0 is_shrink=n
436 0.004 10.73661 2.66615 B m e v  arsize_top=0 arsize_bot=0 is_shrink=n
437 0.0126 10.81161 2.19115 T e e  arsize_top=0 arsize_bot=0 is_shrink=n
437 0 12.30501 1.93959 D 0.02 0.02 e e staggered 0 0 0  is_shrink=n
437 0.004 10.83661 2.16615 B m e v  arsize_top=0 arsize_bot=0 is_shrink=n
438 0.0126 10.81161 2.74115 T e e  arsize_top=0 arsize_bot=0 is_shrink=n
438 0 11.65062 2.785 D 0.02 0.02 e e staggered 0 0 0  is_shrink=n
438 0 11.72031 2.82441 D 0.03543 0.01575 e e staggered 0 0 0  is_shrink=n
438 0.015 11.555 2.82 D m e v t  arsize_top=0 arsize_bot=0 is_shrink=n
438 0.004 10.78661 2.71615 B m e v  arsize_top=0 arsize_bot=0 is_shrink=n
439 0.0126 10.86161 2.19115 T e e  arsize_top=0 arsize_bot=0 is_shrink=n
439 0 12.30501 1.98959 D 0.02 0.02 e e staggered 0 0 0  is_shrink=n
439 0.004 10.88661 2.16615 B m e v  arsize_top=0 arsize_bot=0 is_shrink=n
440 0.0126 10.86161 2.74115 T e e  arsize_top=0 arsize_bot=0 is_shrink=n
440 0 11.65062 2.905 D 0.02 0.02 e e staggered 0 0 0  is_shrink=n
440 0 11.72031 2.87559 D 0.03543 0.01575 e e staggered 0 0 0  is_shrink=n
440 0.015 11.56 2.945 D m e v t  arsize_top=0 arsize_bot=0 is_shrink=n
440 0.004 10.88661 2.71615 B m e v  arsize_top=0 arsize_bot=0 is_shrink=n
441 0.0126 10.91161 2.64115 T e e  arsize_top=0 arsize_bot=0 is_shrink=n
441 0.004 10.93661 2.61615 B m e v  arsize_top=0 arsize_bot=0 is_shrink=n
442 0.0126 10.91161 2.69115 T e e  arsize_top=0 arsize_bot=0 is_shrink=n
442 0.004 10.93661 2.66615 B m e v  arsize_top=0 arsize_bot=0 is_shrink=n
443 0.0126 10.96161 2.59115 T e e  arsize_top=0 arsize_bot=0 is_shrink=n
443 0.004 10.98661 2.56615 B m e v  arsize_top=0 arsize_bot=0 is_shrink=n
444 0.0126 10.96161 2.64115 T e e  arsize_top=0 arsize_bot=0 is_shrink=n
444 0.004 10.98661 2.61615 B m e v  arsize_top=0 arsize_bot=0 is_shrink=n
445 0.0126 10.96161 2.74115 T e e  arsize_top=0 arsize_bot=0 is_shrink=n
445 0 11.31662 2.8 D 0.02 0.02 e e staggered 0 0 0  is_shrink=n
445 0 11.43662 2.8 D 0.02 0.02 e e staggered 0 0 0  is_shrink=n
445 0.015 11.27 2.8 D m e v t  arsize_top=0 arsize_bot=0 is_shrink=n
445 0.004 10.98661 2.71615 B m e v  arsize_top=0 arsize_bot=0 is_shrink=n
446 0 3.89 4.717 T 0.02 0.02 e e staggered 0 0 0  is_shrink=n
446 0 3.8899 4.79499 T 0.02 0.02 e e staggered 0 0 0  is_shrink=n
446 0.0126 11.01161 2.19115 T e e  arsize_top=0 arsize_bot=0 is_shrink=n
446 0.005 3.8899 4.765 B m e v  arsize_top=0 arsize_bot=0 is_shrink=n
446 0.004 11.03661 2.16615 B m e v  arsize_top=0 arsize_bot=0 is_shrink=n
447 0.0126 11.01161 2.64115 T e e  arsize_top=0 arsize_bot=0 is_shrink=n
447 0.004 11.03661 2.61615 B m e v  arsize_top=0 arsize_bot=0 is_shrink=n
448 0.0126 11.01161 2.69115 T e e  arsize_top=0 arsize_bot=0 is_shrink=n
448 0.004 11.03661 2.66615 B m e v  arsize_top=0 arsize_bot=0 is_shrink=n
449 0.0126 11.06161 2.59115 T e e  arsize_top=0 arsize_bot=0 is_shrink=n
449 0.004 11.08661 2.56615 B m e v  arsize_top=0 arsize_bot=0 is_shrink=n
450 0.0126 11.06161 2.64115 T e e  arsize_top=0 arsize_bot=0 is_shrink=n
450 0.004 11.08661 2.61615 B m e v  arsize_top=0 arsize_bot=0 is_shrink=n
451 0 3.9599 4.96077 T 0.01575 0.06693 e e staggered 0 0 0  is_shrink=n
451 0 3.9899 4.82899 T 0.02 0.02 e e staggered 0 0 0  is_shrink=n
451 0.0126 11.06161 2.74115 T e e  arsize_top=0 arsize_bot=0 is_shrink=n
451 0.005 3.985 4.88999 B m e v  arsize_top=0 arsize_bot=0 is_shrink=n
451 0.004 11.08661 2.71615 B m e v  arsize_top=0 arsize_bot=0 is_shrink=n
452 0.0126 11.06161 3.79115 T e e  arsize_top=0 arsize_bot=0 is_shrink=n
452 0 7.82694 3.61 D 0.02 0.02 e e staggered 0 0 0  is_shrink=n
452 0.005 7.425 3.43 B m e v  arsize_top=0 arsize_bot=0 is_shrink=n
452 0.004 11.03661 3.81615 B m e v  arsize_top=0 arsize_bot=0 is_shrink=n
452 0.005 11.135 2.845 B m e v  arsize_top=0 arsize_bot=0 is_shrink=n
452 0.005 7.445 1.705 B m e v  arsize_top=0 arsize_bot=0 is_shrink=n
453 0 0.705 5.417 T 0.02 0.02 e e staggered 0 0 0  is_shrink=n
453 0 0.755 5.417 T 0.02 0.02 e e staggered 0 0 0  is_shrink=n
453 0 0.72933 5.53642 T 0.03937 0.10827 e e staggered 0 0 0  is_shrink=n
453 0.005 0.72933 5.463 B m e v  arsize_top=0 arsize_bot=0 is_shrink=n
454 0 0.73 5.823 T 0.02 0.02 e e staggered 0 0 0  is_shrink=n
454 0 3.8599 5.35899 T 0.02 0.02 e e staggered 0 0 0  is_shrink=n
454 0 0.72933 5.70374 T 0.03937 0.10827 e e staggered 0 0 0  is_shrink=n
454 0.005 3.775 5.295 B m e v  arsize_top=0 arsize_bot=0 is_shrink=n
454 0.005 0.73 5.78 B m e v  arsize_top=0 arsize_bot=0 is_shrink=n
455 0 0.68 5.147 T 0.02 0.02 e e staggered 0 0 0  is_shrink=n
455 0 0.83 5.417 T 0.02 0.02 e e staggered 0 0 0  is_shrink=n
455 0 3.77441 4.63965 T 0.01575 0.03543 e e staggered 0 0 0  is_shrink=n
455 0 0.80807 5.53642 T 0.03937 0.10827 e e staggered 0 0 0  is_shrink=n
455 0.005 0.80807 5.46194 B m e v  arsize_top=0 arsize_bot=0 is_shrink=n
455 0.005 3.733 5.075 B m e v  arsize_top=0 arsize_bot=0 is_shrink=n
456 0 0.81 5.823 T 0.02 0.02 e e staggered 0 0 0  is_shrink=n
456 0 3.8399 4.79499 T 0.02 0.02 e e staggered 0 0 0  is_shrink=n
456 0 0.80807 5.70374 T 0.03937 0.10827 e e staggered 0 0 0  is_shrink=n
456 0.005 3.8399 4.765 B m e v  arsize_top=0 arsize_bot=0 is_shrink=n
456 0.005 0.81 5.78 B m e v  arsize_top=0 arsize_bot=0 is_shrink=n
457 0 0.9 5.417 T 0.02 0.02 e e staggered 0 0 0  is_shrink=n
457 0 0.82984 5.2361 T 0.01102 0.04331 e e staggered 0 0 0  is_shrink=n
457 0 0.88681 5.53642 T 0.03937 0.10827 e e staggered 0 0 0  is_shrink=n
457 0.015 0.83 5.295 T m e v t  arsize_top=0 arsize_bot=0 is_shrink=n
458 0 0.89 5.823 T 0.02 0.02 e e staggered 0 0 0  is_shrink=n
458 0 3.9599 5.35899 T 0.02 0.02 e e staggered 0 0 0  is_shrink=n
458 0 0.88681 5.70374 T 0.03937 0.10827 e e staggered 0 0 0  is_shrink=n
458 0.005 3.9599 5.395 B m e v  arsize_top=0 arsize_bot=0 is_shrink=n
458 0.005 0.88681 5.78181 B m e v  arsize_top=0 arsize_bot=0 is_shrink=n
459 0 0.996 5.417 T 0.02 0.02 e e staggered 0 0 0  is_shrink=n
459 0 0.948 5.417 T 0.02 0.02 e e staggered 0 0 0  is_shrink=n
459 0 0.96555 5.53642 T 0.03937 0.10827 e e staggered 0 0 0  is_shrink=n
459 0.005 0.95951 5.4595 B m e v  arsize_top=0 arsize_bot=0 is_shrink=n
460 0 4.063 4.59 T 0.02 0.02 e e staggered 0 0 0  is_shrink=n
460 0 0.97 5.823 T 0.02 0.02 e e staggered 0 0 0  is_shrink=n
460 0 0.5574 5.85528 T 0.02362 0.0374 e e staggered 0 0 0  is_shrink=n
460 0 0.96555 5.70374 T 0.03937 0.10827 e e staggered 0 0 0  is_shrink=n
460 0.005 0.96555 5.78055 B m e v  arsize_top=0 arsize_bot=0 is_shrink=n
460 0.005 4.07 4.625 B m e v  arsize_top=0 arsize_bot=0 is_shrink=n
461 0 1.094 5.417 T 0.02 0.02 e e staggered 0 0 0  is_shrink=n
461 0 1.04429 5.53642 T 0.03937 0.10827 e e staggered 0 0 0  is_shrink=n
461 0 5.6492 3 D 0.02 0.02 e e staggered 0 0 0  is_shrink=n
461 0 5.72185 3 D 0.03543 0.01575 e e staggered 0 0 0  is_shrink=n
461 0.005 3.88 4.545 B m e v  arsize_top=0 arsize_bot=0 is_shrink=n
461 0.005 1.122 5.417 B m e v  arsize_top=0 arsize_bot=0 is_shrink=n
461 0.005 5.855 0.925 B m e v  arsize_top=0 arsize_bot=0 is_shrink=n
462 0 1.04 5.823 T 0.02 0.02 e e staggered 0 0 0  is_shrink=n
462 0 3.67 4.67035 T 0.01575 0.03543 e e staggered 0 0 0  is_shrink=n
462 0 1.04429 5.70374 T 0.03937 0.10827 e e staggered 0 0 0  is_shrink=n
462 0.005 1.08 5.85 B m e v  arsize_top=0 arsize_bot=0 is_shrink=n
462 0.005 3.6817 5.74 B m e v  arsize_top=0 arsize_bot=0 is_shrink=n
463 0 1.12 5.823 T 0.02 0.02 e e staggered 0 0 0  is_shrink=n
463 0 10 4.73035 T 0.01575 0.03543 e e staggered 0 0 0  is_shrink=n
463 0 1.12303 5.70374 T 0.03937 0.10827 e e staggered 0 0 0  is_shrink=n
463 0.005 1.16 5.85 B m e v  arsize_top=0 arsize_bot=0 is_shrink=n
463 0.005 3.815 5.815 B m e v  arsize_top=0 arsize_bot=0 is_shrink=n
464 0 0.52 5.649 T 0.03 0.03 e e staggered 0 0 0  is_shrink=n
464 0 0.503 5.7 T 0.02 0.02 e e staggered 0 0 0  is_shrink=n
464 0.015 0.46 5.649 T m e v t  arsize_top=0 arsize_bot=0 is_shrink=n
465 0.00394 6.69009 4.98004 T e e  arsize_top=0 arsize_bot=0 is_shrink=n
465 0 6.803 5 T 0.02 0.02 e e staggered 0 0 0  is_shrink=n
465 0 6.755 5.053 T 0.02 0.02 e e staggered 0 0 0  is_shrink=n
465 0 6.71 5.053 T 0.02 0.02 e e staggered 0 0 0  is_shrink=n
465 0.015 6.8 5.045 T m e v t  arsize_top=0 arsize_bot=0 is_shrink=n
466 0.00394 6.65269 5.00563 T e e  arsize_top=0 arsize_bot=0 is_shrink=n
466 0 6.755 5.087 T 0.02 0.02 e e staggered 0 0 0  is_shrink=n
466 0 5.49094 4.5861 T 0.02 0.02 e e staggered 0 0 0  is_shrink=n
466 0 6.71 5.087 T 0.02 0.02 e e staggered 0 0 0  is_shrink=n
466 0.015 6.755 5.13 T m e v t  arsize_top=0 arsize_bot=0 is_shrink=n
467 0.00394 6.69009 4.8540599 T e e  arsize_top=0 arsize_bot=0 is_shrink=n
467 0.00394 6.69009 4.8698099 T e e  arsize_top=0 arsize_bot=0 is_shrink=n
467 0.00394 6.69009 4.88555 T e e  arsize_top=0 arsize_bot=0 is_shrink=n
467 0 6.87619 4.71823 T 0.0748 0.06693 e e staggered 0 0 0  is_shrink=n
467 0 6.74209 4.7052 T 0.05 0.05 e e staggered 0 0 0  is_shrink=n
467 0 6.83119 4.81705 T 0.05 0.05 e e staggered 0 0 0  is_shrink=n
467 0 6.71319 4.77205 T 0.02 0.02 e e staggered 0 0 0  is_shrink=n
467 0 6.83319 4.89705 D 0.02 0.02 e e staggered 0 0 0  is_shrink=n
467 0 6.74209 4.7052 D 0.05 0.05 e e staggered 0 0 0  is_shrink=n
467 0 6.74209 4.6252 D 0.05 0.05 e e staggered 0 0 0  is_shrink=n
467 0 6.83119 4.73868 D 0.05 0.05 e e staggered 0 0 0  is_shrink=n
467 0 6.83119 4.81705 D 0.05 0.05 e e staggered 0 0 0  is_shrink=n
467 0.005 6.74 4.805 B m e v  arsize_top=0 arsize_bot=0 is_shrink=n
467 0.005 6.74 4.845 B m e v  arsize_top=0 arsize_bot=0 is_shrink=n
467 0.005 6.74019 4.765 B m e v  arsize_top=0 arsize_bot=0 is_shrink=n
467 0.005 6.785 4.685 B m e v  arsize_top=0 arsize_bot=0 is_shrink=n
467 0.005 6.785 4.725 B m e v  arsize_top=0 arsize_bot=0 is_shrink=n
467 0.005 6.785 4.765 B m e v  arsize_top=0 arsize_bot=0 is_shrink=n
467 0.005 6.785 4.805 B m e v  arsize_top=0 arsize_bot=0 is_shrink=n
467 0.005 6.785 4.845 B m e v  arsize_top=0 arsize_bot=0 is_shrink=n
468 0.00394 6.55229 4.96429 T e e  arsize_top=0 arsize_bot=0 is_shrink=n
468 0 6.45819 5.09705 T 0.02 0.02 e e staggered 0 0 0  is_shrink=n
468 0 6.45819 5.04705 T 0.02 0.02 e e staggered 0 0 0  is_shrink=n
468 0 6.45819 5.04705 D 0.02 0.02 e e staggered 0 0 0  is_shrink=n
468 0 6.53919 5.09705 D 0.02 0.02 e e staggered 0 0 0  is_shrink=n
468 0.005 6.49205 5.09705 B m e v  arsize_top=0 arsize_bot=0 is_shrink=n
469 0 6.42419 4.94705 T 0.02 0.02 e e staggered 0 0 0  is_shrink=n
469 0 6.38319 4.94705 T 0.02 0.02 e e staggered 0 0 0  is_shrink=n
470 0 6.43044 4.77205 T 0.07283 0.1378 e e staggered 0 0 0  is_shrink=n
470 0 6.51619 4.78105 T 0.03 0.03 e e staggered 0 0 0  is_shrink=n
470 0.00394 6.55229 4.9013 T e e  arsize_top=0 arsize_bot=0 is_shrink=n
470 0.00394 6.55229 4.88555 T e e  arsize_top=0 arsize_bot=0 is_shrink=n
470 0.00394 6.55229 4.8698099 T e e  arsize_top=0 arsize_bot=0 is_shrink=n
470 0.00394 6.55229 4.8540599 T e e  arsize_top=0 arsize_bot=0 is_shrink=n
470 0 6.34919 4.94705 T 0.02 0.02 e e staggered 0 0 0  is_shrink=n
471 0.00394 6.55229 4.94855 T e e  arsize_top=0 arsize_bot=0 is_shrink=n
471 0 6.45819 4.99705 T 0.02 0.02 e e staggered 0 0 0  is_shrink=n
471 0 6.45819 4.99705 D 0.02 0.02 e e staggered 0 0 0  is_shrink=n
471 0.005 6.501 5.017 B m e v  arsize_top=0 arsize_bot=0 is_shrink=n
472 0.00394 6.69009 4.9328 T e e  arsize_top=0 arsize_bot=0 is_shrink=n
472 0 6.81219 4.94705 T 0.03 0.03 e e staggered 0 0 0  is_shrink=n
472 0 6.60819 4.99705 D 0.02 0.02 e e staggered 0 0 0  is_shrink=n
472 0 6.65419 4.99705 D 0.02 0.02 e e staggered 0 0 0  is_shrink=n
472 0.005 6.78 4.94705 B m e v  arsize_top=0 arsize_bot=0 is_shrink=n
473 0 6.57519 4.66705 T 0.03 0.03 e e staggered 0 0 0  is_shrink=n
473 0 6.57619 4.73505 T 0.02 0.02 e e staggered 0 0 0  is_shrink=n
473 0.015 6.57519 4.605 T m e v t  arsize_top=0 arsize_bot=0 is_shrink=n
474 0.00394 6.69009 4.91705 T e e  arsize_top=0 arsize_bot=0 is_shrink=n
474 0 6.81219 4.88705 T 0.03 0.03 e e staggered 0 0 0  is_shrink=n
474 0 6.79919 4.89705 D 0.02 0.02 e e staggered 0 0 0  is_shrink=n
474 0.005 6.755 4.89705 B m e v  arsize_top=0 arsize_bot=0 is_shrink=n
475 0 6.38349 4.99705 T 0.02 0.02 e e staggered 0 0 0  is_shrink=n
475 0 6.42419 4.99705 D 0.02 0.02 e e staggered 0 0 0  is_shrink=n
475 0 6.38349 4.99705 D 0.02 0.02 e e staggered 0 0 0  is_shrink=n
475 0.015 6.415 4.955 D m e v t  arsize_top=0 arsize_bot=0 is_shrink=n
475 0.005 6.385 5.03 B m e v  arsize_top=0 arsize_bot=0 is_shrink=n
476 0 6.51719 4.66705 T 0.03 0.03 e e staggered 0 0 0  is_shrink=n
476 0 6.51619 4.72305 T 0.03 0.03 e e staggered 0 0 0  is_shrink=n
476 0.015 6.52 4.605 T m e v t  arsize_top=0 arsize_bot=0 is_shrink=n
477 0.00394 6.69009 4.94855 T e e  arsize_top=0 arsize_bot=0 is_shrink=n
477 0 6.803 5 D 0.02 0.02 e e staggered 0 0 0  is_shrink=n
477 0 6.68819 4.99705 D 0.02 0.02 e e staggered 0 0 0  is_shrink=n
477 0.005 6.74 4.987 B m e v  arsize_top=0 arsize_bot=0 is_shrink=n
478 0.00394 6.63694 5.00563 T e e  arsize_top=0 arsize_bot=0 is_shrink=n
478 0 6.65819 5.09705 T 0.02 0.02 e e staggered 0 0 0  is_shrink=n
478 0.005 6.65 5.055 B m e v  arsize_top=0 arsize_bot=0 is_shrink=n
479 0.00394 6.55229 4.98004 T e e  arsize_top=0 arsize_bot=0 is_shrink=n
479 0 6.53919 5.09705 T 0.02 0.02 e e staggered 0 0 0  is_shrink=n
479 0 6.57419 4.99705 D 0.02 0.02 e e staggered 0 0 0  is_shrink=n
479 0.005 6.55119 5.04705 B m e v  arsize_top=0 arsize_bot=0 is_shrink=n
480 0 4.86 5.408 T 0.02 0.02 e e staggered 0 0 0  is_shrink=n
480 0 0.73 4.993 T 0.02 0.02 e e staggered 0 0 0  is_shrink=n
480 0 3.8 4.63965 T 0.01575 0.03543 e e staggered 0 0 0  is_shrink=n
480 0 6.57319 5.09705 D 0.02 0.02 e e staggered 0 0 0  is_shrink=n
480 0.005 0.73 4.96 B m e v  arsize_top=0 arsize_bot=0 is_shrink=n
480 0.005 3.795 4.6 B m e v  arsize_top=0 arsize_bot=0 is_shrink=n
480 0.005 4.86 5.375 B m e v  arsize_top=0 arsize_bot=0 is_shrink=n
481 0.00394 6.55229 4.9328 T e e  arsize_top=0 arsize_bot=0 is_shrink=n
481 0 6.45819 4.94705 T 0.02 0.02 e e staggered 0 0 0  is_shrink=n
481 0.005 6.495 4.9328 B m e v  arsize_top=0 arsize_bot=0 is_shrink=n
482 0 0.537 5.7 T 0.02 0.02 e e staggered 0 0 0  is_shrink=n
482 0 0.52 5.76472 T 0.02362 0.0374 e e staggered 0 0 0  is_shrink=n
482 0.015 0.46 5.735 T m e v t  arsize_top=0 arsize_bot=0 is_shrink=n
483 0 5.917 3.07 D 0.02 0.02 e e staggered 0 0 0  is_shrink=n
483 0 5.917 3.02 D 0.02 0.02 e e staggered 0 0 0  is_shrink=n
483 0 11.80693 2.82441 D 0.03543 0.01575 e e staggered 0 0 0  is_shrink=n
483 0 5.803 2.82441 D 0.03543 0.01575 e e staggered 0 0 0  is_shrink=n
483 0.005 5.815 0.925 B m e v  arsize_top=0 arsize_bot=0 is_shrink=n
483 0.005 11.235 3.3 B m e v  arsize_top=0 arsize_bot=0 is_shrink=n
484 0 5.883 3.02 D 0.02 0.02 e e staggered 0 0 0  is_shrink=n
484 0 5.80255 3.02559 D 0.03543 0.01575 e e staggered 0 0 0  is_shrink=n
484 0.015 5.795 3.09 D m e v t  arsize_top=0 arsize_bot=0 is_shrink=n
485 0 4.01108 5.18321 T 0.01575 0.06693 e e staggered 0 0 0  is_shrink=n
485 0 3.9599 5.18321 T 0.01575 0.06693 e e staggered 0 0 0  is_shrink=n
485 0 3.9599 5.32499 T 0.02 0.02 e e staggered 0 0 0  is_shrink=n
485 0.015 3.9599 5.275 T m e v t  arsize_top=0 arsize_bot=0 is_shrink=n
486 0 3.93431 5.18321 T 0.01575 0.06693 e e staggered 0 0 0  is_shrink=n
486 0 3.9099 5.32499 T 0.02 0.02 e e staggered 0 0 0  is_shrink=n
486 0.015 3.9099 5.2751 T m e v t  arsize_top=0 arsize_bot=0 is_shrink=n
487 0 3.90872 5.18321 T 0.01575 0.06693 e e staggered 0 0 0  is_shrink=n
487 0 3.8599 5.32499 T 0.02 0.02 e e staggered 0 0 0  is_shrink=n
487 0.015 3.8599 5.2751 T m e v t  arsize_top=0 arsize_bot=0 is_shrink=n
488 0 3.90872 4.96077 T 0.01575 0.06693 e e staggered 0 0 0  is_shrink=n
488 0 3.8899 4.82899 T 0.02 0.02 e e staggered 0 0 0  is_shrink=n
488 0.015 3.89 4.87 T m e v t  arsize_top=0 arsize_bot=0 is_shrink=n
489 0 3.88313 4.96077 T 0.01575 0.06693 e e staggered 0 0 0  is_shrink=n
489 0 3.8399 4.82899 T 0.02 0.02 e e staggered 0 0 0  is_shrink=n
489 0.015 3.84 4.87 T m e v t  arsize_top=0 arsize_bot=0 is_shrink=n
490 0 0.91 5.267 T 0.02 0.02 e e staggered 0 0 0  is_shrink=n
490 0 0.84953 5.2361 T 0.01102 0.04331 e e staggered 0 0 0  is_shrink=n
490 0.015 0.91 5.31 T m e v t  arsize_top=0 arsize_bot=0 is_shrink=n
491 0 0.91 5.147 T 0.02 0.02 e e staggered 0 0 0  is_shrink=n
491 0 0.91 5.233 T 0.02 0.02 e e staggered 0 0 0  is_shrink=n
491 0 1.02559 5.29035 T 0.01575 0.03543 e e staggered 0 0 0  is_shrink=n
491 0.015 0.91 5.19 T m e v t  arsize_top=0 arsize_bot=0 is_shrink=n
492 0 4.01677 5.48 T 0.07874 0.04331 e e staggered 0 0 0  is_shrink=n
492 0 10.099 2.928 D 0.02 0.02 e e staggered 0 0 0  is_shrink=n
492 0 10.099 2.88 D 0.02 0.02 e e staggered 0 0 0  is_shrink=n
492 0 10.03814 2.87559 D 0.03543 0.01575 e e staggered 0 0 0  is_shrink=n
492 0.005 4.105 4.985 B m e v  arsize_top=0 arsize_bot=0 is_shrink=n
492 0.005 10.07 2.928 B m e v  arsize_top=0 arsize_bot=0 is_shrink=n
493 0 1.33906 4.66551 T 0.02 0.02 e e staggered 0 0 0  is_shrink=n
493 0 1.30186 4.79682 T 0.01575 0.06693 e e staggered 0 0 0  is_shrink=n
493 0 1.31906 4.94151 D 0.02 0.02 e e staggered 0 0 0  is_shrink=n
493 0 1.823 3.56 D 0.02 0.02 e e staggered 0 0 0  is_shrink=n
493 0.005 1.33906 4.69351 B m e v  arsize_top=0 arsize_bot=0 is_shrink=n
494 0 1.28906 4.66551 T 0.02 0.02 e e staggered 0 0 0  is_shrink=n
494 0 1.27626 4.79682 T 0.01575 0.06693 e e staggered 0 0 0  is_shrink=n
494 0 1.26906 4.94151 D 0.02 0.02 e e staggered 0 0 0  is_shrink=n
494 0 1.823 3.51 D 0.02 0.02 e e staggered 0 0 0  is_shrink=n
494 0.005 1.28906 4.69351 B m e v  arsize_top=0 arsize_bot=0 is_shrink=n
495 0 1.38906 5.09151 T 0.02 0.02 e e staggered 0 0 0  is_shrink=n
495 0 1.32745 4.9602 T 0.01575 0.06693 e e staggered 0 0 0  is_shrink=n
495 0.015 1.38906 5.04851 T m e v t  arsize_top=0 arsize_bot=0 is_shrink=n
496 0 1.33906 5.09151 T 0.02 0.02 e e staggered 0 0 0  is_shrink=n
496 0 1.28906 5.09151 T 0.02 0.02 e e staggered 0 0 0  is_shrink=n
496 0 1.30186 4.9602 T 0.01575 0.06693 e e staggered 0 0 0  is_shrink=n
496 0 1.31906 4.97551 D 0.02 0.02 e e staggered 0 0 0  is_shrink=n
496 0.005 1.28906 5.04351 B m e v  arsize_top=0 arsize_bot=0 is_shrink=n
497 0 1.18906 5.09151 T 0.02 0.02 e e staggered 0 0 0  is_shrink=n
497 0 1.23906 5.09151 T 0.02 0.02 e e staggered 0 0 0  is_shrink=n
497 0 1.27626 4.9602 T 0.01575 0.06693 e e staggered 0 0 0  is_shrink=n
497 0 1.26906 4.97551 D 0.02 0.02 e e staggered 0 0 0  is_shrink=n
497 0.005 1.23906 5.04351 B m e v  arsize_top=0 arsize_bot=0 is_shrink=n
498 0 7.3426 5.09151 T 0.02 0.02 e e staggered 0 0 0  is_shrink=n
498 0 7.2926 5.09151 T 0.02 0.02 e e staggered 0 0 0  is_shrink=n
498 0 7.3054 4.9602 T 0.01575 0.06693 e e staggered 0 0 0  is_shrink=n
498 0 7.3226 4.97551 D 0.02 0.02 e e staggered 0 0 0  is_shrink=n
498 0.005 7.2926 5.04351 B m e v  arsize_top=0 arsize_bot=0 is_shrink=n
499 0 7.3426 4.66551 T 0.02 0.02 e e staggered 0 0 0  is_shrink=n
499 0 7.3054 4.79682 T 0.01575 0.06693 e e staggered 0 0 0  is_shrink=n
499 0 7.82694 3.56 D 0.02 0.02 e e staggered 0 0 0  is_shrink=n
499 0 7.3226 4.94151 D 0.02 0.02 e e staggered 0 0 0  is_shrink=n
499 0.005 7.3426 4.69351 B m e v  arsize_top=0 arsize_bot=0 is_shrink=n
500 0 7.1926 5.09151 T 0.02 0.02 e e staggered 0 0 0  is_shrink=n
500 0 7.2426 5.09151 T 0.02 0.02 e e staggered 0 0 0  is_shrink=n
500 0 7.2798 4.9602 T 0.01575 0.06693 e e staggered 0 0 0  is_shrink=n
500 0 7.2726 4.97551 D 0.02 0.02 e e staggered 0 0 0  is_shrink=n
500 0.005 7.2426 5.04351 B m e v  arsize_top=0 arsize_bot=0 is_shrink=n
501 0 7.2926 4.66551 T 0.02 0.02 e e staggered 0 0 0  is_shrink=n
501 0 7.2798 4.79682 T 0.01575 0.06693 e e staggered 0 0 0  is_shrink=n
501 0 7.82694 3.51 D 0.02 0.02 e e staggered 0 0 0  is_shrink=n
501 0 7.2726 4.94151 D 0.02 0.02 e e staggered 0 0 0  is_shrink=n
501 0.005 7.2926 4.69351 B m e v  arsize_top=0 arsize_bot=0 is_shrink=n
502 0 7.3926 5.09151 T 0.02 0.02 e e staggered 0 0 0  is_shrink=n
502 0 7.33099 4.9602 T 0.01575 0.06693 e e staggered 0 0 0  is_shrink=n
502 0.015 7.3926 5.04851 T m e v t  arsize_top=0 arsize_bot=0 is_shrink=n
503 0 0.61698 1.655 D 0.02 0.02 e e staggered 0 0 0  is_shrink=n
503 0 5.803 2.87559 D 0.03543 0.01575 e e staggered 0 0 0  is_shrink=n
503 0.005 5.76 2.66 B m e v  arsize_top=0 arsize_bot=0 is_shrink=n
503 0.005 0.64809 1.655 B m e v  arsize_top=0 arsize_bot=0 is_shrink=n
504 0 12.308 2.11 D 0.02 0.02 e e staggered 0 0 0  is_shrink=n
504 0 11.80693 2.87559 D 0.03543 0.01575 e e staggered 0 0 0  is_shrink=n
504 0.015 11.875 2.885 D m e v t  arsize_top=0 arsize_bot=0 is_shrink=n
505 0 3.93431 4.96077 T 0.01575 0.06693 e e staggered 0 0 0  is_shrink=n
505 0 3.98549 4.96077 T 0.01575 0.06693 e e staggered 0 0 0  is_shrink=n
505 0 3.9399 4.82899 T 0.02 0.02 e e staggered 0 0 0  is_shrink=n
505 0.015 3.94 4.87 T m e v t  arsize_top=0 arsize_bot=0 is_shrink=n
506 0 3.9399 4.79499 T 0.02 0.02 e e staggered 0 0 0  is_shrink=n
506 0 3.94 4.717 T 0.02 0.02 e e staggered 0 0 0  is_shrink=n
506 0 3.99965 4.71559 T 0.03543 0.01575 e e staggered 0 0 0  is_shrink=n
506 0.005 3.94 4.765 B m e v  arsize_top=0 arsize_bot=0 is_shrink=n
507 0 4.01677 5.58 T 0.07874 0.04331 e e staggered 0 0 0  is_shrink=n
507 0 4.057 2.7 D 0.02 0.02 e e staggered 0 0 0  is_shrink=n
507 0 4.05686 2.65 D 0.02 0.02 e e staggered 0 0 0  is_shrink=n
507 0 3.99421 2.64559 D 0.03543 0.01575 e e staggered 0 0 0  is_shrink=n
507 0.005 4.02 4.355 B m e v  arsize_top=0 arsize_bot=0 is_shrink=n
507 0.005 4.125 2.725 B m e v  arsize_top=0 arsize_bot=0 is_shrink=n
508 0 1.044 5.383 T 0.02 0.02 e e staggered 0 0 0  is_shrink=n
508 0 0.996 5.383 T 0.02 0.02 e e staggered 0 0 0  is_shrink=n
508 0 1 5.29035 T 0.01575 0.03543 e e staggered 0 0 0  is_shrink=n
508 0.015 1.043 5.343 T m e v t  arsize_top=0 arsize_bot=0 is_shrink=n
509 0 0.97 5.127 T 0.02 0.02 e e staggered 0 0 0  is_shrink=n
509 0 0.97441 5.20965 T 0.01575 0.03543 e e staggered 0 0 0  is_shrink=n
509 0.015 0.929 5.037 T m e v t  arsize_top=0 arsize_bot=0 is_shrink=n
510 0 1.03 5.027 T 0.02 0.02 e e staggered 0 0 0  is_shrink=n
510 0 0.97 5.027 T 0.02 0.02 e e staggered 0 0 0  is_shrink=n
510 0 0.97 5.093 T 0.02 0.02 e e staggered 0 0 0  is_shrink=n
510 0 3.91351 2.62 D 0.03543 0.01575 e e staggered 0 0 0  is_shrink=n
510 0 9.95744 2.85 D 0.03543 0.01575 e e staggered 0 0 0  is_shrink=n
510 0.005 1.057 5.027 B m e v  arsize_top=0 arsize_bot=0 is_shrink=n
511 0 4.097 4.59 T 0.02 0.02 e e staggered 0 0 0  is_shrink=n
511 0 4.08035 4.66441 T 0.03543 0.01575 e e staggered 0 0 0  is_shrink=n
511 0.015 4.14 4.605 T m e v t  arsize_top=0 arsize_bot=0 is_shrink=n
512 0 4.91 5.408 T 0.02 0.02 e e staggered 0 0 0  is_shrink=n
512 0 3.94 4.593 T 0.02 0.02 e e staggered 0 0 0  is_shrink=n
512 0 3.99965 4.69 T 0.03543 0.01575 e e staggered 0 0 0  is_shrink=n
512 0 3.82559 4.72035 T 0.01575 0.03543 e e staggered 0 0 0  is_shrink=n
512 0.005 3.94 4.545 B m e v  arsize_top=0 arsize_bot=0 is_shrink=n
512 0.005 4.91 5.375 B m e v  arsize_top=0 arsize_bot=0 is_shrink=n
513 0 4.92 5.54685 T 0.02362 0.04134 e e staggered 0 0 0  is_shrink=n
513 0 4.91 5.442 T 0.02 0.02 e e staggered 0 0 0  is_shrink=n
513 0 4.86 5.442 T 0.02 0.02 e e staggered 0 0 0  is_shrink=n
513 0.015 4.91 5.485 T m e v t  arsize_top=0 arsize_bot=0 is_shrink=n
514 0 4.9574 5.65315 T 0.02362 0.04134 e e staggered 0 0 0  is_shrink=n
514 0 4.97 5.733 T 0.02 0.02 e e staggered 0 0 0  is_shrink=n
514 0.015 4.929 5.744 T m e v t  arsize_top=0 arsize_bot=0 is_shrink=n
515 0 4.97 5.767 T 0.02 0.02 e e staggered 0 0 0  is_shrink=n
515 0 5.06 5.733 T 0.02 0.02 e e staggered 0 0 0  is_shrink=n
515 0 5.07 5.64035 T 0.01575 0.03543 e e staggered 0 0 0  is_shrink=n
515 0.015 5.015 5.755 T m e v t  arsize_top=0 arsize_bot=0 is_shrink=n
516 0 4.76 5.71071 T 0.07874 0.03543 e e staggered 0 0 0  is_shrink=n
516 0 4.8826 5.65315 T 0.02362 0.04134 e e staggered 0 0 0  is_shrink=n
516 0 4.86 5.733 T 0.02 0.02 e e staggered 0 0 0  is_shrink=n
516 0.015 4.725 5.775 T m e v t  arsize_top=0 arsize_bot=0 is_shrink=n
517 0 4.585 5.78 T 0.02992 0.05 e e staggered 0 0 0  is_shrink=n
517 0 4.535 5.78 T 0.02992 0.05 e e staggered 0 0 0  is_shrink=n
517 0 5.025 5.467 T 0.02 0.02 e e staggered 0 0 0  is_shrink=n
517 0 5.075 5.467 T 0.02 0.02 e e staggered 0 0 0  is_shrink=n
517 0 5.125 5.467 T 0.02 0.02 e e staggered 0 0 0  is_shrink=n
517 0 5.04441 5.55965 T 0.01575 0.03543 e e staggered 0 0 0  is_shrink=n
517 0.015 4.665 5.48 T m e v t  arsize_top=0 arsize_bot=0 is_shrink=n
518 0.01378 0.725 -0.35 B e e  arsize_top=0 arsize_bot=0 is_shrink=n
518 0.01378 0.875 -0.35 B e e  arsize_top=0 arsize_bot=0 is_shrink=n
518 0.01378 1.025 -0.35 B e e  arsize_top=0 arsize_bot=0 is_shrink=n
518 0.01378 1.175 -0.35 B e e  arsize_top=0 arsize_bot=0 is_shrink=n
518 0.01378 1.325 -0.35 B e e  arsize_top=0 arsize_bot=0 is_shrink=n
519 0.01378 1.325 -0.25 B e e  arsize_top=0 arsize_bot=0 is_shrink=n
520 0.01378 0.875 -0.25 B e e  arsize_top=0 arsize_bot=0 is_shrink=n
521 0.01378 0.725 -0.25 B e e  arsize_top=0 arsize_bot=0 is_shrink=n
522 0.01378 1.175 -0.25 B e e  arsize_top=0 arsize_bot=0 is_shrink=n
523 0.01378 1.025 -0.25 B e e  arsize_top=0 arsize_bot=0 is_shrink=n
524 0.01378 0.74 6.26 B e e  arsize_top=0 arsize_bot=0 is_shrink=n
524 0.01378 0.74 6.36 B e e  arsize_top=0 arsize_bot=0 is_shrink=n
524 0.01378 0.965 6.26 B e e  arsize_top=0 arsize_bot=0 is_shrink=n
524 0.01378 0.965 6.36 B e e  arsize_top=0 arsize_bot=0 is_shrink=n
524 0.01378 1.64 6.26 B e e  arsize_top=0 arsize_bot=0 is_shrink=n
524 0.01378 1.64 6.36 B e e  arsize_top=0 arsize_bot=0 is_shrink=n
524 0.01378 1.415 6.26 B e e  arsize_top=0 arsize_bot=0 is_shrink=n
524 0.01378 1.415 6.36 B e e  arsize_top=0 arsize_bot=0 is_shrink=n
524 0.01378 1.19 6.26 B e e  arsize_top=0 arsize_bot=0 is_shrink=n
524 0.01378 1.19 6.36 B e e  arsize_top=0 arsize_bot=0 is_shrink=n
525 0.01378 1.74 6.36 B e e  arsize_top=0 arsize_bot=0 is_shrink=n
526 0.01378 1.74 6.26 B e e  arsize_top=0 arsize_bot=0 is_shrink=n
527 0.01378 1.065 6.36 B e e  arsize_top=0 arsize_bot=0 is_shrink=n
528 0.01378 1.065 6.26 B e e  arsize_top=0 arsize_bot=0 is_shrink=n
529 0.01378 0.84 6.36 B e e  arsize_top=0 arsize_bot=0 is_shrink=n
530 0.01378 0.84 6.26 B e e  arsize_top=0 arsize_bot=0 is_shrink=n
531 0.01378 1.515 6.36 B e e  arsize_top=0 arsize_bot=0 is_shrink=n
532 0.01378 1.515 6.26 B e e  arsize_top=0 arsize_bot=0 is_shrink=n
533 0.01378 1.29 6.36 B e e  arsize_top=0 arsize_bot=0 is_shrink=n
534 0.01378 1.29 6.26 B e e  arsize_top=0 arsize_bot=0 is_shrink=n

### steps/drc/layers/bd-1-4/features
#
#Feature symbol names
#
$0 r8

#
#Feature attribute names
#
@0 .geometry

#
#Feature attribute text strings
#
&0 V17D8AT30SM11

#
#Layer features
#
P 0.69348996 1.90611998 0 P 1 0;0=0
P 0.69348996 1.86611998 0 P 1 0;0=0
P 10.395 1.32555 0 P 1 0;0=0
P 10.395 1.28555 0 P 1 0;0=0
P 10.42445 1.395 0 P 1 0;0=0
P 10.46445 1.395 0 P 1 0;0=0
P 10.35543002 1.52156998 0 P 1 0;0=0
P 10.38371998 1.49328002 0 P 1 0;0=0
P 10.26 1.66445 0 P 1 0;0=0
P 10.26 1.70445 0 P 1 0;0=0
P 10.26025 1.82845 0 P 1 0;0=0
P 10.26025 1.86845 0 P 1 0;0=0
P 10.225 1.92645 0 P 1 0;0=0
P 10.225 1.96645 0 P 1 0;0=0
P 10.09 2.01655 0 P 1 0;0=0
P 10.09 2.05655 0 P 1 0;0=0
P 10.09 2.13095 0 P 1 0;0=0
P 10.09 2.17095 0 P 1 0;0=0
P 9.975 2.19955 0 P 1 0;0=0
P 9.975 2.23955 0 P 1 0;0=0
P 9.975 2.3358 0 P 1 0;0=0
P 9.975 2.3758 0 P 1 0;0=0
P 10.09 2.26825 0 P 1 0;0=0
P 10.09 2.30825 0 P 1 0;0=0
P 10.09 2.44335 0 P 1 0;0=0
P 10.09 2.40335 0 P 1 0;0=0
P 10.09 2.53845 0 P 1 0;0=0
P 10.09 2.57845 0 P 1 0;0=0
P 9.975 2.4709 0 P 1 0;0=0
P 9.975 2.5109 0 P 1 0;0=0
P 9.975 2.66445 0 P 1 0;0=0
P 9.975 2.62445 0 P 1 0;0=0
P 10.09 2.69655 0 P 1 0;0=0
P 10.09 2.73655 0 P 1 0;0=0
P 2.97721004 2.825 0 P 1 0;0=0
P 2.97721004 2.865 0 P 1 0;0=0
P 8.98115 2.825 0 P 1 0;0=0
P 8.98115 2.865 0 P 1 0;0=0

### steps/drc/layers/bd-1-9/features
#
#Feature symbol names
#
$0 r8

#
#Feature attribute names
#
@0 .geometry

#
#Feature attribute text strings
#
&0 V17D8AT30SM11

#
#Layer features
#
P 5.57531004 1.8108 0 P 1 0;0=0
P 5.57531004 1.8508 0 P 1 0;0=0
P 5.57531004 1.7118 0 P 1 0;0=0
P 5.57531004 1.6718 0 P 1 0;0=0
P 5.42048002 1.6433 0 P 1 0;0=0
P 5.42048002 1.6033 0 P 1 0;0=0
P 5.42048002 1.7396 0 P 1 0;0=0
P 5.42048002 1.7796 0 P 1 0;0=0
P 5.57531004 1.9469 0 P 1 0;0=0
P 5.57531004 1.9869 0 P 1 0;0=0
P 5.42048002 1.87835 0 P 1 0;0=0
P 5.42048002 1.91835 0 P 1 0;0=0
P 5.57531004 2.0878 0 P 1 0;0=0
P 5.57531004 2.1278 0 P 1 0;0=0
P 5.42048002 2.0147 0 P 1 0;0=0
P 5.42048002 2.0547 0 P 1 0;0=0
P 5.57531004 2.2232 0 P 1 0;0=0
P 5.57531004 2.2632 0 P 1 0;0=0
P 5.42048002 2.2908 0 P 1 0;0=0
P 5.42048002 2.3308 0 P 1 0;0=0
P 5.42048002 2.1554 0 P 1 0;0=0
P 5.42048002 2.1954 0 P 1 0;0=0
P 5.57531004 2.3586 0 P 1 0;0=0
P 5.57531004 2.3986 0 P 1 0;0=0
P 5.42048002 2.4262 0 P 1 0;0=0
P 5.42048002 2.4662 0 P 1 0;0=0
P 5.57531004 2.4978 0 P 1 0;0=0
P 5.57531004 2.5378 0 P 1 0;0=0
P 5.57531004 2.633 0 P 1 0;0=0
P 5.57531004 2.673 0 P 1 0;0=0
P 5.42048002 2.5654 0 P 1 0;0=0
P 5.42048002 2.6054 0 P 1 0;0=0
P 11.78316004 1.652 0 P 1 0;0=0
P 11.78316004 1.692 0 P 1 0;0=0
P 11.73316004 1.532 0 P 1 0;0=0
P 11.73316004 1.492 0 P 1 0;0=0
P 11.53316004 1.452 0 P 1 0;0=0
P 11.53316004 1.412 0 P 1 0;0=0
P 11.53316004 1.572 0 P 1 0;0=0
P 11.53316004 1.612 0 P 1 0;0=0
P 11.73316004 1.812 0 P 1 0;0=0
P 11.73316004 1.852 0 P 1 0;0=0
P 11.53316004 1.732 0 P 1 0;0=0
P 11.53316004 1.772 0 P 1 0;0=0
P 11.73316004 1.972 0 P 1 0;0=0
P 11.73316004 2.012 0 P 1 0;0=0
P 11.53316004 1.892 0 P 1 0;0=0
P 11.53316004 1.932 0 P 1 0;0=0
P 11.73316004 2.132 0 P 1 0;0=0
P 11.73316004 2.172 0 P 1 0;0=0
P 11.83316004 2.212 0 P 1 0;0=0
P 11.83316004 2.252 0 P 1 0;0=0
P 11.53316004 2.052 0 P 1 0;0=0
P 11.53316004 2.092 0 P 1 0;0=0
P 11.73316004 2.292 0 P 1 0;0=0
P 11.73316004 2.332 0 P 1 0;0=0
P 11.53316004 2.372 0 P 1 0;0=0
P 11.53316004 2.412 0 P 1 0;0=0
P 11.73316004 2.452 0 P 1 0;0=0
P 11.73316004 2.492 0 P 1 0;0=0
P 11.73316004 2.612 0 P 1 0;0=0
P 11.73316004 2.652 0 P 1 0;0=0
P 11.53316004 2.532 0 P 1 0;0=0
P 11.53316004 2.572 0 P 1 0;0=0

### steps/drc/layers/bd-12-4/features
#
#Feature symbol names
#
$0 r8

#
#Feature attribute names
#
@0 .geometry

#
#Feature attribute text strings
#
&0 V17D8AT30SM11

#
#Layer features
#
P 2.09606004 3.81615 0 P 1 0;0=0
P 3.09656998 5.0535 0 P 1 0;0=0
P 2.09606004 3.86615 0 P 1 0;0=0
P 3.13656998 5.0535 0 P 1 0;0=0
P 2.19606004 3.81615 0 P 1 0;0=0
P 3.02571004 4.667 0 P 1 0;0=0
P 2.19606004 3.86615 0 P 1 0;0=0
P 3.06571004 4.667 0 P 1 0;0=0
P 2.14606004 3.76615 0 P 1 0;0=0
P 3.02571004 5.165 0 P 1 0;0=0
P 2.14606004 3.81615 0 P 1 0;0=0
P 3.06571004 5.165 0 P 1 0;0=0
P 2.04606004 3.76615 0 P 1 0;0=0
P 2.88708002 4.667 0 P 1 0;0=0
P 2.04606004 3.81615 0 P 1 0;0=0
P 2.92708002 4.667 0 P 1 0;0=0
P 2.19606004 3.66615 0 P 1 0;0=0
P 2.81311004 4.78291998 0 P 1 0;0=0
P 2.19606004 3.71615 0 P 1 0;0=0
P 2.85311004 4.78291998 0 P 1 0;0=0
P 2.14606004 3.61615 0 P 1 0;0=0
P 2.88086998 5.17001998 0 P 1 0;0=0
P 2.14606004 3.66615 0 P 1 0;0=0
P 2.92086998 5.17001998 0 P 1 0;0=0
P 2.09606004 3.66615 0 P 1 0;0=0
P 2.74225 4.667 0 P 1 0;0=0
P 2.09606004 3.71615 0 P 1 0;0=0
P 2.78225 4.667 0 P 1 0;0=0
P 2.04606004 3.61615 0 P 1 0;0=0
P 2.74225 5.14 0 P 1 0;0=0
P 2.04606004 3.66615 0 P 1 0;0=0
P 2.78225 5.14 0 P 1 0;0=0
P 8.1 3.81615 0 P 1 0;0=0
P 9.10011004 5.0535 0 P 1 0;0=0
P 8.1 3.86615 0 P 1 0;0=0
P 9.14011004 5.0535 0 P 1 0;0=0
P 8.2 3.81615 0 P 1 0;0=0
P 9.02925 4.667 0 P 1 0;0=0
P 8.2 3.86615 0 P 1 0;0=0
P 9.06925 4.667 0 P 1 0;0=0
P 8.15 3.76615 0 P 1 0;0=0
P 9.02925 5.165 0 P 1 0;0=0
P 8.15 3.81615 0 P 1 0;0=0
P 9.06925 5.165 0 P 1 0;0=0
P 8.05 3.76615 0 P 1 0;0=0
P 8.89061998 4.667 0 P 1 0;0=0
P 8.05 3.81615 0 P 1 0;0=0
P 8.93061998 4.667 0 P 1 0;0=0
P 8.2 3.66615 0 P 1 0;0=0
P 8.81665 4.78291998 0 P 1 0;0=0
P 8.2 3.71615 0 P 1 0;0=0
P 8.85665 4.78291998 0 P 1 0;0=0
P 8.15 3.61615 0 P 1 0;0=0
P 8.88441004 5.17001998 0 P 1 0;0=0
P 8.15 3.66615 0 P 1 0;0=0
P 8.92441004 5.17001998 0 P 1 0;0=0
P 8.1 3.66615 0 P 1 0;0=0
P 8.74578996 4.667 0 P 1 0;0=0
P 8.1 3.71615 0 P 1 0;0=0
P 8.78578996 4.667 0 P 1 0;0=0
P 8.05 3.61615 0 P 1 0;0=0
P 8.74578996 5.14 0 P 1 0;0=0
P 8.05 3.66615 0 P 1 0;0=0
P 8.78578996 5.14 0 P 1 0;0=0
P 2.34606004 3.81615 0 P 1 0;0=0
P 3.27831004 5.22001998 0 P 1 0;0=0
P 2.34606004 3.86615 0 P 1 0;0=0
P 3.23831004 5.22001998 0 P 1 0;0=0
P 2.44606004 3.81615 0 P 1 0;0=0
P 3.20743996 4.78291998 0 P 1 0;0=0
P 2.44606004 3.86615 0 P 1 0;0=0
P 3.16743996 4.78291998 0 P 1 0;0=0
P 2.49606004 3.76615 0 P 1 0;0=0
P 3.34916998 5.1035 0 P 1 0;0=0
P 2.49606004 3.81615 0 P 1 0;0=0
P 3.30916998 5.1035 0 P 1 0;0=0
P 2.39606004 3.76615 0 P 1 0;0=0
P 3.27831004 4.642 0 P 1 0;0=0
P 2.39606004 3.81615 0 P 1 0;0=0
P 3.23831004 4.642 0 P 1 0;0=0
P 2.44606004 3.66615 0 P 1 0;0=0
P 3.42003996 4.78291998 0 P 1 0;0=0
P 2.44606004 3.71615 0 P 1 0;0=0
P 3.38003996 4.78291998 0 P 1 0;0=0
P 2.49606004 3.61615 0 P 1 0;0=0
P 3.56176998 5.14 0 P 1 0;0=0
P 2.49606004 3.66615 0 P 1 0;0=0
P 3.52176998 5.14 0 P 1 0;0=0
P 2.39606004 3.61615 0 P 1 0;0=0
P 3.49091004 4.587 0 P 1 0;0=0
P 2.39606004 3.66615 0 P 1 0;0=0
P 3.45091004 4.587 0 P 1 0;0=0
P 2.34606004 3.66615 0 P 1 0;0=0
P 3.56176998 4.71973002 0 P 1 0;0=0
P 2.34606004 3.71615 0 P 1 0;0=0
P 3.52176998 4.71973002 0 P 1 0;0=0
P 8.35 3.81615 0 P 1 0;0=0
P 9.28185 5.22001998 0 P 1 0;0=0
P 8.35 3.86615 0 P 1 0;0=0
P 9.24185 5.22001998 0 P 1 0;0=0
P 8.45 3.81615 0 P 1 0;0=0
P 9.21098002 4.78291998 0 P 1 0;0=0
P 8.45 3.86615 0 P 1 0;0=0
P 9.17098002 4.78291998 0 P 1 0;0=0
P 8.5 3.76615 0 P 1 0;0=0
P 9.35271004 5.1035 0 P 1 0;0=0
P 8.5 3.81615 0 P 1 0;0=0
P 9.31271004 5.1035 0 P 1 0;0=0
P 8.4 3.76615 0 P 1 0;0=0
P 9.28185 4.642 0 P 1 0;0=0
P 8.4 3.81615 0 P 1 0;0=0
P 9.24185 4.642 0 P 1 0;0=0
P 8.45 3.66615 0 P 1 0;0=0
P 9.42358002 4.78291998 0 P 1 0;0=0
P 8.45 3.71615 0 P 1 0;0=0
P 9.38358002 4.78291998 0 P 1 0;0=0
P 8.5 3.61615 0 P 1 0;0=0
P 9.56531004 5.14 0 P 1 0;0=0
P 8.5 3.66615 0 P 1 0;0=0
P 9.52531004 5.14 0 P 1 0;0=0
P 8.4 3.61615 0 P 1 0;0=0
P 9.49445 4.587 0 P 1 0;0=0
P 8.4 3.66615 0 P 1 0;0=0
P 9.45445 4.587 0 P 1 0;0=0
P 8.35 3.66615 0 P 1 0;0=0
P 9.56531004 4.71973002 0 P 1 0;0=0
P 8.35 3.71615 0 P 1 0;0=0
P 9.52531004 4.71973002 0 P 1 0;0=0

### steps/drc/layers/bd-12-6/features
#
#Feature symbol names
#
$0 r8

#
#Feature attribute names
#
@0 .geometry

#
#Feature attribute text strings
#
&0 V17D8AT30SM11

#
#Layer features
#
P 4.83268002 2.16615 0 P 1 0;0=0
P 4.88268002 2.16615 0 P 1 0;0=0
P 1.93196998 5.0535 0 P 1 0;0=0
P 1.99606004 3.46615 0 P 1 0;0=0
P 1.97196998 5.0535 0 P 1 0;0=0
P 1.99606004 3.51615 0 P 1 0;0=0
P 1.86111004 4.657 0 P 1 0;0=0
P 2.14606004 3.46615 0 P 1 0;0=0
P 1.90111004 4.657 0 P 1 0;0=0
P 2.14606004 3.51615 0 P 1 0;0=0
P 1.86111004 5.169 0 P 1 0;0=0
P 2.19606004 3.41615 0 P 1 0;0=0
P 1.90111004 5.169 0 P 1 0;0=0
P 2.19606004 3.46615 0 P 1 0;0=0
P 1.79025 4.78291998 0 P 1 0;0=0
P 2.09606004 3.41615 0 P 1 0;0=0
P 1.83025 4.78291998 0 P 1 0;0=0
P 2.09606004 3.46615 0 P 1 0;0=0
P 1.64851004 4.78291998 0 P 1 0;0=0
P 2.14606004 3.31615 0 P 1 0;0=0
P 1.68851004 4.78291998 0 P 1 0;0=0
P 2.14606004 3.36615 0 P 1 0;0=0
P 1.6485 5.0535 0 P 1 0;0=0
P 2.19606004 3.26615 0 P 1 0;0=0
P 1.6885 5.0535 0 P 1 0;0=0
P 2.19606004 3.31615 0 P 1 0;0=0
P 1.57765 4.707 0 P 1 0;0=0
P 2.09606004 3.26615 0 P 1 0;0=0
P 1.61765 4.707 0 P 1 0;0=0
P 2.09606004 3.31615 0 P 1 0;0=0
P 1.57765 5.169 0 P 1 0;0=0
P 2.04606004 3.31615 0 P 1 0;0=0
P 1.61765 5.169 0 P 1 0;0=0
P 2.04606004 3.36615 0 P 1 0;0=0
P 7.93551004 5.0535 0 P 1 0;0=0
P 8 3.46615 0 P 1 0;0=0
P 7.97551004 5.0535 0 P 1 0;0=0
P 8 3.51615 0 P 1 0;0=0
P 7.86465 4.657 0 P 1 0;0=0
P 8.15 3.46615 0 P 1 0;0=0
P 7.90465 4.657 0 P 1 0;0=0
P 8.15 3.51615 0 P 1 0;0=0
P 7.86465 5.169 0 P 1 0;0=0
P 8.2 3.41615 0 P 1 0;0=0
P 7.90465 5.169 0 P 1 0;0=0
P 8.2 3.46615 0 P 1 0;0=0
P 7.79378996 4.78291998 0 P 1 0;0=0
P 8.1 3.41615 0 P 1 0;0=0
P 7.83378996 4.78291998 0 P 1 0;0=0
P 8.1 3.46615 0 P 1 0;0=0
P 7.65205 4.78291998 0 P 1 0;0=0
P 8.15 3.31615 0 P 1 0;0=0
P 7.69205 4.78291998 0 P 1 0;0=0
P 8.15 3.36615 0 P 1 0;0=0
P 7.65203996 5.0535 0 P 1 0;0=0
P 8.2 3.26615 0 P 1 0;0=0
P 7.69203996 5.0535 0 P 1 0;0=0
P 8.2 3.31615 0 P 1 0;0=0
P 7.58118996 4.707 0 P 1 0;0=0
P 8.1 3.26615 0 P 1 0;0=0
P 7.62118996 4.707 0 P 1 0;0=0
P 8.1 3.31615 0 P 1 0;0=0
P 7.58118996 5.169 0 P 1 0;0=0
P 8.05 3.31615 0 P 1 0;0=0
P 7.62118996 5.169 0 P 1 0;0=0
P 8.05 3.36615 0 P 1 0;0=0
P 2.11371004 5.169 0 P 1 0;0=0
P 2.39606004 3.46615 0 P 1 0;0=0
P 2.07371004 5.169 0 P 1 0;0=0
P 2.39606004 3.51615 0 P 1 0;0=0
P 2.06853002 4.66688996 0 P 1 0;0=0
P 2.49606004 3.46615 0 P 1 0;0=0
P 2.02853002 4.66688996 0 P 1 0;0=0
P 2.49606004 3.51615 0 P 1 0;0=0
P 2.18456998 5.0535 0 P 1 0;0=0
P 2.44606004 3.41615 0 P 1 0;0=0
P 2.14456998 5.0535 0 P 1 0;0=0
P 2.44606004 3.46615 0 P 1 0;0=0
P 2.11371004 4.78291998 0 P 1 0;0=0
P 2.34606004 3.41615 0 P 1 0;0=0
P 2.07371004 4.78291998 0 P 1 0;0=0
P 2.34606004 3.46615 0 P 1 0;0=0
P 2.25543996 4.78291998 0 P 1 0;0=0
P 2.49606004 3.31615 0 P 1 0;0=0
P 2.21543996 4.78291998 0 P 1 0;0=0
P 2.49606004 3.36615 0 P 1 0;0=0
P 2.39716998 5.115 0 P 1 0;0=0
P 2.44606004 3.26615 0 P 1 0;0=0
P 2.35716998 5.115 0 P 1 0;0=0
P 2.44606004 3.31615 0 P 1 0;0=0
P 2.25855 4.667 0 P 1 0;0=0
P 2.39606004 3.31615 0 P 1 0;0=0
P 2.21855 4.667 0 P 1 0;0=0
P 2.39606004 3.36615 0 P 1 0;0=0
P 2.34606004 3.26615 0 P 1 0;0=0
P 2.39716998 4.742 0 P 1 0;0=0
P 2.34606004 3.31615 0 P 1 0;0=0
P 2.35716998 4.742 0 P 1 0;0=0
P 8.11725 5.169 0 P 1 0;0=0
P 8.4 3.46615 0 P 1 0;0=0
P 8.07725 5.169 0 P 1 0;0=0
P 8.4 3.51615 0 P 1 0;0=0
P 8.07206998 4.66688996 0 P 1 0;0=0
P 8.5 3.46615 0 P 1 0;0=0
P 8.03206998 4.66688996 0 P 1 0;0=0
P 8.5 3.51615 0 P 1 0;0=0
P 8.18811004 5.0535 0 P 1 0;0=0
P 8.45 3.41615 0 P 1 0;0=0
P 8.14811004 5.0535 0 P 1 0;0=0
P 8.45 3.46615 0 P 1 0;0=0
P 8.11725 4.78291998 0 P 1 0;0=0
P 8.35 3.41615 0 P 1 0;0=0
P 8.07725 4.78291998 0 P 1 0;0=0
P 8.35 3.46615 0 P 1 0;0=0
P 8.25898002 4.78291998 0 P 1 0;0=0
P 8.5 3.31615 0 P 1 0;0=0
P 8.21898002 4.78291998 0 P 1 0;0=0
P 8.5 3.36615 0 P 1 0;0=0
P 8.40071004 5.115 0 P 1 0;0=0
P 8.45 3.26615 0 P 1 0;0=0
P 8.36071004 5.115 0 P 1 0;0=0
P 8.45 3.31615 0 P 1 0;0=0
P 8.26208996 4.667 0 P 1 0;0=0
P 8.4 3.31615 0 P 1 0;0=0
P 8.22208996 4.667 0 P 1 0;0=0
P 8.4 3.36615 0 P 1 0;0=0
P 8.35 3.26615 0 P 1 0;0=0
P 8.40071004 4.742 0 P 1 0;0=0
P 8.35 3.31615 0 P 1 0;0=0
P 8.36071004 4.742 0 P 1 0;0=0
P 4.73268002 1.86615 0 P 1 0;0=0
P 4.73268002 1.91615 0 P 1 0;0=0
P 4.68268002 1.91615 0 P 1 0;0=0
P 4.68268002 1.96615 0 P 1 0;0=0
P 4.63268002 1.86615 0 P 1 0;0=0
P 4.63268002 1.91615 0 P 1 0;0=0
P 4.58268002 1.91615 0 P 1 0;0=0
P 4.58268002 1.96615 0 P 1 0;0=0
P 4.73268002 2.01615 0 P 1 0;0=0
P 4.73268002 2.06615 0 P 1 0;0=0
P 4.63268002 2.01615 0 P 1 0;0=0
P 4.63268002 2.06615 0 P 1 0;0=0
P 4.58268002 2.06615 0 P 1 0;0=0
P 4.58268002 2.11615 0 P 1 0;0=0
P 4.68268002 2.06615 0 P 1 0;0=0
P 4.68268002 2.11615 0 P 1 0;0=0
P 4.73268002 2.26615 0 P 1 0;0=0
P 4.73268002 2.31615 0 P 1 0;0=0
P 4.68268002 2.21615 0 P 1 0;0=0
P 4.68268002 2.26615 0 P 1 0;0=0
P 4.58268002 2.21615 0 P 1 0;0=0
P 4.58268002 2.26615 0 P 1 0;0=0
P 4.63268002 2.26615 0 P 1 0;0=0
P 4.63268002 2.31615 0 P 1 0;0=0
P 4.68268002 2.36615 0 P 1 0;0=0
P 4.68268002 2.41615 0 P 1 0;0=0
P 4.58268002 2.36615 0 P 1 0;0=0
P 4.58268002 2.41615 0 P 1 0;0=0
P 4.63268002 2.41615 0 P 1 0;0=0
P 4.63268002 2.46615 0 P 1 0;0=0
P 4.73268002 2.41615 0 P 1 0;0=0
P 4.73268002 2.46615 0 P 1 0;0=0
P 3.42003996 5.22001998 0 P 1 0;0=0
P 3.38003996 5.22001998 0 P 1 0;0=0
P 9.42358002 5.22001998 0 P 1 0;0=0
P 9.38358002 5.22001998 0 P 1 0;0=0

### steps/drc/layers/c-paste/features
#
#Feature symbol names
#
$0 r2
$1 r5
$2 r6
$3 r15
$4 r25.2
$5 r30
$6 r46.06
$7 s20
$8 s30
$9 s33.46
$10 s50
$11 rect100x125.98
$12 rect11.02x43.31
$13 rect13.78x51.18
$14 rect15.75x35.43
$15 rect15.75x66.93
$16 rect161.42x78.74
$17 rect23.62x37.4
$18 rect23.62x41.34
$19 rect236.22x1614.17
$20 rect25.2x72.44
$21 rect29.92x50
$22 rect31.5x7.88xr3.94x14
$23 rect31.5x7.88xr3.94x23
$24 rect33.46x31.5
$25 rect35.43x15.75
$26 rect39.37x108.27
$27 rect7.88x31.5xr3.94x12
$28 rect7.88x31.5xr3.94x34
$29 rect72.83x137.8
$30 rect74.8x66.93
$31 rect78.74x157.48
$32 rect78.74x35.43
$33 rect78.74x43.31

#
#Feature attribute names
#
@0 .nomenclature
@1 .smd
@2 .test_point
@3 .geometry
@4 .string
@5 .pad_usage
@6 .string_angle

#
#Feature attribute text strings
#
&0 R0_35X1_3
&1 S0_508
&2 R1_05X0_6
&3 ICT-TPT30TPM
&4 R1_27X0_76
&5 R0_9X0_4
&6 R0_9X2
&7 R1_1X0_28
&8 C0_64
&9 R2X1_1
&10 R1X2_75
&11 SP-SC0_2X0_8TI-B
&12 R1_7X0_4
&13 S1_27
&14 R1_7X1_9
&15 S0_762
&16 R1_85X3_5
&17 R4X2
&18 R3_2X2_54
&19 R0_95X0_6
&20 R0_64X1_84
&21 R4_1X2
&22 C1_17P0_76TPM
&23 R6X41
&24 E-C40SM100PM5-G
&25 S0TM0_85
&26 R0TM0_85X0_8
&27 SHEET
&28 TITLE
&29 SCALE 1:1
&30 LAYER
&31 OF
&32 ART
&33 -
&34 1
&35 SOLDER PASTE (TOP)
&36 Barreleye G2 SXM2-Riser
&37 A1
&38 DATE OCT/27/2017

#
#Layer features
#
P 7.96733002 4.85788002 13 P 0 0;1,3=0,5=0
P 7.94371004 4.85788002 13 P 0 0;1,3=0,5=0
P 1.96378996 4.85788002 13 P 0 0;1,3=0,5=0
P 1.94016998 4.85788002 13 P 0 0;1,3=0,5=0
P 4.97 5.733 7 P 0 0;1,3=1,5=0
P 4.9574 5.65315 18 P 0 0;1,3=2,5=0
P 4.929 5.744 5 P 0 0;2,3=3,5=1
P 4.535 5.78 21 P 0 0;1,3=4,5=0
P 4.585 5.78 21 P 0 0;1,3=4,5=0
P 5.04441004 5.55965 14 P 0 0;1,3=5,5=0
P 5.125 5.467 7 P 0 0;1,3=1,5=0
P 5.025 5.467 7 P 0 0;1,3=1,5=0
P 5.075 5.467 7 P 0 0;1,3=1,5=0
P 4.665 5.48 5 P 0 0;2,3=3,5=1
P 4.97 5.767 7 P 0 0;1,3=1,5=0
P 5.06 5.733 7 P 0 0;1,3=1,5=0
P 5.07 5.64035 14 P 0 0;1,3=5,5=0
P 5.015 5.755 5 P 0 0;2,3=3,5=1
P 4.92 5.54685 18 P 0 0;1,3=2,5=0
P 4.91 5.442 7 P 0 0;1,3=1,5=0
P 4.86 5.442 7 P 0 0;1,3=1,5=0
P 4.91 5.485 5 P 0 0;2,3=3,5=1
P 4.8826 5.54685 18 P 0 0;1,3=2,5=0
P 4.81 5.442 7 P 0 0;1,3=1,5=0
P 4.76 5.442 7 P 0 0;1,3=1,5=0
P 4.81 5.485 5 P 0 0;2,3=3,5=1
P 4.86 5.733 7 P 0 0;1,3=1,5=0
P 4.76 5.71071004 32 P 0 0;1,3=6,5=0
P 4.8826 5.65315 18 P 0 0;1,3=2,5=0
P 4.725 5.775 5 P 0 0;2,3=3,5=1
P 0.97 4.993 7 P 0 0;1,3=1,5=0
P 0.73 5.027 7 P 0 0;1,3=1,5=0
P 0.73 5.113 7 P 0 0;1,3=1,5=0
P 0.79046998 5.1239 12 P 0 0;1,3=7,5=0
P 0.68 5.113 7 P 0 0;1,3=1,5=0
P 0.73 5.07 5 P 0 0;2,3=3,5=1
P 4.08035 4.66441004 25 P 0 0;1,3=5,5=0
P 4.097 4.59 7 P 0 0;1,3=1,5=0
P 4.14 4.605 5 P 0 0;2,3=3,5=1
P 2.07106004 3.54115 4 P 0 0;1,3=8,5=0
P 8.075 3.54115 4 P 0 0;1,3=8,5=0
P 6.38348996 4.99705 7 P 0 0;1,3=1,5=0
P 3.82558996 4.72035 14 P 0 0;1,3=5,5=0
P 3.94 4.593 7 P 0 0;1,3=1,5=0
P 3.99965 4.69 25 P 0 0;1,3=5,5=0
P 4.91 5.408 7 P 0 0;1,3=1,5=0
P 4.01676998 5.68 33 P 0 0;1,3=9,5=0
P 9.98 4.577 7 P 0 0;1,3=1,5=0
P 9.97441004 4.64965 14 P 0 0;1,3=5,5=0
P 9.91 4.577 7 P 0 0;1,3=1,5=0
P 9.91 4.633 7 P 0 0;1,3=1,5=0
P 9.865 4.635 5 P 0 0;2,3=3,5=1
P 4.01676998 5.78 33 P 0 0;1,3=9,5=0
P 3.62 4.517 7 P 0 0;1,3=1,5=0
P 3.67 4.517 7 P 0 0;1,3=1,5=0
P 3.64441004 4.58965 14 P 0 0;1,3=5,5=0
P 3.57 4.517 7 P 0 0;1,3=1,5=0
P 3.925 5.78 5 P 0 0;2,3=3,5=1
P 1.04 5.823 7 P 0 0;1,3=1,5=0
P 1.04428996 5.70373996 26 P 0 0;1,3=10,5=0
P 3.67 4.67035 14 P 0 0;1,3=5,5=0
P 4.01676998 5.48 33 P 0 0;1,3=9,5=0
P 4.01676998 5.58 33 P 0 0;1,3=9,5=0
P 1.12 5.823 7 P 0 0;1,3=1,5=0
P 1.12303002 5.70373996 26 P 0 0;1,3=10,5=0
P 10 4.73035 14 P 0 0;1,3=5,5=0
P 0.97 5.127 7 P 0 0;1,3=1,5=0
P 0.97441004 5.20965 14 P 0 0;1,3=5,5=0
P 0.929 5.037 5 P 0 0;2,3=3,5=1
P 1 5.29035 14 P 0 0;1,3=5,5=0
P 1.044 5.383 7 P 0 0;1,3=1,5=0
P 0.996 5.383 7 P 0 0;1,3=1,5=0
P 1.043 5.343 5 P 0 0;2,3=3,5=1
P 6.55228996 4.94855 22 P 0 0;1,3=11,5=0
P 6.45818996 4.99705 7 P 0 0;1,3=1,5=0
P 11.06161004 3.79115 4 P 0 0;1,3=8,5=0
P 11.01161004 2.19115 4 P 0 0;1,3=8,5=0
P 3.89 4.717 7 P 0 0;1,3=1,5=0
P 3.8899 4.79498996 7 P 0 0;1,3=1,5=0
P 4.90768002 2.44115 4 P 0 0;1,3=8,5=0
P 4.90768002 2.49115 4 P 0 0;1,3=8,5=0
P 7.2926 5.09151004 7 P 0 0;1,3=1,5=0
P 7.3054 4.9602 15 P 0 0;1,3=12,5=0
P 7.3426 5.09151004 7 P 0 0;1,3=1,5=0
P 7.2426 5.09151004 7 P 0 0;1,3=1,5=0
P 7.2798 4.9602 15 P 0 0;1,3=12,5=0
P 7.1926 5.09151004 7 P 0 0;1,3=1,5=0
P 3.4591 4.97913996 13 P 0 0;1,3=0,5=0
P 1.30186004 4.9602 15 P 0 0;1,3=12,5=0
P 1.28906004 5.09151004 7 P 0 0;1,3=1,5=0
P 1.33906004 5.09151004 7 P 0 0;1,3=1,5=0
P 1.27626004 4.9602 15 P 0 0;1,3=12,5=0
P 1.23906004 5.09151004 7 P 0 0;1,3=1,5=0
P 1.18906004 5.09151004 7 P 0 0;1,3=1,5=0
P 9.46263996 4.97913996 13 P 0 0;1,3=0,5=0
P 4.70768002 2.39115 4 P 0 0;1,3=8,5=0
P 4.60768002 2.39115 4 P 0 0;1,3=8,5=0
P 4.65768002 2.44115 4 P 0 0;1,3=8,5=0
P 4.75768002 2.29115 4 P 0 0;1,3=8,5=0
P 4.75768002 2.44115 4 P 0 0;1,3=8,5=0
P 4.70768002 2.24115 4 P 0 0;1,3=8,5=0
P 4.65768002 2.29115 4 P 0 0;1,3=8,5=0
P 4.60768002 2.09115 4 P 0 0;1,3=8,5=0
P 4.60768002 2.14115 4 P 0 0;1,3=8,5=0
P 4.65768002 1.89115 4 P 0 0;1,3=8,5=0
P 4.60768002 1.99115 4 P 0 0;1,3=8,5=0
P 4.70768002 2.09115 4 P 0 0;1,3=8,5=0
P 4.60768002 1.94115 4 P 0 0;1,3=8,5=0
P 4.65768002 1.94115 4 P 0 0;1,3=8,5=0
P 4.70768002 2.14115 4 P 0 0;1,3=8,5=0
P 4.70768002 1.94115 4 P 0 0;1,3=8,5=0
P 4.70768002 1.99115 4 P 0 0;1,3=8,5=0
P 4.70768002 2.44115 4 P 0 0;1,3=8,5=0
P 4.75768002 2.49115 4 P 0 0;1,3=8,5=0
P 4.65768002 2.49115 4 P 0 0;1,3=8,5=0
P 4.60768002 2.44115 4 P 0 0;1,3=8,5=0
P 4.70768002 2.29115 4 P 0 0;1,3=8,5=0
P 4.75768002 2.34115 4 P 0 0;1,3=8,5=0
P 4.65768002 2.34115 4 P 0 0;1,3=8,5=0
P 4.60768002 2.29115 4 P 0 0;1,3=8,5=0
P 4.75768002 1.94115 4 P 0 0;1,3=8,5=0
P 4.75768002 1.89115 4 P 0 0;1,3=8,5=0
P 4.60768002 2.24115 4 P 0 0;1,3=8,5=0
P 4.75768002 2.09115 4 P 0 0;1,3=8,5=0
P 4.75768002 2.04115 4 P 0 0;1,3=8,5=0
P 4.65768002 2.04115 4 P 0 0;1,3=8,5=0
P 4.65768002 2.09115 4 P 0 0;1,3=8,5=0
P 6.74208996 4.7052 10 P 0 0;1,3=13,5=0
P 6.87618996 4.71823002 30 P 0 0;1,3=14,5=0
P 6.83118996 4.81705 10 P 0 0;1,3=13,5=0
P 6.71318996 4.77205 7 P 0 0;1,3=1,5=0
P 6.69008996 4.88555 23 P 0 0;1,3=11,5=0
P 6.69008996 4.86980994 23 P 0 0;1,3=11,5=0
P 6.69008996 4.85405994 23 P 0 0;1,3=11,5=0
P 6.63693996 5.00563002 28 P 0 0;1,3=11,5=0
P 6.65818996 5.09705 7 P 0 0;1,3=1,5=0
P 6.45818996 5.04705 7 P 0 0;1,3=1,5=0
P 6.45818996 5.09705 7 P 0 0;1,3=1,5=0
P 6.55228996 4.96428996 22 P 0 0;1,3=11,5=0
P 6.55228996 4.9328 22 P 0 0;1,3=11,5=0
P 6.45818996 4.94705 7 P 0 0;1,3=1,5=0
P 6.55228996 4.98003996 22 P 0 0;1,3=11,5=0
P 6.53918996 5.09705 7 P 0 0;1,3=1,5=0
P 6.81218996 4.94705 8 P 0 0;1,3=15,5=0
P 6.69008996 4.9328 23 P 0 0;1,3=11,5=0
P 6.51718996 4.66705 8 P 0 0;1,3=15,5=0
P 6.51618996 4.72305 8 P 0 0;1,3=15,5=0
P 6.52 4.605 5 P 0 0;2,3=3,5=1
P 6.38318996 4.94705 7 P 0 0;1,3=1,5=0
P 6.42418996 4.94705 7 P 0 0;1,3=1,5=0
P 6.81218996 4.88705 8 P 0 0;1,3=15,5=0
P 6.69008996 4.91705 23 P 0 0;1,3=11,5=0
P 6.755 5.13 5 P 0 0;2,3=3,5=1
P 5.49093996 4.5861 7 P 0 0;1,3=1,5=0
P 6.65268996 5.00563002 28 P 0 0;1,3=11,5=0
P 6.71 5.087 7 P 0 0;1,3=1,5=0
P 6.755 5.087 7 P 0 0;1,3=1,5=0
P 6.69008996 4.94855 23 P 0 0;1,3=11,5=0
P 6.57518996 4.66705 8 P 0 0;1,3=15,5=0
P 6.57618996 4.73505 7 P 0 0;1,3=1,5=0
P 6.57518996 4.605 5 P 0 0;2,3=3,5=1
P 6.69008996 4.98003996 23 P 0 0;1,3=11,5=0
P 6.71 5.053 7 P 0 0;1,3=1,5=0
P 6.755 5.053 7 P 0 0;1,3=1,5=0
P 6.803 5 7 P 0 0;1,3=1,5=0
P 6.8 5.045 5 P 0 0;2,3=3,5=1
P 6.43043996 4.77205 29 P 0 0;1,3=16,5=0
P 6.34918996 4.94705 7 P 0 0;1,3=1,5=0
P 6.51618996 4.78105 8 P 0 0;1,3=15,5=0
P 6.55228996 4.9013 22 P 0 0;1,3=11,5=0
P 6.55228996 4.88555 22 P 0 0;1,3=11,5=0
P 6.55228996 4.86980994 22 P 0 0;1,3=11,5=0
P 6.55228996 4.85405994 22 P 0 0;1,3=11,5=0
P 5.00768002 1.94115 4 P 0 0;1,3=8,5=0
P 5.00768002 2.09115 4 P 0 0;1,3=8,5=0
P 5.05768002 2.29115 4 P 0 0;1,3=8,5=0
P 10.61161004 1.94115 4 P 0 0;1,3=8,5=0
P 10.66161004 3.09115 4 P 0 0;1,3=8,5=0
P 10.61161004 3.09115 4 P 0 0;1,3=8,5=0
P 10.61161004 2.99115 4 P 0 0;1,3=8,5=0
P 10.66161004 2.99115 4 P 0 0;1,3=8,5=0
P 10.61161004 2.94115 4 P 0 0;1,3=8,5=0
P 10.66161004 2.94115 4 P 0 0;1,3=8,5=0
P 10.81161004 3.09115 4 P 0 0;1,3=8,5=0
P 10.81161004 2.99115 4 P 0 0;1,3=8,5=0
P 10.86161004 3.09115 4 P 0 0;1,3=8,5=0
P 10.86161004 2.99115 4 P 0 0;1,3=8,5=0
P 10.71161004 3.09115 4 P 0 0;1,3=8,5=0
P 10.76161004 3.09115 4 P 0 0;1,3=8,5=0
P 10.71161004 2.99115 4 P 0 0;1,3=8,5=0
P 10.76161004 2.99115 4 P 0 0;1,3=8,5=0
P 10.81161004 2.94115 4 P 0 0;1,3=8,5=0
P 10.86161004 2.94115 4 P 0 0;1,3=8,5=0
P 10.71161004 2.94115 4 P 0 0;1,3=8,5=0
P 10.76161004 2.94115 4 P 0 0;1,3=8,5=0
P 11.01161004 3.09115 4 P 0 0;1,3=8,5=0
P 11.01161004 2.99115 4 P 0 0;1,3=8,5=0
P 11.06161004 3.09115 4 P 0 0;1,3=8,5=0
P 11.06161004 2.99115 4 P 0 0;1,3=8,5=0
P 10.96161004 3.09115 4 P 0 0;1,3=8,5=0
P 10.91161004 3.09115 4 P 0 0;1,3=8,5=0
P 10.96161004 2.99115 4 P 0 0;1,3=8,5=0
P 10.91161004 2.99115 4 P 0 0;1,3=8,5=0
P 11.01161004 2.94115 4 P 0 0;1,3=8,5=0
P 11.06161004 2.94115 4 P 0 0;1,3=8,5=0
P 10.96161004 2.94115 4 P 0 0;1,3=8,5=0
P 10.91161004 2.94115 4 P 0 0;1,3=8,5=0
P 10.66161004 3.29115 4 P 0 0;1,3=8,5=0
P 10.61161004 3.24115 4 P 0 0;1,3=8,5=0
P 10.61161004 3.29115 4 P 0 0;1,3=8,5=0
P 10.66161004 3.24115 4 P 0 0;1,3=8,5=0
P 10.66161004 3.14115 4 P 0 0;1,3=8,5=0
P 10.61161004 3.14115 4 P 0 0;1,3=8,5=0
P 10.81161004 3.24115 4 P 0 0;1,3=8,5=0
P 10.81161004 3.29115 4 P 0 0;1,3=8,5=0
P 10.86161004 3.29115 4 P 0 0;1,3=8,5=0
P 10.86161004 3.24115 4 P 0 0;1,3=8,5=0
P 10.76161004 3.29115 4 P 0 0;1,3=8,5=0
P 10.76161004 3.24115 4 P 0 0;1,3=8,5=0
P 10.71161004 3.24115 4 P 0 0;1,3=8,5=0
P 10.71161004 3.29115 4 P 0 0;1,3=8,5=0
P 10.81161004 3.14115 4 P 0 0;1,3=8,5=0
P 10.86161004 3.14115 4 P 0 0;1,3=8,5=0
P 10.76161004 3.14115 4 P 0 0;1,3=8,5=0
P 10.71161004 3.14115 4 P 0 0;1,3=8,5=0
P 11.01161004 3.24115 4 P 0 0;1,3=8,5=0
P 11.01161004 3.29115 4 P 0 0;1,3=8,5=0
P 11.06161004 3.24115 4 P 0 0;1,3=8,5=0
P 11.06161004 3.29115 4 P 0 0;1,3=8,5=0
P 10.96161004 3.29115 4 P 0 0;1,3=8,5=0
P 10.96161004 3.24115 4 P 0 0;1,3=8,5=0
P 10.91161004 3.24115 4 P 0 0;1,3=8,5=0
P 10.91161004 3.29115 4 P 0 0;1,3=8,5=0
P 11.01161004 3.14115 4 P 0 0;1,3=8,5=0
P 11.06161004 3.14115 4 P 0 0;1,3=8,5=0
P 10.96161004 3.14115 4 P 0 0;1,3=8,5=0
P 10.91161004 3.14115 4 P 0 0;1,3=8,5=0
P 10.61161004 3.59115 4 P 0 0;1,3=8,5=0
P 10.66161004 3.59115 4 P 0 0;1,3=8,5=0
P 10.61161004 3.54115 4 P 0 0;1,3=8,5=0
P 10.66161004 3.54115 4 P 0 0;1,3=8,5=0
P 10.61161004 3.44115 4 P 0 0;1,3=8,5=0
P 10.66161004 3.39115 4 P 0 0;1,3=8,5=0
P 10.66161004 3.44115 4 P 0 0;1,3=8,5=0
P 10.61161004 3.39115 4 P 0 0;1,3=8,5=0
P 10.81161004 3.59115 4 P 0 0;1,3=8,5=0
P 10.81161004 3.54115 4 P 0 0;1,3=8,5=0
P 10.86161004 3.59115 4 P 0 0;1,3=8,5=0
P 10.86161004 3.54115 4 P 0 0;1,3=8,5=0
P 10.76161004 3.59115 4 P 0 0;1,3=8,5=0
P 10.71161004 3.59115 4 P 0 0;1,3=8,5=0
P 10.76161004 3.54115 4 P 0 0;1,3=8,5=0
P 10.71161004 3.54115 4 P 0 0;1,3=8,5=0
P 10.81161004 3.44115 4 P 0 0;1,3=8,5=0
P 10.81161004 3.39115 4 P 0 0;1,3=8,5=0
P 10.86161004 3.39115 4 P 0 0;1,3=8,5=0
P 10.86161004 3.44115 4 P 0 0;1,3=8,5=0
P 10.76161004 3.39115 4 P 0 0;1,3=8,5=0
P 10.71161004 3.39115 4 P 0 0;1,3=8,5=0
P 10.71161004 3.44115 4 P 0 0;1,3=8,5=0
P 10.76161004 3.44115 4 P 0 0;1,3=8,5=0
P 11.01161004 3.59115 4 P 0 0;1,3=8,5=0
P 11.01161004 3.54115 4 P 0 0;1,3=8,5=0
P 11.06161004 3.59115 4 P 0 0;1,3=8,5=0
P 11.06161004 3.54115 4 P 0 0;1,3=8,5=0
P 10.96161004 3.59115 4 P 0 0;1,3=8,5=0
P 10.91161004 3.59115 4 P 0 0;1,3=8,5=0
P 10.96161004 3.54115 4 P 0 0;1,3=8,5=0
P 10.91161004 3.54115 4 P 0 0;1,3=8,5=0
P 11.01161004 3.44115 4 P 0 0;1,3=8,5=0
P 11.01161004 3.39115 4 P 0 0;1,3=8,5=0
P 11.06161004 3.44115 4 P 0 0;1,3=8,5=0
P 11.06161004 3.39115 4 P 0 0;1,3=8,5=0
P 10.96161004 3.44115 4 P 0 0;1,3=8,5=0
P 10.96161004 3.39115 4 P 0 0;1,3=8,5=0
P 10.91161004 3.44115 4 P 0 0;1,3=8,5=0
P 10.91161004 3.39115 4 P 0 0;1,3=8,5=0
P 10.61161004 3.84115 4 P 0 0;1,3=8,5=0
P 10.66161004 3.84115 4 P 0 0;1,3=8,5=0
P 10.61161004 3.74115 4 P 0 0;1,3=8,5=0
P 10.66161004 3.74115 4 P 0 0;1,3=8,5=0
P 10.61161004 3.69115 4 P 0 0;1,3=8,5=0
P 10.66161004 3.69115 4 P 0 0;1,3=8,5=0
P 10.81161004 3.84115 4 P 0 0;1,3=8,5=0
P 10.81161004 3.74115 4 P 0 0;1,3=8,5=0
P 10.86161004 3.84115 4 P 0 0;1,3=8,5=0
P 10.86161004 3.74115 4 P 0 0;1,3=8,5=0
P 10.76161004 3.84115 4 P 0 0;1,3=8,5=0
P 10.71161004 3.84115 4 P 0 0;1,3=8,5=0
P 10.76161004 3.74115 4 P 0 0;1,3=8,5=0
P 10.71161004 3.74115 4 P 0 0;1,3=8,5=0
P 10.81161004 3.69115 4 P 0 0;1,3=8,5=0
P 10.86161004 3.69115 4 P 0 0;1,3=8,5=0
P 10.76161004 3.69115 4 P 0 0;1,3=8,5=0
P 10.71161004 3.69115 4 P 0 0;1,3=8,5=0
P 11.01161004 3.84115 4 P 0 0;1,3=8,5=0
P 11.01161004 3.74115 4 P 0 0;1,3=8,5=0
P 11.06161004 3.84115 4 P 0 0;1,3=8,5=0
P 11.06161004 3.74115 4 P 0 0;1,3=8,5=0
P 10.96161004 3.84115 4 P 0 0;1,3=8,5=0
P 10.91161004 3.84115 4 P 0 0;1,3=8,5=0
P 10.96161004 3.74115 4 P 0 0;1,3=8,5=0
P 10.91161004 3.74115 4 P 0 0;1,3=8,5=0
P 11.01161004 3.69115 4 P 0 0;1,3=8,5=0
P 11.06161004 3.69115 4 P 0 0;1,3=8,5=0
P 10.96161004 3.69115 4 P 0 0;1,3=8,5=0
P 10.91161004 3.69115 4 P 0 0;1,3=8,5=0
P 10.36698996 4.74133996 31 P 0 0;1,3=17,5=0
P 10.75698996 4.74133996 31 P 0 0;1,3=17,5=0
P 11.10998996 4.75636998 11 P 0 0;1,3=18,5=0
P 5.05768002 2.09115 4 P 0 0;1,3=8,5=0
P 10.61161004 2.39115 4 P 0 0;1,3=8,5=0
P 11.06161004 2.39115 4 P 0 0;1,3=8,5=0
P 5.05768002 2.14115 4 P 0 0;1,3=8,5=0
P 11.06161004 2.44115 4 P 0 0;1,3=8,5=0
P 10.61161004 1.99115 4 P 0 0;1,3=8,5=0
P 10.96161004 2.44115 4 P 0 0;1,3=8,5=0
P 8.475 3.74115 4 P 0 0;1,3=8,5=0
P 9.34453002 4.97913996 13 P 0 0;1,3=0,5=0
P 4.95768002 2.09115 4 P 0 0;1,3=8,5=0
P 8.475 3.79115 4 P 0 0;1,3=8,5=0
P 9.3209 4.97913996 13 P 0 0;1,3=0,5=0
P 4.95768002 2.14115 4 P 0 0;1,3=8,5=0
P 10.96161004 2.39115 4 P 0 0;1,3=8,5=0
P 8.475 3.59115 4 P 0 0;1,3=8,5=0
P 9.55711998 4.97913996 13 P 0 0;1,3=0,5=0
P 4.90768002 2.04115 4 P 0 0;1,3=8,5=0
P 8.475 3.64115 4 P 0 0;1,3=8,5=0
P 9.5335 4.97913996 13 P 0 0;1,3=0,5=0
P 10.66161004 2.09115 4 P 0 0;1,3=8,5=0
P 8.325 3.64115 4 P 0 0;1,3=8,5=0
P 9.55711998 4.85788002 13 P 0 0;1,3=0,5=0
P 4.90768002 2.09115 4 P 0 0;1,3=8,5=0
P 8.325 3.69115 4 P 0 0;1,3=8,5=0
P 9.5335 4.85788002 13 P 0 0;1,3=0,5=0
P 10.61161004 2.14115 4 P 0 0;1,3=8,5=0
P 8.75398002 4.97913996 13 P 0 0;1,3=0,5=0
P 8.025 3.59115 4 P 0 0;1,3=8,5=0
P 10.71161004 2.44115 4 P 0 0;1,3=8,5=0
P 8.7776 4.97913996 13 P 0 0;1,3=0,5=0
P 8.025 3.64115 4 P 0 0;1,3=8,5=0
P 10.76161004 2.09115 4 P 0 0;1,3=8,5=0
P 11.01161004 2.44115 4 P 0 0;1,3=8,5=0
P 8.125 3.59115 4 P 0 0;1,3=8,5=0
P 8.82483996 4.97913996 13 P 0 0;1,3=0,5=0
P 11.01161004 2.49115 4 P 0 0;1,3=8,5=0
P 8.125 3.64115 4 P 0 0;1,3=8,5=0
P 8.84846004 4.97913996 13 P 0 0;1,3=0,5=0
P 0.97 5.093 7 P 0 0;1,3=1,5=0
P 0.97 5.027 7 P 0 0;1,3=1,5=0
P 1.03 5.027 7 P 0 0;1,3=1,5=0
P 10.71161004 2.14115 4 P 0 0;1,3=8,5=0
P 10.66161004 2.04115 4 P 0 0;1,3=8,5=0
P 1.094 5.417 7 P 0 0;1,3=1,5=0
P 1.04428996 5.53641998 26 P 0 0;1,3=10,5=0
P 0.97 5.823 7 P 0 0;1,3=1,5=0
P 0.96555 5.70373996 26 P 0 0;1,3=10,5=0
P 0.5574 5.85528002 17 P 0 0;1,3=19,5=0
P 4.063 4.59 7 P 0 0;1,3=1,5=0
P 10.61161004 2.74115 4 P 0 0;1,3=8,5=0
P 9.91 4.543 7 P 0 0;1,3=1,5=0
P 4.36323002 5.48 33 P 0 0;1,3=9,5=0
P 4.535 5.48 21 P 0 0;1,3=4,5=0
P 4.36323002 5.68 33 P 0 0;1,3=9,5=0
P 5.075 5.433 7 P 0 0;1,3=1,5=0
P 0.46 5.649 5 P 0 0;2,3=3,5=1
P 0.52 5.649 8 P 0 0;1,3=15,5=0
P 0.503 5.7 7 P 0 0;1,3=1,5=0
P 0.537 5.7 7 P 0 0;1,3=1,5=0
P 0.52 5.76471998 17 P 0 0;1,3=19,5=0
P 0.46 5.735 5 P 0 0;2,3=3,5=1
P 1.38906004 5.09151004 7 P 0 0;1,3=1,5=0
P 1.32745 4.9602 15 P 0 0;1,3=12,5=0
P 1.38906004 5.04851004 5 P 0 0;2,3=3,5=1
P 10.61161004 2.09115 4 P 0 0;1,3=8,5=0
P 8.075 3.79115 4 P 0 0;1,3=8,5=0
P 9.10831004 4.97913996 13 P 0 0;1,3=0,5=0
P 8.075 3.84115 4 P 0 0;1,3=8,5=0
P 9.13193002 4.97913996 13 P 0 0;1,3=0,5=0
P 3.9599 5.35898996 7 P 0 0;1,3=1,5=0
P 0.89 5.823 7 P 0 0;1,3=1,5=0
P 0.88681004 5.70373996 26 P 0 0;1,3=10,5=0
P 10.66161004 1.94115 4 P 0 0;1,3=8,5=0
P 8.325 3.79115 4 P 0 0;1,3=8,5=0
P 9.27366004 4.97913996 13 P 0 0;1,3=0,5=0
P 0.755 5.417 7 P 0 0;1,3=1,5=0
P 0.72933002 5.53641998 26 P 0 0;1,3=10,5=0
P 0.705 5.417 7 P 0 0;1,3=1,5=0
P 8.325 3.84115 4 P 0 0;1,3=8,5=0
P 9.25003996 4.97913996 13 P 0 0;1,3=0,5=0
P 3.62 4.483 7 P 0 0;1,3=1,5=0
P 4.36323002 5.58 33 P 0 0;1,3=9,5=0
P 4.36323002 5.78 33 P 0 0;1,3=9,5=0
P 4.585 5.48 21 P 0 0;1,3=4,5=0
P 5.025 5.433 7 P 0 0;1,3=1,5=0
P 4.60768002 2.74115 4 P 0 0;1,3=8,5=0
P 8.425 3.79115 4 P 0 0;1,3=8,5=0
P 9.20278996 4.85788002 13 P 0 0;1,3=0,5=0
P 8.425 3.84115 4 P 0 0;1,3=8,5=0
P 9.17916998 4.85788002 13 P 0 0;1,3=0,5=0
P 3.75998996 0.2711 7 P 0 0;1,3=1,5=0
P 9.55795 0.29243002 7 P 0 0;1,3=1,5=0
P 3.60998996 0.7751 7 P 0 0;1,3=1,5=0
P 3.66998996 0.7751 7 P 0 0;1,3=1,5=0
P 3.70998996 0.62931998 20 P 0 0;1,3=20,5=0
P 9.50795 0.65065 20 P 0 0;1,3=20,5=0
P 9.40795 0.79643002 7 P 0 0;1,3=1,5=0
P 9.46795 0.79643002 7 P 0 0;1,3=1,5=0
P 1.28906004 4.63151004 7 P 0 0;1,3=1,5=0
P 1.33906004 4.63151004 7 P 0 0;1,3=1,5=0
P 3.67 4.483 7 P 0 0;1,3=1,5=0
P 3.72 4.517 7 P 0 0;1,3=1,5=0
P 3.69558996 4.58965 14 P 0 0;1,3=5,5=0
P 7.3426 4.63151004 7 P 0 0;1,3=1,5=0
P 7.2926 4.63151004 7 P 0 0;1,3=1,5=0
P 7.25421004 4.79681998 15 P 0 0;1,3=12,5=0
P 7.2426 4.66551004 7 P 0 0;1,3=1,5=0
P 9.98 4.543 7 P 0 0;1,3=1,5=0
P 10.03 4.577 7 P 0 0;1,3=1,5=0
P 10.02558996 4.64965 14 P 0 0;1,3=5,5=0
P 1.23906004 4.66551004 7 P 0 0;1,3=1,5=0
P 1.25066998 4.79681998 15 P 0 0;1,3=12,5=0
P 3.89 4.683 7 P 0 0;1,3=1,5=0
P 4.0399 4.79498996 7 P 0 0;1,3=1,5=0
P 3.9899 4.79498996 7 P 0 0;1,3=1,5=0
P 4.03666998 4.96076998 15 P 0 0;1,3=12,5=0
P 4.1049 4.82898996 7 P 0 0;1,3=1,5=0
P 4.0599 5.35898996 7 P 0 0;1,3=1,5=0
P 4.0099 5.35898996 7 P 0 0;1,3=1,5=0
P 3.91 5.477 7 P 0 0;1,3=1,5=0
P 5.125 5.433 7 P 0 0;1,3=1,5=0
P 1.43798996 5.70373996 26 P 0 0;1,3=10,5=0
P 1.35925 5.70373996 26 P 0 0;1,3=10,5=0
P 1.355 5.823 7 P 0 0;1,3=1,5=0
P 1.455 5.823 7 P 0 0;1,3=1,5=0
P 1.305 5.823 7 P 0 0;1,3=1,5=0
P 1.405 5.823 7 P 0 0;1,3=1,5=0
P 8.375 3.74115 4 P 0 0;1,3=8,5=0
P 9.27366004 4.85788002 13 P 0 0;1,3=0,5=0
P 10.66161004 2.44115 4 P 0 0;1,3=8,5=0
P 8.375 3.79115 4 P 0 0;1,3=8,5=0
P 9.25003996 4.85788002 13 P 0 0;1,3=0,5=0
P 8.425 3.64115 4 P 0 0;1,3=8,5=0
P 9.41538996 4.85788002 13 P 0 0;1,3=0,5=0
P 0.96555 5.53641998 26 P 0 0;1,3=10,5=0
P 0.948 5.417 7 P 0 0;1,3=1,5=0
P 0.996 5.417 7 P 0 0;1,3=1,5=0
P 8.425 3.69115 4 P 0 0;1,3=8,5=0
P 9.39176998 4.85788002 13 P 0 0;1,3=0,5=0
P 8.375 3.59115 4 P 0 0;1,3=8,5=0
P 9.48626004 4.85788002 13 P 0 0;1,3=0,5=0
P 8.375 3.64115 4 P 0 0;1,3=8,5=0
P 9.46263996 4.85788002 13 P 0 0;1,3=0,5=0
P 7.1926 5.12551004 7 P 0 0;1,3=1,5=0
P 9.10831004 4.85788002 13 P 0 0;1,3=0,5=0
P 8.075 3.64115 4 P 0 0;1,3=8,5=0
P 8.75398002 4.85788002 13 P 0 0;1,3=0,5=0
P 8.075 3.69115 4 P 0 0;1,3=8,5=0
P 8.7776 4.85788002 13 P 0 0;1,3=0,5=0
P 8.175 3.64115 4 P 0 0;1,3=8,5=0
P 8.82483996 4.85788002 13 P 0 0;1,3=0,5=0
P 8.175 3.69115 4 P 0 0;1,3=8,5=0
P 8.84846004 4.85788002 13 P 0 0;1,3=0,5=0
P 8.025 3.74115 4 P 0 0;1,3=8,5=0
P 8.96656998 4.85788002 13 P 0 0;1,3=0,5=0
P 8.025 3.79115 4 P 0 0;1,3=8,5=0
P 8.9902 4.85788002 13 P 0 0;1,3=0,5=0
P 9.03743996 4.85788002 13 P 0 0;1,3=0,5=0
P 8.175 3.79115 4 P 0 0;1,3=8,5=0
P 9.06106004 4.85788002 13 P 0 0;1,3=0,5=0
P 8.175 3.84115 4 P 0 0;1,3=8,5=0
P 4.70768002 2.74115 4 P 0 0;1,3=8,5=0
P 0.91 5.233 7 P 0 0;1,3=1,5=0
P 1.02558996 5.29035 14 P 0 0;1,3=5,5=0
P 0.91 5.147 7 P 0 0;1,3=1,5=0
P 0.91 5.19 5 P 0 0;2,3=3,5=1
P 4.95768002 2.74115 4 P 0 0;1,3=8,5=0
P 2.12106004 2.49115 4 P 0 0;1,3=8,5=0
P 8.425 3.39115 4 P 0 0;1,3=8,5=0
P 8.17993002 4.97913996 13 P 0 0;1,3=0,5=0
P 5.05768002 3.79115 4 P 0 0;1,3=8,5=0
P 8.425 3.44115 4 P 0 0;1,3=8,5=0
P 8.1563 4.97913996 13 P 0 0;1,3=0,5=0
P 5.00768002 2.19115 4 P 0 0;1,3=8,5=0
P 3.91 5.443 7 P 0 0;1,3=1,5=0
P 3.9099 5.35898996 7 P 0 0;1,3=1,5=0
P 8.425 3.24115 4 P 0 0;1,3=8,5=0
P 8.39251998 4.97913996 13 P 0 0;1,3=0,5=0
P 0.84953002 5.2361 12 P 0 0;1,3=7,5=0
P 0.91 5.267 7 P 0 0;1,3=1,5=0
P 0.91 5.31 5 P 0 0;2,3=3,5=1
P 8.425 3.29115 4 P 0 0;1,3=8,5=0
P 8.3689 4.97913996 13 P 0 0;1,3=0,5=0
P 8.325 3.24115 4 P 0 0;1,3=8,5=0
P 8.39251998 4.85788002 13 P 0 0;1,3=0,5=0
P 8.325 3.29115 4 P 0 0;1,3=8,5=0
P 8.3689 4.85788002 13 P 0 0;1,3=0,5=0
P 8.275 3.54115 4 P 0 0;1,3=8,5=0
P 8.025 3.29115 4 P 0 0;1,3=8,5=0
P 7.58938002 4.97913996 13 P 0 0;1,3=0,5=0
P 8.225 3.54115 4 P 0 0;1,3=8,5=0
P 8.025 3.34115 4 P 0 0;1,3=8,5=0
P 7.613 4.97913996 13 P 0 0;1,3=0,5=0
P 2.22106004 2.84115 4 P 0 0;1,3=8,5=0
P 8.475 3.69115 4 P 0 0;1,3=8,5=0
P 8.475 3.84115 4 P 0 0;1,3=8,5=0
P 8.425 3.54115 4 P 0 0;1,3=8,5=0
P 8.475 3.54115 4 P 0 0;1,3=8,5=0
P 8.475 3.24115 4 P 0 0;1,3=8,5=0
P 8.425 3.34115 4 P 0 0;1,3=8,5=0
P 8.475 3.39115 4 P 0 0;1,3=8,5=0
P 8.225 3.69115 4 P 0 0;1,3=8,5=0
P 8.275 3.74115 4 P 0 0;1,3=8,5=0
P 8.225 3.74115 4 P 0 0;1,3=8,5=0
P 8.175 3.74115 4 P 0 0;1,3=8,5=0
P 8.225 3.79115 4 P 0 0;1,3=8,5=0
P 8.225 3.84115 4 P 0 0;1,3=8,5=0
P 8.225 3.44115 4 P 0 0;1,3=8,5=0
P 8.275 3.49115 4 P 0 0;1,3=8,5=0
P 8.225 3.49115 4 P 0 0;1,3=8,5=0
P 8.175 3.49115 4 P 0 0;1,3=8,5=0
P 8.175 3.54115 4 P 0 0;1,3=8,5=0
P 8.175 3.59115 4 P 0 0;1,3=8,5=0
P 8.225 3.59115 4 P 0 0;1,3=8,5=0
P 8.225 3.64115 4 P 0 0;1,3=8,5=0
P 8.275 3.59115 4 P 0 0;1,3=8,5=0
P 8.375 3.54115 4 P 0 0;1,3=8,5=0
P 8.225 3.24115 4 P 0 0;1,3=8,5=0
P 8.225 3.29115 4 P 0 0;1,3=8,5=0
P 8.175 3.34115 4 P 0 0;1,3=8,5=0
P 8.225 3.34115 4 P 0 0;1,3=8,5=0
P 8.275 3.34115 4 P 0 0;1,3=8,5=0
P 8.225 3.39115 4 P 0 0;1,3=8,5=0
P 8.075 3.49115 4 P 0 0;1,3=8,5=0
P 8.025 3.54115 4 P 0 0;1,3=8,5=0
P 8.125 3.54115 4 P 0 0;1,3=8,5=0
P 8.075 3.34115 4 P 0 0;1,3=8,5=0
P 8.025 3.39115 4 P 0 0;1,3=8,5=0
P 10.96161004 3.79115 4 P 0 0;1,3=8,5=0
P 11.01161004 3.79115 4 P 0 0;1,3=8,5=0
P 11.06161004 3.64115 4 P 0 0;1,3=8,5=0
P 10.96161004 3.64115 4 P 0 0;1,3=8,5=0
P 11.01161004 3.64115 4 P 0 0;1,3=8,5=0
P 11.06161004 3.49115 4 P 0 0;1,3=8,5=0
P 10.96161004 3.49115 4 P 0 0;1,3=8,5=0
P 11.01161004 3.49115 4 P 0 0;1,3=8,5=0
P 11.06161004 3.34115 4 P 0 0;1,3=8,5=0
P 10.96161004 3.34115 4 P 0 0;1,3=8,5=0
P 11.01161004 3.34115 4 P 0 0;1,3=8,5=0
P 11.01161004 3.19115 4 P 0 0;1,3=8,5=0
P 10.96161004 3.19115 4 P 0 0;1,3=8,5=0
P 11.06161004 3.19115 4 P 0 0;1,3=8,5=0
P 11.01161004 3.04115 4 P 0 0;1,3=8,5=0
P 10.96161004 3.04115 4 P 0 0;1,3=8,5=0
P 11.06161004 3.04115 4 P 0 0;1,3=8,5=0
P 11.01161004 2.89115 4 P 0 0;1,3=8,5=0
P 10.96161004 2.89115 4 P 0 0;1,3=8,5=0
P 11.06161004 2.89115 4 P 0 0;1,3=8,5=0
P 10.71161004 3.79115 4 P 0 0;1,3=8,5=0
P 10.76161004 3.79115 4 P 0 0;1,3=8,5=0
P 10.81161004 3.79115 4 P 0 0;1,3=8,5=0
P 10.91161004 3.64115 4 P 0 0;1,3=8,5=0
P 10.91161004 3.79115 4 P 0 0;1,3=8,5=0
P 10.86161004 3.79115 4 P 0 0;1,3=8,5=0
P 10.71161004 3.49115 4 P 0 0;1,3=8,5=0
P 10.76161004 3.49115 4 P 0 0;1,3=8,5=0
P 10.81161004 3.49115 4 P 0 0;1,3=8,5=0
P 10.71161004 3.64115 4 P 0 0;1,3=8,5=0
P 10.76161004 3.64115 4 P 0 0;1,3=8,5=0
P 10.81161004 3.64115 4 P 0 0;1,3=8,5=0
P 10.86161004 3.64115 4 P 0 0;1,3=8,5=0
P 10.91161004 3.49115 4 P 0 0;1,3=8,5=0
P 10.86161004 3.49115 4 P 0 0;1,3=8,5=0
P 10.71161004 3.19115 4 P 0 0;1,3=8,5=0
P 10.71161004 3.34115 4 P 0 0;1,3=8,5=0
P 10.76161004 3.19115 4 P 0 0;1,3=8,5=0
P 10.81161004 3.19115 4 P 0 0;1,3=8,5=0
P 10.76161004 3.34115 4 P 0 0;1,3=8,5=0
P 10.81161004 3.34115 4 P 0 0;1,3=8,5=0
P 10.91161004 3.34115 4 P 0 0;1,3=8,5=0
P 10.86161004 3.34115 4 P 0 0;1,3=8,5=0
P 10.86161004 3.19115 4 P 0 0;1,3=8,5=0
P 10.91161004 3.19115 4 P 0 0;1,3=8,5=0
P 10.71161004 3.04115 4 P 0 0;1,3=8,5=0
P 10.76161004 3.04115 4 P 0 0;1,3=8,5=0
P 10.81161004 3.04115 4 P 0 0;1,3=8,5=0
P 10.86161004 3.04115 4 P 0 0;1,3=8,5=0
P 10.91161004 3.04115 4 P 0 0;1,3=8,5=0
P 10.91161004 2.89115 4 P 0 0;1,3=8,5=0
P 10.71161004 2.89115 4 P 0 0;1,3=8,5=0
P 10.76161004 2.89115 4 P 0 0;1,3=8,5=0
P 10.81161004 2.89115 4 P 0 0;1,3=8,5=0
P 10.86161004 2.89115 4 P 0 0;1,3=8,5=0
P 10.61161004 3.79115 4 P 0 0;1,3=8,5=0
P 10.66161004 3.64115 4 P 0 0;1,3=8,5=0
P 10.66161004 3.79115 4 P 0 0;1,3=8,5=0
P 10.61161004 3.49115 4 P 0 0;1,3=8,5=0
P 10.66161004 3.49115 4 P 0 0;1,3=8,5=0
P 10.61161004 3.64115 4 P 0 0;1,3=8,5=0
P 10.61161004 3.19115 4 P 0 0;1,3=8,5=0
P 10.66161004 3.19115 4 P 0 0;1,3=8,5=0
P 10.61161004 3.34115 4 P 0 0;1,3=8,5=0
P 10.66161004 3.34115 4 P 0 0;1,3=8,5=0
P 10.61161004 3.04115 4 P 0 0;1,3=8,5=0
P 10.66161004 3.04115 4 P 0 0;1,3=8,5=0
P 10.61161004 2.89115 4 P 0 0;1,3=8,5=0
P 10.66161004 2.89115 4 P 0 0;1,3=8,5=0
P 4.65768002 2.19115 4 P 0 0;1,3=8,5=0
P 4.80768002 2.79115 4 P 0 0;1,3=8,5=0
P 4.75768002 2.79115 4 P 0 0;1,3=8,5=0
P 4.65768002 2.79115 4 P 0 0;1,3=8,5=0
P 4.65768002 2.74115 4 P 0 0;1,3=8,5=0
P 4.75768002 2.74115 4 P 0 0;1,3=8,5=0
P 4.60768002 2.69115 4 P 0 0;1,3=8,5=0
P 4.70768002 2.69115 4 P 0 0;1,3=8,5=0
P 4.80768002 2.69115 4 P 0 0;1,3=8,5=0
P 4.80768002 2.64115 4 P 0 0;1,3=8,5=0
P 4.80768002 2.59115 4 P 0 0;1,3=8,5=0
P 4.75768002 2.59115 4 P 0 0;1,3=8,5=0
P 4.65768002 2.59115 4 P 0 0;1,3=8,5=0
P 4.60768002 2.54115 4 P 0 0;1,3=8,5=0
P 4.65768002 2.54115 4 P 0 0;1,3=8,5=0
P 4.70768002 2.54115 4 P 0 0;1,3=8,5=0
P 4.75768002 2.54115 4 P 0 0;1,3=8,5=0
P 4.80768002 2.54115 4 P 0 0;1,3=8,5=0
P 5.05768002 2.89115 4 P 0 0;1,3=8,5=0
P 4.95768002 2.89115 4 P 0 0;1,3=8,5=0
P 5.00768002 2.89115 4 P 0 0;1,3=8,5=0
P 4.90768002 2.89115 4 P 0 0;1,3=8,5=0
P 4.85768002 2.89115 4 P 0 0;1,3=8,5=0
P 5.05768002 3.04115 4 P 0 0;1,3=8,5=0
P 4.95768002 3.04115 4 P 0 0;1,3=8,5=0
P 5.00768002 3.04115 4 P 0 0;1,3=8,5=0
P 4.90768002 3.04115 4 P 0 0;1,3=8,5=0
P 4.85768002 3.04115 4 P 0 0;1,3=8,5=0
P 5.05768002 3.19115 4 P 0 0;1,3=8,5=0
P 4.95768002 3.19115 4 P 0 0;1,3=8,5=0
P 5.00768002 3.19115 4 P 0 0;1,3=8,5=0
P 4.90768002 3.19115 4 P 0 0;1,3=8,5=0
P 4.85768002 3.19115 4 P 0 0;1,3=8,5=0
P 5.00768002 3.34115 4 P 0 0;1,3=8,5=0
P 4.95768002 3.34115 4 P 0 0;1,3=8,5=0
P 5.05768002 3.34115 4 P 0 0;1,3=8,5=0
P 4.85768002 3.34115 4 P 0 0;1,3=8,5=0
P 4.90768002 3.34115 4 P 0 0;1,3=8,5=0
P 5.00768002 3.79115 4 P 0 0;1,3=8,5=0
P 4.95768002 3.79115 4 P 0 0;1,3=8,5=0
P 4.85768002 3.79115 4 P 0 0;1,3=8,5=0
P 4.90768002 3.79115 4 P 0 0;1,3=8,5=0
P 5.00768002 3.49115 4 P 0 0;1,3=8,5=0
P 4.95768002 3.49115 4 P 0 0;1,3=8,5=0
P 5.05768002 3.49115 4 P 0 0;1,3=8,5=0
P 4.85768002 3.49115 4 P 0 0;1,3=8,5=0
P 4.90768002 3.49115 4 P 0 0;1,3=8,5=0
P 5.00768002 3.64115 4 P 0 0;1,3=8,5=0
P 4.95768002 3.64115 4 P 0 0;1,3=8,5=0
P 5.05768002 3.64115 4 P 0 0;1,3=8,5=0
P 4.85768002 3.64115 4 P 0 0;1,3=8,5=0
P 4.90768002 3.64115 4 P 0 0;1,3=8,5=0
P 5.05768002 2.79115 4 P 0 0;1,3=8,5=0
P 5.00768002 2.79115 4 P 0 0;1,3=8,5=0
P 5.00768002 2.74115 4 P 0 0;1,3=8,5=0
P 4.90768002 2.79115 4 P 0 0;1,3=8,5=0
P 4.95768002 2.79115 4 P 0 0;1,3=8,5=0
P 4.90768002 2.74115 4 P 0 0;1,3=8,5=0
P 5.05768002 2.69115 4 P 0 0;1,3=8,5=0
P 4.95768002 2.69115 4 P 0 0;1,3=8,5=0
P 5.00768002 2.59115 4 P 0 0;1,3=8,5=0
P 4.90768002 2.59115 4 P 0 0;1,3=8,5=0
P 4.95768002 2.49115 4 P 0 0;1,3=8,5=0
P 5.00768002 2.54115 4 P 0 0;1,3=8,5=0
P 4.95768002 2.54115 4 P 0 0;1,3=8,5=0
P 4.90768002 2.54115 4 P 0 0;1,3=8,5=0
P 5.05768002 2.54115 4 P 0 0;1,3=8,5=0
P 5.05768002 2.49115 4 P 0 0;1,3=8,5=0
P 5.00768002 2.24115 4 P 0 0;1,3=8,5=0
P 4.90768002 2.24115 4 P 0 0;1,3=8,5=0
P 4.95768002 2.34115 4 P 0 0;1,3=8,5=0
P 4.90768002 2.39115 4 P 0 0;1,3=8,5=0
P 5.05768002 2.34115 4 P 0 0;1,3=8,5=0
P 5.05768002 2.19115 4 P 0 0;1,3=8,5=0
P 4.90768002 2.19115 4 P 0 0;1,3=8,5=0
P 4.95768002 2.19115 4 P 0 0;1,3=8,5=0
P 4.90768002 1.99115 4 P 0 0;1,3=8,5=0
P 5.00768002 1.99115 4 P 0 0;1,3=8,5=0
P 5.00768002 2.14115 4 P 0 0;1,3=8,5=0
P 4.90768002 2.14115 4 P 0 0;1,3=8,5=0
P 4.95768002 2.04115 4 P 0 0;1,3=8,5=0
P 5.05768002 2.04115 4 P 0 0;1,3=8,5=0
P 4.95768002 1.89115 4 P 0 0;1,3=8,5=0
P 5.05768002 1.89115 4 P 0 0;1,3=8,5=0
P 4.80768002 3.79115 4 P 0 0;1,3=8,5=0
P 4.80768002 3.64115 4 P 0 0;1,3=8,5=0
P 4.75768002 3.79115 4 P 0 0;1,3=8,5=0
P 4.75768002 3.64115 4 P 0 0;1,3=8,5=0
P 4.70768002 3.79115 4 P 0 0;1,3=8,5=0
P 4.70768002 3.64115 4 P 0 0;1,3=8,5=0
P 4.80768002 3.49115 4 P 0 0;1,3=8,5=0
P 4.75768002 3.49115 4 P 0 0;1,3=8,5=0
P 4.70768002 3.49115 4 P 0 0;1,3=8,5=0
P 4.80768002 3.34115 4 P 0 0;1,3=8,5=0
P 4.75768002 3.34115 4 P 0 0;1,3=8,5=0
P 4.80768002 3.19115 4 P 0 0;1,3=8,5=0
P 4.75768002 3.19115 4 P 0 0;1,3=8,5=0
P 4.70768002 3.34115 4 P 0 0;1,3=8,5=0
P 4.70768002 3.19115 4 P 0 0;1,3=8,5=0
P 4.80768002 3.04115 4 P 0 0;1,3=8,5=0
P 4.75768002 3.04115 4 P 0 0;1,3=8,5=0
P 4.70768002 3.04115 4 P 0 0;1,3=8,5=0
P 4.80768002 2.89115 4 P 0 0;1,3=8,5=0
P 4.75768002 2.89115 4 P 0 0;1,3=8,5=0
P 4.70768002 2.89115 4 P 0 0;1,3=8,5=0
P 4.85768002 2.79115 4 P 0 0;1,3=8,5=0
P 4.85768002 2.69115 4 P 0 0;1,3=8,5=0
P 4.80768002 2.49115 4 P 0 0;1,3=8,5=0
P 4.85768002 2.59115 4 P 0 0;1,3=8,5=0
P 4.85768002 2.64115 4 P 0 0;1,3=8,5=0
P 4.70768002 2.49115 4 P 0 0;1,3=8,5=0
P 4.85768002 2.49115 4 P 0 0;1,3=8,5=0
P 4.85768002 2.54115 4 P 0 0;1,3=8,5=0
P 4.80768002 2.44115 4 P 0 0;1,3=8,5=0
P 4.85768002 2.44115 4 P 0 0;1,3=8,5=0
P 4.80768002 2.39115 4 P 0 0;1,3=8,5=0
P 4.80768002 2.34115 4 P 0 0;1,3=8,5=0
P 4.80768002 2.29115 4 P 0 0;1,3=8,5=0
P 4.80768002 2.24115 4 P 0 0;1,3=8,5=0
P 4.75768002 2.39115 4 P 0 0;1,3=8,5=0
P 4.70768002 2.34115 4 P 0 0;1,3=8,5=0
P 4.75768002 2.24115 4 P 0 0;1,3=8,5=0
P 4.85768002 2.24115 4 P 0 0;1,3=8,5=0
P 4.85768002 2.29115 4 P 0 0;1,3=8,5=0
P 4.85768002 2.34115 4 P 0 0;1,3=8,5=0
P 4.85768002 2.39115 4 P 0 0;1,3=8,5=0
P 4.75768002 2.19115 4 P 0 0;1,3=8,5=0
P 4.70768002 2.19115 4 P 0 0;1,3=8,5=0
P 4.80768002 1.99115 4 P 0 0;1,3=8,5=0
P 4.80768002 2.09115 4 P 0 0;1,3=8,5=0
P 4.80768002 2.04115 4 P 0 0;1,3=8,5=0
P 4.85768002 1.99115 4 P 0 0;1,3=8,5=0
P 4.85768002 2.09115 4 P 0 0;1,3=8,5=0
P 4.85768002 2.04115 4 P 0 0;1,3=8,5=0
P 4.80768002 2.14115 4 P 0 0;1,3=8,5=0
P 4.85768002 2.14115 4 P 0 0;1,3=8,5=0
P 4.75768002 2.14115 4 P 0 0;1,3=8,5=0
P 4.70768002 2.04115 4 P 0 0;1,3=8,5=0
P 4.75768002 1.99115 4 P 0 0;1,3=8,5=0
P 4.80768002 1.89115 4 P 0 0;1,3=8,5=0
P 4.80768002 1.94115 4 P 0 0;1,3=8,5=0
P 4.85768002 1.89115 4 P 0 0;1,3=8,5=0
P 4.85768002 1.94115 4 P 0 0;1,3=8,5=0
P 4.70768002 1.89115 4 P 0 0;1,3=8,5=0
P 4.65768002 3.79115 4 P 0 0;1,3=8,5=0
P 4.65768002 3.64115 4 P 0 0;1,3=8,5=0
P 4.60768002 3.79115 4 P 0 0;1,3=8,5=0
P 4.60768002 3.64115 4 P 0 0;1,3=8,5=0
P 4.65768002 3.49115 4 P 0 0;1,3=8,5=0
P 4.60768002 3.49115 4 P 0 0;1,3=8,5=0
P 4.65768002 3.34115 4 P 0 0;1,3=8,5=0
P 4.60768002 3.34115 4 P 0 0;1,3=8,5=0
P 4.65768002 3.19115 4 P 0 0;1,3=8,5=0
P 4.60768002 3.19115 4 P 0 0;1,3=8,5=0
P 4.65768002 3.04115 4 P 0 0;1,3=8,5=0
P 4.60768002 3.04115 4 P 0 0;1,3=8,5=0
P 4.65768002 2.89115 4 P 0 0;1,3=8,5=0
P 4.60768002 2.89115 4 P 0 0;1,3=8,5=0
P 4.60768002 2.49115 4 P 0 0;1,3=8,5=0
P 4.60768002 2.19115 4 P 0 0;1,3=8,5=0
P 4.65768002 2.24115 4 P 0 0;1,3=8,5=0
P 4.60768002 2.34115 4 P 0 0;1,3=8,5=0
P 4.65768002 2.39115 4 P 0 0;1,3=8,5=0
P 4.60768002 2.04115 4 P 0 0;1,3=8,5=0
P 4.65768002 2.14115 4 P 0 0;1,3=8,5=0
P 4.65768002 1.99115 4 P 0 0;1,3=8,5=0
P 4.60768002 1.89115 4 P 0 0;1,3=8,5=0
P 2.12106004 2.29115 4 P 0 0;1,3=8,5=0
P 2.07106004 2.34115 4 P 0 0;1,3=8,5=0
P 2.07106004 2.19115 4 P 0 0;1,3=8,5=0
P 2.12106004 2.14115 4 P 0 0;1,3=8,5=0
P 2.17106004 2.19115 4 P 0 0;1,3=8,5=0
P 2.22106004 2.24115 4 P 0 0;1,3=8,5=0
P 2.27106004 2.24115 4 P 0 0;1,3=8,5=0
P 2.22106004 2.19115 4 P 0 0;1,3=8,5=0
P 2.22106004 2.09115 4 P 0 0;1,3=8,5=0
P 2.22106004 2.14115 4 P 0 0;1,3=8,5=0
P 2.27106004 2.14115 4 P 0 0;1,3=8,5=0
P 2.27106004 2.09115 4 P 0 0;1,3=8,5=0
P 2.27106004 2.19115 4 P 0 0;1,3=8,5=0
P 2.32106004 2.19115 4 P 0 0;1,3=8,5=0
P 2.37106004 2.14115 4 P 0 0;1,3=8,5=0
P 2.42106004 2.19115 4 P 0 0;1,3=8,5=0
P 2.47106004 2.14115 4 P 0 0;1,3=8,5=0
P 2.42106004 1.89115 4 P 0 0;1,3=8,5=0
P 2.47106004 1.99115 4 P 0 0;1,3=8,5=0
P 2.42106004 2.04115 4 P 0 0;1,3=8,5=0
P 2.37106004 1.99115 4 P 0 0;1,3=8,5=0
P 2.32106004 2.04115 4 P 0 0;1,3=8,5=0
P 2.27106004 2.04115 4 P 0 0;1,3=8,5=0
P 2.22106004 2.04115 4 P 0 0;1,3=8,5=0
P 2.17106004 2.04115 4 P 0 0;1,3=8,5=0
P 2.27106004 1.99115 4 P 0 0;1,3=8,5=0
P 2.22106004 1.99115 4 P 0 0;1,3=8,5=0
P 2.27106004 1.94115 4 P 0 0;1,3=8,5=0
P 2.22106004 1.94115 4 P 0 0;1,3=8,5=0
P 2.32106004 1.89115 4 P 0 0;1,3=8,5=0
P 2.27106004 1.89115 4 P 0 0;1,3=8,5=0
P 2.22106004 1.89115 4 P 0 0;1,3=8,5=0
P 2.17106004 1.89115 4 P 0 0;1,3=8,5=0
P 2.07106004 1.89115 4 P 0 0;1,3=8,5=0
P 2.12106004 1.99115 4 P 0 0;1,3=8,5=0
P 2.07106004 2.04115 4 P 0 0;1,3=8,5=0
P 2.02106004 1.99115 4 P 0 0;1,3=8,5=0
P 2.02106004 2.14115 4 P 0 0;1,3=8,5=0
P 2.02106004 2.29115 4 P 0 0;1,3=8,5=0
P 2.22106004 2.29115 4 P 0 0;1,3=8,5=0
P 2.27106004 2.29115 4 P 0 0;1,3=8,5=0
P 2.32106004 2.34115 4 P 0 0;1,3=8,5=0
P 2.37106004 2.29115 4 P 0 0;1,3=8,5=0
P 2.47106004 2.29115 4 P 0 0;1,3=8,5=0
P 2.42106004 2.34115 4 P 0 0;1,3=8,5=0
P 2.47106004 2.44115 4 P 0 0;1,3=8,5=0
P 2.47106004 2.49115 4 P 0 0;1,3=8,5=0
P 2.47106004 2.54115 4 P 0 0;1,3=8,5=0
P 2.42106004 2.49115 4 P 0 0;1,3=8,5=0
P 2.37106004 2.54115 4 P 0 0;1,3=8,5=0
P 2.37106004 2.49115 4 P 0 0;1,3=8,5=0
P 2.37106004 2.44115 4 P 0 0;1,3=8,5=0
P 2.27106004 2.34115 4 P 0 0;1,3=8,5=0
P 2.17106004 2.34115 4 P 0 0;1,3=8,5=0
P 2.22106004 2.34115 4 P 0 0;1,3=8,5=0
P 2.22106004 2.39115 4 P 0 0;1,3=8,5=0
P 2.27106004 2.39115 4 P 0 0;1,3=8,5=0
P 2.27106004 2.44115 4 P 0 0;1,3=8,5=0
P 2.22106004 2.44115 4 P 0 0;1,3=8,5=0
P 2.12106004 2.44115 4 P 0 0;1,3=8,5=0
P 2.17106004 2.49115 4 P 0 0;1,3=8,5=0
P 2.22106004 2.49115 4 P 0 0;1,3=8,5=0
P 2.27106004 2.49115 4 P 0 0;1,3=8,5=0
P 2.32106004 2.49115 4 P 0 0;1,3=8,5=0
P 2.27106004 2.54115 4 P 0 0;1,3=8,5=0
P 2.27106004 2.59115 4 P 0 0;1,3=8,5=0
P 2.22106004 2.54115 4 P 0 0;1,3=8,5=0
P 2.22106004 2.59115 4 P 0 0;1,3=8,5=0
P 2.12106004 2.54115 4 P 0 0;1,3=8,5=0
P 2.07106004 2.49115 4 P 0 0;1,3=8,5=0
P 2.02106004 2.44115 4 P 0 0;1,3=8,5=0
P 2.02106004 2.49115 4 P 0 0;1,3=8,5=0
P 2.02106004 2.54115 4 P 0 0;1,3=8,5=0
P 2.02106004 2.69115 4 P 0 0;1,3=8,5=0
P 2.07106004 2.64115 4 P 0 0;1,3=8,5=0
P 2.12106004 2.69115 4 P 0 0;1,3=8,5=0
P 2.17106004 2.64115 4 P 0 0;1,3=8,5=0
P 2.22106004 2.64115 4 P 0 0;1,3=8,5=0
P 2.22106004 2.69115 4 P 0 0;1,3=8,5=0
P 2.27106004 2.64115 4 P 0 0;1,3=8,5=0
P 2.27106004 2.69115 4 P 0 0;1,3=8,5=0
P 2.32106004 2.64115 4 P 0 0;1,3=8,5=0
P 2.37106004 2.69115 4 P 0 0;1,3=8,5=0
P 2.42106004 2.64115 4 P 0 0;1,3=8,5=0
P 2.47106004 2.69115 4 P 0 0;1,3=8,5=0
P 2.47106004 2.84115 4 P 0 0;1,3=8,5=0
P 2.42106004 2.79115 4 P 0 0;1,3=8,5=0
P 2.32106004 2.79115 4 P 0 0;1,3=8,5=0
P 2.37106004 2.84115 4 P 0 0;1,3=8,5=0
P 2.42106004 2.84115 4 P 0 0;1,3=8,5=0
P 2.42106004 2.89115 4 P 0 0;1,3=8,5=0
P 2.47106004 2.99115 4 P 0 0;1,3=8,5=0
P 2.42106004 3.04115 4 P 0 0;1,3=8,5=0
P 2.32106004 3.04115 4 P 0 0;1,3=8,5=0
P 2.37106004 2.99115 4 P 0 0;1,3=8,5=0
P 2.27106004 2.89115 4 P 0 0;1,3=8,5=0
P 2.22106004 2.89115 4 P 0 0;1,3=8,5=0
P 2.17106004 2.89115 4 P 0 0;1,3=8,5=0
P 2.02106004 2.84115 4 P 0 0;1,3=8,5=0
P 2.12106004 2.84115 4 P 0 0;1,3=8,5=0
P 2.07106004 2.89115 4 P 0 0;1,3=8,5=0
P 2.02106004 2.99115 4 P 0 0;1,3=8,5=0
P 2.07106004 3.04115 4 P 0 0;1,3=8,5=0
P 2.12106004 2.99115 4 P 0 0;1,3=8,5=0
P 2.17106004 3.04115 4 P 0 0;1,3=8,5=0
P 2.07106004 2.84115 4 P 0 0;1,3=8,5=0
P 2.07106004 2.79115 4 P 0 0;1,3=8,5=0
P 2.17106004 2.79115 4 P 0 0;1,3=8,5=0
P 2.22106004 2.79115 4 P 0 0;1,3=8,5=0
P 2.22106004 2.74115 4 P 0 0;1,3=8,5=0
P 2.27106004 2.79115 4 P 0 0;1,3=8,5=0
P 2.27106004 2.74115 4 P 0 0;1,3=8,5=0
P 2.32106004 2.89115 4 P 0 0;1,3=8,5=0
P 2.32106004 2.84115 4 P 0 0;1,3=8,5=0
P 2.22106004 2.99115 4 P 0 0;1,3=8,5=0
P 2.22106004 2.94115 4 P 0 0;1,3=8,5=0
P 2.22106004 3.09115 4 P 0 0;1,3=8,5=0
P 2.22106004 3.04115 4 P 0 0;1,3=8,5=0
P 2.27106004 2.99115 4 P 0 0;1,3=8,5=0
P 2.27106004 2.94115 4 P 0 0;1,3=8,5=0
P 2.27106004 3.09115 4 P 0 0;1,3=8,5=0
P 2.27106004 3.04115 4 P 0 0;1,3=8,5=0
P 2.02106004 3.39115 4 P 0 0;1,3=8,5=0
P 2.07106004 3.49115 4 P 0 0;1,3=8,5=0
P 2.12106004 3.14115 4 P 0 0;1,3=8,5=0
P 2.02106004 3.14115 4 P 0 0;1,3=8,5=0
P 11.01161004 2.74115 4 P 0 0;1,3=8,5=0
P 10.91161004 2.74115 4 P 0 0;1,3=8,5=0
P 11.01161004 2.79115 4 P 0 0;1,3=8,5=0
P 10.96161004 2.79115 4 P 0 0;1,3=8,5=0
P 10.91161004 2.79115 4 P 0 0;1,3=8,5=0
P 11.06161004 2.79115 4 P 0 0;1,3=8,5=0
P 11.01161004 2.54115 4 P 0 0;1,3=8,5=0
P 11.01161004 2.59115 4 P 0 0;1,3=8,5=0
P 10.91161004 2.59115 4 P 0 0;1,3=8,5=0
P 10.96161004 2.69115 4 P 0 0;1,3=8,5=0
P 10.96161004 2.54115 4 P 0 0;1,3=8,5=0
P 10.91161004 2.54115 4 P 0 0;1,3=8,5=0
P 11.06161004 2.69115 4 P 0 0;1,3=8,5=0
P 11.06161004 2.54115 4 P 0 0;1,3=8,5=0
P 11.06161004 2.49115 4 P 0 0;1,3=8,5=0
P 10.96161004 2.49115 4 P 0 0;1,3=8,5=0
P 11.06161004 2.34115 4 P 0 0;1,3=8,5=0
P 10.91161004 2.39115 4 P 0 0;1,3=8,5=0
P 10.96161004 2.34115 4 P 0 0;1,3=8,5=0
P 10.91161004 2.24115 4 P 0 0;1,3=8,5=0
P 11.01161004 2.24115 4 P 0 0;1,3=8,5=0
P 11.01161004 2.14115 4 P 0 0;1,3=8,5=0
P 10.91161004 2.14115 4 P 0 0;1,3=8,5=0
P 10.96161004 2.04115 4 P 0 0;1,3=8,5=0
P 10.91161004 1.99115 4 P 0 0;1,3=8,5=0
P 11.01161004 1.99115 4 P 0 0;1,3=8,5=0
P 11.06161004 2.04115 4 P 0 0;1,3=8,5=0
P 10.96161004 2.19115 4 P 0 0;1,3=8,5=0
P 10.91161004 2.19115 4 P 0 0;1,3=8,5=0
P 11.06161004 2.19115 4 P 0 0;1,3=8,5=0
P 10.96161004 1.89115 4 P 0 0;1,3=8,5=0
P 11.06161004 1.89115 4 P 0 0;1,3=8,5=0
P 10.76161004 2.74115 4 P 0 0;1,3=8,5=0
P 10.76161004 2.79115 4 P 0 0;1,3=8,5=0
P 10.86161004 2.79115 4 P 0 0;1,3=8,5=0
P 10.81161004 2.79115 4 P 0 0;1,3=8,5=0
P 10.76161004 2.59115 4 P 0 0;1,3=8,5=0
P 10.71161004 2.69115 4 P 0 0;1,3=8,5=0
P 10.76161004 2.54115 4 P 0 0;1,3=8,5=0
P 10.71161004 2.54115 4 P 0 0;1,3=8,5=0
P 10.86161004 2.64115 4 P 0 0;1,3=8,5=0
P 10.86161004 2.69115 4 P 0 0;1,3=8,5=0
P 10.86161004 2.59115 4 P 0 0;1,3=8,5=0
P 10.86161004 2.54115 4 P 0 0;1,3=8,5=0
P 10.81161004 2.59115 4 P 0 0;1,3=8,5=0
P 10.81161004 2.64115 4 P 0 0;1,3=8,5=0
P 10.81161004 2.69115 4 P 0 0;1,3=8,5=0
P 10.81161004 2.54115 4 P 0 0;1,3=8,5=0
P 10.81161004 2.49115 4 P 0 0;1,3=8,5=0
P 10.71161004 2.49115 4 P 0 0;1,3=8,5=0
P 10.86161004 2.49115 4 P 0 0;1,3=8,5=0
P 10.81161004 2.24115 4 P 0 0;1,3=8,5=0
P 10.81161004 2.29115 4 P 0 0;1,3=8,5=0
P 10.81161004 2.34115 4 P 0 0;1,3=8,5=0
P 10.81161004 2.39115 4 P 0 0;1,3=8,5=0
P 10.71161004 2.34115 4 P 0 0;1,3=8,5=0
P 10.76161004 2.39115 4 P 0 0;1,3=8,5=0
P 10.76161004 2.24115 4 P 0 0;1,3=8,5=0
P 10.81161004 2.44115 4 P 0 0;1,3=8,5=0
P 10.86161004 2.44115 4 P 0 0;1,3=8,5=0
P 10.86161004 2.39115 4 P 0 0;1,3=8,5=0
P 10.86161004 2.34115 4 P 0 0;1,3=8,5=0
P 10.86161004 2.29115 4 P 0 0;1,3=8,5=0
P 10.86161004 2.24115 4 P 0 0;1,3=8,5=0
P 10.76161004 1.99115 4 P 0 0;1,3=8,5=0
P 10.71161004 2.04115 4 P 0 0;1,3=8,5=0
P 10.76161004 2.14115 4 P 0 0;1,3=8,5=0
P 10.81161004 2.14115 4 P 0 0;1,3=8,5=0
P 10.81161004 2.04115 4 P 0 0;1,3=8,5=0
P 10.81161004 1.99115 4 P 0 0;1,3=8,5=0
P 10.81161004 2.09115 4 P 0 0;1,3=8,5=0
P 10.71161004 2.19115 4 P 0 0;1,3=8,5=0
P 10.76161004 2.19115 4 P 0 0;1,3=8,5=0
P 10.86161004 2.04115 4 P 0 0;1,3=8,5=0
P 10.86161004 2.09115 4 P 0 0;1,3=8,5=0
P 10.86161004 2.14115 4 P 0 0;1,3=8,5=0
P 10.86161004 1.99115 4 P 0 0;1,3=8,5=0
P 10.81161004 1.94115 4 P 0 0;1,3=8,5=0
P 10.71161004 1.89115 4 P 0 0;1,3=8,5=0
P 10.81161004 1.89115 4 P 0 0;1,3=8,5=0
P 10.86161004 1.89115 4 P 0 0;1,3=8,5=0
P 10.86161004 1.94115 4 P 0 0;1,3=8,5=0
P 10.66161004 2.74115 4 P 0 0;1,3=8,5=0
P 10.66161004 2.79115 4 P 0 0;1,3=8,5=0
P 10.66161004 2.59115 4 P 0 0;1,3=8,5=0
P 10.61161004 2.69115 4 P 0 0;1,3=8,5=0
P 10.66161004 2.54115 4 P 0 0;1,3=8,5=0
P 10.61161004 2.54115 4 P 0 0;1,3=8,5=0
P 10.61161004 2.49115 4 P 0 0;1,3=8,5=0
P 10.66161004 2.39115 4 P 0 0;1,3=8,5=0
P 10.61161004 2.34115 4 P 0 0;1,3=8,5=0
P 10.61161004 2.04115 4 P 0 0;1,3=8,5=0
P 10.66161004 1.99115 4 P 0 0;1,3=8,5=0
P 10.66161004 2.14115 4 P 0 0;1,3=8,5=0
P 10.66161004 2.19115 4 P 0 0;1,3=8,5=0
P 10.61161004 1.89115 4 P 0 0;1,3=8,5=0
P 6.42418996 4.99705 7 P 0 0;1,3=1,5=0
P 6.42418996 5.04705 7 P 0 0;1,3=1,5=0
P 4.76 5.54928996 32 P 0 0;1,3=6,5=0
P 4.81 5.408 7 P 0 0;1,3=1,5=0
P 4.96 5.408 7 P 0 0;1,3=1,5=0
P 5.16 5.617 7 P 0 0;1,3=1,5=0
P 5.04441004 5.64035 14 P 0 0;1,3=5,5=0
P 4.92 5.65315 18 P 0 0;1,3=2,5=0
P 9.91 4.667 7 P 0 0;1,3=1,5=0
P 3.57 4.483 7 P 0 0;1,3=1,5=0
P 11.87126004 4.88 16 P 0 0;1,3=21,5=0
P 3.72 4.483 7 P 0 0;1,3=1,5=0
P 3.64441004 4.67035 14 P 0 0;1,3=5,5=0
P 3.77 4.827 7 P 0 0;1,3=1,5=0
P 9.97441004 4.73035 14 P 0 0;1,3=5,5=0
P 10.03 4.543 7 P 0 0;1,3=1,5=0
P 3.99965 4.66441004 25 P 0 0;1,3=5,5=0
P 4.14 4.683 7 P 0 0;1,3=1,5=0
P 4.1049 4.79498996 7 P 0 0;1,3=1,5=0
P 1.28051004 5.53641998 26 P 0 0;1,3=10,5=0
P 1.28051004 5.70373996 26 P 0 0;1,3=10,5=0
P 3.88313002 5.18321004 15 P 0 0;1,3=12,5=0
P 0.4826 5.85528002 17 P 0 0;1,3=19,5=0
P 0.84953002 5.1239 12 P 0 0;1,3=7,5=0
P 0.97441004 5.29035 14 P 0 0;1,3=5,5=0
P 1.03 5.093 7 P 0 0;1,3=1,5=0
P 0.73 5.147 7 P 0 0;1,3=1,5=0
P 0.73 5.267 7 P 0 0;1,3=1,5=0
P 0.705 5.383 7 P 0 0;1,3=1,5=0
P 1.455 5.857 7 P 0 0;1,3=1,5=0
P 1.405 5.857 7 P 0 0;1,3=1,5=0
P 1.355 5.857 7 P 0 0;1,3=1,5=0
P 1.305 5.857 7 P 0 0;1,3=1,5=0
P 1.46 5.383 7 P 0 0;1,3=1,5=0
P 1.41 5.383 7 P 0 0;1,3=1,5=0
P 1.36 5.383 7 P 0 0;1,3=1,5=0
P 1.31 5.383 7 P 0 0;1,3=1,5=0
P 1.51673002 5.53641998 26 P 0 0;1,3=10,5=0
P 1.20176998 5.53641998 26 P 0 0;1,3=10,5=0
P 1.12303002 5.53641998 26 P 0 0;1,3=10,5=0
P 1.51673002 5.70373996 26 P 0 0;1,3=10,5=0
P 1.20176998 5.70373996 26 P 0 0;1,3=10,5=0
P 9.45795 0.42821004 20 P 0 0;1,3=20,5=0
P 3.65998996 0.40688002 20 P 0 0;1,3=20,5=0
P 6.57318996 5.09705 7 P 0 0;1,3=1,5=0
P 6.87018996 4.94705 8 P 0 0;1,3=15,5=0
P 6.87018996 4.88705 8 P 0 0;1,3=15,5=0
P 6.91118996 4.81705 10 P 0 0;1,3=13,5=0
P 6.67918996 4.77205 7 P 0 0;1,3=1,5=0
P 6.57618996 4.76905 7 P 0 0;1,3=1,5=0
P 6.65268996 4.82846998 27 P 0 0;1,3=11,5=0
P 6.63693996 4.82846998 27 P 0 0;1,3=11,5=0
P 6.62118996 4.82846998 27 P 0 0;1,3=11,5=0
P 6.60543996 4.82846998 27 P 0 0;1,3=11,5=0
P 6.58968996 4.82846998 27 P 0 0;1,3=11,5=0
P 6.66208996 4.6252 10 P 0 0;1,3=13,5=0
P 6.66208996 4.7052 10 P 0 0;1,3=13,5=0
P 6.69008996 4.96428996 23 P 0 0;1,3=11,5=0
P 5.53593996 4.5861 7 P 0 0;1,3=1,5=0
P 5.99708996 4.5552 10 P 0 0;1,3=13,5=0
P 5.91708996 4.5552 10 P 0 0;1,3=13,5=0
P 6.07708996 4.5552 10 P 0 0;1,3=13,5=0
P 5.75708996 4.5552 10 P 0 0;1,3=13,5=0
P 5.83708996 4.5552 10 P 0 0;1,3=13,5=0
P 5.67708996 4.5552 10 P 0 0;1,3=13,5=0
P 5.59778996 4.5552 10 P 0 0;1,3=13,5=0
P 1.32745 4.79681998 15 P 0 0;1,3=12,5=0
P 1.18906004 5.01551004 7 P 0 0;1,3=1,5=0
P 1.23906004 4.63151004 7 P 0 0;1,3=1,5=0
P 7.2426 4.63151004 7 P 0 0;1,3=1,5=0
P 7.33098996 4.79681998 15 P 0 0;1,3=12,5=0
P 7.1926 5.01551004 7 P 0 0;1,3=1,5=0
P 10.61161004 2.19115 4 P 0 0;1,3=8,5=0
P 11.01161004 2.39115 4 P 0 0;1,3=8,5=0
P 10.66161004 2.24115 4 P 0 0;1,3=8,5=0
P 5.00768002 2.39115 4 P 0 0;1,3=8,5=0
P 10.36698996 5.02086004 31 P 0 0;1,3=17,5=0
P 10.75698996 5.02086004 31 P 0 0;1,3=17,5=0
P 4.36305 5.02086004 31 P 0 0;1,3=17,5=0
P 4.75305 5.02086004 31 P 0 0;1,3=17,5=0
P 6.62418996 5.09705 7 P 0 0;1,3=1,5=0
P 6.58968996 5.00563002 28 P 0 0;1,3=11,5=0
P 6.60543996 5.00563002 28 P 0 0;1,3=11,5=0
P 6.837 5 7 P 0 0;1,3=1,5=0
P 3.81998996 0.7751 7 P 0 0;1,3=1,5=0
P 3.60998996 0.2711 7 P 0 0;1,3=1,5=0
P 9.61795 0.79643002 7 P 0 0;1,3=1,5=0
P 9.40795 0.29243002 7 P 0 0;1,3=1,5=0
P 3.82558996 4.63965 14 P 0 0;1,3=5,5=0
P 2.22106004 3.84115 4 P 0 0;1,3=8,5=0
P 2.47106004 3.84115 4 P 0 0;1,3=8,5=0
P 2.22106004 3.79115 4 P 0 0;1,3=8,5=0
P 2.17106004 3.74115 4 P 0 0;1,3=8,5=0
P 2.22106004 3.74115 4 P 0 0;1,3=8,5=0
P 2.27106004 3.74115 4 P 0 0;1,3=8,5=0
P 2.47106004 3.69115 4 P 0 0;1,3=8,5=0
P 2.47106004 3.54115 4 P 0 0;1,3=8,5=0
P 2.42106004 3.54115 4 P 0 0;1,3=8,5=0
P 2.37106004 3.54115 4 P 0 0;1,3=8,5=0
P 2.27106004 3.59115 4 P 0 0;1,3=8,5=0
P 2.22106004 3.69115 4 P 0 0;1,3=8,5=0
P 2.22106004 3.64115 4 P 0 0;1,3=8,5=0
P 2.22106004 3.59115 4 P 0 0;1,3=8,5=0
P 2.17106004 3.59115 4 P 0 0;1,3=8,5=0
P 2.17106004 3.54115 4 P 0 0;1,3=8,5=0
P 2.12106004 3.54115 4 P 0 0;1,3=8,5=0
P 2.02106004 3.54115 4 P 0 0;1,3=8,5=0
P 2.17106004 3.49115 4 P 0 0;1,3=8,5=0
P 2.22106004 3.49115 4 P 0 0;1,3=8,5=0
P 2.27106004 3.49115 4 P 0 0;1,3=8,5=0
P 2.47106004 3.39115 4 P 0 0;1,3=8,5=0
P 2.42106004 3.34115 4 P 0 0;1,3=8,5=0
P 2.22106004 3.44115 4 P 0 0;1,3=8,5=0
P 2.22106004 3.39115 4 P 0 0;1,3=8,5=0
P 2.27106004 3.34115 4 P 0 0;1,3=8,5=0
P 2.22106004 3.34115 4 P 0 0;1,3=8,5=0
P 2.17106004 3.34115 4 P 0 0;1,3=8,5=0
P 2.07106004 3.34115 4 P 0 0;1,3=8,5=0
P 2.22106004 3.29115 4 P 0 0;1,3=8,5=0
P 2.22106004 3.24115 4 P 0 0;1,3=8,5=0
P 2.27106004 3.19115 4 P 0 0;1,3=8,5=0
P 2.22106004 3.19115 4 P 0 0;1,3=8,5=0
P 2.17106004 3.19115 4 P 0 0;1,3=8,5=0
P 2.07106004 3.19115 4 P 0 0;1,3=8,5=0
P 2.22106004 3.14115 4 P 0 0;1,3=8,5=0
P 2.27106004 3.14115 4 P 0 0;1,3=8,5=0
P 2.32106004 3.19115 4 P 0 0;1,3=8,5=0
P 2.42106004 3.19115 4 P 0 0;1,3=8,5=0
P 2.47106004 3.19115 4 P 0 0;1,3=8,5=0
P 2.47106004 3.24115 4 P 0 0;1,3=8,5=0
P 2.47106004 3.14115 4 P 0 0;1,3=8,5=0
P 2.37106004 3.14115 4 P 0 0;1,3=8,5=0
P 2.12106004 3.24115 4 P 0 0;1,3=8,5=0
P 2.02106004 3.24115 4 P 0 0;1,3=8,5=0
P 2.02106004 3.19115 4 P 0 0;1,3=8,5=0
P 2.12106004 3.19115 4 P 0 0;1,3=8,5=0
P 2.37106004 3.19115 4 P 0 0;1,3=8,5=0
P 2.37106004 3.24115 4 P 0 0;1,3=8,5=0
P 2.27106004 3.24115 4 P 0 0;1,3=8,5=0
P 2.27106004 3.29115 4 P 0 0;1,3=8,5=0
P 2.32106004 3.34115 4 P 0 0;1,3=8,5=0
P 2.12106004 3.39115 4 P 0 0;1,3=8,5=0
P 2.07106004 3.59115 4 P 0 0;1,3=8,5=0
P 2.27106004 3.44115 4 P 0 0;1,3=8,5=0
P 2.27106004 3.39115 4 P 0 0;1,3=8,5=0
P 2.37106004 3.39115 4 P 0 0;1,3=8,5=0
P 2.32106004 3.49115 4 P 0 0;1,3=8,5=0
P 2.32106004 3.59115 4 P 0 0;1,3=8,5=0
P 2.32106004 3.54115 4 P 0 0;1,3=8,5=0
P 2.42106004 3.49115 4 P 0 0;1,3=8,5=0
P 2.42106004 3.59115 4 P 0 0;1,3=8,5=0
P 2.12106004 3.69115 4 P 0 0;1,3=8,5=0
P 2.02106004 3.69115 4 P 0 0;1,3=8,5=0
P 2.07106004 3.74115 4 P 0 0;1,3=8,5=0
P 2.12106004 3.84115 4 P 0 0;1,3=8,5=0
P 2.02106004 3.84115 4 P 0 0;1,3=8,5=0
P 2.27106004 3.69115 4 P 0 0;1,3=8,5=0
P 2.27106004 3.64115 4 P 0 0;1,3=8,5=0
P 2.37106004 3.69115 4 P 0 0;1,3=8,5=0
P 2.32106004 3.74115 4 P 0 0;1,3=8,5=0
P 2.27106004 3.79115 4 P 0 0;1,3=8,5=0
P 2.37106004 3.84115 4 P 0 0;1,3=8,5=0
P 2.27106004 3.84115 4 P 0 0;1,3=8,5=0
P 2.42106004 3.74115 4 P 0 0;1,3=8,5=0
P 2.17106004 2.84115 4 P 0 0;1,3=8,5=0
P 8.025 3.24115 4 P 0 0;1,3=8,5=0
P 8.275 3.24115 4 P 0 0;1,3=8,5=0
P 8.275 3.29115 4 P 0 0;1,3=8,5=0
P 8.325 3.34115 4 P 0 0;1,3=8,5=0
P 8.125 3.24115 4 P 0 0;1,3=8,5=0
P 8.375 3.24115 4 P 0 0;1,3=8,5=0
P 8.075 3.59115 4 P 0 0;1,3=8,5=0
P 8.275 3.44115 4 P 0 0;1,3=8,5=0
P 8.275 3.39115 4 P 0 0;1,3=8,5=0
P 8.325 3.49115 4 P 0 0;1,3=8,5=0
P 8.325 3.59115 4 P 0 0;1,3=8,5=0
P 8.325 3.54115 4 P 0 0;1,3=8,5=0
P 8.125 3.39115 4 P 0 0;1,3=8,5=0
P 8.425 3.49115 4 P 0 0;1,3=8,5=0
P 8.425 3.59115 4 P 0 0;1,3=8,5=0
P 8.375 3.39115 4 P 0 0;1,3=8,5=0
P 8.025 3.69115 4 P 0 0;1,3=8,5=0
P 8.075 3.74115 4 P 0 0;1,3=8,5=0
P 8.025 3.84115 4 P 0 0;1,3=8,5=0
P 8.275 3.69115 4 P 0 0;1,3=8,5=0
P 8.275 3.64115 4 P 0 0;1,3=8,5=0
P 8.325 3.74115 4 P 0 0;1,3=8,5=0
P 8.275 3.79115 4 P 0 0;1,3=8,5=0
P 8.275 3.84115 4 P 0 0;1,3=8,5=0
P 8.125 3.69115 4 P 0 0;1,3=8,5=0
P 8.125 3.84115 4 P 0 0;1,3=8,5=0
P 8.425 3.74115 4 P 0 0;1,3=8,5=0
P 8.375 3.69115 4 P 0 0;1,3=8,5=0
P 8.375 3.84115 4 P 0 0;1,3=8,5=0
P 2.37106004 2.59115 4 P 0 0;1,3=8,5=0
P 2.37106004 2.64115 4 P 0 0;1,3=8,5=0
P 2.42106004 2.54115 4 P 0 0;1,3=8,5=0
P 2.42106004 2.59115 4 P 0 0;1,3=8,5=0
P 2.47106004 2.59115 4 P 0 0;1,3=8,5=0
P 2.47106004 2.64115 4 P 0 0;1,3=8,5=0
P 2.32106004 2.69115 4 P 0 0;1,3=8,5=0
P 2.32106004 2.74115 4 P 0 0;1,3=8,5=0
P 2.42106004 2.69115 4 P 0 0;1,3=8,5=0
P 2.42106004 2.74115 4 P 0 0;1,3=8,5=0
P 2.47106004 2.74115 4 P 0 0;1,3=8,5=0
P 2.47106004 2.79115 4 P 0 0;1,3=8,5=0
P 2.37106004 2.74115 4 P 0 0;1,3=8,5=0
P 2.37106004 2.79115 4 P 0 0;1,3=8,5=0
P 2.32106004 2.94115 4 P 0 0;1,3=8,5=0
P 2.32106004 2.99115 4 P 0 0;1,3=8,5=0
P 2.37106004 2.89115 4 P 0 0;1,3=8,5=0
P 2.37106004 2.94115 4 P 0 0;1,3=8,5=0
P 2.47106004 2.89115 4 P 0 0;1,3=8,5=0
P 2.47106004 2.94115 4 P 0 0;1,3=8,5=0
P 2.42106004 2.94115 4 P 0 0;1,3=8,5=0
P 2.42106004 2.99115 4 P 0 0;1,3=8,5=0
P 2.37106004 3.04115 4 P 0 0;1,3=8,5=0
P 2.37106004 3.09115 4 P 0 0;1,3=8,5=0
P 2.47106004 3.04115 4 P 0 0;1,3=8,5=0
P 2.47106004 3.09115 4 P 0 0;1,3=8,5=0
P 2.42106004 3.09115 4 P 0 0;1,3=8,5=0
P 2.42106004 3.14115 4 P 0 0;1,3=8,5=0
P 2.32106004 3.09115 4 P 0 0;1,3=8,5=0
P 2.32106004 3.14115 4 P 0 0;1,3=8,5=0
P 2.32106004 1.94115 4 P 0 0;1,3=8,5=0
P 2.32106004 1.99115 4 P 0 0;1,3=8,5=0
P 2.37106004 1.89115 4 P 0 0;1,3=8,5=0
P 2.37106004 1.94115 4 P 0 0;1,3=8,5=0
P 2.47106004 1.89115 4 P 0 0;1,3=8,5=0
P 2.47106004 1.94115 4 P 0 0;1,3=8,5=0
P 2.42106004 1.94115 4 P 0 0;1,3=8,5=0
P 2.42106004 1.99115 4 P 0 0;1,3=8,5=0
P 2.37106004 2.04115 4 P 0 0;1,3=8,5=0
P 2.37106004 2.09115 4 P 0 0;1,3=8,5=0
P 2.47106004 2.04115 4 P 0 0;1,3=8,5=0
P 2.47106004 2.09115 4 P 0 0;1,3=8,5=0
P 2.42106004 2.09115 4 P 0 0;1,3=8,5=0
P 2.42106004 2.14115 4 P 0 0;1,3=8,5=0
P 2.32106004 2.09115 4 P 0 0;1,3=8,5=0
P 2.32106004 2.14115 4 P 0 0;1,3=8,5=0
P 2.32106004 2.24115 4 P 0 0;1,3=8,5=0
P 2.32106004 2.29115 4 P 0 0;1,3=8,5=0
P 2.37106004 2.19115 4 P 0 0;1,3=8,5=0
P 2.37106004 2.24115 4 P 0 0;1,3=8,5=0
P 2.47106004 2.19115 4 P 0 0;1,3=8,5=0
P 2.47106004 2.24115 4 P 0 0;1,3=8,5=0
P 2.42106004 2.24115 4 P 0 0;1,3=8,5=0
P 2.42106004 2.29115 4 P 0 0;1,3=8,5=0
P 2.37106004 2.34115 4 P 0 0;1,3=8,5=0
P 2.37106004 2.39115 4 P 0 0;1,3=8,5=0
P 2.47106004 2.34115 4 P 0 0;1,3=8,5=0
P 2.47106004 2.39115 4 P 0 0;1,3=8,5=0
P 2.42106004 2.39115 4 P 0 0;1,3=8,5=0
P 2.42106004 2.44115 4 P 0 0;1,3=8,5=0
P 2.32106004 2.39115 4 P 0 0;1,3=8,5=0
P 2.32106004 2.44115 4 P 0 0;1,3=8,5=0
P 2.32106004 2.59115 4 P 0 0;1,3=8,5=0
P 2.32106004 2.54115 4 P 0 0;1,3=8,5=0
P 2.07106004 2.54115 4 P 0 0;1,3=8,5=0
P 2.07106004 2.59115 4 P 0 0;1,3=8,5=0
P 2.17106004 2.54115 4 P 0 0;1,3=8,5=0
P 2.17106004 2.59115 4 P 0 0;1,3=8,5=0
P 2.12106004 2.59115 4 P 0 0;1,3=8,5=0
P 2.12106004 2.64115 4 P 0 0;1,3=8,5=0
P 2.07106004 2.69115 4 P 0 0;1,3=8,5=0
P 2.07106004 2.74115 4 P 0 0;1,3=8,5=0
P 2.17106004 2.69115 4 P 0 0;1,3=8,5=0
P 2.17106004 2.74115 4 P 0 0;1,3=8,5=0
P 2.12106004 2.74115 4 P 0 0;1,3=8,5=0
P 2.12106004 2.79115 4 P 0 0;1,3=8,5=0
P 2.02106004 2.74115 4 P 0 0;1,3=8,5=0
P 2.02106004 2.79115 4 P 0 0;1,3=8,5=0
P 2.02106004 2.89115 4 P 0 0;1,3=8,5=0
P 2.02106004 2.94115 4 P 0 0;1,3=8,5=0
P 2.07106004 2.94115 4 P 0 0;1,3=8,5=0
P 2.07106004 2.99115 4 P 0 0;1,3=8,5=0
P 2.12106004 2.89115 4 P 0 0;1,3=8,5=0
P 2.12106004 2.94115 4 P 0 0;1,3=8,5=0
P 2.17106004 2.94115 4 P 0 0;1,3=8,5=0
P 2.17106004 2.99115 4 P 0 0;1,3=8,5=0
P 2.02106004 3.04115 4 P 0 0;1,3=8,5=0
P 2.02106004 3.09115 4 P 0 0;1,3=8,5=0
P 2.12106004 3.04115 4 P 0 0;1,3=8,5=0
P 2.12106004 3.09115 4 P 0 0;1,3=8,5=0
P 2.17106004 3.09115 4 P 0 0;1,3=8,5=0
P 2.17106004 3.14115 4 P 0 0;1,3=8,5=0
P 2.07106004 3.09115 4 P 0 0;1,3=8,5=0
P 2.07106004 3.14115 4 P 0 0;1,3=8,5=0
P 2.02106004 1.89115 4 P 0 0;1,3=8,5=0
P 2.02106004 1.94115 4 P 0 0;1,3=8,5=0
P 2.07106004 1.94115 4 P 0 0;1,3=8,5=0
P 2.07106004 1.99115 4 P 0 0;1,3=8,5=0
P 2.12106004 1.89115 4 P 0 0;1,3=8,5=0
P 2.12106004 1.94115 4 P 0 0;1,3=8,5=0
P 2.17106004 1.94115 4 P 0 0;1,3=8,5=0
P 2.17106004 1.99115 4 P 0 0;1,3=8,5=0
P 2.02106004 2.04115 4 P 0 0;1,3=8,5=0
P 2.02106004 2.09115 4 P 0 0;1,3=8,5=0
P 2.12106004 2.04115 4 P 0 0;1,3=8,5=0
P 2.12106004 2.09115 4 P 0 0;1,3=8,5=0
P 2.17106004 2.09115 4 P 0 0;1,3=8,5=0
P 2.17106004 2.14115 4 P 0 0;1,3=8,5=0
P 2.07106004 2.09115 4 P 0 0;1,3=8,5=0
P 2.07106004 2.14115 4 P 0 0;1,3=8,5=0
P 2.02106004 2.19115 4 P 0 0;1,3=8,5=0
P 2.02106004 2.24115 4 P 0 0;1,3=8,5=0
P 2.07106004 2.24115 4 P 0 0;1,3=8,5=0
P 2.07106004 2.29115 4 P 0 0;1,3=8,5=0
P 2.12106004 2.19115 4 P 0 0;1,3=8,5=0
P 2.12106004 2.24115 4 P 0 0;1,3=8,5=0
P 2.17106004 2.24115 4 P 0 0;1,3=8,5=0
P 2.17106004 2.29115 4 P 0 0;1,3=8,5=0
P 2.02106004 2.34115 4 P 0 0;1,3=8,5=0
P 2.02106004 2.39115 4 P 0 0;1,3=8,5=0
P 2.12106004 2.34115 4 P 0 0;1,3=8,5=0
P 2.12106004 2.39115 4 P 0 0;1,3=8,5=0
P 2.17106004 2.39115 4 P 0 0;1,3=8,5=0
P 2.17106004 2.44115 4 P 0 0;1,3=8,5=0
P 2.07106004 2.39115 4 P 0 0;1,3=8,5=0
P 2.07106004 2.44115 4 P 0 0;1,3=8,5=0
P 2.02106004 2.64115 4 P 0 0;1,3=8,5=0
P 2.02106004 2.59115 4 P 0 0;1,3=8,5=0
P 8.125 1.89115 4 P 0 0;1,3=8,5=0
P 8.025 1.89115 4 P 0 0;1,3=8,5=0
P 8.075 1.89115 4 P 0 0;1,3=8,5=0
P 8.125 1.94115 4 P 0 0;1,3=8,5=0
P 8.025 1.94115 4 P 0 0;1,3=8,5=0
P 8.075 1.99115 4 P 0 0;1,3=8,5=0
P 8.075 1.94115 4 P 0 0;1,3=8,5=0
P 8.125 2.09115 4 P 0 0;1,3=8,5=0
P 8.125 2.04115 4 P 0 0;1,3=8,5=0
P 8.025 2.09115 4 P 0 0;1,3=8,5=0
P 8.025 2.04115 4 P 0 0;1,3=8,5=0
P 8.075 2.14115 4 P 0 0;1,3=8,5=0
P 8.075 2.09115 4 P 0 0;1,3=8,5=0
P 8.125 2.14115 4 P 0 0;1,3=8,5=0
P 8.125 1.99115 4 P 0 0;1,3=8,5=0
P 8.075 2.04115 4 P 0 0;1,3=8,5=0
P 8.025 1.99115 4 P 0 0;1,3=8,5=0
P 8.025 2.14115 4 P 0 0;1,3=8,5=0
P 8.025 2.19115 4 P 0 0;1,3=8,5=0
P 8.025 2.24115 4 P 0 0;1,3=8,5=0
P 8.125 2.19115 4 P 0 0;1,3=8,5=0
P 8.125 2.24115 4 P 0 0;1,3=8,5=0
P 8.075 2.24115 4 P 0 0;1,3=8,5=0
P 8.075 2.29115 4 P 0 0;1,3=8,5=0
P 8.125 2.34115 4 P 0 0;1,3=8,5=0
P 8.125 2.39115 4 P 0 0;1,3=8,5=0
P 8.025 2.34115 4 P 0 0;1,3=8,5=0
P 8.025 2.39115 4 P 0 0;1,3=8,5=0
P 8.075 2.39115 4 P 0 0;1,3=8,5=0
P 8.125 2.29115 4 P 0 0;1,3=8,5=0
P 8.075 2.34115 4 P 0 0;1,3=8,5=0
P 8.075 2.19115 4 P 0 0;1,3=8,5=0
P 8.025 2.29115 4 P 0 0;1,3=8,5=0
P 8.075 2.44115 4 P 0 0;1,3=8,5=0
P 8.125 2.59115 4 P 0 0;1,3=8,5=0
P 8.125 2.64115 4 P 0 0;1,3=8,5=0
P 8.075 2.54115 4 P 0 0;1,3=8,5=0
P 8.075 2.59115 4 P 0 0;1,3=8,5=0
P 8.025 2.59115 4 P 0 0;1,3=8,5=0
P 8.025 2.64115 4 P 0 0;1,3=8,5=0
P 8.125 2.44115 4 P 0 0;1,3=8,5=0
P 8.125 2.54115 4 P 0 0;1,3=8,5=0
P 8.075 2.49115 4 P 0 0;1,3=8,5=0
P 8.025 2.44115 4 P 0 0;1,3=8,5=0
P 8.025 2.49115 4 P 0 0;1,3=8,5=0
P 8.025 2.54115 4 P 0 0;1,3=8,5=0
P 8.075 2.64115 4 P 0 0;1,3=8,5=0
P 8.025 2.74115 4 P 0 0;1,3=8,5=0
P 8.025 2.79115 4 P 0 0;1,3=8,5=0
P 8.075 2.69115 4 P 0 0;1,3=8,5=0
P 8.075 2.74115 4 P 0 0;1,3=8,5=0
P 8.125 2.74115 4 P 0 0;1,3=8,5=0
P 8.125 2.79115 4 P 0 0;1,3=8,5=0
P 8.025 2.89115 4 P 0 0;1,3=8,5=0
P 8.125 2.89115 4 P 0 0;1,3=8,5=0
P 8.075 2.79115 4 P 0 0;1,3=8,5=0
P 8.075 2.84115 4 P 0 0;1,3=8,5=0
P 8.025 2.84115 4 P 0 0;1,3=8,5=0
P 8.025 2.69115 4 P 0 0;1,3=8,5=0
P 8.125 2.69115 4 P 0 0;1,3=8,5=0
P 8.125 2.84115 4 P 0 0;1,3=8,5=0
P 8.075 2.89115 4 P 0 0;1,3=8,5=0
P 8.025 2.94115 4 P 0 0;1,3=8,5=0
P 8.075 2.99115 4 P 0 0;1,3=8,5=0
P 8.075 2.94115 4 P 0 0;1,3=8,5=0
P 8.125 2.94115 4 P 0 0;1,3=8,5=0
P 8.025 3.04115 4 P 0 0;1,3=8,5=0
P 8.125 3.04115 4 P 0 0;1,3=8,5=0
P 8.125 3.09115 4 P 0 0;1,3=8,5=0
P 8.025 3.09115 4 P 0 0;1,3=8,5=0
P 8.075 3.09115 4 P 0 0;1,3=8,5=0
P 8.075 3.14115 4 P 0 0;1,3=8,5=0
P 8.025 2.99115 4 P 0 0;1,3=8,5=0
P 8.075 3.04115 4 P 0 0;1,3=8,5=0
P 8.125 2.99115 4 P 0 0;1,3=8,5=0
P 8.125 3.14115 4 P 0 0;1,3=8,5=0
P 8.025 3.14115 4 P 0 0;1,3=8,5=0
P 8.125 3.19115 4 P 0 0;1,3=8,5=0
P 8.025 3.19115 4 P 0 0;1,3=8,5=0
P 8.075 3.19115 4 P 0 0;1,3=8,5=0
P 8.375 1.89115 4 P 0 0;1,3=8,5=0
P 8.325 1.89115 4 P 0 0;1,3=8,5=0
P 8.275 1.89115 4 P 0 0;1,3=8,5=0
P 8.225 1.89115 4 P 0 0;1,3=8,5=0
P 8.175 1.89115 4 P 0 0;1,3=8,5=0
P 8.325 2.14115 4 P 0 0;1,3=8,5=0
P 8.325 2.09115 4 P 0 0;1,3=8,5=0
P 8.375 2.09115 4 P 0 0;1,3=8,5=0
P 8.375 2.04115 4 P 0 0;1,3=8,5=0
P 8.375 1.94115 4 P 0 0;1,3=8,5=0
P 8.325 1.99115 4 P 0 0;1,3=8,5=0
P 8.325 1.94115 4 P 0 0;1,3=8,5=0
P 8.175 1.99115 4 P 0 0;1,3=8,5=0
P 8.175 1.94115 4 P 0 0;1,3=8,5=0
P 8.175 2.14115 4 P 0 0;1,3=8,5=0
P 8.175 2.09115 4 P 0 0;1,3=8,5=0
P 8.225 2.09115 4 P 0 0;1,3=8,5=0
P 8.225 2.14115 4 P 0 0;1,3=8,5=0
P 8.275 2.14115 4 P 0 0;1,3=8,5=0
P 8.275 2.09115 4 P 0 0;1,3=8,5=0
P 8.375 2.14115 4 P 0 0;1,3=8,5=0
P 8.375 1.99115 4 P 0 0;1,3=8,5=0
P 8.325 2.04115 4 P 0 0;1,3=8,5=0
P 8.275 2.04115 4 P 0 0;1,3=8,5=0
P 8.225 2.04115 4 P 0 0;1,3=8,5=0
P 8.175 2.04115 4 P 0 0;1,3=8,5=0
P 8.275 1.99115 4 P 0 0;1,3=8,5=0
P 8.225 1.99115 4 P 0 0;1,3=8,5=0
P 8.275 1.94115 4 P 0 0;1,3=8,5=0
P 8.225 1.94115 4 P 0 0;1,3=8,5=0
P 8.325 2.39115 4 P 0 0;1,3=8,5=0
P 8.375 2.34115 4 P 0 0;1,3=8,5=0
P 8.375 2.39115 4 P 0 0;1,3=8,5=0
P 8.375 2.19115 4 P 0 0;1,3=8,5=0
P 8.375 2.24115 4 P 0 0;1,3=8,5=0
P 8.325 2.24115 4 P 0 0;1,3=8,5=0
P 8.325 2.29115 4 P 0 0;1,3=8,5=0
P 8.175 2.24115 4 P 0 0;1,3=8,5=0
P 8.175 2.29115 4 P 0 0;1,3=8,5=0
P 8.175 2.39115 4 P 0 0;1,3=8,5=0
P 8.175 2.19115 4 P 0 0;1,3=8,5=0
P 8.225 2.24115 4 P 0 0;1,3=8,5=0
P 8.275 2.24115 4 P 0 0;1,3=8,5=0
P 8.225 2.19115 4 P 0 0;1,3=8,5=0
P 8.275 2.19115 4 P 0 0;1,3=8,5=0
P 8.325 2.19115 4 P 0 0;1,3=8,5=0
P 8.225 2.29115 4 P 0 0;1,3=8,5=0
P 8.275 2.29115 4 P 0 0;1,3=8,5=0
P 8.325 2.34115 4 P 0 0;1,3=8,5=0
P 8.375 2.29115 4 P 0 0;1,3=8,5=0
P 8.275 2.34115 4 P 0 0;1,3=8,5=0
P 8.175 2.34115 4 P 0 0;1,3=8,5=0
P 8.225 2.34115 4 P 0 0;1,3=8,5=0
P 8.225 2.39115 4 P 0 0;1,3=8,5=0
P 8.275 2.39115 4 P 0 0;1,3=8,5=0
P 8.325 2.44115 4 P 0 0;1,3=8,5=0
P 8.175 2.44115 4 P 0 0;1,3=8,5=0
P 8.175 2.54115 4 P 0 0;1,3=8,5=0
P 8.175 2.59115 4 P 0 0;1,3=8,5=0
P 8.375 2.59115 4 P 0 0;1,3=8,5=0
P 8.375 2.64115 4 P 0 0;1,3=8,5=0
P 8.325 2.54115 4 P 0 0;1,3=8,5=0
P 8.325 2.59115 4 P 0 0;1,3=8,5=0
P 8.375 2.54115 4 P 0 0;1,3=8,5=0
P 8.375 2.49115 4 P 0 0;1,3=8,5=0
P 8.375 2.44115 4 P 0 0;1,3=8,5=0
P 8.275 2.44115 4 P 0 0;1,3=8,5=0
P 8.225 2.44115 4 P 0 0;1,3=8,5=0
P 8.175 2.49115 4 P 0 0;1,3=8,5=0
P 8.225 2.49115 4 P 0 0;1,3=8,5=0
P 8.275 2.49115 4 P 0 0;1,3=8,5=0
P 8.325 2.49115 4 P 0 0;1,3=8,5=0
P 8.275 2.54115 4 P 0 0;1,3=8,5=0
P 8.275 2.59115 4 P 0 0;1,3=8,5=0
P 8.225 2.54115 4 P 0 0;1,3=8,5=0
P 8.225 2.59115 4 P 0 0;1,3=8,5=0
P 8.175 2.64115 4 P 0 0;1,3=8,5=0
P 8.225 2.64115 4 P 0 0;1,3=8,5=0
P 8.275 2.64115 4 P 0 0;1,3=8,5=0
P 8.325 2.64115 4 P 0 0;1,3=8,5=0
P 8.175 2.69115 4 P 0 0;1,3=8,5=0
P 8.175 2.74115 4 P 0 0;1,3=8,5=0
P 8.325 2.69115 4 P 0 0;1,3=8,5=0
P 8.325 2.74115 4 P 0 0;1,3=8,5=0
P 8.375 2.74115 4 P 0 0;1,3=8,5=0
P 8.375 2.79115 4 P 0 0;1,3=8,5=0
P 8.375 2.89115 4 P 0 0;1,3=8,5=0
P 8.175 2.84115 4 P 0 0;1,3=8,5=0
P 8.225 2.69115 4 P 0 0;1,3=8,5=0
P 8.275 2.69115 4 P 0 0;1,3=8,5=0
P 8.375 2.69115 4 P 0 0;1,3=8,5=0
P 8.325 2.79115 4 P 0 0;1,3=8,5=0
P 8.375 2.84115 4 P 0 0;1,3=8,5=0
P 8.275 2.89115 4 P 0 0;1,3=8,5=0
P 8.225 2.89115 4 P 0 0;1,3=8,5=0
P 8.175 2.89115 4 P 0 0;1,3=8,5=0
P 8.175 2.79115 4 P 0 0;1,3=8,5=0
P 8.225 2.79115 4 P 0 0;1,3=8,5=0
P 8.225 2.74115 4 P 0 0;1,3=8,5=0
P 8.275 2.79115 4 P 0 0;1,3=8,5=0
P 8.275 2.74115 4 P 0 0;1,3=8,5=0
P 8.325 2.89115 4 P 0 0;1,3=8,5=0
P 8.325 2.84115 4 P 0 0;1,3=8,5=0
P 8.375 2.94115 4 P 0 0;1,3=8,5=0
P 8.325 2.94115 4 P 0 0;1,3=8,5=0
P 8.325 2.99115 4 P 0 0;1,3=8,5=0
P 8.175 2.94115 4 P 0 0;1,3=8,5=0
P 8.175 2.99115 4 P 0 0;1,3=8,5=0
P 8.375 3.09115 4 P 0 0;1,3=8,5=0
P 8.375 3.04115 4 P 0 0;1,3=8,5=0
P 8.325 3.09115 4 P 0 0;1,3=8,5=0
P 8.325 3.14115 4 P 0 0;1,3=8,5=0
P 8.175 3.09115 4 P 0 0;1,3=8,5=0
P 8.175 3.14115 4 P 0 0;1,3=8,5=0
P 8.325 3.04115 4 P 0 0;1,3=8,5=0
P 8.375 2.99115 4 P 0 0;1,3=8,5=0
P 8.175 3.04115 4 P 0 0;1,3=8,5=0
P 8.225 2.99115 4 P 0 0;1,3=8,5=0
P 8.225 2.94115 4 P 0 0;1,3=8,5=0
P 8.225 3.09115 4 P 0 0;1,3=8,5=0
P 8.225 3.04115 4 P 0 0;1,3=8,5=0
P 8.275 2.99115 4 P 0 0;1,3=8,5=0
P 8.275 2.94115 4 P 0 0;1,3=8,5=0
P 8.275 3.09115 4 P 0 0;1,3=8,5=0
P 8.275 3.04115 4 P 0 0;1,3=8,5=0
P 8.225 3.14115 4 P 0 0;1,3=8,5=0
P 8.275 3.14115 4 P 0 0;1,3=8,5=0
P 8.375 3.14115 4 P 0 0;1,3=8,5=0
P 8.375 3.19115 4 P 0 0;1,3=8,5=0
P 8.275 3.19115 4 P 0 0;1,3=8,5=0
P 8.225 3.19115 4 P 0 0;1,3=8,5=0
P 8.175 3.19115 4 P 0 0;1,3=8,5=0
P 8.325 3.19115 4 P 0 0;1,3=8,5=0
P 8.475 1.89115 4 P 0 0;1,3=8,5=0
P 8.425 1.89115 4 P 0 0;1,3=8,5=0
P 8.475 2.09115 4 P 0 0;1,3=8,5=0
P 8.475 2.04115 4 P 0 0;1,3=8,5=0
P 8.425 2.14115 4 P 0 0;1,3=8,5=0
P 8.425 2.09115 4 P 0 0;1,3=8,5=0
P 8.475 1.94115 4 P 0 0;1,3=8,5=0
P 8.425 1.99115 4 P 0 0;1,3=8,5=0
P 8.425 1.94115 4 P 0 0;1,3=8,5=0
P 8.475 2.14115 4 P 0 0;1,3=8,5=0
P 8.475 1.99115 4 P 0 0;1,3=8,5=0
P 8.425 2.04115 4 P 0 0;1,3=8,5=0
P 8.425 2.39115 4 P 0 0;1,3=8,5=0
P 8.475 2.34115 4 P 0 0;1,3=8,5=0
P 8.475 2.39115 4 P 0 0;1,3=8,5=0
P 8.475 2.19115 4 P 0 0;1,3=8,5=0
P 8.475 2.24115 4 P 0 0;1,3=8,5=0
P 8.425 2.24115 4 P 0 0;1,3=8,5=0
P 8.425 2.29115 4 P 0 0;1,3=8,5=0
P 8.425 2.19115 4 P 0 0;1,3=8,5=0
P 8.475 2.29115 4 P 0 0;1,3=8,5=0
P 8.425 2.34115 4 P 0 0;1,3=8,5=0
P 8.425 2.44115 4 P 0 0;1,3=8,5=0
P 8.475 2.59115 4 P 0 0;1,3=8,5=0
P 8.475 2.64115 4 P 0 0;1,3=8,5=0
P 8.425 2.54115 4 P 0 0;1,3=8,5=0
P 8.425 2.59115 4 P 0 0;1,3=8,5=0
P 8.475 2.44115 4 P 0 0;1,3=8,5=0
P 8.475 2.49115 4 P 0 0;1,3=8,5=0
P 8.475 2.54115 4 P 0 0;1,3=8,5=0
P 8.425 2.49115 4 P 0 0;1,3=8,5=0
P 8.425 2.64115 4 P 0 0;1,3=8,5=0
P 8.425 2.69115 4 P 0 0;1,3=8,5=0
P 8.425 2.74115 4 P 0 0;1,3=8,5=0
P 8.475 2.74115 4 P 0 0;1,3=8,5=0
P 8.475 2.79115 4 P 0 0;1,3=8,5=0
P 8.475 2.89115 4 P 0 0;1,3=8,5=0
P 8.475 2.69115 4 P 0 0;1,3=8,5=0
P 8.475 2.84115 4 P 0 0;1,3=8,5=0
P 8.425 2.79115 4 P 0 0;1,3=8,5=0
P 8.425 2.84115 4 P 0 0;1,3=8,5=0
P 8.425 2.89115 4 P 0 0;1,3=8,5=0
P 8.475 2.94115 4 P 0 0;1,3=8,5=0
P 8.425 2.94115 4 P 0 0;1,3=8,5=0
P 8.425 2.99115 4 P 0 0;1,3=8,5=0
P 8.475 3.04115 4 P 0 0;1,3=8,5=0
P 8.475 3.09115 4 P 0 0;1,3=8,5=0
P 8.425 3.09115 4 P 0 0;1,3=8,5=0
P 8.425 3.14115 4 P 0 0;1,3=8,5=0
P 8.475 2.99115 4 P 0 0;1,3=8,5=0
P 8.425 3.04115 4 P 0 0;1,3=8,5=0
P 8.475 3.14115 4 P 0 0;1,3=8,5=0
P 8.425 3.19115 4 P 0 0;1,3=8,5=0
P 8.475 3.19115 4 P 0 0;1,3=8,5=0
P 1.79843002 4.97913996 13 P 0 0;1,3=0,5=0
P 1.75118996 4.85788002 13 P 0 0;1,3=0,5=0
P 1.72756998 4.85788002 13 P 0 0;1,3=0,5=0
P 1.75118996 4.97913996 13 P 0 0;1,3=0,5=0
P 1.82206004 4.97913996 13 P 0 0;1,3=0,5=0
P 1.72756998 4.97913996 13 P 0 0;1,3=0,5=0
P 2.22363002 4.97913996 13 P 0 0;1,3=0,5=0
P 2.17638996 4.85788002 13 P 0 0;1,3=0,5=0
P 2.15276004 4.85788002 13 P 0 0;1,3=0,5=0
P 2.31811998 4.97913996 13 P 0 0;1,3=0,5=0
P 2.2945 4.97913996 13 P 0 0;1,3=0,5=0
P 2.24725 4.97913996 13 P 0 0;1,3=0,5=0
P 2.41261004 4.97913996 13 P 0 0;1,3=0,5=0
P 2.34173996 4.97913996 13 P 0 0;1,3=0,5=0
P 2.27086998 4.97913996 13 P 0 0;1,3=0,5=0
P 2.20001004 4.97913996 13 P 0 0;1,3=0,5=0
P 2.12913996 4.97913996 13 P 0 0;1,3=0,5=0
P 2.05828002 4.97913996 13 P 0 0;1,3=0,5=0
P 1.98741004 4.97913996 13 P 0 0;1,3=0,5=0
P 1.91653996 4.97913996 13 P 0 0;1,3=0,5=0
P 1.84568002 4.97913996 13 P 0 0;1,3=0,5=0
P 1.77481004 4.97913996 13 P 0 0;1,3=0,5=0
P 1.70395 4.97913996 13 P 0 0;1,3=0,5=0
P 1.63308002 4.97913996 13 P 0 0;1,3=0,5=0
P 1.56221004 4.97913996 13 P 0 0;1,3=0,5=0
P 2.41261004 4.85788002 13 P 0 0;1,3=0,5=0
P 2.34173996 4.85788002 13 P 0 0;1,3=0,5=0
P 2.27086998 4.85788002 13 P 0 0;1,3=0,5=0
P 2.20001004 4.85788002 13 P 0 0;1,3=0,5=0
P 2.12913996 4.85788002 13 P 0 0;1,3=0,5=0
P 2.05828002 4.85788002 13 P 0 0;1,3=0,5=0
P 1.98741004 4.85788002 13 P 0 0;1,3=0,5=0
P 1.91653996 4.85788002 13 P 0 0;1,3=0,5=0
P 1.84568002 4.85788002 13 P 0 0;1,3=0,5=0
P 1.77481004 4.85788002 13 P 0 0;1,3=0,5=0
P 1.70395 4.85788002 13 P 0 0;1,3=0,5=0
P 1.63308002 4.85788002 13 P 0 0;1,3=0,5=0
P 1.56221004 4.85788002 13 P 0 0;1,3=0,5=0
P 2.45985 4.77875 6 P 0 0;3=22,5=0
P 1.51496998 4.77875 6 P 0 0;3=22,5=0
P 2.44016998 5.05826998 6 P 0 0;3=22,5=0
P 1.53465 5.05826998 6 P 0 0;3=22,5=0
P 3.34098996 4.85788002 13 P 0 0;1,3=0,5=0
P 3.31736004 4.85788002 13 P 0 0;1,3=0,5=0
P 3.48271998 4.97913996 13 P 0 0;1,3=0,5=0
P 2.96303002 4.97913996 13 P 0 0;1,3=0,5=0
P 2.91578996 4.85788002 13 P 0 0;1,3=0,5=0
P 2.89216998 4.85788002 13 P 0 0;1,3=0,5=0
P 2.91578996 4.97913996 13 P 0 0;1,3=0,5=0
P 2.89216998 4.97913996 13 P 0 0;1,3=0,5=0
P 2.98666004 4.97913996 13 P 0 0;1,3=0,5=0
P 3.36461004 4.85788002 13 P 0 0;1,3=0,5=0
P 3.29373996 4.85788002 13 P 0 0;1,3=0,5=0
P 3.22288002 4.85788002 13 P 0 0;1,3=0,5=0
P 3.15201004 4.85788002 13 P 0 0;1,3=0,5=0
P 3.08113996 4.85788002 13 P 0 0;1,3=0,5=0
P 3.01028002 4.85788002 13 P 0 0;1,3=0,5=0
P 2.93941004 4.85788002 13 P 0 0;1,3=0,5=0
P 2.86855 4.85788002 13 P 0 0;1,3=0,5=0
P 2.79768002 4.85788002 13 P 0 0;1,3=0,5=0
P 2.72681004 4.85788002 13 P 0 0;1,3=0,5=0
P 3.60476998 4.77875 6 P 0 0;3=22,5=0
P 2.67956998 4.77875 6 P 0 0;3=22,5=0
P 3.60476998 5.05826998 6 P 0 0;3=22,5=0
P 2.69925 5.05826998 6 P 0 0;3=22,5=0
P 3.57721004 4.97913996 13 P 0 0;1,3=0,5=0
P 3.50633996 4.97913996 13 P 0 0;1,3=0,5=0
P 3.43546998 4.97913996 13 P 0 0;1,3=0,5=0
P 3.36461004 4.97913996 13 P 0 0;1,3=0,5=0
P 3.29373996 4.97913996 13 P 0 0;1,3=0,5=0
P 3.22288002 4.97913996 13 P 0 0;1,3=0,5=0
P 3.15201004 4.97913996 13 P 0 0;1,3=0,5=0
P 3.08113996 4.97913996 13 P 0 0;1,3=0,5=0
P 3.01028002 4.97913996 13 P 0 0;1,3=0,5=0
P 2.93941004 4.97913996 13 P 0 0;1,3=0,5=0
P 2.86855 4.97913996 13 P 0 0;1,3=0,5=0
P 2.79768002 4.97913996 13 P 0 0;1,3=0,5=0
P 2.72681004 4.97913996 13 P 0 0;1,3=0,5=0
P 3.57721004 4.85788002 13 P 0 0;1,3=0,5=0
P 3.50633996 4.85788002 13 P 0 0;1,3=0,5=0
P 3.43546998 4.85788002 13 P 0 0;1,3=0,5=0
P 8.25078996 4.97913996 13 P 0 0;1,3=0,5=0
P 8.22716998 4.97913996 13 P 0 0;1,3=0,5=0
P 8.17993002 4.85788002 13 P 0 0;1,3=0,5=0
P 8.1563 4.85788002 13 P 0 0;1,3=0,5=0
P 8.32166004 4.97913996 13 P 0 0;1,3=0,5=0
P 8.29803996 4.97913996 13 P 0 0;1,3=0,5=0
P 7.80196998 4.97913996 13 P 0 0;1,3=0,5=0
P 7.75473002 4.85788002 13 P 0 0;1,3=0,5=0
P 7.73111004 4.85788002 13 P 0 0;1,3=0,5=0
P 7.75473002 4.97913996 13 P 0 0;1,3=0,5=0
P 7.73111004 4.97913996 13 P 0 0;1,3=0,5=0
P 7.8256 4.97913996 13 P 0 0;1,3=0,5=0
P 8.20355 4.85788002 13 P 0 0;1,3=0,5=0
P 8.13268002 4.85788002 13 P 0 0;1,3=0,5=0
P 8.06181998 4.85788002 13 P 0 0;1,3=0,5=0
P 7.99095 4.85788002 13 P 0 0;1,3=0,5=0
P 7.92008002 4.85788002 13 P 0 0;1,3=0,5=0
P 7.84921998 4.85788002 13 P 0 0;1,3=0,5=0
P 7.77835 4.85788002 13 P 0 0;1,3=0,5=0
P 7.70748996 4.85788002 13 P 0 0;1,3=0,5=0
P 7.63661998 4.85788002 13 P 0 0;1,3=0,5=0
P 7.56575 4.85788002 13 P 0 0;1,3=0,5=0
P 8.46338996 4.77875 6 P 0 0;3=22,5=0
P 7.51851004 4.77875 6 P 0 0;3=22,5=0
P 8.44371004 5.05826998 6 P 0 0;3=22,5=0
P 7.53818996 5.05826998 6 P 0 0;3=22,5=0
P 8.41615 4.97913996 13 P 0 0;1,3=0,5=0
P 8.34528002 4.97913996 13 P 0 0;1,3=0,5=0
P 8.27441004 4.97913996 13 P 0 0;1,3=0,5=0
P 8.20355 4.97913996 13 P 0 0;1,3=0,5=0
P 8.13268002 4.97913996 13 P 0 0;1,3=0,5=0
P 8.06181998 4.97913996 13 P 0 0;1,3=0,5=0
P 7.99095 4.97913996 13 P 0 0;1,3=0,5=0
P 7.92008002 4.97913996 13 P 0 0;1,3=0,5=0
P 7.84921998 4.97913996 13 P 0 0;1,3=0,5=0
P 7.77835 4.97913996 13 P 0 0;1,3=0,5=0
P 7.70748996 4.97913996 13 P 0 0;1,3=0,5=0
P 7.63661998 4.97913996 13 P 0 0;1,3=0,5=0
P 7.56575 4.97913996 13 P 0 0;1,3=0,5=0
P 8.41615 4.85788002 13 P 0 0;1,3=0,5=0
P 8.34528002 4.85788002 13 P 0 0;1,3=0,5=0
P 8.27441004 4.85788002 13 P 0 0;1,3=0,5=0
P 9.34453002 4.85788002 13 P 0 0;1,3=0,5=0
P 9.3209 4.85788002 13 P 0 0;1,3=0,5=0
P 9.48626004 4.97913996 13 P 0 0;1,3=0,5=0
P 8.96656998 4.97913996 13 P 0 0;1,3=0,5=0
P 8.91933002 4.85788002 13 P 0 0;1,3=0,5=0
P 8.89571004 4.85788002 13 P 0 0;1,3=0,5=0
P 8.91933002 4.97913996 13 P 0 0;1,3=0,5=0
P 8.89571004 4.97913996 13 P 0 0;1,3=0,5=0
P 8.9902 4.97913996 13 P 0 0;1,3=0,5=0
P 9.36815 4.85788002 13 P 0 0;1,3=0,5=0
P 9.29728002 4.85788002 13 P 0 0;1,3=0,5=0
P 9.22641998 4.85788002 13 P 0 0;1,3=0,5=0
P 9.15555 4.85788002 13 P 0 0;1,3=0,5=0
P 9.08468002 4.85788002 13 P 0 0;1,3=0,5=0
P 9.01381998 4.85788002 13 P 0 0;1,3=0,5=0
P 8.94295 4.85788002 13 P 0 0;1,3=0,5=0
P 8.87208996 4.85788002 13 P 0 0;1,3=0,5=0
P 8.80121998 4.85788002 13 P 0 0;1,3=0,5=0
P 8.73035 4.85788002 13 P 0 0;1,3=0,5=0
P 9.60831004 4.77875 6 P 0 0;3=22,5=0
P 8.68311004 4.77875 6 P 0 0;3=22,5=0
P 9.60831004 5.05826998 6 P 0 0;3=22,5=0
P 8.70278996 5.05826998 6 P 0 0;3=22,5=0
P 9.58075 4.97913996 13 P 0 0;1,3=0,5=0
P 9.50988002 4.97913996 13 P 0 0;1,3=0,5=0
P 9.43901004 4.97913996 13 P 0 0;1,3=0,5=0
P 9.36815 4.97913996 13 P 0 0;1,3=0,5=0
P 9.29728002 4.97913996 13 P 0 0;1,3=0,5=0
P 9.22641998 4.97913996 13 P 0 0;1,3=0,5=0
P 9.15555 4.97913996 13 P 0 0;1,3=0,5=0
P 9.08468002 4.97913996 13 P 0 0;1,3=0,5=0
P 9.01381998 4.97913996 13 P 0 0;1,3=0,5=0
P 8.94295 4.97913996 13 P 0 0;1,3=0,5=0
P 8.87208996 4.97913996 13 P 0 0;1,3=0,5=0
P 8.80121998 4.97913996 13 P 0 0;1,3=0,5=0
P 8.73035 4.97913996 13 P 0 0;1,3=0,5=0
P 9.58075 4.85788002 13 P 0 0;1,3=0,5=0
P 9.50988002 4.85788002 13 P 0 0;1,3=0,5=0
P 9.43901004 4.85788002 13 P 0 0;1,3=0,5=0
P 8.78543996 2.86613996 19 P 0 0;1,3=23,5=0
P 10.30118002 2.86613996 19 P 0 0;1,3=23,5=0
P 2.7815 2.86613996 19 P 0 0;1,3=23,5=0
P 4.29723996 2.86613996 19 P 0 0;1,3=23,5=0
P 12.04 4.96 10 P 0 0;1,3=13,5=0
P 12.2 4.96 10 P 0 0;1,3=13,5=0
P 12.12 4.993 7 P 0 0;1,3=1,5=0
P 10.51 5.18 10 P 0 0;1,3=13,5=0
P 10.51 5.26 10 P 0 0;1,3=13,5=0
P 10.543 5.32 7 P 0 0;1,3=1,5=0
P 2.22106004 3.54115 4 P 0 0;1,3=8,5=0
P 8.175 3.24115 4 P 0 0;1,3=8,5=0
P 7.66023996 4.97913996 13 P 0 0;1,3=0,5=0
P 2.27106004 2.84115 4 P 0 0;1,3=8,5=0
P 2.27106004 3.54115 4 P 0 0;1,3=8,5=0
P 7.68386004 4.97913996 13 P 0 0;1,3=0,5=0
P 8.175 3.29115 4 P 0 0;1,3=8,5=0
P 1.30186004 4.79681998 15 P 0 0;1,3=12,5=0
P 1.33906004 4.66551004 7 P 0 0;1,3=1,5=0
P 0.80806998 5.53641998 26 P 0 0;1,3=10,5=0
P 0.83 5.417 7 P 0 0;1,3=1,5=0
P 0.68 5.147 7 P 0 0;1,3=1,5=0
P 3.77441004 4.63965 14 P 0 0;1,3=5,5=0
P 1.28906004 4.66551004 7 P 0 0;1,3=1,5=0
P 1.27626004 4.79681998 15 P 0 0;1,3=12,5=0
P 8.175 3.39115 4 P 0 0;1,3=8,5=0
P 7.87283996 4.97913996 13 P 0 0;1,3=0,5=0
P 3.9399 4.79498996 7 P 0 0;1,3=1,5=0
P 3.94 4.717 7 P 0 0;1,3=1,5=0
P 3.99965 4.71558996 25 P 0 0;1,3=5,5=0
P 2.32106004 3.24115 4 P 0 0;1,3=8,5=0
P 2.38898002 4.85788002 13 P 0 0;1,3=0,5=0
P 8.175 3.44115 4 P 0 0;1,3=8,5=0
P 7.89646004 4.97913996 13 P 0 0;1,3=0,5=0
P 2.03465 4.97913996 13 P 0 0;1,3=0,5=0
P 2.32106004 3.29115 4 P 0 0;1,3=8,5=0
P 2.36536004 4.85788002 13 P 0 0;1,3=0,5=0
P 1.33906004 5.12551004 7 P 0 0;1,3=1,5=0
P 3.12838996 4.85788002 13 P 0 0;1,3=0,5=0
P 8.025 3.44115 4 P 0 0;1,3=8,5=0
P 7.94371004 4.97913996 13 P 0 0;1,3=0,5=0
P 2.01103002 4.97913996 13 P 0 0;1,3=0,5=0
P 2.31811998 4.85788002 13 P 0 0;1,3=0,5=0
P 2.37106004 3.29115 4 P 0 0;1,3=8,5=0
P 1.18906004 5.12551004 7 P 0 0;1,3=1,5=0
P 3.10476998 4.85788002 13 P 0 0;1,3=0,5=0
P 8.025 3.49115 4 P 0 0;1,3=8,5=0
P 7.96733002 4.97913996 13 P 0 0;1,3=0,5=0
P 2.2945 4.85788002 13 P 0 0;1,3=0,5=0
P 2.37106004 3.34115 4 P 0 0;1,3=8,5=0
P 8.10906004 4.97913996 13 P 0 0;1,3=0,5=0
P 8.375 3.44115 4 P 0 0;1,3=8,5=0
P 3.60998996 0.62931998 20 P 0 0;1,3=20,5=0
P 3.60998996 0.7411 7 P 0 0;1,3=1,5=0
P 4.65768002 2.84115 4 P 0 0;1,3=8,5=0
P 2.42106004 3.24115 4 P 0 0;1,3=8,5=0
P 2.38898002 4.97913996 13 P 0 0;1,3=0,5=0
P 8.08543996 4.97913996 13 P 0 0;1,3=0,5=0
P 8.375 3.49115 4 P 0 0;1,3=8,5=0
P 2.42106004 3.29115 4 P 0 0;1,3=8,5=0
P 2.36536004 4.97913996 13 P 0 0;1,3=0,5=0
P 8.475 3.44115 4 P 0 0;1,3=8,5=0
P 8.03818996 4.85788002 13 P 0 0;1,3=0,5=0
P 2.47106004 3.29115 4 P 0 0;1,3=8,5=0
P 2.24725 4.85788002 13 P 0 0;1,3=0,5=0
P 8.475 3.49115 4 P 0 0;1,3=8,5=0
P 8.01456998 4.85788002 13 P 0 0;1,3=0,5=0
P 4.03666998 5.18321004 15 P 0 0;1,3=12,5=0
P 4.0599 5.32498996 7 P 0 0;1,3=1,5=0
P 4.60768002 2.79115 4 P 0 0;1,3=8,5=0
P 2.47106004 3.34115 4 P 0 0;1,3=8,5=0
P 2.22363002 4.85788002 13 P 0 0;1,3=0,5=0
P 8.325 3.39115 4 P 0 0;1,3=8,5=0
P 8.10906004 4.85788002 13 P 0 0;1,3=0,5=0
P 4.80768002 2.74115 4 P 0 0;1,3=8,5=0
P 2.10551998 4.85788002 13 P 0 0;1,3=0,5=0
P 2.32106004 3.39115 4 P 0 0;1,3=8,5=0
P 8.325 3.44115 4 P 0 0;1,3=8,5=0
P 8.08543996 4.85788002 13 P 0 0;1,3=0,5=0
P 5.05768002 2.74115 4 P 0 0;1,3=8,5=0
P 4.01108002 4.96076998 15 P 0 0;1,3=12,5=0
P 4.0399 4.82898996 7 P 0 0;1,3=1,5=0
P 2.0819 4.85788002 13 P 0 0;1,3=0,5=0
P 2.32106004 3.44115 4 P 0 0;1,3=8,5=0
P 2.17638996 4.97913996 13 P 0 0;1,3=0,5=0
P 2.42106004 3.39115 4 P 0 0;1,3=8,5=0
P 10.91161004 2.44115 4 P 0 0;1,3=8,5=0
P 2.15276004 4.97913996 13 P 0 0;1,3=0,5=0
P 2.42106004 3.44115 4 P 0 0;1,3=8,5=0
P 10.91161004 2.49115 4 P 0 0;1,3=8,5=0
P 8.475 3.29115 4 P 0 0;1,3=8,5=0
P 8.25078996 4.85788002 13 P 0 0;1,3=0,5=0
P 4.85768002 2.74115 4 P 0 0;1,3=8,5=0
P 2.03465 4.85788002 13 P 0 0;1,3=0,5=0
P 2.47106004 3.44115 4 P 0 0;1,3=8,5=0
P 8.475 3.34115 4 P 0 0;1,3=8,5=0
P 8.22716998 4.85788002 13 P 0 0;1,3=0,5=0
P 2.01103002 4.85788002 13 P 0 0;1,3=0,5=0
P 2.47106004 3.49115 4 P 0 0;1,3=8,5=0
P 8.375 3.29115 4 P 0 0;1,3=8,5=0
P 8.32166004 4.85788002 13 P 0 0;1,3=0,5=0
P 2.10551998 4.97913996 13 P 0 0;1,3=0,5=0
P 2.37106004 3.44115 4 P 0 0;1,3=8,5=0
P 8.375 3.34115 4 P 0 0;1,3=8,5=0
P 8.29803996 4.85788002 13 P 0 0;1,3=0,5=0
P 3.81998996 0.7411 7 P 0 0;1,3=1,5=0
P 3.80998996 0.62931998 20 P 0 0;1,3=20,5=0
P 4.70768002 2.79115 4 P 0 0;1,3=8,5=0
P 2.0819 4.97913996 13 P 0 0;1,3=0,5=0
P 2.37106004 3.49115 4 P 0 0;1,3=8,5=0
P 3.75998996 0.62931998 20 P 0 0;1,3=20,5=0
P 4.75768002 2.84115 4 P 0 0;1,3=8,5=0
P 2.02106004 3.29115 4 P 0 0;1,3=8,5=0
P 1.58583996 4.97913996 13 P 0 0;1,3=0,5=0
P 7.3426 5.12551004 7 P 0 0;1,3=1,5=0
P 9.13193002 4.85788002 13 P 0 0;1,3=0,5=0
P 3.66998996 0.7411 7 P 0 0;1,3=1,5=0
P 3.65998996 0.62931998 20 P 0 0;1,3=20,5=0
P 4.80768002 2.84115 4 P 0 0;1,3=8,5=0
P 2.02106004 3.34115 4 P 0 0;1,3=8,5=0
P 1.60946004 4.97913996 13 P 0 0;1,3=0,5=0
P 0.82983996 5.2361 12 P 0 0;1,3=7,5=0
P 0.9 5.417 7 P 0 0;1,3=1,5=0
P 0.88681004 5.53641998 26 P 0 0;1,3=10,5=0
P 0.83 5.295 5 P 0 0;2,3=3,5=1
P 8.075 3.24115 4 P 0 0;1,3=8,5=0
P 7.58938002 4.85788002 13 P 0 0;1,3=0,5=0
P 2.07106004 3.24115 4 P 0 0;1,3=8,5=0
P 1.58583996 4.85788002 13 P 0 0;1,3=0,5=0
P 5.05768002 1.99115 4 P 0 0;1,3=8,5=0
P 8.075 3.29115 4 P 0 0;1,3=8,5=0
P 7.613 4.85788002 13 P 0 0;1,3=0,5=0
P 3.75998996 0.3051 7 P 0 0;1,3=1,5=0
P 3.75998996 0.40688002 20 P 0 0;1,3=20,5=0
P 4.70768002 2.84115 4 P 0 0;1,3=8,5=0
P 2.07106004 3.29115 4 P 0 0;1,3=8,5=0
P 1.60946004 4.85788002 13 P 0 0;1,3=0,5=0
P 0.52 5.591 8 P 0 0;1,3=15,5=0
P 7.2926 5.12551004 7 P 0 0;1,3=1,5=0
P 7.2426 5.12551004 7 P 0 0;1,3=1,5=0
P 7.1926 4.98151004 7 P 0 0;1,3=1,5=0
P 7.25421004 4.9602 15 P 0 0;1,3=12,5=0
P 7.3926 5.12551004 7 P 0 0;1,3=1,5=0
P 3.94 4.627 7 P 0 0;1,3=1,5=0
P 3.94 4.683 7 P 0 0;1,3=1,5=0
P 3.77441004 4.72035 14 P 0 0;1,3=5,5=0
P 3.77 4.793 7 P 0 0;1,3=1,5=0
P 4.08035 4.71558996 25 P 0 0;1,3=5,5=0
P 4.14 4.717 7 P 0 0;1,3=1,5=0
P 4.76 5.408 7 P 0 0;1,3=1,5=0
P 4.9574 5.54685 18 P 0 0;1,3=2,5=0
P 5.09558996 5.55965 14 P 0 0;1,3=5,5=0
P 5.16 5.583 7 P 0 0;1,3=1,5=0
P 4.86 5.767 7 P 0 0;1,3=1,5=0
P 5.06 5.767 7 P 0 0;1,3=1,5=0
P 0.91 5.113 7 P 0 0;1,3=1,5=0
P 1.03 4.993 7 P 0 0;1,3=1,5=0
P 1.02558996 5.20965 14 P 0 0;1,3=5,5=0
P 1.03 5.127 7 P 0 0;1,3=1,5=0
P 1.38906004 5.12551004 7 P 0 0;1,3=1,5=0
P 1.23906004 5.12551004 7 P 0 0;1,3=1,5=0
P 1.28906004 5.12551004 7 P 0 0;1,3=1,5=0
P 1.25066998 4.9602 15 P 0 0;1,3=12,5=0
P 1.18906004 4.98151004 7 P 0 0;1,3=1,5=0
P 0.83 5.383 7 P 0 0;1,3=1,5=0
P 0.948 5.383 7 P 0 0;1,3=1,5=0
P 0.9 5.383 7 P 0 0;1,3=1,5=0
P 0.755 5.383 7 P 0 0;1,3=1,5=0
P 0.81016004 5.2361 12 P 0 0;1,3=7,5=0
P 0.73 5.233 7 P 0 0;1,3=1,5=0
P 0.79046998 5.2361 12 P 0 0;1,3=7,5=0
P 0.81016004 5.1239 12 P 0 0;1,3=7,5=0
P 1.094 5.383 7 P 0 0;1,3=1,5=0
P 1.044 5.417 7 P 0 0;1,3=1,5=0
P 1.31 5.417 7 P 0 0;1,3=1,5=0
P 1.46 5.417 7 P 0 0;1,3=1,5=0
P 1.41 5.417 7 P 0 0;1,3=1,5=0
P 1.36 5.417 7 P 0 0;1,3=1,5=0
P 1.43798996 5.53641998 26 P 0 0;1,3=10,5=0
P 1.35925 5.53641998 26 P 0 0;1,3=10,5=0
P 0.89 5.857 7 P 0 0;1,3=1,5=0
P 0.81 5.857 7 P 0 0;1,3=1,5=0
P 0.73 5.857 7 P 0 0;1,3=1,5=0
P 0.97 5.857 7 P 0 0;1,3=1,5=0
P 1.04 5.857 7 P 0 0;1,3=1,5=0
P 1.12 5.857 7 P 0 0;1,3=1,5=0
P 4.96 5.442 7 P 0 0;1,3=1,5=0
P 8.125 3.29115 4 P 0 0;1,3=8,5=0
P 7.66023996 4.85788002 13 P 0 0;1,3=0,5=0
P 3.60998996 0.3051 7 P 0 0;1,3=1,5=0
P 3.60998996 0.40688002 20 P 0 0;1,3=20,5=0
P 4.60768002 2.84115 4 P 0 0;1,3=8,5=0
P 2.17106004 3.24115 4 P 0 0;1,3=8,5=0
P 1.6567 4.97913996 13 P 0 0;1,3=0,5=0
P 8.125 3.34115 4 P 0 0;1,3=8,5=0
P 7.68386004 4.85788002 13 P 0 0;1,3=0,5=0
P 2.17106004 3.29115 4 P 0 0;1,3=8,5=0
P 1.68031998 4.97913996 13 P 0 0;1,3=0,5=0
P 8.075 3.39115 4 P 0 0;1,3=8,5=0
P 7.80196998 4.85788002 13 P 0 0;1,3=0,5=0
P 2.12106004 3.29115 4 P 0 0;1,3=8,5=0
P 1.6567 4.85788002 13 P 0 0;1,3=0,5=0
P 8.075 3.44115 4 P 0 0;1,3=8,5=0
P 7.8256 4.85788002 13 P 0 0;1,3=0,5=0
P 2.12106004 3.34115 4 P 0 0;1,3=8,5=0
P 1.68031998 4.85788002 13 P 0 0;1,3=0,5=0
P 0.73 4.993 7 P 0 0;1,3=1,5=0
P 3.8 4.63965 14 P 0 0;1,3=5,5=0
P 4.86 5.408 7 P 0 0;1,3=1,5=0
P 8.125 3.44115 4 P 0 0;1,3=8,5=0
P 7.87283996 4.85788002 13 P 0 0;1,3=0,5=0
P 2.07106004 3.39115 4 P 0 0;1,3=8,5=0
P 1.79843002 4.85788002 13 P 0 0;1,3=0,5=0
P 8.125 3.49115 4 P 0 0;1,3=8,5=0
P 7.89646004 4.85788002 13 P 0 0;1,3=0,5=0
P 2.07106004 3.44115 4 P 0 0;1,3=8,5=0
P 1.82206004 4.85788002 13 P 0 0;1,3=0,5=0
P 2.17106004 3.39115 4 P 0 0;1,3=8,5=0
P 1.8693 4.97913996 13 P 0 0;1,3=0,5=0
P 2.17106004 3.44115 4 P 0 0;1,3=8,5=0
P 1.89291998 4.97913996 13 P 0 0;1,3=0,5=0
P 6.82978002 4.53096998 5 P 0 0;2,3=3,5=1
P 6.87618996 4.61586998 30 P 0 0;1,3=14,5=0
P 6.74208996 4.6252 10 P 0 0;1,3=13,5=0
P 11.10998996 5.03983002 11 P 0 0;1,3=18,5=0
P 11.52873996 4.88 16 P 0 0;1,3=21,5=0
P 10.577 5.32 7 P 0 0;1,3=1,5=0
P 10.59 5.18 10 P 0 0;1,3=13,5=0
P 10.59 5.26 10 P 0 0;1,3=13,5=0
P 12.04 5.04 10 P 0 0;1,3=13,5=0
P 12.12 5.027 7 P 0 0;1,3=1,5=0
P 12.2 5.04 10 P 0 0;1,3=13,5=0
P 5.10605 5.03983002 11 P 0 0;1,3=18,5=0
P 5.205 5.205 5 P 0 0;2,3=3,5=1
P 6.34948996 4.99705 7 P 0 0;1,3=1,5=0
P 2.75043996 4.97913996 13 P 0 0;1,3=0,5=0
P 2.02106004 3.59115 4 P 0 0;1,3=8,5=0
P 2.12106004 3.44115 4 P 0 0;1,3=8,5=0
P 1.8693 4.85788002 13 P 0 0;1,3=0,5=0
P 2.77406004 4.97913996 13 P 0 0;1,3=0,5=0
P 2.02106004 3.64115 4 P 0 0;1,3=8,5=0
P 2.12106004 3.49115 4 P 0 0;1,3=8,5=0
P 1.89291998 4.85788002 13 P 0 0;1,3=0,5=0
P 1.94016998 4.97913996 13 P 0 0;1,3=0,5=0
P 2.02106004 3.44115 4 P 0 0;1,3=8,5=0
P 4.60768002 2.59115 4 P 0 0;1,3=8,5=0
P 1.96378996 4.97913996 13 P 0 0;1,3=0,5=0
P 2.02106004 3.49115 4 P 0 0;1,3=8,5=0
P 2.12106004 3.59115 4 P 0 0;1,3=8,5=0
P 2.8213 4.97913996 13 P 0 0;1,3=0,5=0
P 2.32106004 3.64115 4 P 0 0;1,3=8,5=0
P 3.55358002 4.85788002 13 P 0 0;1,3=0,5=0
P 2.12106004 3.64115 4 P 0 0;1,3=8,5=0
P 2.84491998 4.97913996 13 P 0 0;1,3=0,5=0
P 2.32106004 3.69115 4 P 0 0;1,3=8,5=0
P 3.52996004 4.85788002 13 P 0 0;1,3=0,5=0
P 2.37106004 3.59115 4 P 0 0;1,3=8,5=0
P 3.48271998 4.85788002 13 P 0 0;1,3=0,5=0
P 2.37106004 3.64115 4 P 0 0;1,3=8,5=0
P 3.4591 4.85788002 13 P 0 0;1,3=0,5=0
P 2.47106004 3.59115 4 P 0 0;1,3=8,5=0
P 3.55358002 4.97913996 13 P 0 0;1,3=0,5=0
P 2.47106004 3.64115 4 P 0 0;1,3=8,5=0
P 3.52996004 4.97913996 13 P 0 0;1,3=0,5=0
P 2.42106004 3.64115 4 P 0 0;1,3=8,5=0
P 3.41185 4.85788002 13 P 0 0;1,3=0,5=0
P 4.65768002 2.99115 4 P 0 0;1,3=8,5=0
P 4.60768002 3.09115 4 P 0 0;1,3=8,5=0
P 4.60768002 2.99115 4 P 0 0;1,3=8,5=0
P 4.65768002 3.09115 4 P 0 0;1,3=8,5=0
P 4.65768002 2.94115 4 P 0 0;1,3=8,5=0
P 4.60768002 2.94115 4 P 0 0;1,3=8,5=0
P 4.80768002 2.99115 4 P 0 0;1,3=8,5=0
P 4.80768002 3.09115 4 P 0 0;1,3=8,5=0
P 4.85768002 3.09115 4 P 0 0;1,3=8,5=0
P 4.85768002 2.99115 4 P 0 0;1,3=8,5=0
P 4.75768002 2.99115 4 P 0 0;1,3=8,5=0
P 4.75768002 3.09115 4 P 0 0;1,3=8,5=0
P 4.70768002 2.99115 4 P 0 0;1,3=8,5=0
P 4.70768002 3.09115 4 P 0 0;1,3=8,5=0
P 4.80768002 2.94115 4 P 0 0;1,3=8,5=0
P 4.85768002 2.94115 4 P 0 0;1,3=8,5=0
P 4.75768002 2.94115 4 P 0 0;1,3=8,5=0
P 4.70768002 2.94115 4 P 0 0;1,3=8,5=0
P 5.00768002 2.99115 4 P 0 0;1,3=8,5=0
P 5.00768002 3.09115 4 P 0 0;1,3=8,5=0
P 5.05768002 2.99115 4 P 0 0;1,3=8,5=0
P 5.05768002 3.09115 4 P 0 0;1,3=8,5=0
P 4.90768002 2.99115 4 P 0 0;1,3=8,5=0
P 4.90768002 3.09115 4 P 0 0;1,3=8,5=0
P 4.95768002 3.09115 4 P 0 0;1,3=8,5=0
P 4.95768002 2.99115 4 P 0 0;1,3=8,5=0
P 5.05768002 2.94115 4 P 0 0;1,3=8,5=0
P 5.00768002 2.94115 4 P 0 0;1,3=8,5=0
P 4.90768002 2.94115 4 P 0 0;1,3=8,5=0
P 4.95768002 2.94115 4 P 0 0;1,3=8,5=0
P 4.65768002 3.24115 4 P 0 0;1,3=8,5=0
P 4.60768002 3.29115 4 P 0 0;1,3=8,5=0
P 4.60768002 3.24115 4 P 0 0;1,3=8,5=0
P 4.65768002 3.29115 4 P 0 0;1,3=8,5=0
P 4.60768002 3.14115 4 P 0 0;1,3=8,5=0
P 4.65768002 3.14115 4 P 0 0;1,3=8,5=0
P 4.80768002 3.29115 4 P 0 0;1,3=8,5=0
P 4.80768002 3.24115 4 P 0 0;1,3=8,5=0
P 4.85768002 3.24115 4 P 0 0;1,3=8,5=0
P 4.85768002 3.29115 4 P 0 0;1,3=8,5=0
P 4.70768002 3.29115 4 P 0 0;1,3=8,5=0
P 4.70768002 3.24115 4 P 0 0;1,3=8,5=0
P 4.75768002 3.24115 4 P 0 0;1,3=8,5=0
P 4.75768002 3.29115 4 P 0 0;1,3=8,5=0
P 4.80768002 3.14115 4 P 0 0;1,3=8,5=0
P 4.85768002 3.14115 4 P 0 0;1,3=8,5=0
P 4.70768002 3.14115 4 P 0 0;1,3=8,5=0
P 4.75768002 3.14115 4 P 0 0;1,3=8,5=0
P 5.00768002 3.29115 4 P 0 0;1,3=8,5=0
P 5.05768002 3.29115 4 P 0 0;1,3=8,5=0
P 5.00768002 3.24115 4 P 0 0;1,3=8,5=0
P 5.05768002 3.24115 4 P 0 0;1,3=8,5=0
P 4.95768002 3.24115 4 P 0 0;1,3=8,5=0
P 4.95768002 3.29115 4 P 0 0;1,3=8,5=0
P 4.90768002 3.29115 4 P 0 0;1,3=8,5=0
P 4.90768002 3.24115 4 P 0 0;1,3=8,5=0
P 5.00768002 3.14115 4 P 0 0;1,3=8,5=0
P 5.05768002 3.14115 4 P 0 0;1,3=8,5=0
P 4.95768002 3.14115 4 P 0 0;1,3=8,5=0
P 4.90768002 3.14115 4 P 0 0;1,3=8,5=0
P 4.65768002 3.54115 4 P 0 0;1,3=8,5=0
P 4.65768002 3.59115 4 P 0 0;1,3=8,5=0
P 4.60768002 3.54115 4 P 0 0;1,3=8,5=0
P 4.60768002 3.59115 4 P 0 0;1,3=8,5=0
P 4.60768002 3.39115 4 P 0 0;1,3=8,5=0
P 4.65768002 3.44115 4 P 0 0;1,3=8,5=0
P 4.65768002 3.39115 4 P 0 0;1,3=8,5=0
P 4.60768002 3.44115 4 P 0 0;1,3=8,5=0
P 4.80768002 3.54115 4 P 0 0;1,3=8,5=0
P 4.80768002 3.59115 4 P 0 0;1,3=8,5=0
P 4.85768002 3.54115 4 P 0 0;1,3=8,5=0
P 4.85768002 3.59115 4 P 0 0;1,3=8,5=0
P 4.70768002 3.59115 4 P 0 0;1,3=8,5=0
P 4.70768002 3.54115 4 P 0 0;1,3=8,5=0
P 4.75768002 3.59115 4 P 0 0;1,3=8,5=0
P 4.75768002 3.54115 4 P 0 0;1,3=8,5=0
P 4.80768002 3.39115 4 P 0 0;1,3=8,5=0
P 4.80768002 3.44115 4 P 0 0;1,3=8,5=0
P 4.85768002 3.44115 4 P 0 0;1,3=8,5=0
P 4.85768002 3.39115 4 P 0 0;1,3=8,5=0
P 4.75768002 3.44115 4 P 0 0;1,3=8,5=0
P 4.70768002 3.44115 4 P 0 0;1,3=8,5=0
P 4.70768002 3.39115 4 P 0 0;1,3=8,5=0
P 4.75768002 3.39115 4 P 0 0;1,3=8,5=0
P 5.00768002 3.59115 4 P 0 0;1,3=8,5=0
P 5.05768002 3.59115 4 P 0 0;1,3=8,5=0
P 5.00768002 3.54115 4 P 0 0;1,3=8,5=0
P 5.05768002 3.54115 4 P 0 0;1,3=8,5=0
P 4.95768002 3.59115 4 P 0 0;1,3=8,5=0
P 4.95768002 3.54115 4 P 0 0;1,3=8,5=0
P 4.90768002 3.59115 4 P 0 0;1,3=8,5=0
P 4.90768002 3.54115 4 P 0 0;1,3=8,5=0
P 5.00768002 3.39115 4 P 0 0;1,3=8,5=0
P 5.05768002 3.39115 4 P 0 0;1,3=8,5=0
P 5.00768002 3.44115 4 P 0 0;1,3=8,5=0
P 5.05768002 3.44115 4 P 0 0;1,3=8,5=0
P 4.90768002 3.39115 4 P 0 0;1,3=8,5=0
P 4.90768002 3.44115 4 P 0 0;1,3=8,5=0
P 4.95768002 3.39115 4 P 0 0;1,3=8,5=0
P 4.95768002 3.44115 4 P 0 0;1,3=8,5=0
P 4.65768002 3.84115 4 P 0 0;1,3=8,5=0
P 4.65768002 3.74115 4 P 0 0;1,3=8,5=0
P 4.60768002 3.84115 4 P 0 0;1,3=8,5=0
P 4.60768002 3.74115 4 P 0 0;1,3=8,5=0
P 4.65768002 3.69115 4 P 0 0;1,3=8,5=0
P 4.60768002 3.69115 4 P 0 0;1,3=8,5=0
P 4.80768002 3.84115 4 P 0 0;1,3=8,5=0
P 4.80768002 3.74115 4 P 0 0;1,3=8,5=0
P 4.85768002 3.84115 4 P 0 0;1,3=8,5=0
P 4.85768002 3.74115 4 P 0 0;1,3=8,5=0
P 4.70768002 3.84115 4 P 0 0;1,3=8,5=0
P 4.70768002 3.74115 4 P 0 0;1,3=8,5=0
P 4.75768002 3.84115 4 P 0 0;1,3=8,5=0
P 4.75768002 3.74115 4 P 0 0;1,3=8,5=0
P 4.80768002 3.69115 4 P 0 0;1,3=8,5=0
P 4.85768002 3.69115 4 P 0 0;1,3=8,5=0
P 4.70768002 3.69115 4 P 0 0;1,3=8,5=0
P 4.75768002 3.69115 4 P 0 0;1,3=8,5=0
P 5.00768002 3.84115 4 P 0 0;1,3=8,5=0
P 5.00768002 3.74115 4 P 0 0;1,3=8,5=0
P 5.05768002 3.84115 4 P 0 0;1,3=8,5=0
P 5.05768002 3.74115 4 P 0 0;1,3=8,5=0
P 4.90768002 3.84115 4 P 0 0;1,3=8,5=0
P 4.95768002 3.74115 4 P 0 0;1,3=8,5=0
P 4.90768002 3.74115 4 P 0 0;1,3=8,5=0
P 4.95768002 3.84115 4 P 0 0;1,3=8,5=0
P 5.00768002 3.69115 4 P 0 0;1,3=8,5=0
P 5.05768002 3.69115 4 P 0 0;1,3=8,5=0
P 4.95768002 3.69115 4 P 0 0;1,3=8,5=0
P 4.90768002 3.69115 4 P 0 0;1,3=8,5=0
P 4.36305 4.74133996 31 P 0 0;1,3=17,5=0
P 4.75305 4.74133996 31 P 0 0;1,3=17,5=0
P 5.10605 4.75636998 11 P 0 0;1,3=18,5=0
P 2.42106004 3.69115 4 P 0 0;1,3=8,5=0
P 3.38823002 4.85788002 13 P 0 0;1,3=0,5=0
P 2.17106004 3.79115 4 P 0 0;1,3=8,5=0
P 3.0339 4.85788002 13 P 0 0;1,3=0,5=0
P 2.17106004 3.84115 4 P 0 0;1,3=8,5=0
P 3.05751998 4.85788002 13 P 0 0;1,3=0,5=0
P 2.37106004 3.74115 4 P 0 0;1,3=8,5=0
P 3.27011998 4.85788002 13 P 0 0;1,3=0,5=0
P 4.75768002 2.69115 4 P 0 0;1,3=8,5=0
P 10.76161004 2.69115 4 P 0 0;1,3=8,5=0
P 2.37106004 3.79115 4 P 0 0;1,3=8,5=0
P 3.2465 4.85788002 13 P 0 0;1,3=0,5=0
P 5.00768002 2.64115 4 P 0 0;1,3=8,5=0
P 2.47106004 3.74115 4 P 0 0;1,3=8,5=0
P 3.34098996 4.97913996 13 P 0 0;1,3=0,5=0
P 2.47106004 3.79115 4 P 0 0;1,3=8,5=0
P 3.31736004 4.97913996 13 P 0 0;1,3=0,5=0
P 11.01161004 2.64115 4 P 0 0;1,3=8,5=0
P 2.07106004 3.64115 4 P 0 0;1,3=8,5=0
P 2.75043996 4.85788002 13 P 0 0;1,3=0,5=0
P 2.42106004 3.79115 4 P 0 0;1,3=8,5=0
P 3.19925 4.85788002 13 P 0 0;1,3=0,5=0
P 2.07106004 3.69115 4 P 0 0;1,3=8,5=0
P 2.77406004 4.85788002 13 P 0 0;1,3=0,5=0
P 2.42106004 3.84115 4 P 0 0;1,3=8,5=0
P 3.17563002 4.85788002 13 P 0 0;1,3=0,5=0
P 2.32106004 3.79115 4 P 0 0;1,3=8,5=0
P 3.27011998 4.97913996 13 P 0 0;1,3=0,5=0
P 2.32106004 3.84115 4 P 0 0;1,3=8,5=0
P 3.2465 4.97913996 13 P 0 0;1,3=0,5=0
P 4.65768002 2.64115 4 P 0 0;1,3=8,5=0
P 10.96161004 2.64115 4 P 0 0;1,3=8,5=0
P 2.17106004 3.64115 4 P 0 0;1,3=8,5=0
P 2.8213 4.85788002 13 P 0 0;1,3=0,5=0
P 10.96161004 2.59115 4 P 0 0;1,3=8,5=0
P 2.17106004 3.69115 4 P 0 0;1,3=8,5=0
P 2.84491998 4.85788002 13 P 0 0;1,3=0,5=0
P 10.66161004 2.64115 4 P 0 0;1,3=8,5=0
P 2.07106004 3.79115 4 P 0 0;1,3=8,5=0
P 3.10476998 4.97913996 13 P 0 0;1,3=0,5=0
P 2.07106004 3.84115 4 P 0 0;1,3=8,5=0
P 3.12838996 4.97913996 13 P 0 0;1,3=0,5=0
P 2.02106004 3.74115 4 P 0 0;1,3=8,5=0
P 2.96303002 4.85788002 13 P 0 0;1,3=0,5=0
P 10.76161004 2.64115 4 P 0 0;1,3=8,5=0
P 2.02106004 3.79115 4 P 0 0;1,3=8,5=0
P 2.98666004 4.85788002 13 P 0 0;1,3=0,5=0
P 10.71161004 2.64115 4 P 0 0;1,3=8,5=0
P 5.00768002 2.44115 4 P 0 0;1,3=8,5=0
P 5.00768002 2.49115 4 P 0 0;1,3=8,5=0
P 11.06161004 2.59115 4 P 0 0;1,3=8,5=0
P 10.71161004 2.59115 4 P 0 0;1,3=8,5=0
P 9.20278996 4.97913996 13 P 0 0;1,3=0,5=0
P 4.75768002 2.64115 4 P 0 0;1,3=8,5=0
P 9.17916998 4.97913996 13 P 0 0;1,3=0,5=0
P 5.05768002 2.44115 4 P 0 0;1,3=8,5=0
P 10.91161004 2.69115 4 P 0 0;1,3=8,5=0
P 10.61161004 2.64115 4 P 0 0;1,3=8,5=0
P 8.125 3.74115 4 P 0 0;1,3=8,5=0
P 9.03743996 4.97913996 13 P 0 0;1,3=0,5=0
P 4.95768002 2.24115 4 P 0 0;1,3=8,5=0
P 10.61161004 2.59115 4 P 0 0;1,3=8,5=0
P 8.125 3.79115 4 P 0 0;1,3=8,5=0
P 9.06106004 4.97913996 13 P 0 0;1,3=0,5=0
P 11.01161004 2.69115 4 P 0 0;1,3=8,5=0
P 4.95768002 2.29115 4 P 0 0;1,3=8,5=0
P 10.91161004 2.64115 4 P 0 0;1,3=8,5=0
P 5.00768002 2.29115 4 P 0 0;1,3=8,5=0
P 11.06161004 2.64115 4 P 0 0;1,3=8,5=0
P 5.00768002 2.34115 4 P 0 0;1,3=8,5=0
P 10.66161004 2.69115 4 P 0 0;1,3=8,5=0
P 3.8399 4.82898996 7 P 0 0;1,3=1,5=0
P 3.88313002 4.96076998 15 P 0 0;1,3=12,5=0
P 3.84 4.87 5 P 0 0;2,3=3,5=1
P 3.8599 5.35898996 7 P 0 0;1,3=1,5=0
P 0.73 5.823 7 P 0 0;1,3=1,5=0
P 0.72933002 5.70373996 26 P 0 0;1,3=10,5=0
P 8.03818996 4.97913996 13 P 0 0;1,3=0,5=0
P 0.81 5.823 7 P 0 0;1,3=1,5=0
P 0.80806998 5.70373996 26 P 0 0;1,3=10,5=0
P 3.8399 4.79498996 7 P 0 0;1,3=1,5=0
P 8.01456998 4.97913996 13 P 0 0;1,3=0,5=0
P 3.90871998 5.18321004 15 P 0 0;1,3=12,5=0
P 3.8599 5.32498996 7 P 0 0;1,3=1,5=0
P 3.8599 5.2751 5 P 0 0;2,3=3,5=1
P 11.06161004 1.94115 4 P 0 0;1,3=8,5=0
P 4.95768002 1.94115 4 P 0 0;1,3=8,5=0
P 4.95768002 1.99115 4 P 0 0;1,3=8,5=0
P 4.90768002 1.89115 4 P 0 0;1,3=8,5=0
P 4.90768002 1.94115 4 P 0 0;1,3=8,5=0
P 3.8899 4.82898996 7 P 0 0;1,3=1,5=0
P 3.90871998 4.96076998 15 P 0 0;1,3=12,5=0
P 3.89 4.87 5 P 0 0;2,3=3,5=1
P 5.00768002 1.89115 4 P 0 0;1,3=8,5=0
P 3.9099 5.32498996 7 P 0 0;1,3=1,5=0
P 3.93431004 5.18321004 15 P 0 0;1,3=12,5=0
P 3.9099 5.2751 5 P 0 0;2,3=3,5=1
P 5.05768002 1.94115 4 P 0 0;1,3=8,5=0
P 5.05768002 2.59115 4 P 0 0;1,3=8,5=0
P 8.125 2.49115 4 P 0 0;1,3=8,5=0
P 4.95768002 2.64115 4 P 0 0;1,3=8,5=0
P 10.71161004 2.74115 4 P 0 0;1,3=8,5=0
P 10.96161004 2.74115 4 P 0 0;1,3=8,5=0
P 10.81161004 2.74115 4 P 0 0;1,3=8,5=0
P 4.90768002 2.69115 4 P 0 0;1,3=8,5=0
P 10.86161004 2.74115 4 P 0 0;1,3=8,5=0
P 10.71161004 2.79115 4 P 0 0;1,3=8,5=0
P 9.60795 0.65065 20 P 0 0;1,3=20,5=0
P 9.61795 0.76243002 7 P 0 0;1,3=1,5=0
P 10.61161004 2.84115 4 P 0 0;1,3=8,5=0
P 9.40795 0.42821004 20 P 0 0;1,3=20,5=0
P 9.40795 0.32643002 7 P 0 0;1,3=1,5=0
P 10.66161004 2.84115 4 P 0 0;1,3=8,5=0
P 9.40795 0.65065 20 P 0 0;1,3=20,5=0
P 9.40795 0.76243002 7 P 0 0;1,3=1,5=0
P 4.70768002 2.59115 4 P 0 0;1,3=8,5=0
P 10.71161004 2.84115 4 P 0 0;1,3=8,5=0
P 9.55795 0.32643002 7 P 0 0;1,3=1,5=0
P 9.55795 0.42821004 20 P 0 0;1,3=20,5=0
P 10.76161004 2.84115 4 P 0 0;1,3=8,5=0
P 9.55795 0.65065 20 P 0 0;1,3=20,5=0
P 5.00768002 2.69115 4 P 0 0;1,3=8,5=0
P 10.81161004 2.84115 4 P 0 0;1,3=8,5=0
P 9.45795 0.65065 20 P 0 0;1,3=20,5=0
P 9.46795 0.76243002 7 P 0 0;1,3=1,5=0
P 5.05768002 2.64115 4 P 0 0;1,3=8,5=0
P 11.06161004 1.99115 4 P 0 0;1,3=8,5=0
P 11.01161004 1.89115 4 P 0 0;1,3=8,5=0
P 11.01161004 1.94115 4 P 0 0;1,3=8,5=0
P 10.91161004 1.89115 4 P 0 0;1,3=8,5=0
P 10.91161004 1.94115 4 P 0 0;1,3=8,5=0
P 10.96161004 1.94115 4 P 0 0;1,3=8,5=0
P 10.96161004 1.99115 4 P 0 0;1,3=8,5=0
P 4.90768002 2.64115 4 P 0 0;1,3=8,5=0
P 11.01161004 2.04115 4 P 0 0;1,3=8,5=0
P 11.01161004 2.09115 4 P 0 0;1,3=8,5=0
P 10.91161004 2.04115 4 P 0 0;1,3=8,5=0
P 10.91161004 2.09115 4 P 0 0;1,3=8,5=0
P 10.96161004 2.09115 4 P 0 0;1,3=8,5=0
P 10.96161004 2.14115 4 P 0 0;1,3=8,5=0
P 11.06161004 2.09115 4 P 0 0;1,3=8,5=0
P 11.06161004 2.14115 4 P 0 0;1,3=8,5=0
P 3.17563002 4.97913996 13 P 0 0;1,3=0,5=0
P 4.65768002 2.69115 4 P 0 0;1,3=8,5=0
P 11.06161004 2.24115 4 P 0 0;1,3=8,5=0
P 4.95768002 2.59115 4 P 0 0;1,3=8,5=0
P 11.06161004 2.29115 4 P 0 0;1,3=8,5=0
P 11.01161004 2.29115 4 P 0 0;1,3=8,5=0
P 2.12106004 3.74115 4 P 0 0;1,3=8,5=0
P 3.0339 4.97913996 13 P 0 0;1,3=0,5=0
P 11.01161004 2.34115 4 P 0 0;1,3=8,5=0
P 10.96161004 2.24115 4 P 0 0;1,3=8,5=0
P 10.96161004 2.29115 4 P 0 0;1,3=8,5=0
P 3.19925 4.97913996 13 P 0 0;1,3=0,5=0
P 4.70768002 2.64115 4 P 0 0;1,3=8,5=0
P 10.91161004 2.29115 4 P 0 0;1,3=8,5=0
P 10.61161004 2.79115 4 P 0 0;1,3=8,5=0
P 3.98548996 5.18321004 15 P 0 0;1,3=12,5=0
P 4.0099 5.32498996 7 P 0 0;1,3=1,5=0
P 10.91161004 2.34115 4 P 0 0;1,3=8,5=0
P 10.86161004 2.19115 4 P 0 0;1,3=8,5=0
P 3.93431004 4.96076998 15 P 0 0;1,3=12,5=0
P 3.98548996 4.96076998 15 P 0 0;1,3=12,5=0
P 3.9399 4.82898996 7 P 0 0;1,3=1,5=0
P 3.94 4.87 5 P 0 0;2,3=3,5=1
P 10.76161004 1.94115 4 P 0 0;1,3=8,5=0
P 9.41538996 4.97913996 13 P 0 0;1,3=0,5=0
P 3.9599 5.18321004 15 P 0 0;1,3=12,5=0
P 4.01108002 5.18321004 15 P 0 0;1,3=12,5=0
P 3.9599 5.32498996 7 P 0 0;1,3=1,5=0
P 3.9599 5.275 5 P 0 0;2,3=3,5=1
P 4.60768002 2.64115 4 P 0 0;1,3=8,5=0
P 9.39176998 4.97913996 13 P 0 0;1,3=0,5=0
P 2.12106004 3.79115 4 P 0 0;1,3=8,5=0
P 3.05751998 4.97913996 13 P 0 0;1,3=0,5=0
P 11.06161004 2.74115 4 P 0 0;1,3=8,5=0
P 3.9599 4.96076998 15 P 0 0;1,3=12,5=0
P 3.9899 4.82898996 7 P 0 0;1,3=1,5=0
P 8.275 2.84115 4 P 0 0;1,3=8,5=0
P 4.80768002 2.19115 4 P 0 0;1,3=8,5=0
P 4.85768002 2.19115 4 P 0 0;1,3=8,5=0
P 8.225 2.84115 4 P 0 0;1,3=8,5=0
P 10.81161004 2.19115 4 P 0 0;1,3=8,5=0
P 10.71161004 2.29115 4 P 0 0;1,3=8,5=0
P 10.76161004 2.34115 4 P 0 0;1,3=8,5=0
P 10.71161004 1.94115 4 P 0 0;1,3=8,5=0
P 10.76161004 2.04115 4 P 0 0;1,3=8,5=0
P 10.61161004 2.24115 4 P 0 0;1,3=8,5=0
P 10.76161004 2.44115 4 P 0 0;1,3=8,5=0
P 7.3426 4.66551004 7 P 0 0;1,3=1,5=0
P 7.3054 4.79681998 15 P 0 0;1,3=12,5=0
P 7.2926 4.66551004 7 P 0 0;1,3=1,5=0
P 7.2798 4.79681998 15 P 0 0;1,3=12,5=0
P 10.71161004 2.24115 4 P 0 0;1,3=8,5=0
P 7.33098996 4.9602 15 P 0 0;1,3=12,5=0
P 7.3926 5.09151004 7 P 0 0;1,3=1,5=0
P 7.3926 5.04851004 5 P 0 0;2,3=3,5=1
P 10.76161004 2.29115 4 P 0 0;1,3=8,5=0
P 4.95768002 2.39115 4 P 0 0;1,3=8,5=0
P 10.76161004 1.89115 4 P 0 0;1,3=8,5=0
P 3.38823002 4.97913996 13 P 0 0;1,3=0,5=0
P 4.95768002 2.44115 4 P 0 0;1,3=8,5=0
P 3.41185 4.97913996 13 P 0 0;1,3=0,5=0
P 4.85768002 2.84115 4 P 0 0;1,3=8,5=0
P 4.90768002 2.84115 4 P 0 0;1,3=8,5=0
P 4.95768002 2.84115 4 P 0 0;1,3=8,5=0
P 5.00768002 2.84115 4 P 0 0;1,3=8,5=0
P 5.05768002 2.84115 4 P 0 0;1,3=8,5=0
P 11.01161004 2.84115 4 P 0 0;1,3=8,5=0
P 11.06161004 2.84115 4 P 0 0;1,3=8,5=0
P 10.96161004 2.84115 4 P 0 0;1,3=8,5=0
P 10.91161004 2.84115 4 P 0 0;1,3=8,5=0
P 10.86161004 2.84115 4 P 0 0;1,3=8,5=0
P 6.42418996 5.09705 7 P 0 0;1,3=1,5=0
P 5.53593996 4.6201 7 P 0 0;1,3=1,5=0
P 5.59778996 4.6352 10 P 0 0;1,3=13,5=0
P 5.49093996 4.6201 7 P 0 0;1,3=1,5=0
P 5.67708996 4.6352 10 P 0 0;1,3=13,5=0
P 5.83708996 4.6352 10 P 0 0;1,3=13,5=0
P 5.75708996 4.6352 10 P 0 0;1,3=13,5=0
P 6.07708996 4.6352 10 P 0 0;1,3=13,5=0
P 5.91708996 4.6352 10 P 0 0;1,3=13,5=0
P 5.99708996 4.6352 10 P 0 0;1,3=13,5=0
P 6.21193996 4.77205 29 P 0 0;1,3=16,5=0
P 4.90768002 2.29115 4 P 0 0;1,3=8,5=0
P 4.90768002 2.34115 4 P 0 0;1,3=8,5=0
P 5.05768002 2.39115 4 P 0 0;1,3=8,5=0
P 10.71161004 2.09115 4 P 0 0;1,3=8,5=0
P 10.66161004 2.34115 4 P 0 0;1,3=8,5=0
P 10.61161004 2.29115 4 P 0 0;1,3=8,5=0
P 10.66161004 2.49115 4 P 0 0;1,3=8,5=0
P 10.76161004 2.49115 4 P 0 0;1,3=8,5=0
P 10.66161004 2.29115 4 P 0 0;1,3=8,5=0
P 10.61161004 2.44115 4 P 0 0;1,3=8,5=0
P 10.71161004 2.39115 4 P 0 0;1,3=8,5=0
P 10.66161004 1.89115 4 P 0 0;1,3=8,5=0
P 5.00768002 2.04115 4 P 0 0;1,3=8,5=0
P 5.05768002 2.24115 4 P 0 0;1,3=8,5=0
P 10.71161004 1.99115 4 P 0 0;1,3=8,5=0
P 0.82983996 5.1239 12 P 0 0;1,3=7
P 9.50795 0.42821004 20 P 0 0;1,3=20
P 9.60795 0.42821004 20 P 0 0;1,3=20
P 3.70998996 0.40688002 20 P 0 0;1,3=20
P 3.80998996 0.40688002 20 P 0 0;1,3=20
P 0.5836 5.36731998 1 P 0 0;1,3=24
P 0.9211 0.2854 1 P 0 0;1,3=24
P 11.99518996 0.29 1 P 0 0;1,3=24
P 0.5 -0.293 1 P 0 0;1,3=24
P 12.4252 -0.293 1 P 0 0;1,3=24
P 0.5 6.31661998 1 P 0 0;1,3=24
P 12.4252 6.31661998 1 P 0 0;1,3=24
P 6.55228996 4.91705 22 P 0 0;1,3=11
P 6.69008996 4.9013 23 P 0 0;1,3=11
P 6.62118996 5.00563002 28 P 0 0;1,3=11
P 10.02558996 4.73035 14 P 0 0;1,3=5
P 3.69558996 4.67035 14 P 0 0;1,3=5
P 5.09558996 5.64035 14 P 0 0;1,3=5
L 1.88908002 -1.91246004 1.89293002 -1.91246004 0 P 0 
L 1.89126998 -1.91146004 1.89656998 -1.91146004 0 P 0 
L 1.89393996 -1.91046004 1.9155 -1.91046004 0 P 0 
L 1.91593996 -1.91246004 1.92048996 -1.91246004 0 P 0 
L 1.9126 -1.91146004 1.9184 -1.91146004 0 P 0 
L 1.89763002 -1.90946004 1.91016998 -1.90946004 0 P 0 
L 1.89053002 -1.96001004 1.8974 -1.96001004 0 P 0 
L 1.89053002 -1.95901004 1.8974 -1.95901004 0 P 0 
L 1.89053002 -1.95801004 1.8974 -1.95801004 0 P 0 
L 1.89053002 -1.95701004 1.8974 -1.95701004 0 P 0 
L 1.89053002 -1.95601004 1.8974 -1.95601004 0 P 0 
L 1.89053002 -1.95501004 1.8974 -1.95501004 0 P 0 
L 1.89053002 -1.95401004 1.8974 -1.95401004 0 P 0 
L 1.89053002 -1.95301004 1.89741004 -1.95301004 0 P 0 
L 1.89053002 -1.95201004 1.89741998 -1.95201004 0 P 0 
L 1.89053002 -1.95101004 1.89743996 -1.95101004 0 P 0 
L 1.89053002 -1.95001004 1.89745 -1.95001004 0 P 0 
L 1.89053002 -1.94901004 1.89746004 -1.94901004 0 P 0 
L 1.89053002 -1.94801004 1.89753002 -1.94801004 0 P 0 
L 1.89053002 -1.94701004 1.8977 -1.94701004 0 P 0 
L 1.89053002 -1.94601004 1.89798002 -1.94601004 0 P 0 
L 1.89053002 -1.94501004 1.89861004 -1.94501004 0 P 0 
L 1.89053002 -1.94401004 1.90005 -1.94401004 0 P 0 
L 1.89053002 -1.94301004 1.9113 -1.94301004 0 P 0 
L 1.89053002 -1.94201004 1.91168002 -1.94201004 0 P 0 
L 1.89053002 -1.94101004 1.91246998 -1.94101004 0 P 0 
L 1.89053002 -1.94001004 1.90093996 -1.94001004 0 P 0 
L 1.89053002 -1.93901004 1.89856004 -1.93901004 0 P 0 
L 1.89053002 -1.93801004 1.89786998 -1.93801004 0 P 0 
L 1.89053002 -1.93701004 1.89753996 -1.93701004 0 P 0 
L 1.89053002 -1.93601004 1.89746998 -1.93601004 0 P 0 
L 1.89053002 -1.93501004 1.89743996 -1.93501004 0 P 0 
L 1.89053002 -1.93401004 1.89741998 -1.93401004 0 P 0 
L 1.89053002 -1.93301004 1.8974 -1.93301004 0 P 0 
L 1.89053002 -1.93201004 1.8974 -1.93201004 0 P 0 
L 1.89053002 -1.93101004 1.8974 -1.93101004 0 P 0 
L 1.89053002 -1.93001004 1.8974 -1.93001004 0 P 0 
L 1.89053002 -1.92901004 1.8974 -1.92901004 0 P 0 
L 1.89053002 -1.92801004 1.89753002 -1.92801004 0 P 0 
L 1.89053002 -1.92701004 1.89793996 -1.92701004 0 P 0 
L 1.89053002 -1.92601004 1.91713002 -1.92601004 0 P 0 
L 1.89053002 -1.92501004 1.91628996 -1.92501004 0 P 0 
L 1.89053002 -1.92401004 1.91513996 -1.92401004 0 P 0 
L 1.89053002 -1.92301004 1.91321998 -1.92301004 0 P 0 
L 1.89053002 -1.92201004 1.90551004 -1.92201004 0 P 0 
L 1.89438996 -1.97246004 1.91331004 -1.97246004 0 P 0 
L 1.89106998 -1.97146004 1.89973002 -1.97146004 0 P 0 
L 1.88878002 -1.97046004 1.8949 -1.97046004 0 P 0 
L 1.88698002 -1.96946004 1.89206998 -1.96946004 0 P 0 
L 1.88546004 -1.96846004 1.88986998 -1.96846004 0 P 0 
L 1.88416998 -1.96746004 1.88808996 -1.96746004 0 P 0 
L 1.88288002 -1.96646004 1.88655 -1.96646004 0 P 0 
L 1.88176998 -1.96546004 1.88518002 -1.96546004 0 P 0 
L 1.88068996 -1.96446004 1.88393996 -1.96446004 0 P 0 
L 1.87968996 -1.96346004 1.88286004 -1.96346004 0 P 0 
L 1.87878002 -1.96246004 1.88186004 -1.96246004 0 P 0 
L 1.8786 -1.92046004 1.88126998 -1.92046004 0 P 0 
L 1.87946998 -1.91946004 1.88223002 -1.91946004 0 P 0 
L 1.88048002 -1.91846004 1.88321004 -1.91846004 0 P 0 
L 1.88153996 -1.91746004 1.88436998 -1.91746004 0 P 0 
L 1.88273002 -1.91646004 1.88558996 -1.91646004 0 P 0 
L 1.88406004 -1.91546004 1.88696998 -1.91546004 0 P 0 
L 1.88548996 -1.91446004 1.88853002 -1.91446004 0 P 0 
L 1.88718002 -1.91346004 1.89041998 -1.91346004 0 P 0 
L 1.90896004 -1.92963996 1.90921998 -1.92991998 0 P 0 
L 1.90921998 -1.92991998 1.90945 -1.93021998 0 P 0 
L 1.90945 -1.93021998 1.90966004 -1.93053002 0 P 0 
L 1.90966004 -1.93053002 1.90983002 -1.93086004 0 P 0 
L 1.90983002 -1.93086004 1.90998002 -1.93121004 0 P 0 
L 1.90998002 -1.93121004 1.9101 -1.93156998 0 P 0 
L 1.9101 -1.93156998 1.91018996 -1.93193996 0 P 0 
L 1.91018996 -1.93193996 1.91023996 -1.93231004 0 P 0 
L 1.91023996 -1.93231004 1.91026998 -1.93265 0 P 0 
L 1.91026998 -1.93265 1.91026004 -1.93298002 0 P 0 
L 1.91026004 -1.93298002 1.91023002 -1.93331004 0 P 0 
L 1.91023002 -1.93331004 1.91016998 -1.93363996 0 P 0 
L 1.91016998 -1.93363996 1.91008996 -1.93396004 0 P 0 
L 1.91008996 -1.93396004 1.90998002 -1.93428002 0 P 0 
L 1.90998002 -1.93428002 1.90983996 -1.93458002 0 P 0 
L 1.90983996 -1.93458002 1.90968996 -1.93486998 0 P 0 
L 1.90968996 -1.93486998 1.90951004 -1.93516004 0 P 0 
L 1.90951004 -1.93516004 1.90921004 -1.93556004 0 P 0 
L 1.90921004 -1.93556004 1.90888002 -1.93593002 0 P 0 
L 1.90888002 -1.93593002 1.90853002 -1.93626998 0 P 0 
L 1.90853002 -1.93626998 1.90815 -1.93658996 0 P 0 
L 1.90815 -1.93658996 1.90773996 -1.93686998 0 P 0 
L 1.90773996 -1.93686998 1.90731998 -1.93711998 0 P 0 
L 1.90731998 -1.93711998 1.90686998 -1.93733996 0 P 0 
L 1.90686998 -1.93733996 1.90615 -1.93761004 0 P 0 
L 1.90615 -1.93761004 1.90541998 -1.93783002 0 P 0 
L 1.90541998 -1.93783002 1.90466004 -1.93798002 0 P 0 
L 1.90466004 -1.93798002 1.9039 -1.93808002 0 P 0 
L 1.9039 -1.93808002 1.90311998 -1.9381 0 P 0 
L 1.90311998 -1.9381 1.90196004 -1.93808002 0 P 0 
L 1.90196004 -1.93808002 1.90078996 -1.93798996 0 P 0 
L 1.90078996 -1.93798996 1.90068002 -1.93798002 0 P 0 
L 1.90068002 -1.93798002 1.90058002 -1.93795 0 P 0 
L 1.90058002 -1.93795 1.90046998 -1.93791998 0 P 0 
L 1.90046998 -1.93791998 1.90038002 -1.93788002 0 P 0 
L 1.90038002 -1.93788002 1.90028002 -1.93783002 0 P 0 
L 1.90028002 -1.93783002 1.90018996 -1.93778002 0 P 0 
L 1.90018996 -1.93778002 1.9001 -1.93771004 0 P 0 
L 1.9001 -1.93771004 1.90001998 -1.93763996 0 P 0 
L 1.90001998 -1.93763996 1.89988002 -1.93748002 0 P 0 
L 1.89988002 -1.93748002 1.89978002 -1.93733996 0 P 0 
L 1.89978002 -1.93733996 1.89961998 -1.93703996 0 P 0 
L 1.89961998 -1.93703996 1.89956998 -1.93688002 0 P 0 
L 1.89956998 -1.93688002 1.89951998 -1.93671004 0 P 0 
L 1.89951998 -1.93671004 1.89948996 -1.93655 0 P 0 
L 1.89948996 -1.93655 1.89946998 -1.93636998 0 P 0 
L 1.89946998 -1.93636998 1.8994 -1.93323002 0 P 0 
L 1.8994 -1.93323002 1.8994 -1.92833002 0 P 0 
L 1.8994 -1.92833002 1.90353996 -1.92833002 0 P 0 
L 1.90353996 -1.92833002 1.90436998 -1.92835 0 P 0 
L 1.90436998 -1.92835 1.9052 -1.92843002 0 P 0 
L 1.9052 -1.92843002 1.90603002 -1.92853996 0 P 0 
L 1.90603002 -1.92853996 1.90683996 -1.92871004 0 P 0 
L 1.90683996 -1.92871004 1.90751004 -1.9289 0 P 0 
L 1.90751004 -1.9289 1.90818002 -1.92913002 0 P 0 
L 1.90818002 -1.92913002 1.90851998 -1.92928996 0 P 0 
L 1.90851998 -1.92928996 1.90868002 -1.92938996 0 P 0 
L 1.90868002 -1.92938996 1.90883002 -1.92951004 0 P 0 
L 1.90883002 -1.92951004 1.90896004 -1.92963996 0 P 0 
L 1.91188996 -1.96001004 1.91638996 -1.96001004 0 P 0 
L 1.91156998 -1.95901004 1.91926998 -1.95901004 0 P 0 
L 1.91125 -1.95801004 1.91891998 -1.95801004 0 P 0 
L 1.91091998 -1.95701004 1.91853002 -1.95701004 0 P 0 
L 1.9106 -1.95601004 1.91811004 -1.95601004 0 P 0 
L 1.91025 -1.95501004 1.91765 -1.95501004 0 P 0 
L 1.90988996 -1.95401004 1.91718996 -1.95401004 0 P 0 
L 1.90953002 -1.95301004 1.91673002 -1.95301004 0 P 0 
L 1.90918002 -1.95201004 1.91626998 -1.95201004 0 P 0 
L 1.90881998 -1.95101004 1.91576004 -1.95101004 0 P 0 
L 1.90841004 -1.95001004 1.91523996 -1.95001004 0 P 0 
L 1.90793996 -1.94901004 1.91471004 -1.94901004 0 P 0 
L 1.90738996 -1.94801004 1.91418002 -1.94801004 0 P 0 
L 1.90676998 -1.94701004 1.9136 -1.94701004 0 P 0 
L 1.90598996 -1.94601004 1.91261004 -1.94601004 0 P 0 
L 1.90495 -1.94501004 1.91175 -1.94501004 0 P 0 
L 1.90325 -1.94401004 1.91133002 -1.94401004 0 P 0 
L 1.90456004 -1.94001004 1.91383002 -1.94001004 0 P 0 
L 1.90801004 -1.93901004 1.91523002 -1.93901004 0 P 0 
L 1.90956998 -1.93801004 1.91635 -1.93801004 0 P 0 
L 1.9106 -1.93701004 1.91718002 -1.93701004 0 P 0 
L 1.91133996 -1.93601004 1.91781004 -1.93601004 0 P 0 
L 1.91183996 -1.93501004 1.91826004 -1.93501004 0 P 0 
L 1.91213002 -1.93401004 1.9186 -1.93401004 0 P 0 
L 1.91226004 -1.93301004 1.9188 -1.93301004 0 P 0 
L 1.91221998 -1.93201004 1.9189 -1.93201004 0 P 0 
L 1.91201998 -1.93101004 1.9189 -1.93101004 0 P 0 
L 1.91163996 -1.93001004 1.91878996 -1.93001004 0 P 0 
L 1.91105 -1.92901004 1.91856998 -1.92901004 0 P 0 
L 1.91013996 -1.92801004 1.91823002 -1.92801004 0 P 0 
L 1.90816998 -1.92701004 1.91776004 -1.92701004 0 P 0 
L 1.90313996 -1.94011004 1.90316998 -1.9401 0 P 0 
L 1.90316998 -1.9401 1.9032 -1.9401 0 P 0 
L 1.9032 -1.9401 1.90398002 -1.94006998 0 P 0 
L 1.90398002 -1.94006998 1.90406004 -1.94006998 0 P 0 
L 1.90406004 -1.94006998 1.90413996 -1.94006004 0 P 0 
L 1.90413996 -1.94006004 1.9049 -1.93996998 0 P 0 
L 1.9049 -1.93996998 1.90493996 -1.93996004 0 P 0 
L 1.90493996 -1.93996004 1.90498996 -1.93996004 0 P 0 
L 1.90498996 -1.93996004 1.90506998 -1.93993996 0 P 0 
L 1.90506998 -1.93993996 1.90581998 -1.93978002 0 P 0 
L 1.90581998 -1.93978002 1.90586004 -1.93978002 0 P 0 
L 1.90586004 -1.93978002 1.90593996 -1.93976004 0 P 0 
L 1.90593996 -1.93976004 1.90596998 -1.93973996 0 P 0 
L 1.90596998 -1.93973996 1.90671004 -1.93953002 0 P 0 
L 1.90671004 -1.93953002 1.90678996 -1.93951004 0 P 0 
L 1.90678996 -1.93951004 1.90758996 -1.93921004 0 P 0 
L 1.90758996 -1.93921004 1.90766004 -1.93916998 0 P 0 
L 1.90766004 -1.93916998 1.9077 -1.93915 0 P 0 
L 1.9077 -1.93915 1.90773996 -1.93913996 0 P 0 
L 1.90773996 -1.93913996 1.90818996 -1.93891998 0 P 0 
L 1.90818996 -1.93891998 1.90821998 -1.9389 0 P 0 
L 1.90821998 -1.9389 1.90826004 -1.93888996 0 P 0 
L 1.90826004 -1.93888996 1.90828996 -1.93886998 0 P 0 
L 1.90828996 -1.93886998 1.90833002 -1.93885 0 P 0 
L 1.90833002 -1.93885 1.90875 -1.9386 0 P 0 
L 1.90875 -1.9386 1.90883002 -1.93856004 0 P 0 
L 1.90883002 -1.93856004 1.90888996 -1.93851004 0 P 0 
L 1.90888996 -1.93851004 1.90928996 -1.93823002 0 P 0 
L 1.90928996 -1.93823002 1.90933002 -1.9382 0 P 0 
L 1.90933002 -1.9382 1.90936004 -1.93818002 0 P 0 
L 1.90936004 -1.93818002 1.90938996 -1.93815 0 P 0 
L 1.90938996 -1.93815 1.90941998 -1.93813002 0 P 0 
L 1.90941998 -1.93813002 1.9098 -1.93781998 0 P 0 
L 1.9098 -1.93781998 1.90986004 -1.93776004 0 P 0 
L 1.90986004 -1.93776004 1.90988996 -1.93773996 0 P 0 
L 1.90988996 -1.93773996 1.90991998 -1.93771004 0 P 0 
L 1.90991998 -1.93771004 1.91028002 -1.93736004 0 P 0 
L 1.91028002 -1.93736004 1.91038996 -1.93725 0 P 0 
L 1.91038996 -1.93725 1.91071004 -1.93688002 0 P 0 
L 1.91071004 -1.93688002 1.91073996 -1.93685 0 P 0 
L 1.91073996 -1.93685 1.91116004 -1.9363 0 P 0 
L 1.91116004 -1.9363 1.9112 -1.93623002 0 P 0 
L 1.9112 -1.93623002 1.91138002 -1.93595 0 P 0 
L 1.91138002 -1.93595 1.9114 -1.93591004 0 P 0 
L 1.9114 -1.93591004 1.91143996 -1.93585 0 P 0 
L 1.91143996 -1.93585 1.91146004 -1.93581004 0 P 0 
L 1.91146004 -1.93581004 1.91161004 -1.93551998 0 P 0 
L 1.91161004 -1.93551998 1.91163002 -1.93548996 0 P 0 
L 1.91163002 -1.93548996 1.91165 -1.93545 0 P 0 
L 1.91165 -1.93545 1.91166004 -1.93541004 0 P 0 
L 1.91166004 -1.93541004 1.91168002 -1.93538002 0 P 0 
L 1.91168002 -1.93538002 1.91181004 -1.93506998 0 P 0 
L 1.91181004 -1.93506998 1.91183996 -1.935 0 P 0 
L 1.91183996 -1.935 1.91186004 -1.93496004 0 P 0 
L 1.91186004 -1.93496004 1.91186998 -1.93493002 0 P 0 
L 1.91186998 -1.93493002 1.91198002 -1.93461004 0 P 0 
L 1.91198002 -1.93461004 1.91198996 -1.93456998 0 P 0 
L 1.91198996 -1.93456998 1.912 -1.93453996 0 P 0 
L 1.912 -1.93453996 1.9121 -1.93413996 0 P 0 
L 1.9121 -1.93413996 1.91211998 -1.9341 0 P 0 
L 1.91211998 -1.9341 1.91211998 -1.93406004 0 P 0 
L 1.91211998 -1.93406004 1.91213002 -1.93401998 0 P 0 
L 1.91213002 -1.93401998 1.91213996 -1.93398996 0 P 0 
L 1.91213996 -1.93398996 1.9122 -1.93366004 0 P 0 
L 1.9122 -1.93366004 1.91221004 -1.93358002 0 P 0 
L 1.91221004 -1.93358002 1.91221004 -1.93353996 0 P 0 
L 1.91221004 -1.93353996 1.91221998 -1.9335 0 P 0 
L 1.91221998 -1.9335 1.91225 -1.93316998 0 P 0 
L 1.91225 -1.93316998 1.91226004 -1.93308996 0 P 0 
L 1.91226004 -1.93308996 1.91226004 -1.93268002 0 P 0 
L 1.91226004 -1.93268002 1.91226998 -1.93263996 0 P 0 
L 1.91226998 -1.93263996 1.91226998 -1.9326 0 P 0 
L 1.91226998 -1.9326 1.91226004 -1.93251998 0 P 0 
L 1.91226004 -1.93251998 1.91223996 -1.93218996 0 P 0 
L 1.91223996 -1.93218996 1.91223996 -1.93215 0 P 0 
L 1.91223996 -1.93215 1.91223002 -1.9321 0 P 0 
L 1.91223002 -1.9321 1.91223002 -1.93206004 0 P 0 
L 1.91223002 -1.93206004 1.91221998 -1.93201998 0 P 0 
L 1.91221998 -1.93201998 1.91216998 -1.93163996 0 P 0 
L 1.91216998 -1.93163996 1.91216004 -1.9316 0 P 0 
L 1.91216004 -1.9316 1.91213996 -1.93151004 0 P 0 
L 1.91213996 -1.93151004 1.91213002 -1.93146998 0 P 0 
L 1.91213002 -1.93146998 1.91205 -1.93111004 0 P 0 
L 1.91205 -1.93111004 1.91203996 -1.93106004 0 P 0 
L 1.91203996 -1.93106004 1.91203002 -1.93101998 0 P 0 
L 1.91203002 -1.93101998 1.91201004 -1.93098002 0 P 0 
L 1.91201004 -1.93098002 1.912 -1.93093996 0 P 0 
L 1.912 -1.93093996 1.91188002 -1.93058002 0 P 0 
L 1.91188002 -1.93058002 1.91186998 -1.93053996 0 P 0 
L 1.91186998 -1.93053996 1.91185 -1.9305 0 P 0 
L 1.91185 -1.9305 1.91183996 -1.93046004 0 P 0 
L 1.91183996 -1.93046004 1.91181998 -1.93043002 0 P 0 
L 1.91181998 -1.93043002 1.91166998 -1.93008002 0 P 0 
L 1.91166998 -1.93008002 1.91166004 -1.93003996 0 P 0 
L 1.91166004 -1.93003996 1.9116 -1.92991998 0 P 0 
L 1.9116 -1.92991998 1.91141998 -1.92958996 0 P 0 
L 1.91141998 -1.92958996 1.9114 -1.92955 0 P 0 
L 1.9114 -1.92955 1.91138002 -1.92951998 0 P 0 
L 1.91138002 -1.92951998 1.91133002 -1.92945 0 P 0 
L 1.91133002 -1.92945 1.91113002 -1.92913002 0 P 0 
L 1.91113002 -1.92913002 1.91111004 -1.92908996 0 P 0 
L 1.91111004 -1.92908996 1.91108996 -1.92906004 0 P 0 
L 1.91108996 -1.92906004 1.91106004 -1.92901998 0 P 0 
L 1.91106004 -1.92901998 1.91103002 -1.92898996 0 P 0 
L 1.91103002 -1.92898996 1.9108 -1.92868996 0 P 0 
L 1.9108 -1.92868996 1.91076998 -1.92866004 0 P 0 
L 1.91076998 -1.92866004 1.91075 -1.92861998 0 P 0 
L 1.91075 -1.92861998 1.91068996 -1.92856004 0 P 0 
L 1.91068996 -1.92856004 1.91043002 -1.92828002 0 P 0 
L 1.91043002 -1.92828002 1.91035 -1.9282 0 P 0 
L 1.91035 -1.9282 1.91033002 -1.92816998 0 P 0 
L 1.91033002 -1.92816998 1.91018996 -1.92803996 0 P 0 
L 1.91018996 -1.92803996 1.91018002 -1.92803996 0 P 0 
L 1.91018002 -1.92803996 1.91016004 -1.92801998 0 P 0 
L 1.91016004 -1.92801998 1.91011998 -1.92798996 0 P 0 
L 1.91011998 -1.92798996 1.91006004 -1.92793002 0 P 0 
L 1.91006004 -1.92793002 1.90991004 -1.92781998 0 P 0 
L 1.90991004 -1.92781998 1.90988002 -1.9278 0 P 0 
L 1.90988002 -1.9278 1.90983996 -1.92776998 0 P 0 
L 1.90983996 -1.92776998 1.90976998 -1.92771998 0 P 0 
L 1.90976998 -1.92771998 1.90961004 -1.92761998 0 P 0 
L 1.90961004 -1.92761998 1.90953996 -1.92756998 0 P 0 
L 1.90953996 -1.92756998 1.9095 -1.92755 0 P 0 
L 1.9095 -1.92755 1.90946998 -1.92753002 0 P 0 
L 1.90946998 -1.92753002 1.9093 -1.92743996 0 P 0 
L 1.9093 -1.92743996 1.90926004 -1.92741998 0 P 0 
L 1.90926004 -1.92741998 1.90923002 -1.9274 0 P 0 
L 1.90923002 -1.9274 1.90915 -1.92736998 0 P 0 
L 1.90915 -1.92736998 1.90896998 -1.92728996 0 P 0 
L 1.90896998 -1.92728996 1.90893996 -1.92728002 0 P 0 
L 1.90893996 -1.92728002 1.9089 -1.92726004 0 P 0 
L 1.9089 -1.92726004 1.90886998 -1.92725 0 P 0 
L 1.90886998 -1.92725 1.90883002 -1.92723996 0 P 0 
L 1.90883002 -1.92723996 1.90816004 -1.92701004 0 P 0 
L 1.90816004 -1.92701004 1.90813996 -1.927 0 P 0 
L 1.90813996 -1.927 1.9081 -1.92698996 0 P 0 
L 1.9081 -1.92698996 1.90803996 -1.92696998 0 P 0 
L 1.90803996 -1.92696998 1.90736998 -1.92678002 0 P 0 
L 1.90736998 -1.92678002 1.90723996 -1.92675 0 P 0 
L 1.90723996 -1.92675 1.90643002 -1.92658996 0 P 0 
L 1.90643002 -1.92658996 1.90636998 -1.92656998 0 P 0 
L 1.90636998 -1.92656998 1.90633996 -1.92656998 0 P 0 
L 1.90633996 -1.92656998 1.90631004 -1.92656004 0 P 0 
L 1.90631004 -1.92656004 1.90548996 -1.92645 0 P 0 
L 1.90548996 -1.92645 1.90543996 -1.92643996 0 P 0 
L 1.90543996 -1.92643996 1.9054 -1.92643002 0 P 0 
L 1.9054 -1.92643002 1.90538002 -1.92643002 0 P 0 
L 1.90538002 -1.92643002 1.90455 -1.92636004 0 P 0 
L 1.90455 -1.92636004 1.90443002 -1.92636004 0 P 0 
L 1.90443002 -1.92636004 1.9036 -1.92633002 0 P 0 
L 1.9036 -1.92633002 1.8994 -1.92633002 0 P 0 
L 1.8994 -1.92633002 1.89798002 -1.92691004 0 P 0 
L 1.89798002 -1.92691004 1.8974 -1.92833002 0 P 0 
L 1.8974 -1.92833002 1.8974 -1.93328002 0 P 0 
L 1.8974 -1.93328002 1.89748002 -1.93643002 0 P 0 
L 1.89748002 -1.93643002 1.89748002 -1.93656004 0 P 0 
L 1.89748002 -1.93656004 1.8975 -1.93673002 0 P 0 
L 1.8975 -1.93673002 1.89751004 -1.93681004 0 P 0 
L 1.89751004 -1.93681004 1.89751998 -1.9369 0 P 0 
L 1.89751998 -1.9369 1.89755 -1.93706004 0 P 0 
L 1.89755 -1.93706004 1.89758002 -1.93718996 0 P 0 
L 1.89758002 -1.93718996 1.89758996 -1.93723002 0 P 0 
L 1.89758996 -1.93723002 1.89763002 -1.9374 0 P 0 
L 1.89763002 -1.9374 1.89763996 -1.93743996 0 P 0 
L 1.89763996 -1.93743996 1.89766004 -1.93748002 0 P 0 
L 1.89766004 -1.93748002 1.89768002 -1.93756004 0 P 0 
L 1.89768002 -1.93756004 1.89773996 -1.93771998 0 P 0 
L 1.89773996 -1.93771998 1.89776004 -1.93776004 0 P 0 
L 1.89776004 -1.93776004 1.89776998 -1.9378 0 P 0 
L 1.89776998 -1.9378 1.89781004 -1.93788002 0 P 0 
L 1.89781004 -1.93788002 1.89788002 -1.93803996 0 P 0 
L 1.89788002 -1.93803996 1.8979 -1.93808002 0 P 0 
L 1.8979 -1.93808002 1.89791998 -1.93811004 0 P 0 
L 1.89791998 -1.93811004 1.89796004 -1.93818996 0 P 0 
L 1.89796004 -1.93818996 1.89803996 -1.93833996 0 P 0 
L 1.89803996 -1.93833996 1.89813996 -1.93848002 0 P 0 
L 1.89813996 -1.93848002 1.89823002 -1.93861998 0 P 0 
L 1.89823002 -1.93861998 1.89828002 -1.93868996 0 P 0 
L 1.89828002 -1.93868996 1.89831004 -1.93873002 0 P 0 
L 1.89831004 -1.93873002 1.89833996 -1.93876004 0 P 0 
L 1.89833996 -1.93876004 1.8984 -1.93883996 0 P 0 
L 1.8984 -1.93883996 1.89848996 -1.93893002 0 P 0 
L 1.89848996 -1.93893002 1.89851004 -1.93896004 0 P 0 
L 1.89851004 -1.93896004 1.89868002 -1.93913002 0 P 0 
L 1.89868002 -1.93913002 1.89871004 -1.93915 0 P 0 
L 1.89871004 -1.93915 1.89878996 -1.93921998 0 P 0 
L 1.89878996 -1.93921998 1.89885 -1.93928002 0 P 0 
L 1.89885 -1.93928002 1.89888002 -1.9393 0 P 0 
L 1.89888002 -1.9393 1.89891998 -1.93931998 0 P 0 
L 1.89891998 -1.93931998 1.89901004 -1.93938996 0 P 0 
L 1.89901004 -1.93938996 1.89903996 -1.93941004 0 P 0 
L 1.89903996 -1.93941004 1.89906998 -1.93943996 0 P 0 
L 1.89906998 -1.93943996 1.8991 -1.93946004 0 P 0 
L 1.8991 -1.93946004 1.89913996 -1.93948002 0 P 0 
L 1.89913996 -1.93948002 1.89923002 -1.93953996 0 P 0 
L 1.89923002 -1.93953996 1.89926998 -1.93956004 0 P 0 
L 1.89926998 -1.93956004 1.8993 -1.93958002 0 P 0 
L 1.8993 -1.93958002 1.89933996 -1.9396 0 P 0 
L 1.89933996 -1.9396 1.89936998 -1.93961004 0 P 0 
L 1.89936998 -1.93961004 1.89938002 -1.93961004 0 P 0 
L 1.89938002 -1.93961004 1.89946998 -1.93966004 0 P 0 
L 1.89946998 -1.93966004 1.89953996 -1.9397 0 P 0 
L 1.89953996 -1.9397 1.89971998 -1.93976998 0 P 0 
L 1.89971998 -1.93976998 1.89975 -1.93978996 0 P 0 
L 1.89975 -1.93978996 1.89978996 -1.9398 0 P 0 
L 1.89978996 -1.9398 1.89986998 -1.93983002 0 P 0 
L 1.89986998 -1.93983002 1.89996998 -1.93986004 0 P 0 
L 1.89996998 -1.93986004 1.90001004 -1.93986998 0 P 0 
L 1.90001004 -1.93986998 1.90005 -1.93988996 0 P 0 
L 1.90005 -1.93988996 1.90013002 -1.9399 0 P 0 
L 1.90013002 -1.9399 1.90023002 -1.93993002 0 P 0 
L 1.90023002 -1.93993002 1.90023996 -1.93993002 0 P 0 
L 1.90023996 -1.93993002 1.90028002 -1.93993996 0 P 0 
L 1.90028002 -1.93993996 1.90031004 -1.93995 0 P 0 
L 1.90031004 -1.93995 1.90036004 -1.93995 0 P 0 
L 1.90036004 -1.93995 1.9004 -1.93996004 0 P 0 
L 1.9004 -1.93996004 1.9005 -1.93996998 0 P 0 
L 1.9005 -1.93996998 1.90061004 -1.93998996 0 P 0 
L 1.90061004 -1.93998996 1.90063996 -1.93998996 0 P 0 
L 1.90063996 -1.93998996 1.90181004 -1.94006998 0 P 0 
L 1.90181004 -1.94006998 1.90183996 -1.94008002 0 P 0 
L 1.90183996 -1.94008002 1.90191004 -1.94008002 0 P 0 
L 1.90191004 -1.94008002 1.90308002 -1.9401 0 P 0 
L 1.90308002 -1.9401 1.90311004 -1.9401 0 P 0 
L 1.90311004 -1.9401 1.90313996 -1.94011004 0 P 0 
L 1.90841004 -1.97146004 1.91683996 -1.97146004 0 P 0 
L 1.9135 -1.97046004 1.91931004 -1.97046004 0 P 0 
L 1.91655 -1.96946004 1.92131004 -1.96946004 0 P 0 
L 1.91891998 -1.96846004 1.92301004 -1.96846004 0 P 0 
L 1.92088996 -1.96746004 1.9245 -1.96746004 0 P 0 
L 1.92251004 -1.96646004 1.9258 -1.96646004 0 P 0 
L 1.92391004 -1.96546004 1.92696004 -1.96546004 0 P 0 
L 1.92513002 -1.96446004 1.92803002 -1.96446004 0 P 0 
L 1.9262 -1.96346004 1.92898996 -1.96346004 0 P 0 
L 1.92713996 -1.96246004 1.92986004 -1.96246004 0 P 0 
L 1.928 -1.96146004 1.93068996 -1.96146004 0 P 0 
L 1.92878002 -1.96046004 1.93143002 -1.96046004 0 P 0 
L 1.92951004 -1.95946004 1.93216004 -1.95946004 0 P 0 
L 1.93016998 -1.95846004 1.93278996 -1.95846004 0 P 0 
L 1.93078002 -1.95746004 1.93341004 -1.95746004 0 P 0 
L 1.93133002 -1.95646004 1.93396004 -1.95646004 0 P 0 
L 1.93185 -1.95546004 1.93448996 -1.95546004 0 P 0 
L 1.93231004 -1.95446004 1.93495 -1.95446004 0 P 0 
L 1.93275 -1.95346004 1.93541004 -1.95346004 0 P 0 
L 1.93311998 -1.95246004 1.93586004 -1.95246004 0 P 0 
L 1.93348002 -1.95146004 1.93628996 -1.95146004 0 P 0 
L 1.93376998 -1.95046004 1.93666004 -1.95046004 0 P 0 
L 1.93405 -1.94946004 1.93693002 -1.94946004 0 P 0 
L 1.93428002 -1.94846004 1.93715 -1.94846004 0 P 0 
L 1.93446998 -1.94746004 1.93733002 -1.94746004 0 P 0 
L 1.93466004 -1.94646004 1.93743002 -1.94646004 0 P 0 
L 1.93478996 -1.94546004 1.93748996 -1.94546004 0 P 0 
L 1.9349 -1.94446998 1.93751998 -1.94446998 0 P 0 
L 1.93496998 -1.94346004 1.93755 -1.94346004 0 P 0 
L 1.93501998 -1.94246004 1.93758002 -1.94246004 0 P 0 
L 1.93505 -1.94146998 1.93758996 -1.94146998 0 P 0 
L 1.93503002 -1.94046004 1.93755 -1.94046004 0 P 0 
L 1.935 -1.93946004 1.93751998 -1.93946004 0 P 0 
L 1.93491998 -1.93846004 1.93748002 -1.93846004 0 P 0 
L 1.93481004 -1.93746004 1.93738996 -1.93746004 0 P 0 
L 1.93468996 -1.93646004 1.93726998 -1.93646004 0 P 0 
L 1.93451004 -1.93546004 1.93716004 -1.93546004 0 P 0 
L 1.93433002 -1.93446004 1.93703996 -1.93446004 0 P 0 
L 1.93408996 -1.93346004 1.93685 -1.93346004 0 P 0 
L 1.93383002 -1.93246004 1.93666004 -1.93246004 0 P 0 
L 1.93353002 -1.93146004 1.93638996 -1.93146004 0 P 0 
L 1.9332 -1.93046004 1.93611998 -1.93046004 0 P 0 
L 1.93283996 -1.92946004 1.93576998 -1.92946004 0 P 0 
L 1.93241004 -1.92846004 1.93541004 -1.92846004 0 P 0 
L 1.93198996 -1.92746004 1.93498002 -1.92746004 0 P 0 
L 1.93146998 -1.92646004 1.93451004 -1.92646004 0 P 0 
L 1.93096004 -1.92546004 1.93398002 -1.92546004 0 P 0 
L 1.93035 -1.92446998 1.93338002 -1.92446998 0 P 0 
L 1.92973002 -1.92346004 1.93275 -1.92346004 0 P 0 
L 1.92903002 -1.92246004 1.93201004 -1.92246004 0 P 0 
L 1.92831004 -1.92146004 1.93125 -1.92146004 0 P 0 
L 1.92746998 -1.92046004 1.93041004 -1.92046004 0 P 0 
L 1.92661004 -1.91946004 1.92948996 -1.91946004 0 P 0 
L 1.92558996 -1.91846004 1.92851004 -1.91846004 0 P 0 
L 1.9245 -1.91746004 1.92741998 -1.91746004 0 P 0 
L 1.92328996 -1.91646004 1.92621998 -1.91646004 0 P 0 
L 1.92188002 -1.91546004 1.92491998 -1.91546004 0 P 0 
L 1.92026004 -1.91446004 1.92358996 -1.91446004 0 P 0 
L 1.91835 -1.91346004 1.92208002 -1.91346004 0 P 0 
L 1.82446998 -2.08323996 1.87608002 -2.08323996 0 P 0 
L 1.82403002 -2.08223996 1.87601004 -2.08223996 0 P 0 
L 1.8234 -2.08123996 1.87591004 -2.08123996 0 P 0 
L 1.82256004 -2.08023996 1.87578002 -2.08023996 0 P 0 
L 1.82166004 -2.07923996 1.87558996 -2.07923996 0 P 0 
L 1.82061998 -2.07823996 1.87533002 -2.07823996 0 P 0 
L 1.81946004 -2.07723996 1.87498996 -2.07723996 0 P 0 
L 1.81818002 -2.07623996 1.8746 -2.07623996 0 P 0 
L 1.8168 -2.07523996 1.87416998 -2.07523996 0 P 0 
L 1.81541998 -2.07423996 1.87371004 -2.07423996 0 P 0 
L 1.81403002 -2.07323996 1.87316998 -2.07323996 0 P 0 
L 1.81265 -2.07223996 1.87261004 -2.07223996 0 P 0 
L 1.81126998 -2.07123996 1.87196004 -2.07123996 0 P 0 
L 1.80986004 -2.07023996 1.87128002 -2.07023996 0 P 0 
L 1.80843996 -2.06923996 1.87051998 -2.06923996 0 P 0 
L 1.80703002 -2.06823996 1.8697 -2.06823996 0 P 0 
L 1.80561004 -2.06723996 1.86883002 -2.06723996 0 P 0 
L 1.8042 -2.06623996 1.86796004 -2.06623996 0 P 0 
L 1.80278002 -2.06523996 1.86705 -2.06523996 0 P 0 
L 1.80136004 -2.06423996 1.86608002 -2.06423996 0 P 0 
L 1.79995 -2.06323996 1.8651 -2.06323996 0 P 0 
L 1.79865 -2.06223996 1.86411004 -2.06223996 0 P 0 
L 1.79735 -2.06123996 1.86301998 -2.06123996 0 P 0 
L 1.79605 -2.06023996 1.86193002 -2.06023996 0 P 0 
L 1.79475 -2.05923996 1.86083996 -2.05923996 0 P 0 
L 1.79345 -2.05823996 1.85966998 -2.05823996 0 P 0 
L 1.79215 -2.05723996 1.85846004 -2.05723996 0 P 0 
L 1.79088002 -2.05623996 1.85726004 -2.05623996 0 P 0 
L 1.78971998 -2.05523996 1.85598996 -2.05523996 0 P 0 
L 1.78856004 -2.05423996 1.85461998 -2.05423996 0 P 0 
L 1.7874 -2.05323996 1.85326004 -2.05323996 0 P 0 
L 1.78623002 -2.05223996 1.8519 -2.05223996 0 P 0 
L 1.78506998 -2.05123996 1.85053996 -2.05123996 0 P 0 
L 1.78398002 -2.05023996 1.84918002 -2.05023996 0 P 0 
L 1.783 -2.04923996 1.84781004 -2.04923996 0 P 0 
L 1.87086004 -2.03023996 1.87535 -2.03023996 0 P 0 
L 1.91633002 -1.91473002 1.9183 -1.91565 0 P 0 
L 1.9183 -1.91565 1.92018996 -1.91673002 0 P 0 
L 1.92018996 -1.91673002 1.92196998 -1.91796998 0 P 0 
L 1.92196998 -1.91796998 1.92365 -1.91936004 0 P 0 
L 1.92365 -1.91936004 1.9252 -1.92088002 0 P 0 
L 1.9252 -1.92088002 1.92661004 -1.92253996 0 P 0 
L 1.92661004 -1.92253996 1.92795 -1.92436998 0 P 0 
L 1.92795 -1.92436998 1.92913996 -1.9263 0 P 0 
L 1.92913996 -1.9263 1.93018002 -1.92831998 0 P 0 
L 1.93018002 -1.92831998 1.93106998 -1.93041004 0 P 0 
L 1.93106998 -1.93041004 1.93178996 -1.93256004 0 P 0 
L 1.93178996 -1.93256004 1.93236004 -1.93476004 0 P 0 
L 1.93236004 -1.93476004 1.93276004 -1.93703996 0 P 0 
L 1.93276004 -1.93703996 1.93298996 -1.93933996 0 P 0 
L 1.93298996 -1.93933996 1.93306004 -1.94165 0 P 0 
L 1.93306004 -1.94165 1.93295 -1.94396998 0 P 0 
L 1.93295 -1.94396998 1.93268002 -1.94626004 0 P 0 
L 1.93268002 -1.94626004 1.93223002 -1.94853996 0 P 0 
L 1.93223002 -1.94853996 1.93161998 -1.95071998 0 P 0 
L 1.93161998 -1.95071998 1.93085 -1.95285 0 P 0 
L 1.93085 -1.95285 1.92991004 -1.95491004 0 P 0 
L 1.92991004 -1.95491004 1.92881004 -1.95688996 0 P 0 
L 1.92881004 -1.95688996 1.92756004 -1.95878002 0 P 0 
L 1.92756004 -1.95878002 1.92616004 -1.96056998 0 P 0 
L 1.92616004 -1.96056998 1.92493996 -1.9619 0 P 0 
L 1.92493996 -1.9619 1.92361998 -1.96313996 0 P 0 
L 1.92361998 -1.96313996 1.9222 -1.96426004 0 P 0 
L 1.9222 -1.96426004 1.9207 -1.96526998 0 P 0 
L 1.9207 -1.96526998 1.91911004 -1.96616998 0 P 0 
L 1.91911004 -1.96616998 1.91686998 -1.96721004 0 P 0 
L 1.91686998 -1.96721004 1.91456004 -1.96806998 0 P 0 
L 1.91456004 -1.96806998 1.91218996 -1.96876004 0 P 0 
L 1.91218996 -1.96876004 1.90975 -1.96926998 0 P 0 
L 1.90975 -1.96926998 1.90725 -1.9696 0 P 0 
L 1.90725 -1.9696 1.90473002 -1.96973996 0 P 0 
L 1.90473002 -1.96973996 1.9022 -1.96968996 0 P 0 
L 1.9022 -1.96968996 1.89966998 -1.96945 0 P 0 
L 1.89966998 -1.96945 1.89778002 -1.96913002 0 P 0 
L 1.89778002 -1.96913002 1.89591998 -1.96868996 0 P 0 
L 1.89591998 -1.96868996 1.8941 -1.96811004 0 P 0 
L 1.8941 -1.96811004 1.89231004 -1.96741004 0 P 0 
L 1.89231004 -1.96741004 1.89058002 -1.96658002 0 P 0 
L 1.89058002 -1.96658002 1.88875 -1.96553996 0 P 0 
L 1.88875 -1.96553996 1.88698996 -1.96435 0 P 0 
L 1.88698996 -1.96435 1.88533996 -1.96303002 0 P 0 
L 1.88533996 -1.96303002 1.88378996 -1.9616 0 P 0 
L 1.88378996 -1.9616 1.88235 -1.96003996 0 P 0 
L 1.88235 -1.96003996 1.88103002 -1.95838996 0 P 0 
L 1.88103002 -1.95838996 1.87983996 -1.95663002 0 P 0 
L 1.87983996 -1.95663002 1.87861998 -1.95446998 0 P 0 
L 1.87861998 -1.95446998 1.87758002 -1.9522 0 P 0 
L 1.87758002 -1.9522 1.87673996 -1.94986004 0 P 0 
L 1.87673996 -1.94986004 1.8761 -1.94745 0 P 0 
L 1.8761 -1.94745 1.87568002 -1.945 0 P 0 
L 1.87568002 -1.945 1.87546004 -1.94248996 0 P 0 
L 1.87546004 -1.94248996 1.87546004 -1.93998996 0 P 0 
L 1.87546004 -1.93998996 1.87566998 -1.93748996 0 P 0 
L 1.87566998 -1.93748996 1.87608996 -1.93501998 0 P 0 
L 1.87608996 -1.93501998 1.87671998 -1.9326 0 P 0 
L 1.87671998 -1.9326 1.87755 -1.93023002 0 P 0 
L 1.87755 -1.93023002 1.8786 -1.92793002 0 P 0 
L 1.8786 -1.92793002 1.87981998 -1.92575 0 P 0 
L 1.87981998 -1.92575 1.88123002 -1.92368002 0 P 0 
L 1.88123002 -1.92368002 1.88281004 -1.92175 0 P 0 
L 1.88281004 -1.92175 1.88455 -1.91996004 0 P 0 
L 1.88455 -1.91996004 1.88643002 -1.91831998 0 P 0 
L 1.88643002 -1.91831998 1.88845 -1.91686004 0 P 0 
L 1.88845 -1.91686004 1.88986998 -1.91598996 0 P 0 
L 1.88986998 -1.91598996 1.89135 -1.91523002 0 P 0 
L 1.89135 -1.91523002 1.89288002 -1.91458996 0 P 0 
L 1.89288002 -1.91458996 1.89446998 -1.91406004 0 P 0 
L 1.89446998 -1.91406004 1.89688996 -1.91343996 0 P 0 
L 1.89688996 -1.91343996 1.89935 -1.91298996 0 P 0 
L 1.89935 -1.91298996 1.90183996 -1.91271004 0 P 0 
L 1.90183996 -1.91271004 1.9044 -1.91261004 0 P 0 
L 1.9044 -1.91261004 1.90695 -1.91268002 0 P 0 
L 1.90695 -1.91268002 1.90948996 -1.91291998 0 P 0 
L 1.90948996 -1.91291998 1.91181998 -1.91331998 0 P 0 
L 1.91181998 -1.91331998 1.91408996 -1.91393002 0 P 0 
L 1.91408996 -1.91393002 1.91633002 -1.91473002 0 P 0 
L 1.89498002 -1.90801998 1.8922 -1.90893002 0 P 0 
L 1.8922 -1.90893002 1.88948002 -1.91003002 0 P 0 
L 1.88948002 -1.91003002 1.88686004 -1.91133002 0 P 0 
L 1.88686004 -1.91133002 1.88431004 -1.91283996 0 P 0 
L 1.88431004 -1.91283996 1.88201004 -1.91446004 0 P 0 
L 1.88201004 -1.91446004 1.87985 -1.91626998 0 P 0 
L 1.87985 -1.91626998 1.87785 -1.91826004 0 P 0 
L 1.87785 -1.91826004 1.87601998 -1.92041004 0 P 0 
L 1.87601998 -1.92041004 1.87441004 -1.92266998 0 P 0 
L 1.87441004 -1.92266998 1.87298996 -1.92505 0 P 0 
L 1.87298996 -1.92505 1.87178002 -1.92756004 0 P 0 
L 1.87178002 -1.92756004 1.87078996 -1.93015 0 P 0 
L 1.87078996 -1.93015 1.87 -1.93286998 0 P 0 
L 1.87 -1.93286998 1.86943996 -1.93563996 0 P 0 
L 1.86943996 -1.93563996 1.86908996 -1.93845 0 P 0 
L 1.86908996 -1.93845 1.86898002 -1.94128996 0 P 0 
L 1.86898002 -1.94128996 1.86911998 -1.94485 0 P 0 
L 1.86911998 -1.94485 1.86953996 -1.94841004 0 P 0 
L 1.86953996 -1.94841004 1.86996004 -1.95048996 0 P 0 
L 1.86996004 -1.95048996 1.87053002 -1.95251998 0 P 0 
L 1.87053002 -1.95251998 1.87125 -1.95451998 0 P 0 
L 1.87125 -1.95451998 1.87211004 -1.95643002 0 P 0 
L 1.87211004 -1.95643002 1.8731 -1.95826004 0 P 0 
L 1.8731 -1.95826004 1.87423996 -1.96001998 0 P 0 
L 1.87423996 -1.96001998 1.87636998 -1.96278996 0 P 0 
L 1.87636998 -1.96278996 1.87871998 -1.96536998 0 P 0 
L 1.87871998 -1.96536998 1.88145 -1.96788002 0 P 0 
L 1.88145 -1.96788002 1.88436998 -1.97015 0 P 0 
L 1.88436998 -1.97015 1.88621004 -1.97135 0 P 0 
L 1.88621004 -1.97135 1.88813002 -1.97238002 0 P 0 
L 1.88813002 -1.97238002 1.89013002 -1.97326004 0 P 0 
L 1.89013002 -1.97326004 1.89228002 -1.97398996 0 P 0 
L 1.89228002 -1.97398996 1.89446998 -1.97455 0 P 0 
L 1.89446998 -1.97455 1.89671004 -1.97493996 0 P 0 
L 1.89671004 -1.97493996 1.90076998 -1.97533996 0 P 0 
L 1.90076998 -1.97533996 1.90485 -1.97546998 0 P 0 
L 1.90485 -1.97546998 1.90821004 -1.97531998 0 P 0 
L 1.90821004 -1.97531998 1.91153996 -1.97488996 0 P 0 
L 1.91153996 -1.97488996 1.91481998 -1.97418996 0 P 0 
L 1.91481998 -1.97418996 1.9171 -1.9735 0 P 0 
L 1.9171 -1.9735 1.91933002 -1.97266004 0 P 0 
L 1.91933002 -1.97266004 1.92148002 -1.97166004 0 P 0 
L 1.92148002 -1.97166004 1.92356998 -1.97048996 0 P 0 
L 1.92356998 -1.97048996 1.92553996 -1.96918996 0 P 0 
L 1.92553996 -1.96918996 1.92741004 -1.96773996 0 P 0 
L 1.92741004 -1.96773996 1.92916004 -1.96616998 0 P 0 
L 1.92916004 -1.96616998 1.93081004 -1.96446004 0 P 0 
L 1.93081004 -1.96446004 1.93236998 -1.96256998 0 P 0 
L 1.93236998 -1.96256998 1.93381004 -1.96058996 0 P 0 
L 1.93381004 -1.96058996 1.93511998 -1.95851004 0 P 0 
L 1.93511998 -1.95851004 1.93628996 -1.95633996 0 P 0 
L 1.93628996 -1.95633996 1.93803996 -1.95251998 0 P 0 
L 1.93803996 -1.95251998 1.93858002 -1.95101998 0 P 0 
L 1.93858002 -1.95101998 1.93898996 -1.94948002 0 P 0 
L 1.93898996 -1.94948002 1.93928996 -1.94786998 0 P 0 
L 1.93928996 -1.94786998 1.93946004 -1.94625 0 P 0 
L 1.93946004 -1.94625 1.9396 -1.94178002 0 P 0 
L 1.9396 -1.94178002 1.93946004 -1.93803996 0 P 0 
L 1.93946004 -1.93803996 1.93905 -1.9343 0 P 0 
L 1.93905 -1.9343 1.93863996 -1.93213996 0 P 0 
L 1.93863996 -1.93213996 1.93808002 -1.93001998 0 P 0 
L 1.93808002 -1.93001998 1.93736004 -1.92795 0 P 0 
L 1.93736004 -1.92795 1.93653002 -1.92601004 0 P 0 
L 1.93653002 -1.92601004 1.93555 -1.92415 0 P 0 
L 1.93555 -1.92415 1.93441998 -1.92236004 0 P 0 
L 1.93441998 -1.92236004 1.9331 -1.92056004 0 P 0 
L 1.9331 -1.92056004 1.93166998 -1.91885 0 P 0 
L 1.93166998 -1.91885 1.93011998 -1.91723002 0 P 0 
L 1.93011998 -1.91723002 1.92896004 -1.91615 0 P 0 
L 1.92896004 -1.91615 1.92775 -1.91511004 0 P 0 
L 1.92775 -1.91511004 1.92493002 -1.91295 0 P 0 
L 1.92493002 -1.91295 1.9221 -1.91108002 0 P 0 
L 1.9221 -1.91108002 1.92095 -1.91043002 0 P 0 
L 1.92095 -1.91043002 1.91975 -1.90985 0 P 0 
L 1.91975 -1.90985 1.91796004 -1.90913996 0 P 0 
L 1.91796004 -1.90913996 1.91613002 -1.90856004 0 P 0 
L 1.91613002 -1.90856004 1.91423996 -1.9081 0 P 0 
L 1.91423996 -1.9081 1.91086004 -1.90751998 0 P 0 
L 1.91086004 -1.90751998 1.90743002 -1.90716004 0 P 0 
L 1.90743002 -1.90716004 1.90401004 -1.90701004 0 P 0 
L 1.90401004 -1.90701004 1.90058002 -1.90708002 0 P 0 
L 1.90058002 -1.90708002 1.8987 -1.90726004 0 P 0 
L 1.8987 -1.90726004 1.89683002 -1.90756998 0 P 0 
L 1.89683002 -1.90756998 1.89498002 -1.90801998 0 P 0 
L 1.86643002 -2.02923996 1.87525 -2.02923996 0 P 0 
L 1.86176998 -2.02823996 1.87515 -2.02823996 0 P 0 
L 1.85588996 -2.02723996 1.87505 -2.02723996 0 P 0 
L 1.78365 -2.00523996 1.87281004 -2.00523996 0 P 0 
L 1.78451004 -2.00423996 1.87271004 -2.00423996 0 P 0 
L 1.78546998 -2.00323996 1.87261004 -2.00323996 0 P 0 
L 1.78655 -2.00223996 1.8725 -2.00223996 0 P 0 
L 1.78776004 -2.00123996 1.8724 -2.00123996 0 P 0 
L 1.78915 -2.00023996 1.8723 -2.00023996 0 P 0 
L 1.79078996 -1.99923996 1.8722 -1.99923996 0 P 0 
L 1.79263996 -1.99823996 1.87208996 -1.99823996 0 P 0 
L 1.79458996 -1.99723996 1.87198996 -1.99723996 0 P 0 
L 1.79686998 -1.99623996 1.87188002 -1.99623996 0 P 0 
L 1.79946004 -1.99523996 1.87178002 -1.99523996 0 P 0 
L 1.80231004 -1.99423996 1.86961998 -1.99423996 0 P 0 
L 1.80596004 -1.99323996 1.86218002 -1.99323996 0 P 0 
L 1.81051004 -1.99223996 1.85398002 -1.99223996 0 P 0 
L 1.81676004 -1.99123996 1.84395 -1.99123996 0 P 0 
L 1.87786998 -1.96146004 1.88093996 -1.96146004 0 P 0 
L 1.8771 -1.96046004 1.88013002 -1.96046004 0 P 0 
L 1.87633996 -1.95946004 1.87933996 -1.95946004 0 P 0 
L 1.87561998 -1.95846004 1.87866998 -1.95846004 0 P 0 
L 1.87496998 -1.95746004 1.87801998 -1.95746004 0 P 0 
L 1.8744 -1.95646004 1.87745 -1.95646004 0 P 0 
L 1.87386998 -1.95546004 1.87688002 -1.95546004 0 P 0 
L 1.87341998 -1.95446004 1.87641998 -1.95446004 0 P 0 
L 1.87298996 -1.95346004 1.87596004 -1.95346004 0 P 0 
L 1.87263002 -1.95246004 1.87555 -1.95246004 0 P 0 
L 1.87231004 -1.95146004 1.87518996 -1.95146004 0 P 0 
L 1.87203002 -1.95046004 1.87483002 -1.95046004 0 P 0 
L 1.87178996 -1.94946004 1.87456998 -1.94946004 0 P 0 
L 1.87158996 -1.94846004 1.87431004 -1.94846004 0 P 0 
L 1.87143996 -1.94746004 1.87408002 -1.94746004 0 P 0 
L 1.87133002 -1.94646004 1.8739 -1.94646004 0 P 0 
L 1.87121004 -1.94546004 1.87373002 -1.94546004 0 P 0 
L 1.8711 -1.94446998 1.87361998 -1.94446998 0 P 0 
L 1.87106998 -1.94346004 1.87353996 -1.94346004 0 P 0 
L 1.87103002 -1.94246004 1.87346004 -1.94246004 0 P 0 
L 1.87098996 -1.94146998 1.87346004 -1.94146998 0 P 0 
L 1.87101004 -1.94046004 1.87346004 -1.94046004 0 P 0 
L 1.87106004 -1.93946004 1.87348996 -1.93946004 0 P 0 
L 1.87111004 -1.93846004 1.87358002 -1.93846004 0 P 0 
L 1.87123002 -1.93746004 1.87366004 -1.93746004 0 P 0 
L 1.87135 -1.93646004 1.87381998 -1.93646004 0 P 0 
L 1.87151004 -1.93546004 1.87398996 -1.93546004 0 P 0 
L 1.87171998 -1.93446004 1.87416998 -1.93446004 0 P 0 
L 1.87191998 -1.93346004 1.87443002 -1.93346004 0 P 0 
L 1.8722 -1.93246004 1.87468996 -1.93246004 0 P 0 
L 1.87248996 -1.93146004 1.875 -1.93146004 0 P 0 
L 1.87281004 -1.93046004 1.87535 -1.93046004 0 P 0 
L 1.87318996 -1.92946004 1.87571004 -1.92946004 0 P 0 
L 1.87356998 -1.92846004 1.87616004 -1.92846004 0 P 0 
L 1.87405 -1.92746004 1.87661004 -1.92746004 0 P 0 
L 1.87453002 -1.92646004 1.87711998 -1.92646004 0 P 0 
L 1.87506998 -1.92546004 1.87768996 -1.92546004 0 P 0 
L 1.87566004 -1.92446998 1.87826998 -1.92446998 0 P 0 
L 1.87628996 -1.92346004 1.87896004 -1.92346004 0 P 0 
L 1.87701004 -1.92246004 1.87963996 -1.92246004 0 P 0 
L 1.87775 -1.92146004 1.88046004 -1.92146004 0 P 0 
L 1.90483996 -1.97346004 1.9009 -1.97333996 0 P 0 
L 1.9009 -1.97333996 1.89698002 -1.97295 0 P 0 
L 1.89698002 -1.97295 1.89488996 -1.97258996 0 P 0 
L 1.89488996 -1.97258996 1.89285 -1.97206998 0 P 0 
L 1.89285 -1.97206998 1.89086004 -1.97138996 0 P 0 
L 1.89086004 -1.97138996 1.889 -1.97058002 0 P 0 
L 1.889 -1.97058002 1.88723002 -1.96961998 0 P 0 
L 1.88723002 -1.96961998 1.88553002 -1.96851998 0 P 0 
L 1.88553002 -1.96851998 1.88273996 -1.96636004 0 P 0 
L 1.88273996 -1.96636004 1.88013996 -1.96396004 0 P 0 
L 1.88013996 -1.96396004 1.8779 -1.9615 0 P 0 
L 1.8779 -1.9615 1.87588002 -1.95886998 0 P 0 
L 1.87588002 -1.95886998 1.87483002 -1.95723996 0 P 0 
L 1.87483002 -1.95723996 1.8739 -1.95553996 0 P 0 
L 1.8739 -1.95553996 1.87311004 -1.95376998 0 P 0 
L 1.87311004 -1.95376998 1.87243002 -1.95191004 0 P 0 
L 1.87243002 -1.95191004 1.8719 -1.95001998 0 P 0 
L 1.8719 -1.95001998 1.87151998 -1.9481 0 P 0 
L 1.87151998 -1.9481 1.87111004 -1.94468996 0 P 0 
L 1.87111004 -1.94468996 1.87098002 -1.94128996 0 P 0 
L 1.87098002 -1.94128996 1.87108996 -1.93861004 0 P 0 
L 1.87108996 -1.93861004 1.87141004 -1.93596998 0 P 0 
L 1.87141004 -1.93596998 1.87195 -1.93335 0 P 0 
L 1.87195 -1.93335 1.87268996 -1.93078996 0 P 0 
L 1.87268996 -1.93078996 1.87361998 -1.92835 0 P 0 
L 1.87361998 -1.92835 1.87475 -1.926 0 P 0 
L 1.87475 -1.926 1.87608996 -1.92376004 0 P 0 
L 1.87608996 -1.92376004 1.8776 -1.92163996 0 P 0 
L 1.8776 -1.92163996 1.87931998 -1.91961998 0 P 0 
L 1.87931998 -1.91961998 1.8812 -1.91775 0 P 0 
L 1.8812 -1.91775 1.88323002 -1.91605 0 P 0 
L 1.88323002 -1.91605 1.8854 -1.91451998 0 P 0 
L 1.8854 -1.91451998 1.88781004 -1.91308996 0 P 0 
L 1.88781004 -1.91308996 1.89031004 -1.91186004 0 P 0 
L 1.89031004 -1.91186004 1.89288002 -1.9108 0 P 0 
L 1.89288002 -1.9108 1.89553002 -1.90995 0 P 0 
L 1.89553002 -1.90995 1.89723002 -1.90953002 0 P 0 
L 1.89723002 -1.90953002 1.89896004 -1.90923996 0 P 0 
L 1.89896004 -1.90923996 1.90068996 -1.90908002 0 P 0 
L 1.90068996 -1.90908002 1.90398996 -1.90901004 0 P 0 
L 1.90398996 -1.90901004 1.90728002 -1.90915 0 P 0 
L 1.90728002 -1.90915 1.91058996 -1.90951004 0 P 0 
L 1.91058996 -1.90951004 1.91383996 -1.91006004 0 P 0 
L 1.91383996 -1.91006004 1.91558996 -1.91048996 0 P 0 
L 1.91558996 -1.91048996 1.91728996 -1.91101998 0 P 0 
L 1.91728996 -1.91101998 1.91895 -1.91168002 0 P 0 
L 1.91895 -1.91168002 1.92001998 -1.9122 0 P 0 
L 1.92001998 -1.9122 1.92105 -1.91278996 0 P 0 
L 1.92105 -1.91278996 1.92376998 -1.91458002 0 P 0 
L 1.92376998 -1.91458002 1.92648996 -1.91666998 0 P 0 
L 1.92648996 -1.91666998 1.92763002 -1.91763996 0 P 0 
L 1.92763002 -1.91763996 1.92871004 -1.91865 0 P 0 
L 1.92871004 -1.91865 1.93018002 -1.92018996 0 P 0 
L 1.93018002 -1.92018996 1.93153002 -1.9218 0 P 0 
L 1.93153002 -1.9218 1.93276998 -1.92348996 0 P 0 
L 1.93276998 -1.92348996 1.93381004 -1.92515 0 P 0 
L 1.93381004 -1.92515 1.93471998 -1.92686998 0 P 0 
L 1.93471998 -1.92686998 1.9355 -1.92866998 0 P 0 
L 1.9355 -1.92866998 1.93616998 -1.93061004 0 P 0 
L 1.93616998 -1.93061004 1.93668996 -1.93258002 0 P 0 
L 1.93668996 -1.93258002 1.93706998 -1.93458996 0 P 0 
L 1.93706998 -1.93458996 1.93746998 -1.93818996 0 P 0 
L 1.93746998 -1.93818996 1.9376 -1.94178996 0 P 0 
L 1.9376 -1.94178996 1.93746004 -1.94611004 0 P 0 
L 1.93746004 -1.94611004 1.93731004 -1.94758996 0 P 0 
L 1.93731004 -1.94758996 1.93705 -1.94903996 0 P 0 
L 1.93705 -1.94903996 1.93666998 -1.95041998 0 P 0 
L 1.93666998 -1.95041998 1.93618002 -1.95176004 0 P 0 
L 1.93618002 -1.95176004 1.9345 -1.95545 0 P 0 
L 1.9345 -1.95545 1.93338996 -1.9575 0 P 0 
L 1.93338996 -1.9575 1.93216004 -1.95946998 0 P 0 
L 1.93216004 -1.95946998 1.93078996 -1.96133996 0 P 0 
L 1.93078996 -1.96133996 1.92931004 -1.96311998 0 P 0 
L 1.92931004 -1.96311998 1.92776998 -1.96473002 0 P 0 
L 1.92776998 -1.96473002 1.92613002 -1.96621004 0 P 0 
L 1.92613002 -1.96621004 1.92438002 -1.96756004 0 P 0 
L 1.92438002 -1.96756004 1.92253002 -1.96878002 0 P 0 
L 1.92253002 -1.96878002 1.92056998 -1.96986998 0 P 0 
L 1.92056998 -1.96986998 1.91855 -1.97081998 0 P 0 
L 1.91855 -1.97081998 1.91646004 -1.97161004 0 P 0 
L 1.91646004 -1.97161004 1.91433002 -1.97223996 0 P 0 
L 1.91433002 -1.97223996 1.9112 -1.97291004 0 P 0 
L 1.9112 -1.97291004 1.90803996 -1.97331998 0 P 0 
L 1.90803996 -1.97331998 1.90483996 -1.97346004 0 P 0 
L 1.90476004 -1.97173996 1.9048 -1.97173996 0 P 0 
L 1.9048 -1.97173996 1.90483996 -1.97173002 0 P 0 
L 1.90483996 -1.97173002 1.90736004 -1.9716 0 P 0 
L 1.90736004 -1.9716 1.9074 -1.97158996 0 P 0 
L 1.9074 -1.97158996 1.90746998 -1.97158996 0 P 0 
L 1.90746998 -1.97158996 1.90751004 -1.97158002 0 P 0 
L 1.90751004 -1.97158002 1.91001004 -1.97126004 0 P 0 
L 1.91001004 -1.97126004 1.91005 -1.97125 0 P 0 
L 1.91005 -1.97125 1.91008002 -1.97123996 0 P 0 
L 1.91008002 -1.97123996 1.91011998 -1.97123996 0 P 0 
L 1.91011998 -1.97123996 1.91016004 -1.97123002 0 P 0 
L 1.91016004 -1.97123002 1.9126 -1.97071998 0 P 0 
L 1.9126 -1.97071998 1.9126 -1.97071004 0 P 0 
L 1.9126 -1.97071004 1.91266998 -1.97071004 0 P 0 
L 1.91266998 -1.97071004 1.91271004 -1.97068996 0 P 0 
L 1.91271004 -1.97068996 1.91275 -1.97068002 0 P 0 
L 1.91275 -1.97068002 1.91511998 -1.96998996 0 P 0 
L 1.91511998 -1.96998996 1.91515 -1.96998996 0 P 0 
L 1.91515 -1.96998996 1.91518996 -1.96996998 0 P 0 
L 1.91518996 -1.96996998 1.91523002 -1.96996004 0 P 0 
L 1.91523002 -1.96996004 1.91526004 -1.96995 0 P 0 
L 1.91526004 -1.96995 1.91756998 -1.96908002 0 P 0 
L 1.91756998 -1.96908002 1.91761004 -1.96906998 0 P 0 
L 1.91761004 -1.96906998 1.91768002 -1.96903996 0 P 0 
L 1.91768002 -1.96903996 1.91771004 -1.96901998 0 P 0 
L 1.91771004 -1.96901998 1.91995 -1.96798002 0 P 0 
L 1.91995 -1.96798002 1.92001998 -1.96795 0 P 0 
L 1.92001998 -1.96795 1.92005 -1.96793002 0 P 0 
L 1.92005 -1.96793002 1.92008996 -1.96791004 0 P 0 
L 1.92008996 -1.96791004 1.92168002 -1.96701998 0 P 0 
L 1.92168002 -1.96701998 1.92171998 -1.967 0 P 0 
L 1.92171998 -1.967 1.92175 -1.96698002 0 P 0 
L 1.92175 -1.96698002 1.92178996 -1.96695 0 P 0 
L 1.92178996 -1.96695 1.92181998 -1.96693002 0 P 0 
L 1.92181998 -1.96693002 1.92331998 -1.96591998 0 P 0 
L 1.92331998 -1.96591998 1.92336004 -1.9659 0 P 0 
L 1.92336004 -1.9659 1.92341998 -1.96586004 0 P 0 
L 1.92341998 -1.96586004 1.92345 -1.96583002 0 P 0 
L 1.92345 -1.96583002 1.92486004 -1.9647 0 P 0 
L 1.92486004 -1.9647 1.92493002 -1.96465 0 P 0 
L 1.92493002 -1.96465 1.92496004 -1.96463002 0 P 0 
L 1.92496004 -1.96463002 1.92498996 -1.9646 0 P 0 
L 1.92498996 -1.9646 1.92631004 -1.96336998 0 P 0 
L 1.92631004 -1.96336998 1.9264 -1.96328002 0 P 0 
L 1.9264 -1.96328002 1.92641998 -1.96325 0 P 0 
L 1.92641998 -1.96325 1.92763996 -1.96191998 0 P 0 
L 1.92763996 -1.96191998 1.92766998 -1.96188996 0 P 0 
L 1.92766998 -1.96188996 1.92768996 -1.96186004 0 P 0 
L 1.92768996 -1.96186004 1.92771998 -1.96183002 0 P 0 
L 1.92771998 -1.96183002 1.92773996 -1.9618 0 P 0 
L 1.92773996 -1.9618 1.92913996 -1.96001004 0 P 0 
L 1.92913996 -1.96001004 1.92918996 -1.95995 0 P 0 
L 1.92918996 -1.95995 1.92921004 -1.95991004 0 P 0 
L 1.92921004 -1.95991004 1.92923002 -1.95988002 0 P 0 
L 1.92923002 -1.95988002 1.93048002 -1.95798996 0 P 0 
L 1.93048002 -1.95798996 1.93051998 -1.95793002 0 P 0 
L 1.93051998 -1.95793002 1.93053996 -1.95788996 0 P 0 
L 1.93053996 -1.95788996 1.93056004 -1.95786004 0 P 0 
L 1.93056004 -1.95786004 1.93166004 -1.95588002 0 P 0 
L 1.93166004 -1.95588002 1.93171004 -1.95576998 0 P 0 
L 1.93171004 -1.95576998 1.93173002 -1.95573996 0 P 0 
L 1.93173002 -1.95573996 1.93266998 -1.95366998 0 P 0 
L 1.93266998 -1.95366998 1.93271004 -1.95356998 0 P 0 
L 1.93271004 -1.95356998 1.93273002 -1.95353002 0 P 0 
L 1.93273002 -1.95353002 1.9335 -1.9514 0 P 0 
L 1.9335 -1.9514 1.93351004 -1.95136998 0 P 0 
L 1.93351004 -1.95136998 1.93353002 -1.95133002 0 P 0 
L 1.93353002 -1.95133002 1.93355 -1.95125 0 P 0 
L 1.93355 -1.95125 1.93416004 -1.94906998 0 P 0 
L 1.93416004 -1.94906998 1.93416998 -1.94903002 0 P 0 
L 1.93416998 -1.94903002 1.93418002 -1.949 0 P 0 
L 1.93418002 -1.949 1.93418002 -1.94896004 0 P 0 
L 1.93418002 -1.94896004 1.93418996 -1.94891998 0 P 0 
L 1.93418996 -1.94891998 1.93463996 -1.94665 0 P 0 
L 1.93463996 -1.94665 1.93463996 -1.94661004 0 P 0 
L 1.93463996 -1.94661004 1.93465 -1.94656998 0 P 0 
L 1.93465 -1.94656998 1.93466004 -1.9465 0 P 0 
L 1.93466004 -1.9465 1.93493996 -1.9442 0 P 0 
L 1.93493996 -1.9442 1.93493996 -1.94413002 0 P 0 
L 1.93493996 -1.94413002 1.93495 -1.94408996 0 P 0 
L 1.93495 -1.94408996 1.93495 -1.94406004 0 P 0 
L 1.93495 -1.94406004 1.93505 -1.94173996 0 P 0 
L 1.93505 -1.94173996 1.93506004 -1.94171004 0 P 0 
L 1.93506004 -1.94171004 1.93506004 -1.9416 0 P 0 
L 1.93506004 -1.9416 1.93498996 -1.93928996 0 P 0 
L 1.93498996 -1.93928996 1.93498996 -1.93921004 0 P 0 
L 1.93498996 -1.93921004 1.93498002 -1.93913996 0 P 0 
L 1.93498002 -1.93913996 1.93475 -1.93683996 0 P 0 
L 1.93475 -1.93683996 1.93473996 -1.93676998 0 P 0 
L 1.93473996 -1.93676998 1.93473002 -1.93673002 0 P 0 
L 1.93473002 -1.93673002 1.93473002 -1.93668996 0 P 0 
L 1.93473002 -1.93668996 1.93433002 -1.93441004 0 P 0 
L 1.93433002 -1.93441004 1.93431998 -1.93436998 0 P 0 
L 1.93431998 -1.93436998 1.93431004 -1.93433996 0 P 0 
L 1.93431004 -1.93433996 1.93428996 -1.93426004 0 P 0 
L 1.93428996 -1.93426004 1.93373002 -1.93206004 0 P 0 
L 1.93373002 -1.93206004 1.93368996 -1.93191998 0 P 0 
L 1.93368996 -1.93191998 1.93296004 -1.92976998 0 P 0 
L 1.93296004 -1.92976998 1.93293996 -1.9297 0 P 0 
L 1.93293996 -1.9297 1.93291004 -1.92963002 0 P 0 
L 1.93291004 -1.92963002 1.93201998 -1.92753996 0 P 0 
L 1.93201998 -1.92753996 1.93196998 -1.92743002 0 P 0 
L 1.93196998 -1.92743002 1.93196004 -1.9274 0 P 0 
L 1.93196004 -1.9274 1.93091998 -1.92538996 0 P 0 
L 1.93091998 -1.92538996 1.9309 -1.92536004 0 P 0 
L 1.9309 -1.92536004 1.93088002 -1.92531998 0 P 0 
L 1.93088002 -1.92531998 1.93086004 -1.92528996 0 P 0 
L 1.93086004 -1.92528996 1.93083996 -1.92525 0 P 0 
L 1.93083996 -1.92525 1.92965 -1.92331998 0 P 0 
L 1.92965 -1.92331998 1.92956998 -1.9232 0 P 0 
L 1.92956998 -1.9232 1.92823002 -1.92136004 0 P 0 
L 1.92823002 -1.92136004 1.92818002 -1.9213 0 P 0 
L 1.92818002 -1.9213 1.92816004 -1.92126998 0 P 0 
L 1.92816004 -1.92126998 1.92813002 -1.92123996 0 P 0 
L 1.92813002 -1.92123996 1.92671998 -1.91958002 0 P 0 
L 1.92671998 -1.91958002 1.9266 -1.91946004 0 P 0 
L 1.9266 -1.91946004 1.92505 -1.91793002 0 P 0 
L 1.92505 -1.91793002 1.92498996 -1.91786998 0 P 0 
L 1.92498996 -1.91786998 1.92493002 -1.91781998 0 P 0 
L 1.92493002 -1.91781998 1.92325 -1.91643002 0 P 0 
L 1.92325 -1.91643002 1.92318996 -1.91636998 0 P 0 
L 1.92318996 -1.91636998 1.92311998 -1.91631998 0 P 0 
L 1.92311998 -1.91631998 1.92133002 -1.91508002 0 P 0 
L 1.92133002 -1.91508002 1.92126004 -1.91503996 0 P 0 
L 1.92126004 -1.91503996 1.92121998 -1.91501004 0 P 0 
L 1.92121998 -1.91501004 1.92118002 -1.91498996 0 P 0 
L 1.92118002 -1.91498996 1.91928996 -1.91391004 0 P 0 
L 1.91928996 -1.91391004 1.91926004 -1.91388996 0 P 0 
L 1.91926004 -1.91388996 1.91913996 -1.91383002 0 P 0 
L 1.91913996 -1.91383002 1.91716998 -1.91291004 0 P 0 
L 1.91716998 -1.91291004 1.91711998 -1.91288996 0 P 0 
L 1.91711998 -1.91288996 1.91705 -1.91286004 0 P 0 
L 1.91705 -1.91286004 1.917 -1.91285 0 P 0 
L 1.917 -1.91285 1.91476998 -1.91203996 0 P 0 
L 1.91476998 -1.91203996 1.91468996 -1.91201998 0 P 0 
L 1.91468996 -1.91201998 1.91465 -1.912 0 P 0 
L 1.91465 -1.912 1.9146 -1.91198996 0 P 0 
L 1.9146 -1.91198996 1.91233002 -1.91138996 0 P 0 
L 1.91233002 -1.91138996 1.91228002 -1.91138002 0 P 0 
L 1.91228002 -1.91138002 1.91223996 -1.91136998 0 P 0 
L 1.91223996 -1.91136998 1.91216004 -1.91136004 0 P 0 
L 1.91216004 -1.91136004 1.90983002 -1.91095 0 P 0 
L 1.90983002 -1.91095 1.9098 -1.91093996 0 P 0 
L 1.9098 -1.91093996 1.90976004 -1.91093996 0 P 0 
L 1.90976004 -1.91093996 1.90971998 -1.91093002 0 P 0 
L 1.90971998 -1.91093002 1.90968002 -1.91093002 0 P 0 
L 1.90968002 -1.91093002 1.90713996 -1.91068996 0 P 0 
L 1.90713996 -1.91068996 1.9071 -1.91068002 0 P 0 
L 1.9071 -1.91068002 1.907 -1.91068002 0 P 0 
L 1.907 -1.91068002 1.90445 -1.91061004 0 P 0 
L 1.90445 -1.91061004 1.90431004 -1.91061004 0 P 0 
L 1.90431004 -1.91061004 1.90176004 -1.91071004 0 P 0 
L 1.90176004 -1.91071004 1.90173002 -1.91071998 0 P 0 
L 1.90173002 -1.91071998 1.90166004 -1.91071998 0 P 0 
L 1.90166004 -1.91071998 1.90161998 -1.91073002 0 P 0 
L 1.90161998 -1.91073002 1.89913002 -1.911 0 P 0 
L 1.89913002 -1.911 1.89906004 -1.91101004 0 P 0 
L 1.89906004 -1.91101004 1.89901998 -1.91101998 0 P 0 
L 1.89901998 -1.91101998 1.89898996 -1.91101998 0 P 0 
L 1.89898996 -1.91101998 1.89653002 -1.91146998 0 P 0 
L 1.89653002 -1.91146998 1.8965 -1.91148002 0 P 0 
L 1.8965 -1.91148002 1.89646004 -1.91148002 0 P 0 
L 1.89646004 -1.91148002 1.8964 -1.9115 0 P 0 
L 1.8964 -1.9115 1.89396998 -1.91211998 0 P 0 
L 1.89396998 -1.91211998 1.89393996 -1.91213002 0 P 0 
L 1.89393996 -1.91213002 1.89383002 -1.91216004 0 P 0 
L 1.89383002 -1.91216004 1.89225 -1.91268996 0 P 0 
L 1.89225 -1.91268996 1.89218002 -1.91271998 0 P 0 
L 1.89218002 -1.91271998 1.89211004 -1.91273996 0 P 0 
L 1.89211004 -1.91273996 1.8921 -1.91273996 0 P 0 
L 1.8921 -1.91273996 1.89058002 -1.91338996 0 P 0 
L 1.89058002 -1.91338996 1.89043996 -1.91345 0 P 0 
L 1.89043996 -1.91345 1.88896004 -1.91421004 0 P 0 
L 1.88896004 -1.91421004 1.88893002 -1.91423002 0 P 0 
L 1.88893002 -1.91423002 1.8889 -1.91423996 0 P 0 
L 1.8889 -1.91423996 1.88886004 -1.91426004 0 P 0 
L 1.88886004 -1.91426004 1.88883002 -1.91428002 0 P 0 
L 1.88883002 -1.91428002 1.88741004 -1.91515 0 P 0 
L 1.88741004 -1.91515 1.88733996 -1.91518996 0 P 0 
L 1.88733996 -1.91518996 1.88728002 -1.91523996 0 P 0 
L 1.88728002 -1.91523996 1.88526004 -1.9167 0 P 0 
L 1.88526004 -1.9167 1.88521998 -1.91673002 0 P 0 
L 1.88521998 -1.91673002 1.88518996 -1.91675 0 P 0 
L 1.88518996 -1.91675 1.88516004 -1.91678002 0 P 0 
L 1.88516004 -1.91678002 1.88511998 -1.91681004 0 P 0 
L 1.88511998 -1.91681004 1.88323002 -1.91845 0 P 0 
L 1.88323002 -1.91845 1.8832 -1.91846998 0 P 0 
L 1.8832 -1.91846998 1.88311004 -1.91856004 0 P 0 
L 1.88311004 -1.91856004 1.88136998 -1.92036004 0 P 0 
L 1.88136998 -1.92036004 1.88128002 -1.92045 0 P 0 
L 1.88128002 -1.92045 1.88125 -1.92048996 0 P 0 
L 1.88125 -1.92048996 1.87968002 -1.92241998 0 P 0 
L 1.87968002 -1.92241998 1.87965 -1.92245 0 P 0 
L 1.87965 -1.92245 1.87961998 -1.92248996 0 P 0 
L 1.87961998 -1.92248996 1.87956998 -1.92256004 0 P 0 
L 1.87956998 -1.92256004 1.87816998 -1.92461998 0 P 0 
L 1.87816998 -1.92461998 1.8781 -1.92473002 0 P 0 
L 1.8781 -1.92473002 1.87808002 -1.92476998 0 P 0 
L 1.87808002 -1.92476998 1.87685 -1.92695 0 P 0 
L 1.87685 -1.92695 1.87683002 -1.92698996 0 P 0 
L 1.87683002 -1.92698996 1.87681004 -1.92701998 0 P 0 
L 1.87681004 -1.92701998 1.87678996 -1.92706998 0 P 0 
L 1.87678996 -1.92706998 1.87676998 -1.92711004 0 P 0 
L 1.87676998 -1.92711004 1.87573002 -1.92941004 0 P 0 
L 1.87573002 -1.92941004 1.87571004 -1.92945 0 P 0 
L 1.87571004 -1.92945 1.8757 -1.92948996 0 P 0 
L 1.8757 -1.92948996 1.87568002 -1.92951998 0 P 0 
L 1.87568002 -1.92951998 1.87566998 -1.92956998 0 P 0 
L 1.87566998 -1.92956998 1.87483996 -1.93193002 0 P 0 
L 1.87483996 -1.93193002 1.87481004 -1.93201004 0 P 0 
L 1.87481004 -1.93201004 1.87478996 -1.93208996 0 P 0 
L 1.87478996 -1.93208996 1.87416004 -1.93451998 0 P 0 
L 1.87416004 -1.93451998 1.87413996 -1.93456004 0 P 0 
L 1.87413996 -1.93456004 1.87413002 -1.9346 0 P 0 
L 1.87413002 -1.9346 1.87413002 -1.93463996 0 P 0 
L 1.87413002 -1.93463996 1.87411998 -1.93468002 0 P 0 
L 1.87411998 -1.93468002 1.8737 -1.93715 0 P 0 
L 1.8737 -1.93715 1.87368996 -1.93718996 0 P 0 
L 1.87368996 -1.93718996 1.87368002 -1.93723996 0 P 0 
L 1.87368002 -1.93723996 1.87368002 -1.93731998 0 P 0 
L 1.87368002 -1.93731998 1.87346998 -1.93981998 0 P 0 
L 1.87346998 -1.93981998 1.87346004 -1.93986004 0 P 0 
L 1.87346004 -1.93986004 1.87346004 -1.94258002 0 P 0 
L 1.87346004 -1.94258002 1.87346998 -1.94266004 0 P 0 
L 1.87346998 -1.94266004 1.87368002 -1.94516998 0 P 0 
L 1.87368002 -1.94516998 1.87368996 -1.94521004 0 P 0 
L 1.87368996 -1.94521004 1.87368996 -1.94525 0 P 0 
L 1.87368996 -1.94525 1.87371004 -1.94533996 0 P 0 
L 1.87371004 -1.94533996 1.87413996 -1.94778996 0 P 0 
L 1.87413996 -1.94778996 1.87413996 -1.94783996 0 P 0 
L 1.87413996 -1.94783996 1.87416998 -1.94796004 0 P 0 
L 1.87416998 -1.94796004 1.87481004 -1.95036998 0 P 0 
L 1.87481004 -1.95036998 1.87483996 -1.95048996 0 P 0 
L 1.87483996 -1.95048996 1.87486004 -1.95053002 0 P 0 
L 1.87486004 -1.95053002 1.8757 -1.95288002 0 P 0 
L 1.8757 -1.95288002 1.87571004 -1.95291998 0 P 0 
L 1.87571004 -1.95291998 1.87575 -1.953 0 P 0 
L 1.87575 -1.953 1.87576004 -1.95303996 0 P 0 
L 1.87576004 -1.95303996 1.8768 -1.9553 0 P 0 
L 1.8768 -1.9553 1.87686004 -1.95541998 0 P 0 
L 1.87686004 -1.95541998 1.87688002 -1.95545 0 P 0 
L 1.87688002 -1.95545 1.8781 -1.95761004 0 P 0 
L 1.8781 -1.95761004 1.87811998 -1.95761004 0 P 0 
L 1.87811998 -1.95761004 1.8781 -1.95761998 0 P 0 
L 1.8781 -1.95761998 1.87813996 -1.95768996 0 P 0 
L 1.87813996 -1.95768996 1.87816998 -1.95771998 0 P 0 
L 1.87816998 -1.95771998 1.87818996 -1.95775 0 P 0 
L 1.87818996 -1.95775 1.87938002 -1.95951004 0 P 0 
L 1.87938002 -1.95951004 1.87943996 -1.9596 0 P 0 
L 1.87943996 -1.9596 1.87946998 -1.95963002 0 P 0 
L 1.87946998 -1.95963002 1.88078002 -1.96128996 0 P 0 
L 1.88078002 -1.96128996 1.88081004 -1.96131998 0 P 0 
L 1.88081004 -1.96131998 1.88083002 -1.96135 0 P 0 
L 1.88083002 -1.96135 1.88086004 -1.96136998 0 P 0 
L 1.88086004 -1.96136998 1.88088002 -1.9614 0 P 0 
L 1.88088002 -1.9614 1.88231998 -1.96295 0 P 0 
L 1.88231998 -1.96295 1.88233996 -1.96298002 0 P 0 
L 1.88233996 -1.96298002 1.8824 -1.96303996 0 P 0 
L 1.8824 -1.96303996 1.88243002 -1.96306004 0 P 0 
L 1.88243002 -1.96306004 1.88398002 -1.9645 0 P 0 
L 1.88398002 -1.9645 1.88401004 -1.96451998 0 P 0 
L 1.88401004 -1.96451998 1.88403002 -1.96455 0 P 0 
L 1.88403002 -1.96455 1.88406998 -1.96458002 0 P 0 
L 1.88406998 -1.96458002 1.88408996 -1.9646 0 P 0 
L 1.88408996 -1.9646 1.88575 -1.96591004 0 P 0 
L 1.88575 -1.96591004 1.88578002 -1.96593996 0 P 0 
L 1.88578002 -1.96593996 1.88586998 -1.966 0 P 0 
L 1.88586998 -1.966 1.88761998 -1.96718996 0 P 0 
L 1.88761998 -1.96718996 1.88766004 -1.96721004 0 P 0 
L 1.88766004 -1.96721004 1.88775 -1.96726998 0 P 0 
L 1.88775 -1.96726998 1.88958996 -1.96831998 0 P 0 
L 1.88958996 -1.96831998 1.88965 -1.96836004 0 P 0 
L 1.88965 -1.96836004 1.88968002 -1.96836998 0 P 0 
L 1.88968002 -1.96836998 1.88971998 -1.96838996 0 P 0 
L 1.88971998 -1.96838996 1.89145 -1.96921998 0 P 0 
L 1.89145 -1.96921998 1.89151004 -1.96925 0 P 0 
L 1.89151004 -1.96925 1.89155 -1.96926004 0 P 0 
L 1.89155 -1.96926004 1.89158002 -1.96926998 0 P 0 
L 1.89158002 -1.96926998 1.89336004 -1.96996998 0 P 0 
L 1.89336004 -1.96996998 1.89336004 -1.96998002 0 P 0 
L 1.89336004 -1.96998002 1.89346004 -1.97001004 0 P 0 
L 1.89346004 -1.97001004 1.89348996 -1.97001998 0 P 0 
L 1.89348996 -1.97001998 1.89531998 -1.9706 0 P 0 
L 1.89531998 -1.9706 1.89536004 -1.97061004 0 P 0 
L 1.89536004 -1.97061004 1.89541998 -1.97063002 0 P 0 
L 1.89541998 -1.97063002 1.89546004 -1.97063002 0 P 0 
L 1.89546004 -1.97063002 1.89731998 -1.97108002 0 P 0 
L 1.89731998 -1.97108002 1.89741998 -1.9711 0 P 0 
L 1.89741998 -1.9711 1.89746004 -1.9711 0 P 0 
L 1.89746004 -1.9711 1.89746004 -1.97111004 0 P 0 
L 1.89746004 -1.97111004 1.89933996 -1.97141998 0 P 0 
L 1.89933996 -1.97141998 1.89936998 -1.97143002 0 P 0 
L 1.89936998 -1.97143002 1.89941004 -1.97143002 0 P 0 
L 1.89941004 -1.97143002 1.89945 -1.97143996 0 P 0 
L 1.89945 -1.97143996 1.89948002 -1.97143996 0 P 0 
L 1.89948002 -1.97143996 1.90201004 -1.97168002 0 P 0 
L 1.90201004 -1.97168002 1.90205 -1.97168002 0 P 0 
L 1.90205 -1.97168002 1.90208996 -1.97168996 0 P 0 
L 1.90208996 -1.97168996 1.90216004 -1.97168996 0 P 0 
L 1.90216004 -1.97168996 1.90468996 -1.97173996 0 P 0 
L 1.90468996 -1.97173996 1.90476004 -1.97173996 0 P 0 
L 1.80616004 -2.12823996 1.83348996 -2.12823996 0 P 0 
L 1.79591998 -2.12723996 1.8396 -2.12723996 0 P 0 
L 1.78818002 -2.12623996 1.84465 -2.12623996 0 P 0 
L 1.82003996 -2.09123996 1.87618996 -2.09123996 0 P 0 
L 1.82198996 -2.09023996 1.8762 -2.09023996 0 P 0 
L 1.82325 -2.08923996 1.8762 -2.08923996 0 P 0 
L 1.82411998 -2.08823996 1.87618996 -2.08823996 0 P 0 
L 1.82463002 -2.08723996 1.87616998 -2.08723996 0 P 0 
L 1.82488002 -2.08623996 1.87615 -2.08623996 0 P 0 
L 1.82493002 -2.08523996 1.87613002 -2.08523996 0 P 0 
L 1.82476998 -2.08423996 1.87611004 -2.08423996 0 P 0 
L 1.64846004 -2.08295 1.73316998 -2.08295 0 P 0 
L 1.64811998 -2.08195 1.73356998 -2.08195 0 P 0 
L 1.64776998 -2.08095 1.73398002 -2.08095 0 P 0 
L 1.64743002 -2.07995 1.73438002 -2.07995 0 P 0 
L 1.64708996 -2.07895 1.73478996 -2.07895 0 P 0 
L 1.64673996 -2.07795 1.7352 -2.07795 0 P 0 
L 1.6464 -2.07695 1.7356 -2.07695 0 P 0 
L 1.64605 -2.07595 1.73601004 -2.07595 0 P 0 
L 1.64571004 -2.07495 1.73641004 -2.07495 0 P 0 
L 1.64536004 -2.07395 1.73681004 -2.07395 0 P 0 
L 1.64501998 -2.07295 1.73721998 -2.07295 0 P 0 
L 1.64466998 -2.07195 1.73761998 -2.07195 0 P 0 
L 1.64433002 -2.07095 1.73803002 -2.07095 0 P 0 
L 1.64398002 -2.06995 1.69251004 -2.06995 0 P 0 
L 1.69583002 -2.06995 1.73843996 -2.06995 0 P 0 
L 1.64363002 -2.06895 1.69168002 -2.06895 0 P 0 
L 1.69671998 -2.06895 1.73883996 -2.06895 0 P 0 
L 1.64328996 -2.06795 1.69136004 -2.06795 0 P 0 
L 1.69708996 -2.06795 1.73925 -2.06795 0 P 0 
L 1.64293996 -2.06695 1.69108002 -2.06695 0 P 0 
L 1.69738002 -2.06695 1.73965 -2.06695 0 P 0 
L 1.64258996 -2.06595 1.6908 -2.06595 0 P 0 
L 1.69768002 -2.06595 1.74006004 -2.06595 0 P 0 
L 1.64223996 -2.06495 1.69051998 -2.06495 0 P 0 
L 1.69796998 -2.06495 1.74046004 -2.06495 0 P 0 
L 1.6419 -2.06395 1.69023002 -2.06395 0 P 0 
L 1.69826998 -2.06395 1.74086004 -2.06395 0 P 0 
L 1.64155 -2.06295 1.68996004 -2.06295 0 P 0 
L 1.69856004 -2.06295 1.74126998 -2.06295 0 P 0 
L 1.6412 -2.06195 1.68966998 -2.06195 0 P 0 
L 1.69886004 -2.06195 1.74168002 -2.06195 0 P 0 
L 1.64085 -2.06095 1.68938996 -2.06095 0 P 0 
L 1.69915 -2.06095 1.74208002 -2.06095 0 P 0 
L 1.6405 -2.05995 1.68911004 -2.05995 0 P 0 
L 1.69945 -2.05995 1.74248002 -2.05995 0 P 0 
L 1.64016004 -2.05895 1.68883002 -2.05895 0 P 0 
L 1.69973996 -2.05895 1.74288996 -2.05895 0 P 0 
L 1.63981004 -2.05795 1.68855 -2.05795 0 P 0 
L 1.70003996 -2.05795 1.74328996 -2.05795 0 P 0 
L 1.63946004 -2.05695 1.68826998 -2.05695 0 P 0 
L 1.70033002 -2.05695 1.7437 -2.05695 0 P 0 
L 1.63911004 -2.05595 1.68798996 -2.05595 0 P 0 
L 1.70063002 -2.05595 1.7441 -2.05595 0 P 0 
L 1.63876998 -2.05495 1.68771004 -2.05495 0 P 0 
L 1.70091998 -2.05495 1.74451004 -2.05495 0 P 0 
L 1.63841998 -2.05395 1.68741998 -2.05395 0 P 0 
L 1.70121998 -2.05395 1.74491004 -2.05395 0 P 0 
L 1.63806998 -2.05295 1.68713996 -2.05295 0 P 0 
L 1.70151004 -2.05295 1.74531004 -2.05295 0 P 0 
L 1.63771998 -2.05195 1.68686004 -2.05195 0 P 0 
L 1.70181004 -2.05195 1.74571998 -2.05195 0 P 0 
L 1.63738002 -2.05095 1.68658002 -2.05095 0 P 0 
L 1.7021 -2.05095 1.74611998 -2.05095 0 P 0 
L 1.63703002 -2.04995 1.6863 -2.04995 0 P 0 
L 1.7024 -2.04995 1.74653002 -2.04995 0 P 0 
L 1.63668002 -2.04895 1.68601998 -2.04895 0 P 0 
L 1.70268996 -2.04895 1.74693002 -2.04895 0 P 0 
L 1.63633002 -2.04795 1.68573996 -2.04795 0 P 0 
L 1.70298996 -2.04795 1.74733002 -2.04795 0 P 0 
L 1.63598002 -2.04695 1.68546004 -2.04695 0 P 0 
L 1.70328002 -2.04695 1.74773996 -2.04695 0 P 0 
L 1.63563996 -2.04595 1.68518002 -2.04595 0 P 0 
L 1.70358002 -2.04595 1.74813996 -2.04595 0 P 0 
L 1.63528996 -2.04495 1.6849 -2.04495 0 P 0 
L 1.70386998 -2.04495 1.74855 -2.04495 0 P 0 
L 1.63493996 -2.04395 1.68461004 -2.04395 0 P 0 
L 1.70416998 -2.04395 1.74895 -2.04395 0 P 0 
L 1.63458996 -2.04295 1.68433002 -2.04295 0 P 0 
L 1.70446004 -2.04295 1.74936004 -2.04295 0 P 0 
L 1.63425 -2.04195 1.68405 -2.04195 0 P 0 
L 1.70475 -2.04195 1.74976004 -2.04195 0 P 0 
L 1.6339 -2.04095 1.68376998 -2.04095 0 P 0 
L 1.70503002 -2.04095 1.75016004 -2.04095 0 P 0 
L 1.63355 -2.03995 1.68348996 -2.03995 0 P 0 
L 1.70531998 -2.03995 1.75056998 -2.03995 0 P 0 
L 1.6332 -2.03895 1.68321004 -2.03895 0 P 0 
L 1.7056 -2.03895 1.75096998 -2.03895 0 P 0 
L 1.63286004 -2.03795 1.68293002 -2.03795 0 P 0 
L 1.70588996 -2.03795 1.75138002 -2.03795 0 P 0 
L 1.63251004 -2.03695 1.68266004 -2.03695 0 P 0 
L 1.70618002 -2.03695 1.75178002 -2.03695 0 P 0 
L 1.63216004 -2.03595 1.68238002 -2.03595 0 P 0 
L 1.70646998 -2.03595 1.75218996 -2.03595 0 P 0 
L 1.63181004 -2.03495 1.6821 -2.03495 0 P 0 
L 1.70675 -2.03495 1.75258996 -2.03495 0 P 0 
L 1.63146998 -2.03395 1.68183002 -2.03395 0 P 0 
L 1.70703996 -2.03395 1.75298996 -2.03395 0 P 0 
L 1.63111998 -2.03295 1.68155 -2.03295 0 P 0 
L 1.70733002 -2.03295 1.7534 -2.03295 0 P 0 
L 1.63076998 -2.03195 1.68126998 -2.03195 0 P 0 
L 1.70761004 -2.03195 1.75381004 -2.03195 0 P 0 
L 1.63041998 -2.03095 1.68098996 -2.03095 0 P 0 
L 1.7079 -2.03095 1.75421004 -2.03095 0 P 0 
L 1.63006998 -2.02995 1.68071004 -2.02995 0 P 0 
L 1.70818996 -2.02995 1.75461004 -2.02995 0 P 0 
L 1.62973002 -2.02895 1.68043996 -2.02895 0 P 0 
L 1.70846998 -2.02895 1.75501998 -2.02895 0 P 0 
L 1.62938002 -2.02795 1.68016004 -2.02795 0 P 0 
L 1.70876004 -2.02795 1.75541998 -2.02795 0 P 0 
L 1.62903002 -2.02695 1.67988002 -2.02695 0 P 0 
L 1.70905 -2.02695 1.75583002 -2.02695 0 P 0 
L 1.62868002 -2.02595 1.6796 -2.02595 0 P 0 
L 1.70933996 -2.02595 1.75623002 -2.02595 0 P 0 
L 1.62831004 -2.02495 1.67933002 -2.02495 0 P 0 
L 1.70961998 -2.02495 1.75663996 -2.02495 0 P 0 
L 1.62793996 -2.02395 1.67905 -2.02395 0 P 0 
L 1.70991004 -2.02395 1.75703996 -2.02395 0 P 0 
L 1.62756998 -2.02295 1.67876998 -2.02295 0 P 0 
L 1.7102 -2.02295 1.75743996 -2.02295 0 P 0 
L 1.6272 -2.02195 1.6785 -2.02195 0 P 0 
L 1.71048002 -2.02195 1.75785 -2.02195 0 P 0 
L 1.62683002 -2.02095 1.67821998 -2.02095 0 P 0 
L 1.71076004 -2.02095 1.75825 -2.02095 0 P 0 
L 1.62646998 -2.01995 1.67793996 -2.01995 0 P 0 
L 1.71101004 -2.01995 1.75866004 -2.01995 0 P 0 
L 1.6261 -2.01895 1.67766004 -2.01895 0 P 0 
L 1.71126998 -2.01895 1.75906004 -2.01895 0 P 0 
L 1.62573002 -2.01795 1.67738996 -2.01795 0 P 0 
L 1.71151998 -2.01795 1.75946998 -2.01795 0 P 0 
L 1.62536004 -2.01695 1.67711004 -2.01695 0 P 0 
L 1.71176998 -2.01695 1.75986998 -2.01695 0 P 0 
L 1.62498996 -2.01595 1.67683002 -2.01595 0 P 0 
L 1.71203002 -2.01595 1.76026998 -2.01595 0 P 0 
L 1.62461998 -2.01495 1.67656004 -2.01495 0 P 0 
L 1.71228002 -2.01495 1.76068002 -2.01495 0 P 0 
L 1.62425 -2.01395 1.67628002 -2.01395 0 P 0 
L 1.71253996 -2.01395 1.76108002 -2.01395 0 P 0 
L 1.62388002 -2.01295 1.67601998 -2.01295 0 P 0 
L 1.71278996 -2.01295 1.76148996 -2.01295 0 P 0 
L 1.62351004 -2.01195 1.67576998 -2.01195 0 P 0 
L 1.71305 -2.01195 1.76188996 -2.01195 0 P 0 
L 1.62313996 -2.01095 1.67551998 -2.01095 0 P 0 
L 1.7133 -2.01095 1.76228996 -2.01095 0 P 0 
L 1.62276998 -2.00995 1.67528002 -2.00995 0 P 0 
L 1.71355 -2.00995 1.7627 -2.00995 0 P 0 
L 1.6224 -2.00895 1.67503002 -2.00895 0 P 0 
L 1.71381004 -2.00895 1.7631 -2.00895 0 P 0 
L 1.62203002 -2.00795 1.67478996 -2.00795 0 P 0 
L 1.71406004 -2.00795 1.76351004 -2.00795 0 P 0 
L 1.62166004 -2.00695 1.67453996 -2.00695 0 P 0 
L 1.71431004 -2.00695 1.76391004 -2.00695 0 P 0 
L 1.62128996 -2.00595 1.67428996 -2.00595 0 P 0 
L 1.71453996 -2.00595 1.76431998 -2.00595 0 P 0 
L 1.62091004 -2.00495 1.67405 -2.00495 0 P 0 
L 1.71476998 -2.00495 1.76471998 -2.00495 0 P 0 
L 1.62051998 -2.00395 1.6738 -2.00395 0 P 0 
L 1.715 -2.00395 1.76511998 -2.00395 0 P 0 
L 1.62013002 -2.00295 1.67355 -2.00295 0 P 0 
L 1.71523002 -2.00295 1.76553002 -2.00295 0 P 0 
L 1.61973996 -2.00195 1.67331004 -2.00195 0 P 0 
L 1.71546004 -2.00195 1.76593996 -2.00195 0 P 0 
L 1.61935 -2.00095 1.67306004 -2.00095 0 P 0 
L 1.71568996 -2.00095 1.76633996 -2.00095 0 P 0 
L 1.61896004 -1.99995 1.67283996 -1.99995 0 P 0 
L 1.71591998 -1.99995 1.76673996 -1.99995 0 P 0 
L 1.61856998 -1.99895 1.67261998 -1.99895 0 P 0 
L 1.71613996 -1.99895 1.76715 -1.99895 0 P 0 
L 1.71638002 -1.99795 1.76755 -1.99795 0 P 0 
L 1.7166 -1.99695 1.76796004 -1.99695 0 P 0 
L 1.71683002 -1.99595 1.76836004 -1.99595 0 P 0 
L 1.71866998 -1.99495 1.76876998 -1.99495 0 P 0 
L 1.78213996 -2.04823996 1.84641998 -2.04823996 0 P 0 
L 1.78138002 -2.04723996 1.84498996 -2.04723996 0 P 0 
L 1.78071004 -2.04623996 1.84356004 -2.04623996 0 P 0 
L 1.7801 -2.04523996 1.84213996 -2.04523996 0 P 0 
L 1.77956004 -2.04423996 1.84071004 -2.04423996 0 P 0 
L 1.77908996 -2.04323996 1.83928002 -2.04323996 0 P 0 
L 1.77866004 -2.04223996 1.83786004 -2.04223996 0 P 0 
L 1.77831004 -2.04123996 1.83658996 -2.04123996 0 P 0 
L 1.77796004 -2.04023996 1.83536004 -2.04023996 0 P 0 
L 1.77761004 -2.03923996 1.83428002 -2.03923996 0 P 0 
L 1.77733996 -2.03823996 1.83321998 -2.03823996 0 P 0 
L 1.77706998 -2.03723996 1.83236998 -2.03723996 0 P 0 
L 1.7768 -2.03623996 1.83171004 -2.03623996 0 P 0 
L 1.7766 -2.03523996 1.83121004 -2.03523996 0 P 0 
L 1.77641004 -2.03423996 1.83085 -2.03423996 0 P 0 
L 1.77621004 -2.03323996 1.83071004 -2.03323996 0 P 0 
L 1.77608002 -2.03223996 1.83076998 -2.03223996 0 P 0 
L 1.77596004 -2.03123996 1.83106004 -2.03123996 0 P 0 
L 1.77583996 -2.03023996 1.83158996 -2.03023996 0 P 0 
L 1.77576004 -2.02923996 1.83238002 -2.02923996 0 P 0 
L 1.7757 -2.02823996 1.83356998 -2.02823996 0 P 0 
L 1.7757 -2.02723996 1.83591998 -2.02723996 0 P 0 
L 1.77571998 -2.02623996 1.87495 -2.02623996 0 P 0 
L 1.7758 -2.02523996 1.87485 -2.02523996 0 P 0 
L 1.77588996 -2.02423996 1.87475 -2.02423996 0 P 0 
L 1.77605 -2.02323996 1.87465 -2.02323996 0 P 0 
L 1.77621004 -2.02223996 1.87455 -2.02223996 0 P 0 
L 1.7764 -2.02123996 1.87445 -2.02123996 0 P 0 
L 1.77665 -2.02023996 1.87433996 -2.02023996 0 P 0 
L 1.7769 -2.01923996 1.87425 -2.01923996 0 P 0 
L 1.7772 -2.01823996 1.87413996 -2.01823996 0 P 0 
L 1.77753002 -2.01723996 1.87405 -2.01723996 0 P 0 
L 1.77786004 -2.01623996 1.87393996 -2.01623996 0 P 0 
L 1.77823002 -2.01523996 1.87383996 -2.01523996 0 P 0 
L 1.77863996 -2.01423996 1.87373996 -2.01423996 0 P 0 
L 1.77903996 -2.01323996 1.87363996 -2.01323996 0 P 0 
L 1.7795 -2.01223996 1.87353996 -2.01223996 0 P 0 
L 1.77998996 -2.01123996 1.87343996 -2.01123996 0 P 0 
L 1.78046998 -2.01023996 1.87333002 -2.01023996 0 P 0 
L 1.78103996 -2.00923996 1.87323002 -2.00923996 0 P 0 
L 1.78161004 -2.00823996 1.87311998 -2.00823996 0 P 0 
L 1.78221004 -2.00723996 1.87301998 -2.00723996 0 P 0 
L 1.78288002 -2.00623996 1.87291998 -2.00623996 0 P 0 
L 1.64213996 -2.14795 1.70566004 -2.14795 0 P 0 
L 1.64518996 -2.14695 1.7062 -2.14695 0 P 0 
L 1.64728996 -2.14595 1.70673996 -2.14595 0 P 0 
L 1.64906998 -2.14495 1.70728002 -2.14495 0 P 0 
L 1.65058002 -2.14395 1.70783002 -2.14395 0 P 0 
L 1.6519 -2.14295 1.70836998 -2.14295 0 P 0 
L 1.65311998 -2.14195 1.70881998 -2.14195 0 P 0 
L 1.65416998 -2.14095 1.70926998 -2.14095 0 P 0 
L 1.65508996 -2.13995 1.70973002 -2.13995 0 P 0 
L 1.65588002 -2.13895 1.71018002 -2.13895 0 P 0 
L 1.65658002 -2.13795 1.71063002 -2.13795 0 P 0 
L 1.65726998 -2.13695 1.71108996 -2.13695 0 P 0 
L 1.65791998 -2.13595 1.71153996 -2.13595 0 P 0 
L 1.65853002 -2.13495 1.71198996 -2.13495 0 P 0 
L 1.65913002 -2.13395 1.71245 -2.13395 0 P 0 
L 1.65968002 -2.13295 1.7129 -2.13295 0 P 0 
L 1.66021998 -2.13195 1.71331004 -2.13195 0 P 0 
L 1.66071998 -2.13095 1.71371998 -2.13095 0 P 0 
L 1.66121004 -2.12995 1.71411998 -2.12995 0 P 0 
L 1.66166998 -2.12895 1.71453002 -2.12895 0 P 0 
L 1.66201004 -2.12795 1.71493996 -2.12795 0 P 0 
L 1.66223996 -2.12695 1.71533996 -2.12695 0 P 0 
L 1.66235 -2.12595 1.71575 -2.12595 0 P 0 
L 1.66236004 -2.12495 1.71615 -2.12495 0 P 0 
L 1.66228002 -2.12395 1.71656004 -2.12395 0 P 0 
L 1.66211998 -2.12295 1.71696004 -2.12295 0 P 0 
L 1.66188002 -2.12195 1.71736004 -2.12195 0 P 0 
L 1.66156004 -2.12095 1.71776998 -2.12095 0 P 0 
L 1.66121004 -2.11995 1.71818002 -2.11995 0 P 0 
L 1.66086998 -2.11895 1.71858002 -2.11895 0 P 0 
L 1.66053002 -2.11795 1.71898996 -2.11795 0 P 0 
L 1.66018002 -2.11695 1.71938996 -2.11695 0 P 0 
L 1.65983996 -2.11595 1.7198 -2.11595 0 P 0 
L 1.65948996 -2.11495 1.7202 -2.11495 0 P 0 
L 1.65913996 -2.11395 1.72061004 -2.11395 0 P 0 
L 1.6588 -2.11295 1.72101004 -2.11295 0 P 0 
L 1.65846004 -2.11195 1.72141998 -2.11195 0 P 0 
L 1.65811004 -2.11095 1.72181998 -2.11095 0 P 0 
L 1.65776998 -2.10995 1.72223002 -2.10995 0 P 0 
L 1.65741998 -2.10895 1.72263002 -2.10895 0 P 0 
L 1.65708002 -2.10795 1.72303996 -2.10795 0 P 0 
L 1.65673002 -2.10695 1.72343996 -2.10695 0 P 0 
L 1.65638996 -2.10595 1.72385 -2.10595 0 P 0 
L 1.65605 -2.10495 1.72425 -2.10495 0 P 0 
L 1.6557 -2.10395 1.72466004 -2.10395 0 P 0 
L 1.65536004 -2.10295 1.72506998 -2.10295 0 P 0 
L 1.65501004 -2.10195 1.72546998 -2.10195 0 P 0 
L 1.65466998 -2.10095 1.72588002 -2.10095 0 P 0 
L 1.65431998 -2.09995 1.72628002 -2.09995 0 P 0 
L 1.65398002 -2.09895 1.72668996 -2.09895 0 P 0 
L 1.65363002 -2.09795 1.72708996 -2.09795 0 P 0 
L 1.65328996 -2.09695 1.72748996 -2.09695 0 P 0 
L 1.65293996 -2.09595 1.7279 -2.09595 0 P 0 
L 1.6526 -2.09495 1.72831004 -2.09495 0 P 0 
L 1.65225 -2.09395 1.72871004 -2.09395 0 P 0 
L 1.65191004 -2.09295 1.72911998 -2.09295 0 P 0 
L 1.65156998 -2.09195 1.72951998 -2.09195 0 P 0 
L 1.65121998 -2.09095 1.72993002 -2.09095 0 P 0 
L 1.65088002 -2.08995 1.73033002 -2.08995 0 P 0 
L 1.65053002 -2.08895 1.73073996 -2.08895 0 P 0 
L 1.65018996 -2.08795 1.73113996 -2.08795 0 P 0 
L 1.64983996 -2.08695 1.73155 -2.08695 0 P 0 
L 1.6495 -2.08595 1.73195 -2.08595 0 P 0 
L 1.64915 -2.08495 1.73236004 -2.08495 0 P 0 
L 1.64881004 -2.08395 1.73276004 -2.08395 0 P 0 
L 1.81726998 -1.98915 1.81196004 -1.9899 0 P 0 
L 1.81196004 -1.9899 1.80668996 -1.99096998 0 P 0 
L 1.80668996 -1.99096998 1.8019 -1.99226004 0 P 0 
L 1.8019 -1.99226004 1.79718996 -1.99391004 0 P 0 
L 1.79718996 -1.99391004 1.79316004 -1.99568002 0 P 0 
L 1.79316004 -1.99568002 1.78926998 -1.99778002 0 P 0 
L 1.78926998 -1.99778002 1.78771004 -1.99878002 0 P 0 
L 1.78771004 -1.99878002 1.78623002 -1.99988002 0 P 0 
L 1.78623002 -1.99988002 1.78481004 -2.00108002 0 P 0 
L 1.78481004 -2.00108002 1.78346998 -2.00238996 0 P 0 
L 1.78346998 -2.00238996 1.78228996 -2.00371998 0 P 0 
L 1.78228996 -2.00371998 1.78121004 -2.00513002 0 P 0 
L 1.78121004 -2.00513002 1.78023002 -2.00661004 0 P 0 
L 1.78023002 -2.00661004 1.77868002 -2.00933996 0 P 0 
L 1.77868002 -2.00933996 1.77731998 -2.01216998 0 P 0 
L 1.77731998 -2.01216998 1.77611004 -2.01516004 0 P 0 
L 1.77611004 -2.01516004 1.77508996 -2.01823002 0 P 0 
L 1.77508996 -2.01823002 1.77436998 -2.02111004 0 P 0 
L 1.77436998 -2.02111004 1.77388996 -2.02406004 0 P 0 
L 1.77388996 -2.02406004 1.77371998 -2.02603996 0 P 0 
L 1.77371998 -2.02603996 1.77368996 -2.02801998 0 P 0 
L 1.77368996 -2.02801998 1.7738 -2.03001998 0 P 0 
L 1.7738 -2.03001998 1.7742 -2.03338996 0 P 0 
L 1.7742 -2.03338996 1.77485 -2.03671004 0 P 0 
L 1.77485 -2.03671004 1.77573002 -2.03993996 0 P 0 
L 1.77573002 -2.03993996 1.77683996 -2.04308002 0 P 0 
L 1.77683996 -2.04308002 1.7776 -2.04481998 0 P 0 
L 1.7776 -2.04481998 1.7785 -2.04648996 0 P 0 
L 1.7785 -2.04648996 1.77953002 -2.04808996 0 P 0 
L 1.77953002 -2.04808996 1.78061004 -2.04953996 0 P 0 
L 1.78061004 -2.04953996 1.78181004 -2.05091004 0 P 0 
L 1.78181004 -2.05091004 1.78311004 -2.05218996 0 P 0 
L 1.78311004 -2.05218996 1.78988996 -2.05801998 0 P 0 
L 1.78988996 -2.05801998 1.79883996 -2.06491004 0 P 0 
L 1.79883996 -2.06491004 1.80976998 -2.07261004 0 P 0 
L 1.80976998 -2.07261004 1.81753002 -2.07823002 0 P 0 
L 1.81753002 -2.07823002 1.81896998 -2.07943002 0 P 0 
L 1.81896998 -2.07943002 1.82033002 -2.08073002 0 P 0 
L 1.82033002 -2.08073002 1.82156998 -2.08213996 0 P 0 
L 1.82156998 -2.08213996 1.82186004 -2.08251004 0 P 0 
L 1.82186004 -2.08251004 1.82211004 -2.0829 0 P 0 
L 1.82211004 -2.0829 1.82233002 -2.08331004 0 P 0 
L 1.82233002 -2.08331004 1.82253002 -2.08373996 0 P 0 
L 1.82253002 -2.08373996 1.82268002 -2.08418002 0 P 0 
L 1.82268002 -2.08418002 1.82281004 -2.08463002 0 P 0 
L 1.82281004 -2.08463002 1.8229 -2.0851 0 P 0 
L 1.8229 -2.0851 1.82293002 -2.08533996 0 P 0 
L 1.82293002 -2.08533996 1.82293996 -2.08558996 0 P 0 
L 1.82293996 -2.08558996 1.82291998 -2.08583996 0 P 0 
L 1.82291998 -2.08583996 1.82288002 -2.08608002 0 P 0 
L 1.82288002 -2.08608002 1.82283002 -2.08631998 0 P 0 
L 1.82283002 -2.08631998 1.82275 -2.08656004 0 P 0 
L 1.82275 -2.08656004 1.82265 -2.08678996 0 P 0 
L 1.82265 -2.08678996 1.82253996 -2.087 0 P 0 
L 1.82253996 -2.087 1.8224 -2.08721004 0 P 0 
L 1.8224 -2.08721004 1.82225 -2.08741004 0 P 0 
L 1.82225 -2.08741004 1.82208996 -2.08758996 0 P 0 
L 1.82208996 -2.08758996 1.8216 -2.08803996 0 P 0 
L 1.8216 -2.08803996 1.82106998 -2.08845 0 P 0 
L 1.82106998 -2.08845 1.82051004 -2.08881004 0 P 0 
L 1.82051004 -2.08881004 1.81991998 -2.08911998 0 P 0 
L 1.81991998 -2.08911998 1.81931004 -2.08936998 0 P 0 
L 1.81931004 -2.08936998 1.81868002 -2.08958002 0 P 0 
L 1.81868002 -2.08958002 1.81803002 -2.08973002 0 P 0 
L 1.81803002 -2.08973002 1.81736004 -2.08981998 0 P 0 
L 1.81736004 -2.08981998 1.81293002 -2.09001998 0 P 0 
L 1.81293002 -2.09001998 1.80846998 -2.08986004 0 P 0 
L 1.80846998 -2.08986004 1.80256998 -2.08923002 0 P 0 
L 1.80256998 -2.08923002 1.79668002 -2.08818996 0 P 0 
L 1.79668002 -2.08818996 1.78223002 -2.08458002 0 P 0 
L 1.78223002 -2.08458002 1.77788996 -2.08338002 0 P 0 
L 1.77788996 -2.08338002 1.77415 -2.08246004 0 P 0 
L 1.77415 -2.08246004 1.77095 -2.08175 0 P 0 
L 1.77095 -2.08175 1.7709 -2.08173996 0 P 0 
L 1.7709 -2.08173996 1.77076998 -2.08173996 0 P 0 
L 1.77076998 -2.08173996 1.77068996 -2.08176004 0 P 0 
L 1.77068996 -2.08176004 1.77053002 -2.08183996 0 P 0 
L 1.77053002 -2.08183996 1.77043002 -2.08193996 0 P 0 
L 1.77043002 -2.08193996 1.77036998 -2.08201998 0 P 0 
L 1.77036998 -2.08201998 1.77031998 -2.08211998 0 P 0 
L 1.77031998 -2.08211998 1.7703 -2.08216998 0 P 0 
L 1.7703 -2.08216998 1.77028996 -2.08223002 0 P 0 
L 1.77028996 -2.08223002 1.77028002 -2.08228002 0 P 0 
L 1.77028002 -2.08228002 1.77028002 -2.08238996 0 P 0 
L 1.77028002 -2.08238996 1.77056998 -2.08838996 0 P 0 
L 1.77056998 -2.08838996 1.77096004 -2.09526004 0 P 0 
L 1.77096004 -2.09526004 1.77153996 -2.1033 0 P 0 
L 1.77153996 -2.1033 1.77236004 -2.11291004 0 P 0 
L 1.77236004 -2.11291004 1.77311004 -2.1194 0 P 0 
L 1.77311004 -2.1194 1.77383002 -2.12398002 0 P 0 
L 1.77383002 -2.12398002 1.77386004 -2.12411004 0 P 0 
L 1.77386004 -2.12411004 1.7739 -2.12423002 0 P 0 
L 1.7739 -2.12423002 1.77395 -2.12436004 0 P 0 
L 1.77395 -2.12436004 1.77401004 -2.12448002 0 P 0 
L 1.77401004 -2.12448002 1.77408002 -2.12458996 0 P 0 
L 1.77408002 -2.12458996 1.77416004 -2.1247 0 P 0 
L 1.77416004 -2.1247 1.77425 -2.1248 0 P 0 
L 1.77425 -2.1248 1.77435 -2.12488996 0 P 0 
L 1.77435 -2.12488996 1.77445 -2.12496998 0 P 0 
L 1.77445 -2.12496998 1.77456998 -2.12505 0 P 0 
L 1.77456998 -2.12505 1.77571004 -2.12568996 0 P 0 
L 1.77571004 -2.12568996 1.7769 -2.12623996 0 P 0 
L 1.7769 -2.12623996 1.77813002 -2.12668996 0 P 0 
L 1.77813002 -2.12668996 1.7794 -2.12703996 0 P 0 
L 1.7794 -2.12703996 1.78068996 -2.12728996 0 P 0 
L 1.78068996 -2.12728996 1.79791998 -2.12951004 0 P 0 
L 1.79791998 -2.12951004 1.81536004 -2.13106004 0 P 0 
L 1.81536004 -2.13106004 1.82125 -2.13123996 0 P 0 
L 1.82125 -2.13123996 1.82716004 -2.13098996 0 P 0 
L 1.82716004 -2.13098996 1.83583996 -2.12998002 0 P 0 
L 1.83583996 -2.12998002 1.84445 -2.12836004 0 P 0 
L 1.84445 -2.12836004 1.84911998 -2.12711004 0 P 0 
L 1.84911998 -2.12711004 1.85366004 -2.12548002 0 P 0 
L 1.85366004 -2.12548002 1.85806998 -2.12348002 0 P 0 
L 1.85806998 -2.12348002 1.86078996 -2.12196998 0 P 0 
L 1.86078996 -2.12196998 1.8634 -2.12026998 0 P 0 
L 1.8634 -2.12026998 1.86586998 -2.11836998 0 P 0 
L 1.86586998 -2.11836998 1.86821004 -2.11628002 0 P 0 
L 1.86821004 -2.11628002 1.87026004 -2.11413002 0 P 0 
L 1.87026004 -2.11413002 1.8721 -2.11181998 0 P 0 
L 1.8721 -2.11181998 1.87375 -2.10936004 0 P 0 
L 1.87375 -2.10936004 1.87516998 -2.10673996 0 P 0 
L 1.87516998 -2.10673996 1.87605 -2.10483996 0 P 0 
L 1.87605 -2.10483996 1.87683996 -2.10291004 0 P 0 
L 1.87683996 -2.10291004 1.8772 -2.10188002 0 P 0 
L 1.8772 -2.10188002 1.87748996 -2.10083002 0 P 0 
L 1.87748996 -2.10083002 1.87771004 -2.09976998 0 P 0 
L 1.87771004 -2.09976998 1.87798002 -2.09788996 0 P 0 
L 1.87798002 -2.09788996 1.87811998 -2.09601004 0 P 0 
L 1.87811998 -2.09601004 1.87821004 -2.08966998 0 P 0 
L 1.87821004 -2.08966998 1.8781 -2.08353996 0 P 0 
L 1.8781 -2.08353996 1.87798002 -2.08166004 0 P 0 
L 1.87798002 -2.08166004 1.87773002 -2.07976998 0 P 0 
L 1.87773002 -2.07976998 1.87753002 -2.07873996 0 P 0 
L 1.87753002 -2.07873996 1.87726998 -2.07773996 0 P 0 
L 1.87726998 -2.07773996 1.87695 -2.07673996 0 P 0 
L 1.87695 -2.07673996 1.87628996 -2.07505 0 P 0 
L 1.87628996 -2.07505 1.87553002 -2.07338002 0 P 0 
L 1.87553002 -2.07338002 1.87441004 -2.07133996 0 P 0 
L 1.87441004 -2.07133996 1.87313996 -2.06938002 0 P 0 
L 1.87313996 -2.06938002 1.87171004 -2.06751004 0 P 0 
L 1.87171004 -2.06751004 1.8688 -2.06416004 0 P 0 
L 1.8688 -2.06416004 1.86566998 -2.06095 0 P 0 
L 1.86566998 -2.06095 1.86181998 -2.05741998 0 P 0 
L 1.86181998 -2.05741998 1.85778002 -2.05406998 0 P 0 
L 1.85778002 -2.05406998 1.84833996 -2.04715 0 P 0 
L 1.84833996 -2.04715 1.83913996 -2.0407 0 P 0 
L 1.83913996 -2.0407 1.83686004 -2.0389 0 P 0 
L 1.83686004 -2.0389 1.83471998 -2.03691998 0 P 0 
L 1.83471998 -2.03691998 1.83428002 -2.03643002 0 P 0 
L 1.83428002 -2.03643002 1.83386998 -2.0359 0 P 0 
L 1.83386998 -2.0359 1.83351004 -2.03535 0 P 0 
L 1.83351004 -2.03535 1.83318996 -2.03476004 0 P 0 
L 1.83318996 -2.03476004 1.83291998 -2.03415 0 P 0 
L 1.83291998 -2.03415 1.83283996 -2.03393996 0 P 0 
L 1.83283996 -2.03393996 1.83278002 -2.03371004 0 P 0 
L 1.83278002 -2.03371004 1.83273002 -2.03348996 0 P 0 
L 1.83273002 -2.03348996 1.83271004 -2.03326004 0 P 0 
L 1.83271004 -2.03326004 1.8327 -2.03303002 0 P 0 
L 1.8327 -2.03303002 1.83271004 -2.0328 0 P 0 
L 1.83271004 -2.0328 1.83275 -2.03258002 0 P 0 
L 1.83275 -2.03258002 1.83278996 -2.03235 0 P 0 
L 1.83278996 -2.03235 1.83286004 -2.03213002 0 P 0 
L 1.83286004 -2.03213002 1.83293996 -2.03191998 0 P 0 
L 1.83293996 -2.03191998 1.83305 -2.03171004 0 P 0 
L 1.83305 -2.03171004 1.83325 -2.03135 0 P 0 
L 1.83325 -2.03135 1.83348996 -2.03101998 0 P 0 
L 1.83348996 -2.03101998 1.83375 -2.03071004 0 P 0 
L 1.83375 -2.03071004 1.83403002 -2.03041004 0 P 0 
L 1.83403002 -2.03041004 1.83433996 -2.03015 0 P 0 
L 1.83433996 -2.03015 1.83466998 -2.02991004 0 P 0 
L 1.83466998 -2.02991004 1.83501998 -2.02968996 0 P 0 
L 1.83501998 -2.02968996 1.83538002 -2.02951004 0 P 0 
L 1.83538002 -2.02951004 1.83576004 -2.02936004 0 P 0 
L 1.83576004 -2.02936004 1.83615 -2.02923996 0 P 0 
L 1.83615 -2.02923996 1.83655 -2.02915 0 P 0 
L 1.83655 -2.02915 1.8392 -2.02873996 0 P 0 
L 1.8392 -2.02873996 1.84188002 -2.0285 0 P 0 
L 1.84188002 -2.0285 1.84458002 -2.02841004 0 P 0 
L 1.84458002 -2.02841004 1.84993996 -2.02858002 0 P 0 
L 1.84993996 -2.02858002 1.85526998 -2.02916004 0 P 0 
L 1.85526998 -2.02916004 1.86155 -2.03023002 0 P 0 
L 1.86155 -2.03023002 1.86778002 -2.03158002 0 P 0 
L 1.86778002 -2.03158002 1.8713 -2.03238996 0 P 0 
L 1.8713 -2.03238996 1.87428996 -2.03303002 0 P 0 
L 1.87428996 -2.03303002 1.8769 -2.03356004 0 P 0 
L 1.8769 -2.03356004 1.87691998 -2.03356998 0 P 0 
L 1.87691998 -2.03356998 1.87696004 -2.03356998 0 P 0 
L 1.87696004 -2.03356998 1.87696998 -2.03356004 0 P 0 
L 1.87696998 -2.03356004 1.87701004 -2.03356004 0 P 0 
L 1.87701004 -2.03356004 1.87703996 -2.03353996 0 P 0 
L 1.87703996 -2.03353996 1.87706004 -2.03353002 0 P 0 
L 1.87706004 -2.03353002 1.87706998 -2.03351998 0 P 0 
L 1.87706998 -2.03351998 1.87708996 -2.03351004 0 P 0 
L 1.87708996 -2.03351004 1.8771 -2.03348996 0 P 0 
L 1.8771 -2.03348996 1.87711004 -2.03348002 0 P 0 
L 1.87711004 -2.03348002 1.87721998 -2.0333 0 P 0 
L 1.87721998 -2.0333 1.87731998 -2.0331 0 P 0 
L 1.87731998 -2.0331 1.8774 -2.0329 0 P 0 
L 1.8774 -2.0329 1.87746004 -2.03268996 0 P 0 
L 1.87746004 -2.03268996 1.87751004 -2.03248002 0 P 0 
L 1.87751004 -2.03248002 1.87753002 -2.03226998 0 P 0 
L 1.87753002 -2.03226998 1.87753996 -2.03205 0 P 0 
L 1.87753996 -2.03205 1.87753002 -2.03183002 0 P 0 
L 1.87753002 -2.03183002 1.87565 -2.01323996 0 P 0 
L 1.87565 -2.01323996 1.87371004 -1.99451998 0 P 0 
L 1.87371004 -1.99451998 1.8737 -1.99438996 0 P 0 
L 1.8737 -1.99438996 1.87366998 -1.99426998 0 P 0 
L 1.87366998 -1.99426998 1.87363002 -1.99415 0 P 0 
L 1.87363002 -1.99415 1.87358002 -1.99403002 0 P 0 
L 1.87358002 -1.99403002 1.87351998 -1.99391004 0 P 0 
L 1.87351998 -1.99391004 1.87346004 -1.9938 0 P 0 
L 1.87346004 -1.9938 1.87338002 -1.9937 0 P 0 
L 1.87338002 -1.9937 1.87328996 -1.9936 0 P 0 
L 1.87328996 -1.9936 1.8732 -1.99351004 0 P 0 
L 1.8732 -1.99351004 1.8731 -1.99343002 0 P 0 
L 1.8731 -1.99343002 1.87298996 -1.99335 0 P 0 
L 1.87298996 -1.99335 1.87248002 -1.99305 0 P 0 
L 1.87248002 -1.99305 1.87193996 -1.99278002 0 P 0 
L 1.87193996 -1.99278002 1.87136998 -1.99256998 0 P 0 
L 1.87136998 -1.99256998 1.87078996 -1.99241004 0 P 0 
L 1.87078996 -1.99241004 1.8702 -1.9923 0 P 0 
L 1.8702 -1.9923 1.85876004 -1.99076004 0 P 0 
L 1.85876004 -1.99076004 1.84691998 -1.98943002 0 P 0 
L 1.84691998 -1.98943002 1.83693002 -1.98876004 0 P 0 
L 1.83693002 -1.98876004 1.8318 -1.98863002 0 P 0 
L 1.8318 -1.98863002 1.82623002 -1.98866998 0 P 0 
L 1.82623002 -1.98866998 1.82106004 -1.98883996 0 P 0 
L 1.82106004 -1.98883996 1.81726998 -1.98915 0 P 0 
L 1.78061004 -2.12523996 1.84838002 -2.12523996 0 P 0 
L 1.77733002 -2.12423996 1.85121004 -2.12423996 0 P 0 
L 1.77573996 -2.12323996 1.85376998 -2.12323996 0 P 0 
L 1.77558002 -2.12223996 1.85596998 -2.12223996 0 P 0 
L 1.77541998 -2.12123996 1.85798996 -2.12123996 0 P 0 
L 1.77526998 -2.12023996 1.85978996 -2.12023996 0 P 0 
L 1.77511004 -2.11923996 1.86131998 -2.11923996 0 P 0 
L 1.77498996 -2.11823996 1.86276004 -2.11823996 0 P 0 
L 1.77486998 -2.11723996 1.86406998 -2.11723996 0 P 0 
L 1.77475 -2.11623996 1.86526004 -2.11623996 0 P 0 
L 1.77463996 -2.11523996 1.86638002 -2.11523996 0 P 0 
L 1.77451998 -2.11423996 1.8674 -2.11423996 0 P 0 
L 1.77441004 -2.11323996 1.86835 -2.11323996 0 P 0 
L 1.77431004 -2.11223996 1.86921004 -2.11223996 0 P 0 
L 1.77421998 -2.11123996 1.87001004 -2.11123996 0 P 0 
L 1.77413996 -2.11023996 1.87075 -2.11023996 0 P 0 
L 1.77405 -2.10923996 1.87141998 -2.10923996 0 P 0 
L 1.77396998 -2.10823996 1.87208002 -2.10823996 0 P 0 
L 1.77388002 -2.10723996 1.87261998 -2.10723996 0 P 0 
L 1.7738 -2.10623996 1.87316998 -2.10623996 0 P 0 
L 1.77371004 -2.10523996 1.87366004 -2.10523996 0 P 0 
L 1.77363002 -2.10423996 1.87411998 -2.10423996 0 P 0 
L 1.77353996 -2.10323996 1.87453996 -2.10323996 0 P 0 
L 1.77346998 -2.10223996 1.87495 -2.10223996 0 P 0 
L 1.7734 -2.10123996 1.8753 -2.10123996 0 P 0 
L 1.77333002 -2.10023996 1.87556998 -2.10023996 0 P 0 
L 1.77325 -2.09923996 1.87576998 -2.09923996 0 P 0 
L 1.77318002 -2.09823996 1.87591998 -2.09823996 0 P 0 
L 1.77311004 -2.09723996 1.87603002 -2.09723996 0 P 0 
L 1.77303996 -2.09623996 1.8761 -2.09623996 0 P 0 
L 1.77296998 -2.09523996 1.87613002 -2.09523996 0 P 0 
L 1.77291004 -2.09423996 1.87613996 -2.09423996 0 P 0 
L 1.77285 -2.09323996 1.87616004 -2.09323996 0 P 0 
L 1.77278996 -2.09223996 1.87616998 -2.09223996 0 P 0 
L 1.77273002 -2.09123996 1.80256998 -2.09123996 0 P 0 
L 1.77268002 -2.09023996 1.7968 -2.09023996 0 P 0 
L 1.77261998 -2.08923996 1.79263002 -2.08923996 0 P 0 
L 1.77256004 -2.08823996 1.78861998 -2.08823996 0 P 0 
L 1.77251004 -2.08723996 1.7846 -2.08723996 0 P 0 
L 1.77246004 -2.08623996 1.7807 -2.08623996 0 P 0 
L 1.77241998 -2.08523996 1.77705 -2.08523996 0 P 0 
L 1.77236998 -2.08423996 1.77293996 -2.08423996 0 P 0 
L 1.62463996 -2.18195 1.65948996 -2.18195 0 P 0 
L 1.61963996 -2.18095 1.66483002 -2.18095 0 P 0 
L 1.61818002 -1.99795 1.6724 -1.99795 0 P 0 
L 1.61778996 -1.99695 1.67218002 -1.99695 0 P 0 
L 1.6174 -1.99595 1.67196004 -1.99595 0 P 0 
L 1.61701004 -1.99495 1.67173996 -1.99495 0 P 0 
L 1.61391998 -2.15695 1.70026004 -2.15695 0 P 0 
L 1.61386004 -2.15595 1.70088002 -2.15595 0 P 0 
L 1.61381004 -2.15495 1.70151004 -2.15495 0 P 0 
L 1.61375 -2.15395 1.70213996 -2.15395 0 P 0 
L 1.6137 -2.15295 1.70276004 -2.15295 0 P 0 
L 1.61365 -2.15195 1.70338996 -2.15195 0 P 0 
L 1.6136 -2.15095 1.70401004 -2.15095 0 P 0 
L 1.61355 -2.14995 1.70456998 -2.14995 0 P 0 
L 1.61348996 -2.14895 1.70511998 -2.14895 0 P 0 
L 1.61343996 -2.14795 1.61738002 -2.14795 0 P 0 
L 1.55341004 -2.08286998 1.60538002 -2.08286998 0 P 0 
L 1.55286004 -2.08186998 1.60526998 -2.08186998 0 P 0 
L 1.5521 -2.08086998 1.6051 -2.08086998 0 P 0 
L 1.55126998 -2.07986998 1.6049 -2.07986998 0 P 0 
L 1.55033996 -2.07886998 1.60463996 -2.07886998 0 P 0 
L 1.54928996 -2.07786998 1.60433002 -2.07786998 0 P 0 
L 1.54806998 -2.07686998 1.60398996 -2.07686998 0 P 0 
L 1.5467 -2.07586998 1.60356998 -2.07586998 0 P 0 
L 1.54531004 -2.07486998 1.6031 -2.07486998 0 P 0 
L 1.54391004 -2.07386998 1.60258996 -2.07386998 0 P 0 
L 1.54251004 -2.07286998 1.60201004 -2.07286998 0 P 0 
L 1.54111998 -2.07186998 1.60138002 -2.07186998 0 P 0 
L 1.53971998 -2.07086998 1.60068002 -2.07086998 0 P 0 
L 1.53833002 -2.06986998 1.59993002 -2.06986998 0 P 0 
L 1.53693002 -2.06886998 1.59908002 -2.06886998 0 P 0 
L 1.53556004 -2.06786998 1.59821004 -2.06786998 0 P 0 
L 1.53418996 -2.06686998 1.59733996 -2.06686998 0 P 0 
L 1.53281998 -2.06586998 1.59646998 -2.06586998 0 P 0 
L 1.53145 -2.06486998 1.5955 -2.06486998 0 P 0 
L 1.53008002 -2.06386998 1.59453002 -2.06386998 0 P 0 
L 1.52871004 -2.06286998 1.59356004 -2.06286998 0 P 0 
L 1.52733996 -2.06186998 1.59253002 -2.06186998 0 P 0 
L 1.52596998 -2.06086998 1.59145 -2.06086998 0 P 0 
L 1.5246 -2.05986998 1.59038002 -2.05986998 0 P 0 
L 1.52323002 -2.05886998 1.5893 -2.05886998 0 P 0 
L 1.52186004 -2.05786998 1.58813996 -2.05786998 0 P 0 
L 1.52053996 -2.05686998 1.58696004 -2.05686998 0 P 0 
L 1.51935 -2.05586998 1.58576998 -2.05586998 0 P 0 
L 1.51816004 -2.05486998 1.58456998 -2.05486998 0 P 0 
L 1.51706998 -2.05386998 1.58321004 -2.05386998 0 P 0 
L 1.51603996 -2.05286998 1.58185 -2.05286998 0 P 0 
L 1.51501998 -2.05186998 1.58048996 -2.05186998 0 P 0 
L 1.51408996 -2.05086998 1.57913002 -2.05086998 0 P 0 
L 1.5132 -2.04986998 1.57776998 -2.04986998 0 P 0 
L 1.51231998 -2.04886998 1.57641998 -2.04886998 0 P 0 
L 1.51151004 -2.04786998 1.57505 -2.04786998 0 P 0 
L 1.51075 -2.04686998 1.57365 -2.04686998 0 P 0 
L 1.51008002 -2.04586998 1.57223002 -2.04586998 0 P 0 
L 1.50945 -2.04486998 1.57081004 -2.04486998 0 P 0 
L 1.50888002 -2.04386998 1.56938996 -2.04386998 0 P 0 
L 1.50836004 -2.04286998 1.56796998 -2.04286998 0 P 0 
L 1.5079 -2.04186998 1.56655 -2.04186998 0 P 0 
L 1.50748002 -2.04086998 1.56518996 -2.04086998 0 P 0 
L 1.50708996 -2.03986998 1.564 -2.03986998 0 P 0 
L 1.50676004 -2.03886998 1.56296998 -2.03886998 0 P 0 
L 1.50641998 -2.03786998 1.56206004 -2.03786998 0 P 0 
L 1.50616998 -2.03686998 1.56125 -2.03686998 0 P 0 
L 1.50591004 -2.03586998 1.56066998 -2.03586998 0 P 0 
L 1.5057 -2.03486998 1.56031998 -2.03486998 0 P 0 
L 1.50551998 -2.03386998 1.56016004 -2.03386998 0 P 0 
L 1.50533996 -2.03286998 1.56016998 -2.03286998 0 P 0 
L 1.50523996 -2.03186998 1.56036004 -2.03186998 0 P 0 
L 1.50513002 -2.03086998 1.56071998 -2.03086998 0 P 0 
L 1.50506998 -2.02986998 1.56131004 -2.02986998 0 P 0 
L 1.50503996 -2.02886998 1.5622 -2.02886998 0 P 0 
L 1.50501004 -2.02786998 1.56355 -2.02786998 0 P 0 
L 1.50501998 -2.02686998 1.5657 -2.02686998 0 P 0 
L 1.50506998 -2.02586998 1.60378996 -2.02586998 0 P 0 
L 1.50511998 -2.02486998 1.60371004 -2.02486998 0 P 0 
L 1.50521004 -2.02386998 1.60363996 -2.02386998 0 P 0 
L 1.50533996 -2.02286998 1.60356998 -2.02286998 0 P 0 
L 1.50546998 -2.02186998 1.6035 -2.02186998 0 P 0 
L 1.50563996 -2.02086998 1.60343002 -2.02086998 0 P 0 
L 1.50585 -2.01986998 1.60336004 -2.01986998 0 P 0 
L 1.50606004 -2.01886998 1.60328996 -2.01886998 0 P 0 
L 1.50633002 -2.01786998 1.60321998 -2.01786998 0 P 0 
L 1.50661998 -2.01686998 1.60315 -2.01686998 0 P 0 
L 1.50691004 -2.01586998 1.60308002 -2.01586998 0 P 0 
L 1.50726998 -2.01486998 1.603 -2.01486998 0 P 0 
L 1.50766004 -2.01386998 1.60293002 -2.01386998 0 P 0 
L 1.50808996 -2.01286998 1.60285 -2.01286998 0 P 0 
L 1.50856998 -2.01186998 1.60278002 -2.01186998 0 P 0 
L 1.50908996 -2.01086998 1.6027 -2.01086998 0 P 0 
L 1.50966004 -2.00986998 1.60261998 -2.00986998 0 P 0 
L 1.51028996 -2.00886998 1.60255 -2.00886998 0 P 0 
L 1.51096998 -2.00786998 1.60246998 -2.00786998 0 P 0 
L 1.51171998 -2.00686998 1.6024 -2.00686998 0 P 0 
L 1.51253996 -2.00586998 1.60233002 -2.00586998 0 P 0 
L 1.51343996 -2.00486998 1.60225 -2.00486998 0 P 0 
L 1.5144 -2.00386998 1.60218002 -2.00386998 0 P 0 
L 1.51551998 -2.00286998 1.6021 -2.00286998 0 P 0 
L 1.51663996 -2.00186998 1.60203002 -2.00186998 0 P 0 
L 1.51795 -2.00086998 1.60195 -2.00086998 0 P 0 
L 1.51928996 -1.99986998 1.60183996 -1.99986998 0 P 0 
L 1.52086998 -1.99886998 1.60173002 -1.99886998 0 P 0 
L 1.52258996 -1.99786998 1.60156998 -1.99786998 0 P 0 
L 1.52451004 -1.99686998 1.60138996 -1.99686998 0 P 0 
L 1.52686998 -1.99586998 1.60106998 -1.99586998 0 P 0 
L 1.52976004 -1.99486998 1.59943996 -1.99486998 0 P 0 
L 1.53283002 -1.99386998 1.59543002 -1.99386998 0 P 0 
L 1.53678996 -1.99286998 1.59003996 -1.99286998 0 P 0 
L 1.54173996 -1.99186998 1.58073996 -1.99186998 0 P 0 
L 1.55036998 -1.99086998 1.56493002 -1.99086998 0 P 0 
L 1.6036 -2.03086998 1.60413996 -2.03086998 0 P 0 
L 1.59891004 -2.02986998 1.60406998 -2.02986998 0 P 0 
L 1.59435 -2.02886998 1.604 -2.02886998 0 P 0 
L 1.58838996 -2.02786998 1.60393002 -2.02786998 0 P 0 
L 1.57981004 -2.02686998 1.60386004 -2.02686998 0 P 0 
L 1.54575 -1.98923996 1.53931998 -1.99021998 0 P 0 
L 1.53931998 -1.99021998 1.53298996 -1.99171998 0 P 0 
L 1.53298996 -1.99171998 1.52678996 -1.99373996 0 P 0 
L 1.52678996 -1.99373996 1.52376998 -1.995 0 P 0 
L 1.52376998 -1.995 1.52086998 -1.99651004 0 P 0 
L 1.52086998 -1.99651004 1.5181 -1.99826004 0 P 0 
L 1.5181 -1.99826004 1.51548002 -2.00023002 0 P 0 
L 1.51548002 -2.00023002 1.51301004 -2.00243002 0 P 0 
L 1.51301004 -2.00243002 1.51128996 -2.00423002 0 P 0 
L 1.51128996 -2.00423002 1.50971998 -2.00616004 0 P 0 
L 1.50971998 -2.00616004 1.50831004 -2.00821004 0 P 0 
L 1.50831004 -2.00821004 1.50706998 -2.01036998 0 P 0 
L 1.50706998 -2.01036998 1.50598996 -2.01261998 0 P 0 
L 1.50598996 -2.01261998 1.50508996 -2.01496998 0 P 0 
L 1.50508996 -2.01496998 1.5042 -2.01801004 0 P 0 
L 1.5042 -2.01801004 1.50355 -2.02111004 0 P 0 
L 1.50355 -2.02111004 1.50313996 -2.02426004 0 P 0 
L 1.50313996 -2.02426004 1.50298996 -2.02743002 0 P 0 
L 1.50298996 -2.02743002 1.50308996 -2.03063002 0 P 0 
L 1.50308996 -2.03063002 1.50338002 -2.03326998 0 P 0 
L 1.50338002 -2.03326998 1.50385 -2.03588002 0 P 0 
L 1.50385 -2.03588002 1.50451004 -2.03845 0 P 0 
L 1.50451004 -2.03845 1.50535 -2.04096998 0 P 0 
L 1.50535 -2.04096998 1.50633002 -2.0433 0 P 0 
L 1.50633002 -2.0433 1.5075 -2.04553002 0 P 0 
L 1.5075 -2.04553002 1.50883996 -2.04766998 0 P 0 
L 1.50883996 -2.04766998 1.51036998 -2.04968996 0 P 0 
L 1.51036998 -2.04968996 1.51323002 -2.05291998 0 P 0 
L 1.51323002 -2.05291998 1.51631998 -2.05593996 0 P 0 
L 1.51631998 -2.05593996 1.51961998 -2.05871004 0 P 0 
L 1.51961998 -2.05871004 1.53591004 -2.0706 0 P 0 
L 1.53591004 -2.0706 1.54668002 -2.07831004 0 P 0 
L 1.54668002 -2.07831004 1.54793996 -2.07933996 0 P 0 
L 1.54793996 -2.07933996 1.54911998 -2.08046998 0 P 0 
L 1.54911998 -2.08046998 1.55021004 -2.08168002 0 P 0 
L 1.55021004 -2.08168002 1.5512 -2.08298996 0 P 0 
L 1.5512 -2.08298996 1.55136004 -2.08323002 0 P 0 
L 1.55136004 -2.08323002 1.5515 -2.08348002 0 P 0 
L 1.5515 -2.08348002 1.55161004 -2.08373996 0 P 0 
L 1.55161004 -2.08373996 1.5517 -2.08401998 0 P 0 
L 1.5517 -2.08401998 1.55176998 -2.0843 0 P 0 
L 1.55176998 -2.0843 1.55181004 -2.08458002 0 P 0 
L 1.55181004 -2.08458002 1.55183002 -2.08486998 0 P 0 
L 1.55183002 -2.08486998 1.55181998 -2.08516004 0 P 0 
L 1.55181998 -2.08516004 1.55178996 -2.08545 0 P 0 
L 1.55178996 -2.08545 1.55173996 -2.08573002 0 P 0 
L 1.55173996 -2.08573002 1.55166004 -2.086 0 P 0 
L 1.55166004 -2.086 1.55156004 -2.08628002 0 P 0 
L 1.55156004 -2.08628002 1.55136998 -2.08666998 0 P 0 
L 1.55136998 -2.08666998 1.55115 -2.08703996 0 P 0 
L 1.55115 -2.08703996 1.5509 -2.08738996 0 P 0 
L 1.5509 -2.08738996 1.55063002 -2.08771998 0 P 0 
L 1.55063002 -2.08771998 1.55033002 -2.08803002 0 P 0 
L 1.55033002 -2.08803002 1.55 -2.08831004 0 P 0 
L 1.55 -2.08831004 1.54966004 -2.08856004 0 P 0 
L 1.54966004 -2.08856004 1.54928996 -2.08878996 0 P 0 
L 1.54928996 -2.08878996 1.5489 -2.08898996 0 P 0 
L 1.5489 -2.08898996 1.54786004 -2.08941004 0 P 0 
L 1.54786004 -2.08941004 1.54678996 -2.08973996 0 P 0 
L 1.54678996 -2.08973996 1.54568002 -2.08998002 0 P 0 
L 1.54568002 -2.08998002 1.54456998 -2.09011998 0 P 0 
L 1.54456998 -2.09011998 1.54343996 -2.09016998 0 P 0 
L 1.54343996 -2.09016998 1.53906998 -2.09003002 0 P 0 
L 1.53906998 -2.09003002 1.53468002 -2.08961998 0 P 0 
L 1.53468002 -2.08961998 1.52908996 -2.08878996 0 P 0 
L 1.52908996 -2.08878996 1.52351004 -2.08766004 0 P 0 
L 1.52351004 -2.08766004 1.51005 -2.08418996 0 P 0 
L 1.51005 -2.08418996 1.50631004 -2.08318002 0 P 0 
L 1.50631004 -2.08318002 1.50308002 -2.08238996 0 P 0 
L 1.50308002 -2.08238996 1.50033996 -2.08183002 0 P 0 
L 1.50033996 -2.08183002 1.5003 -2.08181998 0 P 0 
L 1.5003 -2.08181998 1.50016004 -2.08181998 0 P 0 
L 1.50016004 -2.08181998 1.50011998 -2.08183002 0 P 0 
L 1.50011998 -2.08183002 1.50006998 -2.08183996 0 P 0 
L 1.50006998 -2.08183996 1.50003002 -2.08186004 0 P 0 
L 1.50003002 -2.08186004 1.49998996 -2.08186998 0 P 0 
L 1.49998996 -2.08186998 1.49995 -2.08188996 0 P 0 
L 1.49995 -2.08188996 1.49991004 -2.08191998 0 P 0 
L 1.49991004 -2.08191998 1.49988002 -2.08195 0 P 0 
L 1.49988002 -2.08195 1.49983996 -2.08198002 0 P 0 
L 1.49983996 -2.08198002 1.4997 -2.08213996 0 P 0 
L 1.4997 -2.08213996 1.49956004 -2.08231998 0 P 0 
L 1.49956004 -2.08231998 1.49943996 -2.0825 0 P 0 
L 1.49943996 -2.0825 1.49933996 -2.0827 0 P 0 
L 1.49933996 -2.0827 1.49925 -2.0829 0 P 0 
L 1.49925 -2.0829 1.49918996 -2.08311004 0 P 0 
L 1.49918996 -2.08311004 1.49913996 -2.08333002 0 P 0 
L 1.49913996 -2.08333002 1.49911004 -2.08355 0 P 0 
L 1.49911004 -2.08355 1.4991 -2.08376998 0 P 0 
L 1.4991 -2.08376998 1.49911004 -2.08398996 0 P 0 
L 1.49911004 -2.08398996 1.50071004 -2.10395 0 P 0 
L 1.50071004 -2.10395 1.5024 -2.12403996 0 P 0 
L 1.5024 -2.12403996 1.50241998 -2.12418002 0 P 0 
L 1.50241998 -2.12418002 1.50246004 -2.12431004 0 P 0 
L 1.50246004 -2.12431004 1.50248996 -2.12445 0 P 0 
L 1.50248996 -2.12445 1.50255 -2.12456998 0 P 0 
L 1.50255 -2.12456998 1.50261004 -2.1247 0 P 0 
L 1.50261004 -2.1247 1.50276998 -2.12491998 0 P 0 
L 1.50276998 -2.12491998 1.50286004 -2.12501998 0 P 0 
L 1.50286004 -2.12501998 1.50296998 -2.12511998 0 P 0 
L 1.50296998 -2.12511998 1.50308002 -2.12521004 0 P 0 
L 1.50308002 -2.12521004 1.50318996 -2.12528002 0 P 0 
L 1.50318996 -2.12528002 1.50331998 -2.12535 0 P 0 
L 1.50331998 -2.12535 1.50343996 -2.1254 0 P 0 
L 1.50343996 -2.1254 1.50391998 -2.12556004 0 P 0 
L 1.50391998 -2.12556004 1.5044 -2.12568996 0 P 0 
L 1.5044 -2.12568996 1.50848002 -2.12648996 0 P 0 
L 1.50848002 -2.12648996 1.51328996 -2.12738002 0 P 0 
L 1.51328996 -2.12738002 1.51873996 -2.12833996 0 P 0 
L 1.51873996 -2.12833996 1.52606004 -2.12945 0 P 0 
L 1.52606004 -2.12945 1.53343996 -2.13023002 0 P 0 
L 1.53343996 -2.13023002 1.54886998 -2.13086998 0 P 0 
L 1.54886998 -2.13086998 1.56305 -2.1303 0 P 0 
L 1.56305 -2.1303 1.56666004 -2.12988996 0 P 0 
L 1.56666004 -2.12988996 1.57023002 -2.12926998 0 P 0 
L 1.57023002 -2.12926998 1.5738 -2.12843002 0 P 0 
L 1.5738 -2.12843002 1.57945 -2.12668996 0 P 0 
L 1.57945 -2.12668996 1.58498002 -2.12456998 0 P 0 
L 1.58498002 -2.12456998 1.58793996 -2.12318002 0 P 0 
L 1.58793996 -2.12318002 1.59078996 -2.12156004 0 P 0 
L 1.59078996 -2.12156004 1.59348996 -2.11971998 0 P 0 
L 1.59348996 -2.11971998 1.59525 -2.11833002 0 P 0 
L 1.59525 -2.11833002 1.5969 -2.11681998 0 P 0 
L 1.5969 -2.11681998 1.59846004 -2.11521004 0 P 0 
L 1.59846004 -2.11521004 1.59991004 -2.11348002 0 P 0 
L 1.59991004 -2.11348002 1.60175 -2.11093996 0 P 0 
L 1.60175 -2.11093996 1.60338002 -2.10826998 0 P 0 
L 1.60338002 -2.10826998 1.60481004 -2.10548002 0 P 0 
L 1.60481004 -2.10548002 1.60573002 -2.10321004 0 P 0 
L 1.60573002 -2.10321004 1.60646004 -2.10088002 0 P 0 
L 1.60646004 -2.10088002 1.60698002 -2.09848996 0 P 0 
L 1.60698002 -2.09848996 1.60756004 -2.09421998 0 P 0 
L 1.60756004 -2.09421998 1.6078 -2.08991004 0 P 0 
L 1.6078 -2.08991004 1.60768996 -2.08565 0 P 0 
L 1.60768996 -2.08565 1.60723002 -2.08141998 0 P 0 
L 1.60723002 -2.08141998 1.60691998 -2.07968002 0 P 0 
L 1.60691998 -2.07968002 1.60646998 -2.07796998 0 P 0 
L 1.60646998 -2.07796998 1.60591998 -2.0763 0 P 0 
L 1.60591998 -2.0763 1.60523002 -2.07466998 0 P 0 
L 1.60523002 -2.07466998 1.60411998 -2.07246998 0 P 0 
L 1.60411998 -2.07246998 1.60281004 -2.07038002 0 P 0 
L 1.60281004 -2.07038002 1.60131998 -2.06838996 0 P 0 
L 1.60131998 -2.06838996 1.59803996 -2.06461998 0 P 0 
L 1.59803996 -2.06461998 1.59455 -2.06101998 0 P 0 
L 1.59455 -2.06101998 1.59031998 -2.05708996 0 P 0 
L 1.59031998 -2.05708996 1.58586004 -2.05333996 0 P 0 
L 1.58586004 -2.05333996 1.57588002 -2.04598996 0 P 0 
L 1.57588002 -2.04598996 1.56685 -2.03963996 0 P 0 
L 1.56685 -2.03963996 1.56578002 -2.03878996 0 P 0 
L 1.56578002 -2.03878996 1.56476998 -2.03786004 0 P 0 
L 1.56476998 -2.03786004 1.56383002 -2.03686998 0 P 0 
L 1.56383002 -2.03686998 1.56295 -2.0358 0 P 0 
L 1.56295 -2.0358 1.56276998 -2.03555 0 P 0 
L 1.56276998 -2.03555 1.56261004 -2.03528002 0 P 0 
L 1.56261004 -2.03528002 1.56246998 -2.035 0 P 0 
L 1.56246998 -2.035 1.56236004 -2.03471998 0 P 0 
L 1.56236004 -2.03471998 1.56226998 -2.03441998 0 P 0 
L 1.56226998 -2.03441998 1.5622 -2.03411998 0 P 0 
L 1.5622 -2.03411998 1.56216004 -2.03381998 0 P 0 
L 1.56216004 -2.03381998 1.56213996 -2.03351004 0 P 0 
L 1.56213996 -2.03351004 1.56215 -2.0332 0 P 0 
L 1.56215 -2.0332 1.56218002 -2.03288996 0 P 0 
L 1.56218002 -2.03288996 1.56225 -2.03253996 0 P 0 
L 1.56225 -2.03253996 1.56233996 -2.03221004 0 P 0 
L 1.56233996 -2.03221004 1.56246004 -2.03186998 0 P 0 
L 1.56246004 -2.03186998 1.56261004 -2.03156004 0 P 0 
L 1.56261004 -2.03156004 1.56278996 -2.03125 0 P 0 
L 1.56278996 -2.03125 1.56298002 -2.03096004 0 P 0 
L 1.56298002 -2.03096004 1.56321004 -2.03068996 0 P 0 
L 1.56321004 -2.03068996 1.56345 -2.03043996 0 P 0 
L 1.56345 -2.03043996 1.56371004 -2.0302 0 P 0 
L 1.56371004 -2.0302 1.56416004 -2.02986004 0 P 0 
L 1.56416004 -2.02986004 1.56463002 -2.02955 0 P 0 
L 1.56463002 -2.02955 1.56511998 -2.02928002 0 P 0 
L 1.56511998 -2.02928002 1.56561998 -2.02903002 0 P 0 
L 1.56561998 -2.02903002 1.56611998 -2.02883996 0 P 0 
L 1.56611998 -2.02883996 1.56663996 -2.02866998 0 P 0 
L 1.56663996 -2.02866998 1.56716004 -2.02855 0 P 0 
L 1.56716004 -2.02855 1.5677 -2.02846998 0 P 0 
L 1.5677 -2.02846998 1.56926998 -2.02835 0 P 0 
L 1.56926998 -2.02835 1.57085 -2.02833996 0 P 0 
L 1.57085 -2.02833996 1.57725 -2.02866998 0 P 0 
L 1.57725 -2.02866998 1.58205 -2.02906004 0 P 0 
L 1.58205 -2.02906004 1.58746998 -2.02975 0 P 0 
L 1.58746998 -2.02975 1.59271004 -2.03056998 0 P 0 
L 1.59271004 -2.03056998 1.59681004 -2.03143002 0 P 0 
L 1.59681004 -2.03143002 1.60016004 -2.03221998 0 P 0 
L 1.60016004 -2.03221998 1.60308002 -2.03281004 0 P 0 
L 1.60308002 -2.03281004 1.60553996 -2.03323996 0 P 0 
L 1.60553996 -2.03323996 1.60568996 -2.03323996 0 P 0 
L 1.60568996 -2.03323996 1.60576998 -2.03321998 0 P 0 
L 1.60576998 -2.03321998 1.60586004 -2.03316004 0 P 0 
L 1.60586004 -2.03316004 1.6059 -2.03313996 0 P 0 
L 1.6059 -2.03313996 1.60591998 -2.03311004 0 P 0 
L 1.60591998 -2.03311004 1.60598996 -2.03303996 0 P 0 
L 1.60598996 -2.03303996 1.60605 -2.03296998 0 P 0 
L 1.60605 -2.03296998 1.6061 -2.03288996 0 P 0 
L 1.6061 -2.03288996 1.60618002 -2.03273002 0 P 0 
L 1.60618002 -2.03273002 1.60621004 -2.03263002 0 P 0 
L 1.60621004 -2.03263002 1.60623002 -2.03253996 0 P 0 
L 1.60623002 -2.03253996 1.60625 -2.03236004 0 P 0 
L 1.60625 -2.03236004 1.60623996 -2.03226004 0 P 0 
L 1.60623996 -2.03226004 1.60508002 -2.01578002 0 P 0 
L 1.60508002 -2.01578002 1.60393996 -2.00068002 0 P 0 
L 1.60393996 -2.00068002 1.60368002 -1.99833996 0 P 0 
L 1.60368002 -1.99833996 1.60326998 -1.99601004 0 P 0 
L 1.60326998 -1.99601004 1.60321004 -1.99576998 0 P 0 
L 1.60321004 -1.99576998 1.60313996 -1.99553002 0 P 0 
L 1.60313996 -1.99553002 1.60303996 -1.9953 0 P 0 
L 1.60303996 -1.9953 1.60293002 -1.99508002 0 P 0 
L 1.60293002 -1.99508002 1.60281004 -1.99486004 0 P 0 
L 1.60281004 -1.99486004 1.60261998 -1.9946 0 P 0 
L 1.60261998 -1.9946 1.60241004 -1.99435 0 P 0 
L 1.60241004 -1.99435 1.60218002 -1.99411998 0 P 0 
L 1.60218002 -1.99411998 1.60191998 -1.99391004 0 P 0 
L 1.60191998 -1.99391004 1.60161004 -1.99368996 0 P 0 
L 1.60161004 -1.99368996 1.60128996 -1.99348996 0 P 0 
L 1.60128996 -1.99348996 1.60095 -1.99331998 0 P 0 
L 1.60095 -1.99331998 1.6006 -1.99316004 0 P 0 
L 1.6006 -1.99316004 1.59966004 -1.99283002 0 P 0 
L 1.59966004 -1.99283002 1.59871004 -1.99255 0 P 0 
L 1.59871004 -1.99255 1.5933 -1.99135 0 P 0 
L 1.5933 -1.99135 1.5878 -1.9905 0 P 0 
L 1.5878 -1.9905 1.57285 -1.98915 0 P 0 
L 1.57285 -1.98915 1.55763996 -1.98861004 0 P 0 
L 1.55763996 -1.98861004 1.55171004 -1.98876004 0 P 0 
L 1.55171004 -1.98876004 1.54575 -1.98923996 0 P 0 
L 1.53011998 -2.12786998 1.5666 -2.12786998 0 P 0 
L 1.52236004 -2.12686998 1.57168002 -2.12686998 0 P 0 
L 1.51621998 -2.12586998 1.5753 -2.12586998 0 P 0 
L 1.51071004 -2.12486998 1.57856004 -2.12486998 0 P 0 
L 1.50553002 -2.12386998 1.58121004 -2.12386998 0 P 0 
L 1.50431004 -2.12286998 1.58381998 -2.12286998 0 P 0 
L 1.50423002 -2.12186998 1.58601998 -2.12186998 0 P 0 
L 1.50413996 -2.12086998 1.58796004 -2.12086998 0 P 0 
L 1.50406004 -2.11986998 1.58971004 -2.11986998 0 P 0 
L 1.50396998 -2.11886998 1.59118002 -2.11886998 0 P 0 
L 1.50388996 -2.11786998 1.5926 -2.11786998 0 P 0 
L 1.50381004 -2.11686998 1.59386004 -2.11686998 0 P 0 
L 1.50371998 -2.11586998 1.59496998 -2.11586998 0 P 0 
L 1.50363996 -2.11486998 1.59601004 -2.11486998 0 P 0 
L 1.50355 -2.11386998 1.59696998 -2.11386998 0 P 0 
L 1.50346998 -2.11286998 1.59781004 -2.11286998 0 P 0 
L 1.50338002 -2.11186998 1.5986 -2.11186998 0 P 0 
L 1.5033 -2.11086998 1.59933002 -2.11086998 0 P 0 
L 1.50321004 -2.10986998 1.60005 -2.10986998 0 P 0 
L 1.50313002 -2.10886998 1.60066998 -2.10886998 0 P 0 
L 1.50305 -2.10786998 1.60128002 -2.10786998 0 P 0 
L 1.50296004 -2.10686998 1.60185 -2.10686998 0 P 0 
L 1.50288002 -2.10586998 1.60236004 -2.10586998 0 P 0 
L 1.50278996 -2.10486998 1.60286998 -2.10486998 0 P 0 
L 1.50271004 -2.10386998 1.6033 -2.10386998 0 P 0 
L 1.50263002 -2.10286998 1.60371004 -2.10286998 0 P 0 
L 1.50255 -2.10186998 1.60405 -2.10186998 0 P 0 
L 1.50246998 -2.10086998 1.60436004 -2.10086998 0 P 0 
L 1.50238996 -2.09986998 1.60463002 -2.09986998 0 P 0 
L 1.50231004 -2.09886998 1.60485 -2.09886998 0 P 0 
L 1.50223002 -2.09786998 1.60505 -2.09786998 0 P 0 
L 1.50215 -2.09686998 1.60518002 -2.09686998 0 P 0 
L 1.50206998 -2.09586998 1.60531998 -2.09586998 0 P 0 
L 1.50198996 -2.09486998 1.60545 -2.09486998 0 P 0 
L 1.50191004 -2.09386998 1.60558002 -2.09386998 0 P 0 
L 1.50183002 -2.09286998 1.60563002 -2.09286998 0 P 0 
L 1.50175 -2.09186998 1.53725 -2.09186998 0 P 0 
L 1.54638996 -2.09186998 1.60568996 -2.09186998 0 P 0 
L 1.50166998 -2.09086998 1.5295 -2.09086998 0 P 0 
L 1.54956998 -2.09086998 1.60573996 -2.09086998 0 P 0 
L 1.50158996 -2.08986998 1.52436004 -2.08986998 0 P 0 
L 1.55125 -2.08986998 1.60578996 -2.08986998 0 P 0 
L 1.50151004 -2.08886998 1.52021004 -2.08886998 0 P 0 
L 1.55226998 -2.08886998 1.60576998 -2.08886998 0 P 0 
L 1.50143002 -2.08786998 1.51633002 -2.08786998 0 P 0 
L 1.55298002 -2.08786998 1.60573996 -2.08786998 0 P 0 
L 1.50133996 -2.08686998 1.51246004 -2.08686998 0 P 0 
L 1.55346998 -2.08686998 1.60571998 -2.08686998 0 P 0 
L 1.50126998 -2.08586998 1.50861998 -2.08586998 0 P 0 
L 1.55375 -2.08586998 1.60568996 -2.08586998 0 P 0 
L 1.50118002 -2.08486998 1.50481004 -2.08486998 0 P 0 
L 1.55383002 -2.08486998 1.60558996 -2.08486998 0 P 0 
L 1.55371998 -2.08386998 1.60548996 -2.08386998 0 P 0 
L 1.54886998 -2.12886998 1.53358996 -2.12823996 0 P 0 
L 1.53358996 -2.12823996 1.52631998 -2.12746998 0 P 0 
L 1.52631998 -2.12746998 1.51906004 -2.12636998 0 P 0 
L 1.51906004 -2.12636998 1.51363002 -2.12541004 0 P 0 
L 1.51363002 -2.12541004 1.50886998 -2.12451998 0 P 0 
L 1.50886998 -2.12451998 1.50483996 -2.12373996 0 P 0 
L 1.50483996 -2.12373996 1.50448996 -2.12365 0 P 0 
L 1.50448996 -2.12365 1.50438002 -2.12361004 0 P 0 
L 1.50438002 -2.12361004 1.5027 -2.10378002 0 P 0 
L 1.5027 -2.10378002 1.50111998 -2.08403002 0 P 0 
L 1.50111998 -2.08403002 1.50263996 -2.08433996 0 P 0 
L 1.50263996 -2.08433996 1.50581004 -2.08511004 0 P 0 
L 1.50581004 -2.08511004 1.50955 -2.08611998 0 P 0 
L 1.50955 -2.08611998 1.52306004 -2.08961004 0 P 0 
L 1.52306004 -2.08961004 1.52311004 -2.08961998 0 P 0 
L 1.52311004 -2.08961998 1.52875 -2.09076004 0 P 0 
L 1.52875 -2.09076004 1.5288 -2.09076004 0 P 0 
L 1.5288 -2.09076004 1.53443996 -2.09161004 0 P 0 
L 1.53443996 -2.09161004 1.53893996 -2.09203002 0 P 0 
L 1.53893996 -2.09203002 1.54346004 -2.09216998 0 P 0 
L 1.54346004 -2.09216998 1.54473996 -2.09211004 0 P 0 
L 1.54473996 -2.09211004 1.54603002 -2.09195 0 P 0 
L 1.54603002 -2.09195 1.54728996 -2.09166998 0 P 0 
L 1.54728996 -2.09166998 1.54853002 -2.09128996 0 P 0 
L 1.54853002 -2.09128996 1.54973002 -2.09081004 0 P 0 
L 1.54973002 -2.09081004 1.55026998 -2.09053996 0 P 0 
L 1.55026998 -2.09053996 1.55076998 -2.09023002 0 P 0 
L 1.55076998 -2.09023002 1.55118002 -2.08991998 0 P 0 
L 1.55118002 -2.08991998 1.55118002 -2.08991004 0 P 0 
L 1.55118002 -2.08991004 1.5512 -2.08991004 0 P 0 
L 1.5512 -2.08991004 1.55125 -2.08986998 0 P 0 
L 1.55125 -2.08986998 1.55131004 -2.08981998 0 P 0 
L 1.55131004 -2.08981998 1.55126998 -2.08978002 0 P 0 
L 1.55126998 -2.08978002 1.55136004 -2.08978002 0 P 0 
L 1.55136004 -2.08978002 1.5517 -2.08948996 0 P 0 
L 1.5517 -2.08948996 1.55206004 -2.08911998 0 P 0 
L 1.55206004 -2.08911998 1.55205 -2.08911004 0 P 0 
L 1.55205 -2.08911004 1.55206004 -2.08911004 0 P 0 
L 1.55206004 -2.08911004 1.55211998 -2.08906004 0 P 0 
L 1.55211998 -2.08906004 1.55248996 -2.08861004 0 P 0 
L 1.55248996 -2.08861004 1.55283996 -2.08811998 0 P 0 
L 1.55283996 -2.08811998 1.55313996 -2.08761004 0 P 0 
L 1.55313996 -2.08761004 1.5534 -2.08706998 0 P 0 
L 1.5534 -2.08706998 1.55356004 -2.08663002 0 P 0 
L 1.55356004 -2.08663002 1.55368996 -2.08618996 0 P 0 
L 1.55368996 -2.08618996 1.55376998 -2.08573996 0 P 0 
L 1.55376998 -2.08573996 1.55378002 -2.08565 0 P 0 
L 1.55378002 -2.08565 1.55381998 -2.08528002 0 P 0 
L 1.55381998 -2.08528002 1.55383002 -2.08481998 0 P 0 
L 1.55383002 -2.08481998 1.5538 -2.08436998 0 P 0 
L 1.5538 -2.08436998 1.55373002 -2.08391998 0 P 0 
L 1.55373002 -2.08391998 1.55361998 -2.08346998 0 P 0 
L 1.55361998 -2.08346998 1.55348002 -2.08303996 0 P 0 
L 1.55348002 -2.08303996 1.5533 -2.08261004 0 P 0 
L 1.5533 -2.08261004 1.55308996 -2.08221004 0 P 0 
L 1.55308996 -2.08221004 1.55283996 -2.08183002 0 P 0 
L 1.55283996 -2.08183002 1.55175 -2.0804 0 P 0 
L 1.55175 -2.0804 1.55055 -2.07908002 0 P 0 
L 1.55055 -2.07908002 1.54926004 -2.07783996 0 P 0 
L 1.54926004 -2.07783996 1.54788996 -2.07671998 0 P 0 
L 1.54788996 -2.07671998 1.53706998 -2.06898002 0 P 0 
L 1.53706998 -2.06898002 1.52085 -2.05713996 0 P 0 
L 1.52085 -2.05713996 1.51766004 -2.05445 0 P 0 
L 1.51766004 -2.05445 1.51468002 -2.05153996 0 P 0 
L 1.51468002 -2.05153996 1.51191998 -2.04841998 0 P 0 
L 1.51191998 -2.04841998 1.51048996 -2.04651998 0 P 0 
L 1.51048996 -2.04651998 1.50923002 -2.04453002 0 P 0 
L 1.50923002 -2.04453002 1.50813996 -2.04245 0 P 0 
L 1.50813996 -2.04245 1.50721998 -2.04026004 0 P 0 
L 1.50721998 -2.04026004 1.50643002 -2.03788002 0 P 0 
L 1.50643002 -2.03788002 1.50581004 -2.03545 0 P 0 
L 1.50581004 -2.03545 1.50536004 -2.03298996 0 P 0 
L 1.50536004 -2.03298996 1.50508996 -2.0305 0 P 0 
L 1.50508996 -2.0305 1.50498996 -2.02745 0 P 0 
L 1.50498996 -2.02745 1.50513996 -2.02443996 0 P 0 
L 1.50513996 -2.02443996 1.50551998 -2.02145 0 P 0 
L 1.50551998 -2.02145 1.50613996 -2.0185 0 P 0 
L 1.50613996 -2.0185 1.50698996 -2.01561004 0 P 0 
L 1.50698996 -2.01561004 1.50783002 -2.01341004 0 P 0 
L 1.50783002 -2.01341004 1.50883002 -2.0113 0 P 0 
L 1.50883002 -2.0113 1.51 -2.00928002 0 P 0 
L 1.51 -2.00928002 1.51133002 -2.00736004 0 P 0 
L 1.51133002 -2.00736004 1.5128 -2.00555 0 P 0 
L 1.5128 -2.00555 1.5144 -2.00386004 0 P 0 
L 1.5144 -2.00386004 1.51675 -2.00176998 0 P 0 
L 1.51675 -2.00176998 1.51923002 -1.9999 0 P 0 
L 1.51923002 -1.9999 1.52186004 -1.99823996 0 P 0 
L 1.52186004 -1.99823996 1.52461998 -1.99681004 0 P 0 
L 1.52461998 -1.99681004 1.52748996 -1.99561004 0 P 0 
L 1.52748996 -1.99561004 1.53353002 -1.99363996 0 P 0 
L 1.53353002 -1.99363996 1.5397 -1.99218002 0 P 0 
L 1.5397 -1.99218002 1.54598002 -1.99123002 0 P 0 
L 1.54598002 -1.99123002 1.55181004 -1.99075 0 P 0 
L 1.55181004 -1.99075 1.55763002 -1.99061998 0 P 0 
L 1.55763002 -1.99061998 1.57273002 -1.99113996 0 P 0 
L 1.57273002 -1.99113996 1.58755 -1.99248996 0 P 0 
L 1.58755 -1.99248996 1.59293002 -1.99331998 0 P 0 
L 1.59293002 -1.99331998 1.59821004 -1.99448996 0 P 0 
L 1.59821004 -1.99448996 1.59905 -1.99473002 0 P 0 
L 1.59905 -1.99473002 1.59986004 -1.99501998 0 P 0 
L 1.59986004 -1.99501998 1.60008002 -1.99511998 0 P 0 
L 1.60008002 -1.99511998 1.6003 -1.99523002 0 P 0 
L 1.6003 -1.99523002 1.60051004 -1.99536004 0 P 0 
L 1.60051004 -1.99536004 1.60071004 -1.9955 0 P 0 
L 1.60071004 -1.9955 1.60083002 -1.99561004 0 P 0 
L 1.60083002 -1.99561004 1.60093996 -1.99571004 0 P 0 
L 1.60093996 -1.99571004 1.60103996 -1.99583002 0 P 0 
L 1.60103996 -1.99583002 1.60111998 -1.99595 0 P 0 
L 1.60111998 -1.99595 1.60116998 -1.99601998 0 P 0 
L 1.60116998 -1.99601998 1.60121004 -1.99611004 0 P 0 
L 1.60121004 -1.99611004 1.60125 -1.99621004 0 P 0 
L 1.60125 -1.99621004 1.60128002 -1.9963 0 P 0 
L 1.60128002 -1.9963 1.60131004 -1.99641004 0 P 0 
L 1.60131004 -1.99641004 1.6017 -1.99861998 0 P 0 
L 1.6017 -1.99861998 1.60195 -2.00086998 0 P 0 
L 1.60195 -2.00086998 1.60308002 -2.01593002 0 P 0 
L 1.60308002 -2.01593002 1.60415 -2.03096998 0 P 0 
L 1.60415 -2.03096998 1.60345 -2.03083996 0 P 0 
L 1.60345 -2.03083996 1.60058996 -2.03026004 0 P 0 
L 1.60058996 -2.03026004 1.59723002 -2.02948002 0 P 0 
L 1.59723002 -2.02948002 1.59721998 -2.02948002 0 P 0 
L 1.59721998 -2.02948002 1.59306998 -2.0286 0 P 0 
L 1.59306998 -2.0286 1.58776004 -2.02776998 0 P 0 
L 1.58776004 -2.02776998 1.58226004 -2.02708002 0 P 0 
L 1.58226004 -2.02708002 1.57738002 -2.02666998 0 P 0 
L 1.57738002 -2.02666998 1.5709 -2.02633996 0 P 0 
L 1.5709 -2.02633996 1.56918996 -2.02635 0 P 0 
L 1.56918996 -2.02635 1.56746998 -2.02648996 0 P 0 
L 1.56746998 -2.02648996 1.56678996 -2.02658996 0 P 0 
L 1.56678996 -2.02658996 1.56611998 -2.02673996 0 P 0 
L 1.56611998 -2.02673996 1.56546004 -2.02695 0 P 0 
L 1.56546004 -2.02695 1.56481998 -2.0272 0 P 0 
L 1.56481998 -2.0272 1.56418996 -2.0275 0 P 0 
L 1.56418996 -2.0275 1.56358002 -2.02785 0 P 0 
L 1.56358002 -2.02785 1.563 -2.02823002 0 P 0 
L 1.563 -2.02823002 1.56245 -2.02865 0 P 0 
L 1.56245 -2.02865 1.56206998 -2.02898996 0 P 0 
L 1.56206998 -2.02898996 1.56171004 -2.02936004 0 P 0 
L 1.56171004 -2.02936004 1.56138002 -2.02976004 0 P 0 
L 1.56138002 -2.02976004 1.56108996 -2.03018996 0 P 0 
L 1.56108996 -2.03018996 1.56083002 -2.03063996 0 P 0 
L 1.56083002 -2.03063996 1.56061998 -2.0311 0 P 0 
L 1.56061998 -2.0311 1.56043996 -2.03158996 0 P 0 
L 1.56043996 -2.03158996 1.5603 -2.03208002 0 P 0 
L 1.5603 -2.03208002 1.5602 -2.0326 0 P 0 
L 1.5602 -2.0326 1.56015 -2.03308002 0 P 0 
L 1.56015 -2.03308002 1.56013996 -2.03353996 0 P 0 
L 1.56013996 -2.03353996 1.56016004 -2.03391004 0 P 0 
L 1.56016004 -2.03391004 1.56048002 -2.03391004 0 P 0 
L 1.56048002 -2.03391004 1.56016004 -2.03393002 0 P 0 
L 1.56016004 -2.03393002 1.56016998 -2.03401004 0 P 0 
L 1.56016998 -2.03401004 1.56023002 -2.03448002 0 P 0 
L 1.56023002 -2.03448002 1.56025 -2.03456004 0 P 0 
L 1.56025 -2.03456004 1.56033002 -2.03493002 0 P 0 
L 1.56033002 -2.03493002 1.56046998 -2.03538002 0 P 0 
L 1.56046998 -2.03538002 1.56063996 -2.03581998 0 P 0 
L 1.56063996 -2.03581998 1.56085 -2.03623996 0 P 0 
L 1.56085 -2.03623996 1.56108996 -2.03663996 0 P 0 
L 1.56108996 -2.03663996 1.56136004 -2.03701998 0 P 0 
L 1.56136004 -2.03701998 1.56233002 -2.03818996 0 P 0 
L 1.56233002 -2.03818996 1.56336998 -2.03928996 0 P 0 
L 1.56336998 -2.03928996 1.56448002 -2.04031004 0 P 0 
L 1.56448002 -2.04031004 1.56566004 -2.04123996 0 P 0 
L 1.56566004 -2.04123996 1.57471004 -2.04761998 0 P 0 
L 1.57471004 -2.04761998 1.58461998 -2.05491004 0 P 0 
L 1.58461998 -2.05491004 1.58898996 -2.05858996 0 P 0 
L 1.58898996 -2.05858996 1.59315 -2.06245 0 P 0 
L 1.59315 -2.06245 1.59656998 -2.06596998 0 P 0 
L 1.59656998 -2.06596998 1.59976004 -2.06965 0 P 0 
L 1.59976004 -2.06965 1.60116004 -2.07151004 0 P 0 
L 1.60116004 -2.07151004 1.60238002 -2.07346004 0 P 0 
L 1.60238002 -2.07346004 1.60341998 -2.0755 0 P 0 
L 1.60341998 -2.0755 1.60403996 -2.077 0 P 0 
L 1.60403996 -2.077 1.60456004 -2.07853996 0 P 0 
L 1.60456004 -2.07853996 1.60496004 -2.08011004 0 P 0 
L 1.60496004 -2.08011004 1.60525 -2.0817 0 P 0 
L 1.60525 -2.0817 1.60568996 -2.08578002 0 P 0 
L 1.60568996 -2.08578002 1.60578996 -2.08988002 0 P 0 
L 1.60578996 -2.08988002 1.60556998 -2.09403002 0 P 0 
L 1.60556998 -2.09403002 1.60501004 -2.09813996 0 P 0 
L 1.60501004 -2.09813996 1.60451998 -2.10036998 0 P 0 
L 1.60451998 -2.10036998 1.60383996 -2.10253996 0 P 0 
L 1.60383996 -2.10253996 1.60298996 -2.10465 0 P 0 
L 1.60298996 -2.10465 1.60163996 -2.1073 0 P 0 
L 1.60163996 -2.1073 1.60008002 -2.10983002 0 P 0 
L 1.60008002 -2.10983002 1.59833002 -2.11225 0 P 0 
L 1.59833002 -2.11225 1.59696998 -2.11386998 0 P 0 
L 1.59696998 -2.11386998 1.59551004 -2.11538996 0 P 0 
L 1.59551004 -2.11538996 1.59395 -2.1168 0 P 0 
L 1.59395 -2.1168 1.59231004 -2.11811004 0 P 0 
L 1.59231004 -2.11811004 1.58973002 -2.11986004 0 P 0 
L 1.58973002 -2.11986004 1.58701998 -2.1214 0 P 0 
L 1.58701998 -2.1214 1.5842 -2.12273002 0 P 0 
L 1.5842 -2.12273002 1.5788 -2.1248 0 P 0 
L 1.5788 -2.1248 1.57326998 -2.12648996 0 P 0 
L 1.57326998 -2.12648996 1.56983002 -2.12731004 0 P 0 
L 1.56983002 -2.12731004 1.56638002 -2.12791004 0 P 0 
L 1.56638002 -2.12791004 1.56288996 -2.1283 0 P 0 
L 1.56288996 -2.1283 1.54886998 -2.12886998 0 P 0 
L 1.35851998 -2.06545 1.47866004 -2.06545 0 P 0 
L 1.35936004 -2.06445 1.47871004 -2.06445 0 P 0 
L 1.36041004 -2.06345 1.47875 -2.06345 0 P 0 
L 1.36163996 -2.06245 1.4788 -2.06245 0 P 0 
L 1.36293996 -2.06145 1.47883996 -2.06145 0 P 0 
L 1.36436004 -2.06045 1.47888996 -2.06045 0 P 0 
L 1.36598002 -2.05945 1.47893996 -2.05945 0 P 0 
L 1.36776004 -2.05845 1.47898996 -2.05845 0 P 0 
L 1.36971004 -2.05745 1.47903002 -2.05745 0 P 0 
L 1.37166004 -2.05645 1.47908002 -2.05645 0 P 0 
L 1.37391004 -2.05545 1.47911998 -2.05545 0 P 0 
L 1.37616998 -2.05445 1.47916998 -2.05445 0 P 0 
L 1.37873002 -2.05345 1.47921004 -2.05345 0 P 0 
L 1.38136004 -2.05245 1.47926004 -2.05245 0 P 0 
L 1.36875 -2.03345 1.37108996 -2.03345 0 P 0 
L 1.36886004 -2.03245 1.37385 -2.03245 0 P 0 
L 1.36896998 -2.03145 1.37678002 -2.03145 0 P 0 
L 1.36908996 -2.03045 1.3797 -2.03045 0 P 0 
L 1.36921004 -2.02945 1.38261998 -2.02945 0 P 0 
L 1.36933002 -2.02845 1.38638996 -2.02845 0 P 0 
L 1.36946004 -2.02745 1.39023996 -2.02745 0 P 0 
L 1.36958002 -2.02645 1.39503002 -2.02645 0 P 0 
L 1.3697 -2.02545 1.40068002 -2.02545 0 P 0 
L 1.36981998 -2.02445 1.41053996 -2.02445 0 P 0 
L 1.36993996 -2.02345 1.47993996 -2.02345 0 P 0 
L 1.37008002 -2.02245 1.47988002 -2.02245 0 P 0 
L 1.37021004 -2.02145 1.47978002 -2.02145 0 P 0 
L 1.37033996 -2.02045 1.47968002 -2.02045 0 P 0 
L 1.37046998 -2.01945 1.47953002 -2.01945 0 P 0 
L 1.3706 -2.01845 1.47936004 -2.01845 0 P 0 
L 1.37073002 -2.01745 1.47918002 -2.01745 0 P 0 
L 1.37086004 -2.01645 1.47893002 -2.01645 0 P 0 
L 1.37098996 -2.01545 1.47868002 -2.01545 0 P 0 
L 1.37113002 -2.01445 1.4784 -2.01445 0 P 0 
L 1.37126998 -2.01345 1.47806004 -2.01345 0 P 0 
L 1.3714 -2.01245 1.47773002 -2.01245 0 P 0 
L 1.37153996 -2.01145 1.47733002 -2.01145 0 P 0 
L 1.37168002 -2.01045 1.47691004 -2.01045 0 P 0 
L 1.37181004 -2.00945 1.47641004 -2.00945 0 P 0 
L 1.37195 -2.00845 1.47588996 -2.00845 0 P 0 
L 1.37208002 -2.00745 1.47528002 -2.00745 0 P 0 
L 1.37221004 -2.00645 1.47463996 -2.00645 0 P 0 
L 1.37235 -2.00545 1.47391998 -2.00545 0 P 0 
L 1.37248996 -2.00445 1.47311004 -2.00445 0 P 0 
L 1.37261998 -2.00345 1.47225 -2.00345 0 P 0 
L 1.37276004 -2.00245 1.47126998 -2.00245 0 P 0 
L 1.3729 -2.00145 1.4702 -2.00145 0 P 0 
L 1.37303002 -2.00045 1.46903996 -2.00045 0 P 0 
L 1.37316998 -1.99945 1.46775 -1.99945 0 P 0 
L 1.3733 -1.99845 1.46625 -1.99845 0 P 0 
L 1.37343996 -1.99745 1.46455 -1.99745 0 P 0 
L 1.37356998 -1.99645 1.46253996 -1.99645 0 P 0 
L 1.37753002 -1.99545 1.46041004 -1.99545 0 P 0 
L 1.38218996 -1.99445 1.45781004 -1.99445 0 P 0 
L 1.42925 -2.08345 1.47785 -2.08345 0 P 0 
L 1.42931998 -2.08245 1.47788996 -2.08245 0 P 0 
L 1.42938002 -2.08145 1.47793002 -2.08145 0 P 0 
L 1.42945 -2.08045 1.47796998 -2.08045 0 P 0 
L 1.42951004 -2.07945 1.47801004 -2.07945 0 P 0 
L 1.42958002 -2.07845 1.47806004 -2.07845 0 P 0 
L 1.42963996 -2.07745 1.4781 -2.07745 0 P 0 
L 1.4297 -2.07645 1.47815 -2.07645 0 P 0 
L 1.42976998 -2.07545 1.4782 -2.07545 0 P 0 
L 1.42983002 -2.07445 1.47825 -2.07445 0 P 0 
L 1.4299 -2.07345 1.47828996 -2.07345 0 P 0 
L 1.42963996 -2.07245 1.47833996 -2.07245 0 P 0 
L 1.42918996 -2.07145 1.47838002 -2.07145 0 P 0 
L 1.38425 -2.05145 1.47931004 -2.05145 0 P 0 
L 1.38731998 -2.05045 1.47933996 -2.05045 0 P 0 
L 1.39088002 -2.04945 1.47938002 -2.04945 0 P 0 
L 1.3947 -2.04845 1.47941004 -2.04845 0 P 0 
L 1.39851004 -2.04745 1.47945 -2.04745 0 P 0 
L 1.40233002 -2.04645 1.47948002 -2.04645 0 P 0 
L 1.40608002 -2.04545 1.47951004 -2.04545 0 P 0 
L 1.40983002 -2.04445 1.47955 -2.04445 0 P 0 
L 1.41306998 -2.04345 1.47958996 -2.04345 0 P 0 
L 1.41591998 -2.04245 1.47961998 -2.04245 0 P 0 
L 1.41876998 -2.04145 1.47965 -2.04145 0 P 0 
L 1.42133996 -2.04045 1.47968996 -2.04045 0 P 0 
L 1.42361998 -2.03945 1.47971998 -2.03945 0 P 0 
L 1.42591004 -2.03845 1.47975 -2.03845 0 P 0 
L 1.42805 -2.03745 1.47978002 -2.03745 0 P 0 
L 1.42936004 -2.03645 1.47981004 -2.03645 0 P 0 
L 1.43003002 -2.03545 1.47983002 -2.03545 0 P 0 
L 1.43081998 -2.03445 1.47986004 -2.03445 0 P 0 
L 1.43121004 -2.03345 1.47988002 -2.03345 0 P 0 
L 1.43141998 -2.03245 1.4799 -2.03245 0 P 0 
L 1.43146998 -2.03145 1.47993002 -2.03145 0 P 0 
L 1.43136004 -2.03045 1.47996004 -2.03045 0 P 0 
L 1.43108002 -2.02945 1.47998002 -2.02945 0 P 0 
L 1.4306 -2.02845 1.48001004 -2.02845 0 P 0 
L 1.42986998 -2.02745 1.48001004 -2.02745 0 P 0 
L 1.42875 -2.02645 1.47998996 -2.02645 0 P 0 
L 1.42658996 -2.02545 1.47996998 -2.02545 0 P 0 
L 1.42203996 -2.02445 1.47996004 -2.02445 0 P 0 
L 1.38748002 -1.99345 1.45483002 -1.99345 0 P 0 
L 1.39331998 -1.99245 1.45108996 -1.99245 0 P 0 
L 1.40051004 -1.99145 1.44503002 -1.99145 0 P 0 
L 1.38096998 -2.12745 1.4051 -2.12745 0 P 0 
L 1.37671004 -2.12645 1.41113996 -2.12645 0 P 0 
L 1.3736 -2.12545 1.41238996 -2.12545 0 P 0 
L 1.37096998 -2.12445 1.41268002 -2.12445 0 P 0 
L 1.36876998 -2.12345 1.41296998 -2.12345 0 P 0 
L 1.36685 -2.12245 1.41326998 -2.12245 0 P 0 
L 1.36516004 -2.12145 1.41356004 -2.12145 0 P 0 
L 1.36366004 -2.12045 1.41385 -2.12045 0 P 0 
L 1.36225 -2.11945 1.41413996 -2.11945 0 P 0 
L 1.361 -2.11845 1.41443002 -2.11845 0 P 0 
L 1.35983002 -2.11745 1.41471998 -2.11745 0 P 0 
L 1.35876004 -2.11645 1.41501004 -2.11645 0 P 0 
L 1.42661998 -2.12445 1.47693002 -2.12445 0 P 0 
L 1.42665 -2.12345 1.47693002 -2.12345 0 P 0 
L 1.4267 -2.12245 1.47693002 -2.12245 0 P 0 
L 1.42675 -2.12145 1.47693002 -2.12145 0 P 0 
L 1.42681004 -2.12045 1.47693002 -2.12045 0 P 0 
L 1.42686998 -2.11945 1.47693002 -2.11945 0 P 0 
L 1.42691998 -2.11845 1.47693002 -2.11845 0 P 0 
L 1.42698996 -2.11745 1.47693002 -2.11745 0 P 0 
L 1.42705 -2.11645 1.47693002 -2.11645 0 P 0 
L 1.42711004 -2.11545 1.47693002 -2.11545 0 P 0 
L 1.42716998 -2.11445 1.47693002 -2.11445 0 P 0 
L 1.42723002 -2.11345 1.47693996 -2.11345 0 P 0 
L 1.4273 -2.11245 1.47695 -2.11245 0 P 0 
L 1.42736998 -2.11145 1.47696004 -2.11145 0 P 0 
L 1.42743996 -2.11045 1.47698002 -2.11045 0 P 0 
L 1.42751004 -2.10945 1.47698996 -2.10945 0 P 0 
L 1.42758002 -2.10845 1.47701004 -2.10845 0 P 0 
L 1.42765 -2.10745 1.47703002 -2.10745 0 P 0 
L 1.42771004 -2.10645 1.47703996 -2.10645 0 P 0 
L 1.42778002 -2.10545 1.47706998 -2.10545 0 P 0 
L 1.42783996 -2.10445 1.4771 -2.10445 0 P 0 
L 1.42791004 -2.10345 1.47713002 -2.10345 0 P 0 
L 1.42798002 -2.10245 1.47716004 -2.10245 0 P 0 
L 1.42805 -2.10145 1.4772 -2.10145 0 P 0 
L 1.42811004 -2.10045 1.47723002 -2.10045 0 P 0 
L 1.40953002 -2.09945 1.41973002 -2.09945 0 P 0 
L 1.42818002 -2.09945 1.47726004 -2.09945 0 P 0 
L 1.41618002 -2.09845 1.41996998 -2.09845 0 P 0 
L 1.42825 -2.09845 1.47728996 -2.09845 0 P 0 
L 1.42831998 -2.09745 1.47733002 -2.09745 0 P 0 
L 1.42838996 -2.09645 1.47736004 -2.09645 0 P 0 
L 1.42846004 -2.09545 1.47738996 -2.09545 0 P 0 
L 1.42851998 -2.09445 1.47741998 -2.09445 0 P 0 
L 1.42858996 -2.09345 1.47746004 -2.09345 0 P 0 
L 1.42866004 -2.09245 1.4775 -2.09245 0 P 0 
L 1.42873002 -2.09145 1.47753996 -2.09145 0 P 0 
L 1.42878996 -2.09045 1.47758002 -2.09045 0 P 0 
L 1.42886004 -2.08945 1.47761998 -2.08945 0 P 0 
L 1.42893002 -2.08845 1.47766004 -2.08845 0 P 0 
L 1.42898996 -2.08745 1.4777 -2.08745 0 P 0 
L 1.42906004 -2.08645 1.47773002 -2.08645 0 P 0 
L 1.42911998 -2.08545 1.47776998 -2.08545 0 P 0 
L 1.42918996 -2.08445 1.47781004 -2.08445 0 P 0 
L 1.61686004 -2.17995 1.66846004 -2.17995 0 P 0 
L 1.61591004 -2.17895 1.67158996 -2.17895 0 P 0 
L 1.61553996 -2.17795 1.67431998 -2.17795 0 P 0 
L 1.61526998 -2.17695 1.67675 -2.17695 0 P 0 
L 1.61508002 -2.17595 1.67903996 -2.17595 0 P 0 
L 1.61496998 -2.17495 1.68108002 -2.17495 0 P 0 
L 1.61491004 -2.17395 1.68295 -2.17395 0 P 0 
L 1.61485 -2.17295 1.68458996 -2.17295 0 P 0 
L 1.61478996 -2.17195 1.6861 -2.17195 0 P 0 
L 1.61473002 -2.17095 1.6875 -2.17095 0 P 0 
L 1.61466998 -2.16995 1.68876998 -2.16995 0 P 0 
L 1.61461004 -2.16895 1.68998002 -2.16895 0 P 0 
L 1.61455 -2.16795 1.69108002 -2.16795 0 P 0 
L 1.61448996 -2.16695 1.69211998 -2.16695 0 P 0 
L 1.61443002 -2.16595 1.69316004 -2.16595 0 P 0 
L 1.61436998 -2.16495 1.69411998 -2.16495 0 P 0 
L 1.61431004 -2.16395 1.69498996 -2.16395 0 P 0 
L 1.61425 -2.16295 1.69586004 -2.16295 0 P 0 
L 1.61418996 -2.16195 1.69673002 -2.16195 0 P 0 
L 1.61413002 -2.16095 1.69746998 -2.16095 0 P 0 
L 1.61406998 -2.15995 1.6982 -2.15995 0 P 0 
L 1.61401998 -2.15895 1.69893996 -2.15895 0 P 0 
L 1.61396998 -2.15795 1.69963002 -2.15795 0 P 0 
L 1.64433002 -2.18295 1.63151004 -2.18271004 0 P 0 
L 1.63151004 -2.18271004 1.62658002 -2.18226998 0 P 0 
L 1.62658002 -2.18226998 1.62168996 -2.18146998 0 P 0 
L 1.62168996 -2.18146998 1.6201 -2.1811 0 P 0 
L 1.6201 -2.1811 1.61853996 -2.18061004 0 P 0 
L 1.61853996 -2.18061004 1.61701004 -2.18001998 0 P 0 
L 1.61701004 -2.18001998 1.61686004 -2.17995 0 P 0 
L 1.61686004 -2.17995 1.61671004 -2.17986998 0 P 0 
L 1.61671004 -2.17986998 1.61656998 -2.17976998 0 P 0 
L 1.61656998 -2.17976998 1.61643996 -2.17966998 0 P 0 
L 1.61643996 -2.17966998 1.61631998 -2.17955 0 P 0 
L 1.61631998 -2.17955 1.61621004 -2.17943002 0 P 0 
L 1.61621004 -2.17943002 1.6161 -2.1793 0 P 0 
L 1.6161 -2.1793 1.61601004 -2.17915 0 P 0 
L 1.61601004 -2.17915 1.61593002 -2.179 0 P 0 
L 1.61593002 -2.179 1.61586004 -2.17885 0 P 0 
L 1.61586004 -2.17885 1.61553002 -2.17791004 0 P 0 
L 1.61553002 -2.17791004 1.61526998 -2.17696004 0 P 0 
L 1.61526998 -2.17696004 1.61508996 -2.17598996 0 P 0 
L 1.61508996 -2.17598996 1.61496998 -2.17496998 0 P 0 
L 1.61496998 -2.17496998 1.61408002 -2.16011004 0 P 0 
L 1.61408002 -2.16011004 1.61341998 -2.14758996 0 P 0 
L 1.61341998 -2.14758996 1.6202 -2.14821004 0 P 0 
L 1.6202 -2.14821004 1.62023002 -2.14821004 0 P 0 
L 1.62023002 -2.14821004 1.63216998 -2.14893996 0 P 0 
L 1.63216998 -2.14893996 1.6349 -2.14893002 0 P 0 
L 1.6349 -2.14893002 1.63761998 -2.14873002 0 P 0 
L 1.63761998 -2.14873002 1.64031998 -2.14835 0 P 0 
L 1.64031998 -2.14835 1.64198996 -2.14798996 0 P 0 
L 1.64198996 -2.14798996 1.64363002 -2.14751998 0 P 0 
L 1.64363002 -2.14751998 1.64523002 -2.14693002 0 P 0 
L 1.64523002 -2.14693002 1.64678996 -2.14623002 0 P 0 
L 1.64678996 -2.14623002 1.64888002 -2.14506998 0 P 0 
L 1.64888002 -2.14506998 1.65086998 -2.14376004 0 P 0 
L 1.65086998 -2.14376004 1.65093996 -2.14371004 0 P 0 
L 1.65093996 -2.14371004 1.65275 -2.14228996 0 P 0 
L 1.65275 -2.14228996 1.6539 -2.14123996 0 P 0 
L 1.6539 -2.14123996 1.65496004 -2.14011004 0 P 0 
L 1.65496004 -2.14011004 1.65591998 -2.13891004 0 P 0 
L 1.65591998 -2.13891004 1.65755 -2.13653996 0 P 0 
L 1.65755 -2.13653996 1.65901998 -2.13415 0 P 0 
L 1.65901998 -2.13415 1.65903002 -2.13413002 0 P 0 
L 1.65903002 -2.13413002 1.66035 -2.13171998 0 P 0 
L 1.66035 -2.13171998 1.66155 -2.12925 0 P 0 
L 1.66155 -2.12925 1.66183996 -2.12851998 0 P 0 
L 1.66183996 -2.12851998 1.66206998 -2.12776004 0 P 0 
L 1.66206998 -2.12776004 1.66223996 -2.12696998 0 P 0 
L 1.66223996 -2.12696998 1.66233996 -2.12618002 0 P 0 
L 1.66233996 -2.12618002 1.66236998 -2.12538996 0 P 0 
L 1.66236998 -2.12538996 1.66233002 -2.12436004 0 P 0 
L 1.66233002 -2.12436004 1.66221004 -2.12335 0 P 0 
L 1.66221004 -2.12335 1.662 -2.12235 0 P 0 
L 1.662 -2.12235 1.66171004 -2.12141004 0 P 0 
L 1.66171004 -2.12141004 1.64438996 -2.07113002 0 P 0 
L 1.64438996 -2.07113002 1.62871998 -2.02606004 0 P 0 
L 1.62871998 -2.02606004 1.62116004 -2.00558996 0 P 0 
L 1.62116004 -2.00558996 1.62116004 -2.00556998 0 P 0 
L 1.62116004 -2.00556998 1.61681004 -1.99443996 0 P 0 
L 1.61681004 -1.99443996 1.67163002 -1.99443996 0 P 0 
L 1.67163002 -1.99443996 1.67301004 -2.00076004 0 P 0 
L 1.67301004 -2.00076004 1.67613002 -2.01341998 0 P 0 
L 1.67613002 -2.01341998 1.68331004 -2.03931998 0 P 0 
L 1.68331004 -2.03931998 1.69153002 -2.06856998 0 P 0 
L 1.69153002 -2.06856998 1.6916 -2.06876004 0 P 0 
L 1.6916 -2.06876004 1.69168996 -2.06896998 0 P 0 
L 1.69168996 -2.06896998 1.69181004 -2.06918002 0 P 0 
L 1.69181004 -2.06918002 1.69193002 -2.06936998 0 P 0 
L 1.69193002 -2.06936998 1.69208002 -2.06956004 0 P 0 
L 1.69208002 -2.06956004 1.69223996 -2.06973002 0 P 0 
L 1.69223996 -2.06973002 1.69241998 -2.06988002 0 P 0 
L 1.69241998 -2.06988002 1.6926 -2.07001998 0 P 0 
L 1.6926 -2.07001998 1.6928 -2.07015 0 P 0 
L 1.6928 -2.07015 1.69301004 -2.07025 0 P 0 
L 1.69301004 -2.07025 1.69323002 -2.07033996 0 P 0 
L 1.69323002 -2.07033996 1.69346004 -2.07041004 0 P 0 
L 1.69346004 -2.07041004 1.69368002 -2.07045 0 P 0 
L 1.69368002 -2.07045 1.69391998 -2.07048002 0 P 0 
L 1.69391998 -2.07048002 1.69413996 -2.07048996 0 P 0 
L 1.69413996 -2.07048996 1.6944 -2.07048002 0 P 0 
L 1.6944 -2.07048002 1.69465 -2.07045 0 P 0 
L 1.69465 -2.07045 1.69488996 -2.07038996 0 P 0 
L 1.69488996 -2.07038996 1.69513996 -2.07031998 0 P 0 
L 1.69513996 -2.07031998 1.69536998 -2.07021998 0 P 0 
L 1.69536998 -2.07021998 1.69558996 -2.0701 0 P 0 
L 1.69558996 -2.0701 1.69581004 -2.06996998 0 P 0 
L 1.69581004 -2.06996998 1.69601004 -2.06981998 0 P 0 
L 1.69601004 -2.06981998 1.6962 -2.06965 0 P 0 
L 1.6962 -2.06965 1.69636998 -2.06946004 0 P 0 
L 1.69636998 -2.06946004 1.69653002 -2.06926004 0 P 0 
L 1.69653002 -2.06926004 1.69666004 -2.06905 0 P 0 
L 1.69666004 -2.06905 1.69678996 -2.06883002 0 P 0 
L 1.69678996 -2.06883002 1.69688002 -2.0686 0 P 0 
L 1.69688002 -2.0686 1.69695 -2.0684 0 P 0 
L 1.69695 -2.0684 1.70426004 -2.04365 0 P 0 
L 1.70426004 -2.04365 1.70426004 -2.04363002 0 P 0 
L 1.70426004 -2.04363002 1.71066998 -2.0213 0 P 0 
L 1.71066998 -2.0213 1.71068002 -2.02126004 0 P 0 
L 1.71068002 -2.02126004 1.71431998 -2.00693996 0 P 0 
L 1.71431998 -2.00693996 1.71706004 -1.99496998 0 P 0 
L 1.71706004 -1.99496998 1.74335 -1.9947 0 P 0 
L 1.74335 -1.9947 1.75403002 -1.99461004 0 P 0 
L 1.75403002 -1.99461004 1.76301004 -1.99465 0 P 0 
L 1.76301004 -1.99465 1.76886004 -1.99471004 0 P 0 
L 1.76886004 -1.99471004 1.76883996 -1.99476004 0 P 0 
L 1.76883996 -1.99476004 1.74021004 -2.06556004 0 P 0 
L 1.74021004 -2.06556004 1.71298002 -2.13276998 0 P 0 
L 1.71298002 -2.13276998 1.70836998 -2.14293996 0 P 0 
L 1.70836998 -2.14293996 1.70413996 -2.15076004 0 P 0 
L 1.70413996 -2.15076004 1.69941998 -2.15828996 0 P 0 
L 1.69941998 -2.15828996 1.6967 -2.16198996 0 P 0 
L 1.6967 -2.16198996 1.6937 -2.16541998 0 P 0 
L 1.6937 -2.16541998 1.69041998 -2.1686 0 P 0 
L 1.69041998 -2.1686 1.68793996 -2.17063002 0 P 0 
L 1.68793996 -2.17063002 1.68535 -2.17248002 0 P 0 
L 1.68535 -2.17248002 1.68263996 -2.17413996 0 P 0 
L 1.68263996 -2.17413996 1.67981004 -2.17561004 0 P 0 
L 1.67981004 -2.17561004 1.67525 -2.17761004 0 P 0 
L 1.67525 -2.17761004 1.6706 -2.17931998 0 P 0 
L 1.6706 -2.17931998 1.66586004 -2.18073002 0 P 0 
L 1.66586004 -2.18073002 1.66141998 -2.1817 0 P 0 
L 1.66141998 -2.1817 1.65691998 -2.18228996 0 P 0 
L 1.65691998 -2.18228996 1.64433002 -2.18295 0 P 0 
L 1.61928996 -2.00628002 1.62683996 -2.02673002 0 P 0 
L 1.62683996 -2.02673002 1.6425 -2.07178002 0 P 0 
L 1.6425 -2.07178002 1.65981004 -2.12201998 0 P 0 
L 1.65981004 -2.12201998 1.66006004 -2.12283996 0 P 0 
L 1.66006004 -2.12283996 1.66023002 -2.12368002 0 P 0 
L 1.66023002 -2.12368002 1.66033996 -2.12451998 0 P 0 
L 1.66033996 -2.12451998 1.66036998 -2.12538002 0 P 0 
L 1.66036998 -2.12538002 1.66033996 -2.12601004 0 P 0 
L 1.66033996 -2.12601004 1.66026998 -2.12663996 0 P 0 
L 1.66026998 -2.12663996 1.66013996 -2.12725 0 P 0 
L 1.66013996 -2.12725 1.65995 -2.12786004 0 P 0 
L 1.65995 -2.12786004 1.65971004 -2.12843996 0 P 0 
L 1.65971004 -2.12843996 1.65856998 -2.1308 0 P 0 
L 1.65856998 -2.1308 1.6573 -2.13313002 0 P 0 
L 1.6573 -2.13313002 1.65586998 -2.13545 0 P 0 
L 1.65586998 -2.13545 1.65431004 -2.13771998 0 P 0 
L 1.65431004 -2.13771998 1.65343996 -2.1388 0 P 0 
L 1.65343996 -2.1388 1.65248996 -2.13981998 0 P 0 
L 1.65248996 -2.13981998 1.65146004 -2.14076004 0 P 0 
L 1.65146004 -2.14076004 1.64971004 -2.14213002 0 P 0 
L 1.64971004 -2.14213002 1.64785 -2.14336004 0 P 0 
L 1.64785 -2.14336004 1.64588996 -2.14443996 0 P 0 
L 1.64588996 -2.14443996 1.64446998 -2.14508002 0 P 0 
L 1.64446998 -2.14508002 1.64301004 -2.14561998 0 P 0 
L 1.64301004 -2.14561998 1.64151004 -2.14605 0 P 0 
L 1.64151004 -2.14605 1.63996998 -2.14636998 0 P 0 
L 1.63996998 -2.14636998 1.63741004 -2.14673996 0 P 0 
L 1.63741004 -2.14673996 1.63483002 -2.14693002 0 P 0 
L 1.63483002 -2.14693002 1.63223002 -2.14693996 0 P 0 
L 1.63223002 -2.14693996 1.62036004 -2.14621998 0 P 0 
L 1.62036004 -2.14621998 1.6113 -2.14538002 0 P 0 
L 1.6113 -2.14538002 1.61208996 -2.16023002 0 P 0 
L 1.61208996 -2.16023002 1.61298002 -2.17515 0 P 0 
L 1.61298002 -2.17515 1.6131 -2.17628002 0 P 0 
L 1.6131 -2.17628002 1.61331998 -2.17741004 0 P 0 
L 1.61331998 -2.17741004 1.61361998 -2.17851004 0 P 0 
L 1.61361998 -2.17851004 1.614 -2.17958996 0 P 0 
L 1.614 -2.17958996 1.61413996 -2.17988996 0 P 0 
L 1.61413996 -2.17988996 1.61428996 -2.18018002 0 P 0 
L 1.61428996 -2.18018002 1.61446998 -2.18045 0 P 0 
L 1.61446998 -2.18045 1.61466998 -2.18071004 0 P 0 
L 1.61466998 -2.18071004 1.61488996 -2.18095 0 P 0 
L 1.61488996 -2.18095 1.61511998 -2.18116998 0 P 0 
L 1.61511998 -2.18116998 1.61538002 -2.18138002 0 P 0 
L 1.61538002 -2.18138002 1.61565 -2.18156004 0 P 0 
L 1.61565 -2.18156004 1.61593002 -2.18173002 0 P 0 
L 1.61593002 -2.18173002 1.61623002 -2.18186004 0 P 0 
L 1.61623002 -2.18186004 1.61788002 -2.1825 0 P 0 
L 1.61788002 -2.1825 1.61956998 -2.18301998 0 P 0 
L 1.61956998 -2.18301998 1.6213 -2.18343002 0 P 0 
L 1.6213 -2.18343002 1.62633002 -2.18426004 0 P 0 
L 1.62633002 -2.18426004 1.6314 -2.18471004 0 P 0 
L 1.6314 -2.18471004 1.64436004 -2.18495 0 P 0 
L 1.64436004 -2.18495 1.65711004 -2.18428002 0 P 0 
L 1.65711004 -2.18428002 1.66176998 -2.18366998 0 P 0 
L 1.66176998 -2.18366998 1.66636004 -2.18266998 0 P 0 
L 1.66636004 -2.18266998 1.67123002 -2.18121004 0 P 0 
L 1.67123002 -2.18121004 1.676 -2.17946998 0 P 0 
L 1.676 -2.17946998 1.68068002 -2.17741998 0 P 0 
L 1.68068002 -2.17741998 1.68361998 -2.17588002 0 P 0 
L 1.68361998 -2.17588002 1.68646004 -2.17415 0 P 0 
L 1.68646004 -2.17415 1.68916004 -2.17221998 0 P 0 
L 1.68916004 -2.17221998 1.69175 -2.17008996 0 P 0 
L 1.69175 -2.17008996 1.69515 -2.1668 0 P 0 
L 1.69515 -2.1668 1.69826004 -2.16323996 0 P 0 
L 1.69826004 -2.16323996 1.70108002 -2.15941998 0 P 0 
L 1.70108002 -2.15941998 1.70586004 -2.15176998 0 P 0 
L 1.70586004 -2.15176998 1.71016004 -2.14383002 0 P 0 
L 1.71016004 -2.14383002 1.71481998 -2.13356004 0 P 0 
L 1.71481998 -2.13356004 1.74206998 -2.06631004 0 P 0 
L 1.74206998 -2.06631004 1.77071004 -1.99548002 0 P 0 
L 1.77071004 -1.99548002 1.77088002 -1.99498996 0 P 0 
L 1.77088002 -1.99498996 1.77101998 -1.99448996 0 P 0 
L 1.77101998 -1.99448996 1.77111998 -1.99398996 0 P 0 
L 1.77111998 -1.99398996 1.77118002 -1.99346998 0 P 0 
L 1.77118002 -1.99346998 1.7712 -1.99295 0 P 0 
L 1.7712 -1.99295 1.7712 -1.99293002 0 P 0 
L 1.7712 -1.99293002 1.77118996 -1.99286998 0 P 0 
L 1.77118996 -1.99286998 1.77118002 -1.99286004 0 P 0 
L 1.77118002 -1.99286004 1.77118002 -1.99283996 0 P 0 
L 1.77118002 -1.99283996 1.77111004 -1.99276998 0 P 0 
L 1.77111004 -1.99276998 1.77106998 -1.99275 0 P 0 
L 1.77106998 -1.99275 1.77106004 -1.99273996 0 P 0 
L 1.77106004 -1.99273996 1.771 -1.99273002 0 P 0 
L 1.771 -1.99273002 1.77098002 -1.99273002 0 P 0 
L 1.77098002 -1.99273002 1.76301004 -1.99265 0 P 0 
L 1.76301004 -1.99265 1.75401998 -1.99261004 0 P 0 
L 1.75401998 -1.99261004 1.74333002 -1.9927 0 P 0 
L 1.74333002 -1.9927 1.71546004 -1.99298996 0 P 0 
L 1.71546004 -1.99298996 1.71236998 -2.00646998 0 P 0 
L 1.71236998 -2.00646998 1.70873996 -2.02078002 0 P 0 
L 1.70873996 -2.02078002 1.70233996 -2.04308002 0 P 0 
L 1.70233996 -2.04308002 1.69505 -2.0678 0 P 0 
L 1.69505 -2.0678 1.69501998 -2.06788002 0 P 0 
L 1.69501998 -2.06788002 1.69498996 -2.06795 0 P 0 
L 1.69498996 -2.06795 1.69495 -2.06801998 0 P 0 
L 1.69495 -2.06801998 1.69485 -2.06816004 0 P 0 
L 1.69485 -2.06816004 1.69478996 -2.06821998 0 P 0 
L 1.69478996 -2.06821998 1.69466998 -2.06831998 0 P 0 
L 1.69466998 -2.06831998 1.69453002 -2.0684 0 P 0 
L 1.69453002 -2.0684 1.69445 -2.06843002 0 P 0 
L 1.69445 -2.06843002 1.69438002 -2.06846004 0 P 0 
L 1.69438002 -2.06846004 1.69428996 -2.06846998 0 P 0 
L 1.69428996 -2.06846998 1.69421004 -2.06848996 0 P 0 
L 1.69421004 -2.06848996 1.69406998 -2.06848996 0 P 0 
L 1.69406998 -2.06848996 1.69395 -2.06846998 0 P 0 
L 1.69395 -2.06846998 1.69383002 -2.06843002 0 P 0 
L 1.69383002 -2.06843002 1.69373002 -2.06836998 0 P 0 
L 1.69373002 -2.06836998 1.69363002 -2.06828996 0 P 0 
L 1.69363002 -2.06828996 1.69358996 -2.06823996 0 P 0 
L 1.69358996 -2.06823996 1.69355 -2.0682 0 P 0 
L 1.69355 -2.0682 1.69351998 -2.06815 0 P 0 
L 1.69351998 -2.06815 1.69346004 -2.06803996 0 P 0 
L 1.69346004 -2.06803996 1.69343996 -2.06798002 0 P 0 
L 1.69343996 -2.06798002 1.68523002 -2.03878002 0 P 0 
L 1.68523002 -2.03878002 1.67806998 -2.01291998 0 P 0 
L 1.67806998 -2.01291998 1.67496004 -2.00031004 0 P 0 
L 1.67496004 -2.00031004 1.67323002 -1.99243996 0 P 0 
L 1.67323002 -1.99243996 1.61388002 -1.99243996 0 P 0 
L 1.61388002 -1.99243996 1.61928996 -2.00628002 0 P 0 
L 1.35018002 -2.08345 1.39488996 -2.08345 0 P 0 
L 1.35026004 -2.08245 1.39586004 -2.08245 0 P 0 
L 1.35041004 -2.08145 1.39708996 -2.08145 0 P 0 
L 1.35058996 -2.08045 1.39853002 -2.08045 0 P 0 
L 1.35083996 -2.07945 1.40031998 -2.07945 0 P 0 
L 1.35116998 -2.07845 1.40271004 -2.07845 0 P 0 
L 1.35158002 -2.07745 1.40561998 -2.07745 0 P 0 
L 1.35203002 -2.07645 1.4092 -2.07645 0 P 0 
L 1.35248002 -2.07545 1.41288996 -2.07545 0 P 0 
L 1.35293002 -2.07445 1.4164 -2.07445 0 P 0 
L 1.35338996 -2.07345 1.41975 -2.07345 0 P 0 
L 1.35393996 -2.07245 1.42293996 -2.07245 0 P 0 
L 1.35448996 -2.07145 1.42606998 -2.07145 0 P 0 
L 1.35505 -2.07045 1.47843002 -2.07045 0 P 0 
L 1.3557 -2.06945 1.47846998 -2.06945 0 P 0 
L 1.35635 -2.06845 1.47851998 -2.06845 0 P 0 
L 1.35701998 -2.06745 1.47856998 -2.06745 0 P 0 
L 1.35776998 -2.06645 1.47861004 -2.06645 0 P 0 
L 1.29346998 -2.00516004 1.33388996 -2.00516004 0 P 0 
L 1.29448996 -2.00416004 1.33385 -2.00416004 0 P 0 
L 1.29551004 -2.00316004 1.33381004 -2.00316004 0 P 0 
L 1.29653996 -2.00216004 1.33376004 -2.00216004 0 P 0 
L 1.29756004 -2.00116004 1.33371004 -2.00116004 0 P 0 
L 1.29861998 -2.00016004 1.33366004 -2.00016004 0 P 0 
L 1.29973002 -1.99916004 1.3336 -1.99916004 0 P 0 
L 1.30101004 -1.99816004 1.33355 -1.99816004 0 P 0 
L 1.30238996 -1.99716004 1.3335 -1.99716004 0 P 0 
L 1.30393996 -1.99616004 1.33345 -1.99616004 0 P 0 
L 1.30571004 -1.99516004 1.33338996 -1.99516004 0 P 0 
L 1.3077 -1.99416004 1.33333002 -1.99416004 0 P 0 
L 1.31001004 -1.99316004 1.33328002 -1.99316004 0 P 0 
L 1.31288002 -1.99216004 1.33321998 -1.99216004 0 P 0 
L 1.31688996 -1.99116004 1.33316004 -1.99116004 0 P 0 
L 1.39798996 -1.98971998 1.39326998 -1.99043002 0 P 0 
L 1.39326998 -1.99043002 1.38806998 -1.9913 0 P 0 
L 1.38806998 -1.9913 1.38316004 -1.9922 0 P 0 
L 1.38316004 -1.9922 1.37946004 -1.99296998 0 P 0 
L 1.37946004 -1.99296998 1.3718 -1.99466998 0 P 0 
L 1.3718 -1.99466998 1.36896004 -2.01553996 0 P 0 
L 1.36896004 -2.01553996 1.36791004 -2.02358996 0 P 0 
L 1.36791004 -2.02358996 1.36708002 -2.03043002 0 P 0 
L 1.36708002 -2.03043002 1.36638996 -2.03646004 0 P 0 
L 1.36638996 -2.03646004 1.36638002 -2.03648996 0 P 0 
L 1.36638002 -2.03648996 1.36638996 -2.03653002 0 P 0 
L 1.36638996 -2.03653002 1.36638996 -2.03656998 0 P 0 
L 1.36638996 -2.03656998 1.3664 -2.03663996 0 P 0 
L 1.3664 -2.03663996 1.36641998 -2.03666998 0 P 0 
L 1.36641998 -2.03666998 1.36643002 -2.03671004 0 P 0 
L 1.36643002 -2.03671004 1.36648996 -2.0368 0 P 0 
L 1.36648996 -2.0368 1.36656004 -2.03686004 0 P 0 
L 1.36656004 -2.03686004 1.3666 -2.03688996 0 P 0 
L 1.3666 -2.03688996 1.36663002 -2.03691004 0 P 0 
L 1.36663002 -2.03691004 1.36666004 -2.03691004 0 P 0 
L 1.36666004 -2.03691004 1.36671004 -2.03693002 0 P 0 
L 1.36671004 -2.03693002 1.36676998 -2.03693002 0 P 0 
L 1.36676998 -2.03693002 1.36685 -2.03691998 0 P 0 
L 1.36685 -2.03691998 1.36895 -2.03628002 0 P 0 
L 1.36895 -2.03628002 1.37143002 -2.03545 0 P 0 
L 1.37143002 -2.03545 1.37428996 -2.03441004 0 P 0 
L 1.37428996 -2.03441004 1.38346004 -2.03126998 0 P 0 
L 1.38346004 -2.03126998 1.39251998 -2.02891998 0 P 0 
L 1.39251998 -2.02891998 1.40156004 -2.02731998 0 P 0 
L 1.40156004 -2.02731998 1.41068002 -2.02643996 0 P 0 
L 1.41068002 -2.02643996 1.41566998 -2.02628002 0 P 0 
L 1.41566998 -2.02628002 1.42066004 -2.02633996 0 P 0 
L 1.42066004 -2.02633996 1.42221004 -2.02646998 0 P 0 
L 1.42221004 -2.02646998 1.42375 -2.02671998 0 P 0 
L 1.42375 -2.02671998 1.42525 -2.0271 0 P 0 
L 1.42525 -2.0271 1.42671998 -2.02761004 0 P 0 
L 1.42671998 -2.02761004 1.42706004 -2.02776004 0 P 0 
L 1.42706004 -2.02776004 1.42738002 -2.02793002 0 P 0 
L 1.42738002 -2.02793002 1.42768002 -2.02813996 0 P 0 
L 1.42768002 -2.02813996 1.42796998 -2.02836004 0 P 0 
L 1.42796998 -2.02836004 1.42823002 -2.02861004 0 P 0 
L 1.42823002 -2.02861004 1.42848002 -2.02888996 0 P 0 
L 1.42848002 -2.02888996 1.4287 -2.02918002 0 P 0 
L 1.4287 -2.02918002 1.42888996 -2.02948996 0 P 0 
L 1.42888996 -2.02948996 1.42906004 -2.02981004 0 P 0 
L 1.42906004 -2.02981004 1.4292 -2.03015 0 P 0 
L 1.4292 -2.03015 1.42931998 -2.0305 0 P 0 
L 1.42931998 -2.0305 1.4294 -2.03086004 0 P 0 
L 1.4294 -2.03086004 1.42945 -2.03121998 0 P 0 
L 1.42945 -2.03121998 1.42946998 -2.03158002 0 P 0 
L 1.42946998 -2.03158002 1.42946004 -2.03195 0 P 0 
L 1.42946004 -2.03195 1.42941998 -2.03231004 0 P 0 
L 1.42941998 -2.03231004 1.42935 -2.03266998 0 P 0 
L 1.42935 -2.03266998 1.42925 -2.03301998 0 P 0 
L 1.42925 -2.03301998 1.42911998 -2.03336004 0 P 0 
L 1.42911998 -2.03336004 1.42896004 -2.03368996 0 P 0 
L 1.42896004 -2.03368996 1.42875 -2.03405 0 P 0 
L 1.42875 -2.03405 1.42851004 -2.03438996 0 P 0 
L 1.42851004 -2.03438996 1.42825 -2.03471004 0 P 0 
L 1.42825 -2.03471004 1.42796004 -2.03501004 0 P 0 
L 1.42796004 -2.03501004 1.42765 -2.03528996 0 P 0 
L 1.42765 -2.03528996 1.42731998 -2.03553996 0 P 0 
L 1.42731998 -2.03553996 1.42696998 -2.03576004 0 P 0 
L 1.42696998 -2.03576004 1.4266 -2.03596004 0 P 0 
L 1.4266 -2.03596004 1.41951004 -2.03906004 0 P 0 
L 1.41951004 -2.03906004 1.4109 -2.04208996 0 P 0 
L 1.4109 -2.04208996 1.40178002 -2.04451998 0 P 0 
L 1.40178002 -2.04451998 1.3878 -2.04818996 0 P 0 
L 1.3878 -2.04818996 1.38176998 -2.05015 0 P 0 
L 1.38176998 -2.05015 1.3758 -2.05243002 0 P 0 
L 1.3758 -2.05243002 1.37086998 -2.0546 0 P 0 
L 1.37086998 -2.0546 1.36603996 -2.05708002 0 P 0 
L 1.36603996 -2.05708002 1.36356004 -2.05856004 0 P 0 
L 1.36356004 -2.05856004 1.36118996 -2.06023002 0 P 0 
L 1.36118996 -2.06023002 1.35895 -2.06206004 0 P 0 
L 1.35895 -2.06206004 1.35805 -2.06291004 0 P 0 
L 1.35805 -2.06291004 1.35721998 -2.06385 0 P 0 
L 1.35721998 -2.06385 1.35518996 -2.06655 0 P 0 
L 1.35518996 -2.06655 1.3532 -2.06961998 0 P 0 
L 1.3532 -2.06961998 1.35156004 -2.07263002 0 P 0 
L 1.35156004 -2.07263002 1.34951004 -2.07718002 0 P 0 
L 1.34951004 -2.07718002 1.34911004 -2.07825 0 P 0 
L 1.34911004 -2.07825 1.34878996 -2.07935 0 P 0 
L 1.34878996 -2.07935 1.34853002 -2.08046998 0 P 0 
L 1.34853002 -2.08046998 1.34825 -2.08238002 0 P 0 
L 1.34825 -2.08238002 1.34811998 -2.08431004 0 P 0 
L 1.34811998 -2.08431004 1.348 -2.09128996 0 P 0 
L 1.348 -2.09128996 1.3481 -2.09761004 0 P 0 
L 1.3481 -2.09761004 1.34823002 -2.09961004 0 P 0 
L 1.34823002 -2.09961004 1.34846998 -2.10161004 0 P 0 
L 1.34846998 -2.10161004 1.34876998 -2.10321998 0 P 0 
L 1.34876998 -2.10321998 1.3492 -2.10478996 0 P 0 
L 1.3492 -2.10478996 1.3498 -2.10648996 0 P 0 
L 1.3498 -2.10648996 1.3505 -2.10815 0 P 0 
L 1.3505 -2.10815 1.35178996 -2.11066004 0 P 0 
L 1.35178996 -2.11066004 1.35328002 -2.11305 0 P 0 
L 1.35328002 -2.11305 1.35496998 -2.1153 0 P 0 
L 1.35496998 -2.1153 1.35685 -2.1174 0 P 0 
L 1.35685 -2.1174 1.35891998 -2.11933996 0 P 0 
L 1.35891998 -2.11933996 1.36126998 -2.12121998 0 P 0 
L 1.36126998 -2.12121998 1.36373996 -2.12293002 0 P 0 
L 1.36373996 -2.12293002 1.36633002 -2.12446004 0 P 0 
L 1.36633002 -2.12446004 1.36901004 -2.1258 0 P 0 
L 1.36901004 -2.1258 1.3718 -2.12695 0 P 0 
L 1.3718 -2.12695 1.37578996 -2.12828002 0 P 0 
L 1.37578996 -2.12828002 1.37986998 -2.12928996 0 P 0 
L 1.37986998 -2.12928996 1.38401998 -2.12998996 0 P 0 
L 1.38401998 -2.12998996 1.3882 -2.13036004 0 P 0 
L 1.3882 -2.13036004 1.39443002 -2.13045 0 P 0 
L 1.39443002 -2.13045 1.40066004 -2.13006998 0 P 0 
L 1.40066004 -2.13006998 1.40685 -2.12923002 0 P 0 
L 1.40685 -2.12923002 1.41371004 -2.12801998 0 P 0 
L 1.41371004 -2.12801998 1.41583002 -2.12081004 0 P 0 
L 1.41583002 -2.12081004 1.41953996 -2.10798996 0 P 0 
L 1.41953996 -2.10798996 1.42135 -2.10126998 0 P 0 
L 1.42135 -2.10126998 1.42236998 -2.097 0 P 0 
L 1.42236998 -2.097 1.42238996 -2.09691004 0 P 0 
L 1.42238996 -2.09691004 1.4224 -2.09681998 0 P 0 
L 1.4224 -2.09681998 1.4224 -2.09673996 0 P 0 
L 1.4224 -2.09673996 1.42238002 -2.09656004 0 P 0 
L 1.42238002 -2.09656004 1.42235 -2.09648002 0 P 0 
L 1.42235 -2.09648002 1.42233002 -2.09638996 0 P 0 
L 1.42233002 -2.09638996 1.42225 -2.09623002 0 P 0 
L 1.42225 -2.09623002 1.4222 -2.09616004 0 P 0 
L 1.4222 -2.09616004 1.42213996 -2.09608996 0 P 0 
L 1.42213996 -2.09608996 1.42208996 -2.09601998 0 P 0 
L 1.42208996 -2.09601998 1.42203996 -2.09598996 0 P 0 
L 1.42203996 -2.09598996 1.42198996 -2.09595 0 P 0 
L 1.42198996 -2.09595 1.42188996 -2.09588996 0 P 0 
L 1.42188996 -2.09588996 1.42183002 -2.09586004 0 P 0 
L 1.42183002 -2.09586004 1.42178002 -2.09585 0 P 0 
L 1.42178002 -2.09585 1.42171998 -2.09583002 0 P 0 
L 1.42171998 -2.09583002 1.42166004 -2.09581998 0 P 0 
L 1.42166004 -2.09581998 1.42153996 -2.09581998 0 P 0 
L 1.42153996 -2.09581998 1.41978002 -2.09591004 0 P 0 
L 1.41978002 -2.09591004 1.41763996 -2.09615 0 P 0 
L 1.41763996 -2.09615 1.41521998 -2.09658002 0 P 0 
L 1.41521998 -2.09658002 1.4107 -2.09733002 0 P 0 
L 1.4107 -2.09733002 1.40613002 -2.09775 0 P 0 
L 1.40613002 -2.09775 1.40481004 -2.09778002 0 P 0 
L 1.40481004 -2.09778002 1.40348996 -2.09771998 0 P 0 
L 1.40348996 -2.09771998 1.40216998 -2.09756004 0 P 0 
L 1.40216998 -2.09756004 1.40086998 -2.0973 0 P 0 
L 1.40086998 -2.0973 1.39958996 -2.09695 0 P 0 
L 1.39958996 -2.09695 1.39895 -2.09671998 0 P 0 
L 1.39895 -2.09671998 1.39831998 -2.09643002 0 P 0 
L 1.39831998 -2.09643002 1.39773002 -2.0961 0 P 0 
L 1.39773002 -2.0961 1.39716004 -2.09571004 0 P 0 
L 1.39716004 -2.09571004 1.39663002 -2.09528002 0 P 0 
L 1.39663002 -2.09528002 1.39613996 -2.0948 0 P 0 
L 1.39613996 -2.0948 1.39568002 -2.09428002 0 P 0 
L 1.39568002 -2.09428002 1.39533996 -2.09381998 0 P 0 
L 1.39533996 -2.09381998 1.39505 -2.09333996 0 P 0 
L 1.39505 -2.09333996 1.39478996 -2.09281998 0 P 0 
L 1.39478996 -2.09281998 1.39456998 -2.09228996 0 P 0 
L 1.39456998 -2.09228996 1.3944 -2.09173996 0 P 0 
L 1.3944 -2.09173996 1.39428002 -2.09118996 0 P 0 
L 1.39428002 -2.09118996 1.39421004 -2.09061998 0 P 0 
L 1.39421004 -2.09061998 1.39418002 -2.09003996 0 P 0 
L 1.39418002 -2.09003996 1.39421004 -2.08943002 0 P 0 
L 1.39421004 -2.08943002 1.39428002 -2.08883002 0 P 0 
L 1.39428002 -2.08883002 1.39441004 -2.08823002 0 P 0 
L 1.39441004 -2.08823002 1.3946 -2.08765 0 P 0 
L 1.3946 -2.08765 1.39483002 -2.08708002 0 P 0 
L 1.39483002 -2.08708002 1.39511004 -2.08653996 0 P 0 
L 1.39511004 -2.08653996 1.39555 -2.08583996 0 P 0 
L 1.39555 -2.08583996 1.39603996 -2.08518002 0 P 0 
L 1.39603996 -2.08518002 1.39658002 -2.08456004 0 P 0 
L 1.39658002 -2.08456004 1.39716004 -2.08396998 0 P 0 
L 1.39716004 -2.08396998 1.39778002 -2.08343002 0 P 0 
L 1.39778002 -2.08343002 1.39878996 -2.08266998 0 P 0 
L 1.39878996 -2.08266998 1.39985 -2.08196998 0 P 0 
L 1.39985 -2.08196998 1.40096004 -2.08135 0 P 0 
L 1.40096004 -2.08135 1.40211998 -2.08081004 0 P 0 
L 1.40211998 -2.08081004 1.40503002 -2.07971004 0 P 0 
L 1.40503002 -2.07971004 1.40801998 -2.07881998 0 P 0 
L 1.40801998 -2.07881998 1.41128996 -2.07796004 0 P 0 
L 1.41128996 -2.07796004 1.41506004 -2.07691998 0 P 0 
L 1.41506004 -2.07691998 1.41871998 -2.07585 0 P 0 
L 1.41871998 -2.07585 1.42165 -2.07495 0 P 0 
L 1.42165 -2.07495 1.42791998 -2.07295 0 P 0 
L 1.42791998 -2.07295 1.42731998 -2.08241004 0 P 0 
L 1.42731998 -2.08241004 1.42701004 -2.08708002 0 P 0 
L 1.42701004 -2.08708002 1.42658002 -2.09353996 0 P 0 
L 1.42658002 -2.09353996 1.4261 -2.10055 0 P 0 
L 1.4261 -2.10055 1.42566998 -2.10706004 0 P 0 
L 1.42566998 -2.10706004 1.42525 -2.11306004 0 P 0 
L 1.42525 -2.11306004 1.42491998 -2.11851998 0 P 0 
L 1.42491998 -2.11851998 1.42466004 -2.1231 0 P 0 
L 1.42466004 -2.1231 1.42461004 -2.12471004 0 P 0 
L 1.42461004 -2.12471004 1.4246 -2.12716004 0 P 0 
L 1.4246 -2.12716004 1.47893002 -2.12716004 0 P 0 
L 1.47893002 -2.12716004 1.47893002 -2.11358002 0 P 0 
L 1.47893002 -2.11358002 1.47905 -2.10616998 0 P 0 
L 1.47905 -2.10616998 1.47943996 -2.09385 0 P 0 
L 1.47943996 -2.09385 1.48 -2.07968996 0 P 0 
L 1.48 -2.07968996 1.48066004 -2.0655 0 P 0 
L 1.48066004 -2.0655 1.4813 -2.05168996 0 P 0 
L 1.4813 -2.05168996 1.48175 -2.03873996 0 P 0 
L 1.48175 -2.03873996 1.48201998 -2.02785 0 P 0 
L 1.48201998 -2.02785 1.48191998 -2.02286004 0 P 0 
L 1.48191998 -2.02286004 1.48165 -2.01995 0 P 0 
L 1.48165 -2.01995 1.48115 -2.01708002 0 P 0 
L 1.48115 -2.01708002 1.48043996 -2.01425 0 P 0 
L 1.48043996 -2.01425 1.47951004 -2.01146998 0 P 0 
L 1.47951004 -2.01146998 1.47866998 -2.00946998 0 P 0 
L 1.47866998 -2.00946998 1.47768002 -2.00753996 0 P 0 
L 1.47768002 -2.00753996 1.47655 -2.00568002 0 P 0 
L 1.47655 -2.00568002 1.47528002 -2.00391998 0 P 0 
L 1.47528002 -2.00391998 1.47388002 -2.00225 0 P 0 
L 1.47388002 -2.00225 1.47228996 -2.00063002 0 P 0 
L 1.47228996 -2.00063002 1.4706 -1.99911998 0 P 0 
L 1.4706 -1.99911998 1.4688 -1.99773002 0 P 0 
L 1.4688 -1.99773002 1.46691004 -1.99648002 0 P 0 
L 1.46691004 -1.99648002 1.46491998 -1.99535 0 P 0 
L 1.46491998 -1.99535 1.46098996 -1.99351004 0 P 0 
L 1.46098996 -1.99351004 1.45693002 -1.99196998 0 P 0 
L 1.45693002 -1.99196998 1.45276004 -1.99076004 0 P 0 
L 1.45276004 -1.99076004 1.44953996 -1.99006004 0 P 0 
L 1.44953996 -1.99006004 1.44628996 -1.98956004 0 P 0 
L 1.44628996 -1.98956004 1.44298002 -1.98923996 0 P 0 
L 1.44298002 -1.98923996 1.42695 -1.98856998 0 P 0 
L 1.42695 -1.98856998 1.41038996 -1.98865 0 P 0 
L 1.41038996 -1.98865 1.4042 -1.98901004 0 P 0 
L 1.4042 -1.98901004 1.39798996 -1.98971998 0 P 0 
L 1.35778996 -2.11545 1.4153 -2.11545 0 P 0 
L 1.35688996 -2.11445 1.41558996 -2.11445 0 P 0 
L 1.35608002 -2.11345 1.41588002 -2.11345 0 P 0 
L 1.35533002 -2.11245 1.41616998 -2.11245 0 P 0 
L 1.35463996 -2.11145 1.41646004 -2.11145 0 P 0 
L 1.35401004 -2.11045 1.41675 -2.11045 0 P 0 
L 1.35341004 -2.10945 1.41703996 -2.10945 0 P 0 
L 1.3529 -2.10845 1.41733002 -2.10845 0 P 0 
L 1.35238002 -2.10745 1.41761998 -2.10745 0 P 0 
L 1.35195 -2.10645 1.41788002 -2.10645 0 P 0 
L 1.35155 -2.10545 1.41816004 -2.10545 0 P 0 
L 1.3512 -2.10445 1.41841998 -2.10445 0 P 0 
L 1.35091004 -2.10345 1.41868996 -2.10345 0 P 0 
L 1.35066004 -2.10245 1.41896004 -2.10245 0 P 0 
L 1.35046998 -2.10145 1.41923002 -2.10145 0 P 0 
L 1.35033996 -2.10045 1.41948996 -2.10045 0 P 0 
L 1.35021998 -2.09945 1.40141004 -2.09945 0 P 0 
L 1.35016004 -2.09845 1.39791004 -2.09845 0 P 0 
L 1.3501 -2.09745 1.39616004 -2.09745 0 P 0 
L 1.35008002 -2.09645 1.39496004 -2.09645 0 P 0 
L 1.35006998 -2.09545 1.39406004 -2.09545 0 P 0 
L 1.35005 -2.09445 1.39338002 -2.09445 0 P 0 
L 1.35003996 -2.09345 1.39288002 -2.09345 0 P 0 
L 1.35001998 -2.09245 1.39253002 -2.09245 0 P 0 
L 1.35001004 -2.09145 1.3923 -2.09145 0 P 0 
L 1.35001998 -2.09045 1.3922 -2.09045 0 P 0 
L 1.35003002 -2.08945 1.3922 -2.08945 0 P 0 
L 1.35005 -2.08845 1.39231998 -2.08845 0 P 0 
L 1.35006998 -2.08745 1.39256004 -2.08745 0 P 0 
L 1.35008002 -2.08645 1.39293002 -2.08645 0 P 0 
L 1.3501 -2.08545 1.39343002 -2.08545 0 P 0 
L 1.35011004 -2.08445 1.39408996 -2.08445 0 P 0 
L 1.39438002 -2.12845 1.3883 -2.12836004 0 P 0 
L 1.3883 -2.12836004 1.38426998 -2.128 0 P 0 
L 1.38426998 -2.128 1.38028002 -2.12733002 0 P 0 
L 1.38028002 -2.12733002 1.37635 -2.12636004 0 P 0 
L 1.37635 -2.12636004 1.37248996 -2.12508002 0 P 0 
L 1.37248996 -2.12508002 1.36983996 -2.12398002 0 P 0 
L 1.36983996 -2.12398002 1.36728996 -2.1227 0 P 0 
L 1.36728996 -2.1227 1.36481998 -2.12123996 0 P 0 
L 1.36481998 -2.12123996 1.36246004 -2.11961004 0 P 0 
L 1.36246004 -2.11961004 1.36023002 -2.11781998 0 P 0 
L 1.36023002 -2.11781998 1.35828996 -2.116 0 P 0 
L 1.35828996 -2.116 1.35651998 -2.11403002 0 P 0 
L 1.35651998 -2.11403002 1.35493002 -2.11191004 0 P 0 
L 1.35493002 -2.11191004 1.35353002 -2.10966998 0 P 0 
L 1.35353002 -2.10966998 1.35231004 -2.10731004 0 P 0 
L 1.35231004 -2.10731004 1.35166998 -2.10576998 0 P 0 
L 1.35166998 -2.10576998 1.35111004 -2.1042 0 P 0 
L 1.35111004 -2.1042 1.35071998 -2.10276004 0 P 0 
L 1.35071998 -2.10276004 1.35045 -2.1013 0 P 0 
L 1.35045 -2.1013 1.35021998 -2.09943002 0 P 0 
L 1.35021998 -2.09943002 1.3501 -2.09753002 0 P 0 
L 1.3501 -2.09753002 1.35001004 -2.09128002 0 P 0 
L 1.35001004 -2.09128002 1.35011998 -2.0844 0 P 0 
L 1.35011998 -2.0844 1.35023996 -2.08258996 0 P 0 
L 1.35023996 -2.08258996 1.3505 -2.08083996 0 P 0 
L 1.3505 -2.08083996 1.35071998 -2.07985 0 P 0 
L 1.35071998 -2.07985 1.35101004 -2.07888002 0 P 0 
L 1.35101004 -2.07888002 1.35136004 -2.07793002 0 P 0 
L 1.35136004 -2.07793002 1.35335 -2.07351998 0 P 0 
L 1.35335 -2.07351998 1.35491998 -2.07065 0 P 0 
L 1.35491998 -2.07065 1.35683002 -2.0677 0 P 0 
L 1.35683002 -2.0677 1.35876998 -2.06511004 0 P 0 
L 1.35876998 -2.06511004 1.35948996 -2.0643 0 P 0 
L 1.35948996 -2.0643 1.36026998 -2.06356004 0 P 0 
L 1.36026998 -2.06356004 1.3624 -2.06181998 0 P 0 
L 1.3624 -2.06181998 1.36465 -2.06023996 0 P 0 
L 1.36465 -2.06023996 1.36701004 -2.05883002 0 P 0 
L 1.36701004 -2.05883002 1.37173002 -2.05641004 0 P 0 
L 1.37173002 -2.05641004 1.37656004 -2.05426998 0 P 0 
L 1.37656004 -2.05426998 1.38243002 -2.05203996 0 P 0 
L 1.38243002 -2.05203996 1.38836004 -2.0501 0 P 0 
L 1.38836004 -2.0501 1.4023 -2.04645 0 P 0 
L 1.4023 -2.04645 1.41148996 -2.044 0 P 0 
L 1.41148996 -2.044 1.42016998 -2.04095 0 P 0 
L 1.42016998 -2.04095 1.42016998 -2.04093996 0 P 0 
L 1.42016998 -2.04093996 1.42021004 -2.04093996 0 P 0 
L 1.42021004 -2.04093996 1.42023996 -2.04093002 0 P 0 
L 1.42023996 -2.04093002 1.42746998 -2.03776004 0 P 0 
L 1.42746998 -2.03776004 1.42753002 -2.03773002 0 P 0 
L 1.42753002 -2.03773002 1.42796998 -2.03748996 0 P 0 
L 1.42796998 -2.03748996 1.42846004 -2.03718996 0 P 0 
L 1.42846004 -2.03718996 1.42891998 -2.03683996 0 P 0 
L 1.42891998 -2.03683996 1.42935 -2.03646004 0 P 0 
L 1.42935 -2.03646004 1.42975 -2.03603996 0 P 0 
L 1.42975 -2.03603996 1.43011004 -2.0356 0 P 0 
L 1.43011004 -2.0356 1.43016004 -2.03553002 0 P 0 
L 1.43016004 -2.03553002 1.4299 -2.03535 0 P 0 
L 1.4299 -2.03535 1.43028002 -2.03535 0 P 0 
L 1.43028002 -2.03535 1.43043996 -2.03513002 0 P 0 
L 1.43043996 -2.03513002 1.43048002 -2.03506004 0 P 0 
L 1.43048002 -2.03506004 1.43041998 -2.03501998 0 P 0 
L 1.43041998 -2.03501998 1.4305 -2.03501998 0 P 0 
L 1.4305 -2.03501998 1.43073002 -2.03463002 0 P 0 
L 1.43073002 -2.03463002 1.43096004 -2.03415 0 P 0 
L 1.43096004 -2.03415 1.43115 -2.03365 0 P 0 
L 1.43115 -2.03365 1.4313 -2.03313002 0 P 0 
L 1.4313 -2.03313002 1.4314 -2.03261004 0 P 0 
L 1.4314 -2.03261004 1.43146004 -2.03208002 0 P 0 
L 1.43146004 -2.03208002 1.43146998 -2.03155 0 P 0 
L 1.43146998 -2.03155 1.43143996 -2.03101004 0 P 0 
L 1.43143996 -2.03101004 1.43143002 -2.03093002 0 P 0 
L 1.43143002 -2.03093002 1.43136004 -2.03048996 0 P 0 
L 1.43136004 -2.03048996 1.43125 -2.02996998 0 P 0 
L 1.43125 -2.02996998 1.43108002 -2.02946004 0 P 0 
L 1.43108002 -2.02946004 1.43086998 -2.02896004 0 P 0 
L 1.43086998 -2.02896004 1.43063002 -2.02848996 0 P 0 
L 1.43063002 -2.02848996 1.43033996 -2.02803996 0 P 0 
L 1.43033996 -2.02803996 1.43001998 -2.02761004 0 P 0 
L 1.43001998 -2.02761004 1.42966004 -2.02721004 0 P 0 
L 1.42966004 -2.02721004 1.42928002 -2.02685 0 P 0 
L 1.42928002 -2.02685 1.42886004 -2.02651998 0 P 0 
L 1.42886004 -2.02651998 1.42841998 -2.02623002 0 P 0 
L 1.42841998 -2.02623002 1.42795 -2.02596998 0 P 0 
L 1.42795 -2.02596998 1.42746004 -2.02575 0 P 0 
L 1.42746004 -2.02575 1.42583002 -2.02518002 0 P 0 
L 1.42583002 -2.02518002 1.42416004 -2.02476004 0 P 0 
L 1.42416004 -2.02476004 1.42245 -2.02448002 0 P 0 
L 1.42245 -2.02448002 1.42075 -2.02435 0 P 0 
L 1.42075 -2.02435 1.41565 -2.02428002 0 P 0 
L 1.41565 -2.02428002 1.4156 -2.02428002 0 P 0 
L 1.4156 -2.02428002 1.41055 -2.02445 0 P 0 
L 1.41055 -2.02445 1.41048002 -2.02445 0 P 0 
L 1.41048002 -2.02445 1.40128996 -2.02533996 0 P 0 
L 1.40128996 -2.02533996 1.39208996 -2.02696998 0 P 0 
L 1.39208996 -2.02696998 1.38288002 -2.02936004 0 P 0 
L 1.38288002 -2.02936004 1.37363002 -2.03251998 0 P 0 
L 1.37363002 -2.03251998 1.37076998 -2.03356004 0 P 0 
L 1.37076998 -2.03356004 1.36865 -2.03426998 0 P 0 
L 1.36865 -2.03426998 1.36906004 -2.03066998 0 P 0 
L 1.36906004 -2.03066998 1.36988996 -2.02383996 0 P 0 
L 1.36988996 -2.02383996 1.37095 -2.01581004 0 P 0 
L 1.37095 -2.01581004 1.37358996 -1.99631998 0 P 0 
L 1.37358996 -1.99631998 1.37988002 -1.99491998 0 P 0 
L 1.37988002 -1.99491998 1.38353996 -1.99416998 0 P 0 
L 1.38353996 -1.99416998 1.38841998 -1.99326998 0 P 0 
L 1.38841998 -1.99326998 1.39358002 -1.9924 0 P 0 
L 1.39358002 -1.9924 1.39825 -1.9917 0 P 0 
L 1.39825 -1.9917 1.40436998 -1.991 0 P 0 
L 1.40436998 -1.991 1.41045 -1.99065 0 P 0 
L 1.41045 -1.99065 1.42691004 -1.99056998 0 P 0 
L 1.42691004 -1.99056998 1.44283996 -1.99123996 0 P 0 
L 1.44283996 -1.99123996 1.44603996 -1.99153996 0 P 0 
L 1.44603996 -1.99153996 1.44918002 -1.99203002 0 P 0 
L 1.44918002 -1.99203002 1.45226004 -1.9927 0 P 0 
L 1.45226004 -1.9927 1.4563 -1.99386998 0 P 0 
L 1.4563 -1.99386998 1.46021004 -1.99535 0 P 0 
L 1.46021004 -1.99535 1.464 -1.99713002 0 P 0 
L 1.464 -1.99713002 1.46586004 -1.99818996 0 P 0 
L 1.46586004 -1.99818996 1.46763996 -1.99936004 0 P 0 
L 1.46763996 -1.99936004 1.46931998 -2.00066004 0 P 0 
L 1.46931998 -2.00066004 1.47091004 -2.00206998 0 P 0 
L 1.47091004 -2.00206998 1.47238996 -2.00358996 0 P 0 
L 1.47238996 -2.00358996 1.4737 -2.00515 0 P 0 
L 1.4737 -2.00515 1.47488002 -2.00678996 0 P 0 
L 1.47488002 -2.00678996 1.47593996 -2.00851004 0 P 0 
L 1.47593996 -2.00851004 1.47686004 -2.01031004 0 P 0 
L 1.47686004 -2.01031004 1.47763996 -2.01216998 0 P 0 
L 1.47763996 -2.01216998 1.47851998 -2.01481004 0 P 0 
L 1.47851998 -2.01481004 1.47918996 -2.01748996 0 P 0 
L 1.47918996 -2.01748996 1.47966004 -2.02021998 0 P 0 
L 1.47966004 -2.02021998 1.47993002 -2.02296998 0 P 0 
L 1.47993002 -2.02296998 1.48001998 -2.02783996 0 P 0 
L 1.48001998 -2.02783996 1.47975 -2.03868996 0 P 0 
L 1.47975 -2.03868996 1.4793 -2.05161004 0 P 0 
L 1.4793 -2.05161004 1.47866004 -2.06543002 0 P 0 
L 1.47866004 -2.06543002 1.47801004 -2.07961004 0 P 0 
L 1.47801004 -2.07961004 1.47743996 -2.09378996 0 P 0 
L 1.47743996 -2.09378996 1.47705 -2.10613002 0 P 0 
L 1.47705 -2.10613002 1.47693002 -2.11356004 0 P 0 
L 1.47693002 -2.11356004 1.47693002 -2.12516004 0 P 0 
L 1.47693002 -2.12516004 1.42661004 -2.12516004 0 P 0 
L 1.42661004 -2.12516004 1.42661004 -2.12473996 0 P 0 
L 1.42661004 -2.12473996 1.42666004 -2.12318002 0 P 0 
L 1.42666004 -2.12318002 1.42691004 -2.11863996 0 P 0 
L 1.42691004 -2.11863996 1.42725 -2.1132 0 P 0 
L 1.42725 -2.1132 1.42766004 -2.1072 0 P 0 
L 1.42766004 -2.1072 1.42766004 -2.10718996 0 P 0 
L 1.42766004 -2.10718996 1.4281 -2.10068996 0 P 0 
L 1.4281 -2.10068996 1.42858002 -2.09368002 0 P 0 
L 1.42858002 -2.09368002 1.42901004 -2.08721004 0 P 0 
L 1.42901004 -2.08721004 1.42901004 -2.0872 0 P 0 
L 1.42901004 -2.0872 1.42931004 -2.08256004 0 P 0 
L 1.42931004 -2.08256004 1.42991998 -2.07308002 0 P 0 
L 1.42991998 -2.07308002 1.42916004 -2.07136998 0 P 0 
L 1.42916004 -2.07136998 1.42731998 -2.07105 0 P 0 
L 1.42731998 -2.07105 1.42105 -2.07303996 0 P 0 
L 1.42105 -2.07303996 1.41815 -2.07393002 0 P 0 
L 1.41815 -2.07393002 1.41451004 -2.075 0 P 0 
L 1.41451004 -2.075 1.41076004 -2.07603002 0 P 0 
L 1.41076004 -2.07603002 1.40748002 -2.0769 0 P 0 
L 1.40748002 -2.0769 1.40438996 -2.07781004 0 P 0 
L 1.40438996 -2.07781004 1.40431998 -2.07783996 0 P 0 
L 1.40431998 -2.07783996 1.40133996 -2.07896998 0 P 0 
L 1.40133996 -2.07896998 1.40005 -2.07956998 0 P 0 
L 1.40005 -2.07956998 1.39881998 -2.08026004 0 P 0 
L 1.39881998 -2.08026004 1.39763996 -2.08103002 0 P 0 
L 1.39763996 -2.08103002 1.39651998 -2.08188002 0 P 0 
L 1.39651998 -2.08188002 1.39578996 -2.08251004 0 P 0 
L 1.39578996 -2.08251004 1.39573996 -2.08256004 0 P 0 
L 1.39573996 -2.08256004 1.3951 -2.08318996 0 P 0 
L 1.3951 -2.08318996 1.39446998 -2.08393002 0 P 0 
L 1.39446998 -2.08393002 1.3939 -2.08471004 0 P 0 
L 1.3939 -2.08471004 1.39336998 -2.08553996 0 P 0 
L 1.39336998 -2.08553996 1.39301004 -2.08623996 0 P 0 
L 1.39301004 -2.08623996 1.39271004 -2.08696998 0 P 0 
L 1.39271004 -2.08696998 1.39248002 -2.08771998 0 P 0 
L 1.39248002 -2.08771998 1.39231004 -2.08848996 0 P 0 
L 1.39231004 -2.08848996 1.39221004 -2.08926004 0 P 0 
L 1.39221004 -2.08926004 1.39218002 -2.09003996 0 P 0 
L 1.39218002 -2.09003996 1.39221004 -2.0908 0 P 0 
L 1.39221004 -2.0908 1.39231004 -2.09153002 0 P 0 
L 1.39231004 -2.09153002 1.39246998 -2.09226004 0 P 0 
L 1.39246998 -2.09226004 1.39268996 -2.09296998 0 P 0 
L 1.39268996 -2.09296998 1.39296004 -2.09365 0 P 0 
L 1.39296004 -2.09365 1.3933 -2.09431004 0 P 0 
L 1.3933 -2.09431004 1.39368996 -2.09493996 0 P 0 
L 1.39368996 -2.09493996 1.39411998 -2.09553996 0 P 0 
L 1.39411998 -2.09553996 1.39468996 -2.09618002 0 P 0 
L 1.39468996 -2.09618002 1.3953 -2.09678002 0 P 0 
L 1.3953 -2.09678002 1.39596004 -2.09731998 0 P 0 
L 1.39596004 -2.09731998 1.39666998 -2.0978 0 P 0 
L 1.39666998 -2.0978 1.39673996 -2.09783996 0 P 0 
L 1.39673996 -2.09783996 1.39741004 -2.09821998 0 P 0 
L 1.39741004 -2.09821998 1.39748996 -2.09825 0 P 0 
L 1.39748996 -2.09825 1.39818996 -2.09856998 0 P 0 
L 1.39818996 -2.09856998 1.39898996 -2.09886004 0 P 0 
L 1.39898996 -2.09886004 1.39906998 -2.09888002 0 P 0 
L 1.39906998 -2.09888002 1.40043996 -2.09888002 0 P 0 
L 1.40043996 -2.09888002 1.40033996 -2.09923002 0 P 0 
L 1.40033996 -2.09923002 1.40041998 -2.09925 0 P 0 
L 1.40041998 -2.09925 1.40186004 -2.09953002 0 P 0 
L 1.40186004 -2.09953002 1.40331004 -2.09971004 0 P 0 
L 1.40331004 -2.09971004 1.40478002 -2.09978002 0 P 0 
L 1.40478002 -2.09978002 1.40625 -2.09975 0 P 0 
L 1.40625 -2.09975 1.41096004 -2.09931004 0 P 0 
L 1.41096004 -2.09931004 1.41556998 -2.09855 0 P 0 
L 1.41556998 -2.09855 1.41791998 -2.09813002 0 P 0 
L 1.41791998 -2.09813002 1.41995 -2.09791004 0 P 0 
L 1.41995 -2.09791004 1.4201 -2.0979 0 P 0 
L 1.4201 -2.0979 1.41941004 -2.10078002 0 P 0 
L 1.41941004 -2.10078002 1.41761004 -2.10745 0 P 0 
L 1.41761004 -2.10745 1.41391004 -2.12025 0 P 0 
L 1.41391004 -2.12025 1.41215 -2.12626998 0 P 0 
L 1.41215 -2.12626998 1.40655 -2.12725 0 P 0 
L 1.40655 -2.12725 1.40046004 -2.12808002 0 P 0 
L 1.40046004 -2.12808002 1.39438002 -2.12845 0 P 0 
L 1.15303002 -2.08283002 1.20788996 -2.08283002 0 P 0 
L 1.15398996 -2.08183002 1.20795 -2.08183002 0 P 0 
L 1.15483002 -2.08083002 1.208 -2.08083002 0 P 0 
L 1.15555 -2.07983002 1.20805 -2.07983002 0 P 0 
L 1.15621998 -2.07883002 1.2081 -2.07883002 0 P 0 
L 1.15681998 -2.07783002 1.20816004 -2.07783002 0 P 0 
L 1.15733002 -2.07683002 1.20821004 -2.07683002 0 P 0 
L 1.15778996 -2.07583002 1.20826004 -2.07583002 0 P 0 
L 1.15818002 -2.07483002 1.20831004 -2.07483002 0 P 0 
L 1.15853996 -2.07383002 1.20836998 -2.07383002 0 P 0 
L 1.15881998 -2.07283002 1.20841998 -2.07283002 0 P 0 
L 1.1591 -2.07183002 1.20846998 -2.07183002 0 P 0 
L 1.15938002 -2.07083002 1.20853002 -2.07083002 0 P 0 
L 1.1596 -2.06983002 1.20858002 -2.06983002 0 P 0 
L 1.15981004 -2.06883002 1.20863996 -2.06883002 0 P 0 
L 1.16001004 -2.06783002 1.20868996 -2.06783002 0 P 0 
L 1.1602 -2.06683002 1.20875 -2.06683002 0 P 0 
L 1.16033996 -2.06583002 1.2088 -2.06583002 0 P 0 
L 1.16048996 -2.06483002 1.20886004 -2.06483002 0 P 0 
L 1.16063996 -2.06383002 1.20891998 -2.06383002 0 P 0 
L 1.16078002 -2.06283002 1.20896998 -2.06283002 0 P 0 
L 1.16088996 -2.06183002 1.20903002 -2.06183002 0 P 0 
L 1.16098996 -2.06083002 1.20908002 -2.06083002 0 P 0 
L 1.16108996 -2.05983002 1.20913996 -2.05983002 0 P 0 
L 1.16118002 -2.05883002 1.20918996 -2.05883002 0 P 0 
L 1.16128002 -2.05783002 1.20925 -2.05783002 0 P 0 
L 1.16133996 -2.05683002 1.2093 -2.05683002 0 P 0 
L 1.1614 -2.05583002 1.20936004 -2.05583002 0 P 0 
L 1.16146004 -2.05483002 1.20941004 -2.05483002 0 P 0 
L 1.16151998 -2.05383002 1.20946998 -2.05383002 0 P 0 
L 1.16158002 -2.05283002 1.20951998 -2.05283002 0 P 0 
L 1.16163996 -2.05183002 1.20958002 -2.05183002 0 P 0 
L 1.1617 -2.05083002 1.20963996 -2.05083002 0 P 0 
L 1.16175 -2.04983002 1.2097 -2.04983002 0 P 0 
L 1.16181004 -2.04883002 1.20975 -2.04883002 0 P 0 
L 1.16186998 -2.04783002 1.20981004 -2.04783002 0 P 0 
L 1.16193002 -2.04683002 1.20986998 -2.04683002 0 P 0 
L 1.16198996 -2.04583002 1.20993002 -2.04583002 0 P 0 
L 1.16205 -2.04483002 1.20998996 -2.04483002 0 P 0 
L 1.16211004 -2.04383002 1.21005 -2.04383002 0 P 0 
L 1.16215 -2.04283002 1.2101 -2.04283002 0 P 0 
L 1.1622 -2.04183002 1.21016004 -2.04183002 0 P 0 
L 1.16225 -2.04083002 1.21021998 -2.04083002 0 P 0 
L 1.16228996 -2.03983002 1.21028002 -2.03983002 0 P 0 
L 1.16233996 -2.03883002 1.21033996 -2.03883002 0 P 0 
L 1.16238002 -2.03783002 1.2104 -2.03783002 0 P 0 
L 1.16243002 -2.03683002 1.21046004 -2.03683002 0 P 0 
L 1.16246998 -2.03583002 1.21051004 -2.03583002 0 P 0 
L 1.16251998 -2.03483002 1.21056998 -2.03483002 0 P 0 
L 1.16256998 -2.03383002 1.21063996 -2.03383002 0 P 0 
L 1.16261004 -2.03283002 1.2107 -2.03283002 0 P 0 
L 1.16266004 -2.03183002 1.21076004 -2.03183002 0 P 0 
L 1.1627 -2.03083002 1.21083002 -2.03083002 0 P 0 
L 1.16015 -1.97631004 1.17066004 -1.97631004 0 P 0 
L 1.15961998 -1.97531004 1.17026004 -1.97531004 0 P 0 
L 1.1591 -1.97431004 1.16986998 -1.97431004 0 P 0 
L 1.15856998 -1.97331004 1.16946998 -1.97331004 0 P 0 
L 1.15803996 -1.97231004 1.16903002 -1.97231004 0 P 0 
L 1.15746998 -1.97131004 1.16858996 -1.97131004 0 P 0 
L 1.1569 -1.97031004 1.16815 -1.97031004 0 P 0 
L 1.15631998 -1.96931004 1.16771004 -1.96931004 0 P 0 
L 1.15573996 -1.96831004 1.16726998 -1.96831004 0 P 0 
L 1.15516004 -1.96731004 1.16681998 -1.96731004 0 P 0 
L 1.15458996 -1.96631004 1.16638002 -1.96631004 0 P 0 
L 1.15398002 -1.96531004 1.16593996 -1.96531004 0 P 0 
L 1.1533 -1.96431004 1.16548996 -1.96431004 0 P 0 
L 1.15261998 -1.96331004 1.16503002 -1.96331004 0 P 0 
L 1.15193996 -1.96231004 1.16448002 -1.96231004 0 P 0 
L 1.15126004 -1.96131004 1.16393002 -1.96131004 0 P 0 
L 1.15058002 -1.96031004 1.16338002 -1.96031004 0 P 0 
L 1.1499 -1.95931004 1.16283002 -1.95931004 0 P 0 
L 1.1491 -1.95831004 1.16228996 -1.95831004 0 P 0 
L 1.14831004 -1.95731004 1.16173996 -1.95731004 0 P 0 
L 1.14751004 -1.95631004 1.16118996 -1.95631004 0 P 0 
L 1.14671004 -1.95531004 1.16063996 -1.95531004 0 P 0 
L 1.14591998 -1.95431004 1.16008996 -1.95431004 0 P 0 
L 1.14511998 -1.95331004 1.15943996 -1.95331004 0 P 0 
L 1.1442 -1.95231004 1.15878002 -1.95231004 0 P 0 
L 1.14326998 -1.95131004 1.15811004 -1.95131004 0 P 0 
L 1.14233996 -1.95031004 1.15745 -1.95031004 0 P 0 
L 1.14141004 -1.94931004 1.15678002 -1.94931004 0 P 0 
L 1.14048996 -1.94831004 1.15611998 -1.94831004 0 P 0 
L 1.1395 -1.94731004 1.15545 -1.94731004 0 P 0 
L 1.13843002 -1.94631004 1.15478996 -1.94631004 0 P 0 
L 1.13736004 -1.94531004 1.15411998 -1.94531004 0 P 0 
L 1.13628996 -1.94431004 1.15333002 -1.94431004 0 P 0 
L 1.13521004 -1.94331004 1.15253002 -1.94331004 0 P 0 
L 1.13413996 -1.94231004 1.15173996 -1.94231004 0 P 0 
L 1.13306998 -1.94131004 1.15093996 -1.94131004 0 P 0 
L 1.132 -1.94031004 1.15013996 -1.94031004 0 P 0 
L 1.13081004 -1.93931004 1.14935 -1.93931004 0 P 0 
L 1.12958002 -1.93831004 1.14855 -1.93831004 0 P 0 
L 1.12833996 -1.93731004 1.14775 -1.93731004 0 P 0 
L 1.1271 -1.93631004 1.14688996 -1.93631004 0 P 0 
L 1.12586004 -1.93531004 1.14593996 -1.93531004 0 P 0 
L 1.12461998 -1.93431004 1.14498996 -1.93431004 0 P 0 
L 1.12338002 -1.93331004 1.14405 -1.93331004 0 P 0 
L 1.12203002 -1.93231004 1.1431 -1.93231004 0 P 0 
L 1.1206 -1.93131004 1.14216004 -1.93131004 0 P 0 
L 1.11916004 -1.93031004 1.14121004 -1.93031004 0 P 0 
L 1.11771998 -1.92931004 1.14026998 -1.92931004 0 P 0 
L 1.11628996 -1.92831004 1.13931998 -1.92831004 0 P 0 
L 1.11483996 -1.92731004 1.13838002 -1.92731004 0 P 0 
L 1.11338996 -1.92631004 1.13743002 -1.92631004 0 P 0 
L 1.11171998 -1.92531004 1.13648996 -1.92531004 0 P 0 
L 1.11005 -1.92431004 1.13538002 -1.92431004 0 P 0 
L 1.10838002 -1.92331004 1.13426998 -1.92331004 0 P 0 
L 1.1067 -1.92231004 1.13315 -1.92231004 0 P 0 
L 1.10503002 -1.92131004 1.13203002 -1.92131004 0 P 0 
L 1.10336004 -1.92031004 1.13091998 -1.92031004 0 P 0 
L 1.1015 -1.91931004 1.1298 -1.91931004 0 P 0 
L 1.09955 -1.91831004 1.12868002 -1.91831004 0 P 0 
L 1.16275 -2.02983002 1.21088996 -2.02983002 0 P 0 
L 1.16278996 -2.02883002 1.21095 -2.02883002 0 P 0 
L 1.16283996 -2.02783002 1.21101004 -2.02783002 0 P 0 
L 1.16226998 -2.02683002 1.21108002 -2.02683002 0 P 0 
L 1.16153996 -2.02583002 1.21113996 -2.02583002 0 P 0 
L 1.15846004 -2.02483002 1.2112 -2.02483002 0 P 0 
L 1.10036004 -2.00383002 1.21255 -2.00383002 0 P 0 
L 1.10226004 -2.00283002 1.2126 -2.00283002 0 P 0 
L 1.10433996 -2.00183002 1.21266998 -2.00183002 0 P 0 
L 1.1065 -2.00083002 1.21273002 -2.00083002 0 P 0 
L 1.10886998 -1.99983002 1.21278996 -1.99983002 0 P 0 
L 1.11138002 -1.99883002 1.21285 -1.99883002 0 P 0 
L 1.11436998 -1.99783002 1.21288002 -1.99783002 0 P 0 
L 1.11748996 -1.99683002 1.21255 -1.99683002 0 P 0 
L 1.12061998 -1.99583002 1.2089 -1.99583002 0 P 0 
L 1.12433996 -1.99483002 1.2036 -1.99483002 0 P 0 
L 1.12863996 -1.99383002 1.19728002 -1.99383002 0 P 0 
L 1.13295 -1.99283002 1.19096998 -1.99283002 0 P 0 
L 1.13985 -1.99183002 1.18111998 -1.99183002 0 P 0 
L 1.14948002 -1.99083002 1.1651 -1.99083002 0 P 0 
L 1.24218002 -2.08316004 1.29143996 -2.08316004 0 P 0 
L 1.24223002 -2.08216004 1.29151004 -2.08216004 0 P 0 
L 1.24228002 -2.08116004 1.29158996 -2.08116004 0 P 0 
L 1.24233996 -2.08016004 1.29166004 -2.08016004 0 P 0 
L 1.24238996 -2.07916004 1.29173002 -2.07916004 0 P 0 
L 1.24245 -2.07816004 1.29181004 -2.07816004 0 P 0 
L 1.2425 -2.07716004 1.29188002 -2.07716004 0 P 0 
L 1.24256004 -2.07616004 1.29195 -2.07616004 0 P 0 
L 1.24261004 -2.07516004 1.29203002 -2.07516004 0 P 0 
L 1.24266998 -2.07416004 1.2921 -2.07416004 0 P 0 
L 1.24271998 -2.07316004 1.29216998 -2.07316004 0 P 0 
L 1.24278002 -2.07216004 1.29223996 -2.07216004 0 P 0 
L 1.24283002 -2.07116004 1.29231998 -2.07116004 0 P 0 
L 1.24288002 -2.07016004 1.29238996 -2.07016004 0 P 0 
L 1.24293002 -2.06916004 1.29246004 -2.06916004 0 P 0 
L 1.24296998 -2.06816004 1.29253002 -2.06816004 0 P 0 
L 1.24301998 -2.06716004 1.29261004 -2.06716004 0 P 0 
L 1.24306004 -2.06616004 1.2927 -2.06616004 0 P 0 
L 1.24311004 -2.06516004 1.29281004 -2.06516004 0 P 0 
L 1.24315 -2.06416004 1.29291998 -2.06416004 0 P 0 
L 1.2432 -2.06316004 1.29303002 -2.06316004 0 P 0 
L 1.24323996 -2.06216004 1.29315 -2.06216004 0 P 0 
L 1.24328996 -2.06116004 1.29331998 -2.06116004 0 P 0 
L 1.24333002 -2.06016004 1.2935 -2.06016004 0 P 0 
L 1.24338002 -2.05916004 1.29366998 -2.05916004 0 P 0 
L 1.24341998 -2.05816004 1.29385 -2.05816004 0 P 0 
L 1.24346998 -2.05716004 1.29408996 -2.05716004 0 P 0 
L 1.24351004 -2.05616004 1.29433996 -2.05616004 0 P 0 
L 1.24355 -2.05516004 1.29458996 -2.05516004 0 P 0 
L 1.2436 -2.05416004 1.29485 -2.05416004 0 P 0 
L 1.24363996 -2.05316004 1.29516998 -2.05316004 0 P 0 
L 1.24368996 -2.05216004 1.29551998 -2.05216004 0 P 0 
L 1.24373002 -2.05116004 1.29586004 -2.05116004 0 P 0 
L 1.24378002 -2.05016004 1.29621004 -2.05016004 0 P 0 
L 1.24383002 -2.04916004 1.29663996 -2.04916004 0 P 0 
L 1.24386998 -2.04816004 1.29708002 -2.04816004 0 P 0 
L 1.24391004 -2.04716004 1.29753002 -2.04716004 0 P 0 
L 1.24396004 -2.04616004 1.29796998 -2.04616004 0 P 0 
L 1.244 -2.04516004 1.29851004 -2.04516004 0 P 0 
L 1.24405 -2.04416004 1.2991 -2.04416004 0 P 0 
L 1.24408996 -2.04316004 1.29975 -2.04316004 0 P 0 
L 1.24413996 -2.04216004 1.3005 -2.04216004 0 P 0 
L 1.24418002 -2.04116004 1.30131998 -2.04116004 0 P 0 
L 1.24423002 -2.04016004 1.30223002 -2.04016004 0 P 0 
L 1.24426998 -2.03916004 1.30326998 -2.03916004 0 P 0 
L 1.24431998 -2.03816004 1.30446004 -2.03816004 0 P 0 
L 1.24436004 -2.03716004 1.30581998 -2.03716004 0 P 0 
L 1.24441004 -2.03616004 1.30738002 -2.03616004 0 P 0 
L 1.24445 -2.03516004 1.30923002 -2.03516004 0 P 0 
L 1.24448996 -2.03416004 1.31156004 -2.03416004 0 P 0 
L 1.24453996 -2.03316004 1.31478996 -2.03316004 0 P 0 
L 1.24458996 -2.03216004 1.32013002 -2.03216004 0 P 0 
L 1.24461998 -2.03116004 1.33481004 -2.03116004 0 P 0 
L 1.24463996 -2.03016004 1.33478002 -2.03016004 0 P 0 
L 1.24466004 -2.02916004 1.33473996 -2.02916004 0 P 0 
L 1.24468002 -2.02816004 1.33471004 -2.02816004 0 P 0 
L 1.2447 -2.02716004 1.33468002 -2.02716004 0 P 0 
L 1.24471998 -2.02616004 1.33463996 -2.02616004 0 P 0 
L 1.24473996 -2.02516004 1.3346 -2.02516004 0 P 0 
L 1.24476004 -2.02416004 1.33456998 -2.02416004 0 P 0 
L 1.24478002 -2.02316004 1.33453002 -2.02316004 0 P 0 
L 1.2448 -2.02216004 1.3345 -2.02216004 0 P 0 
L 1.24481998 -2.02116004 1.33446998 -2.02116004 0 P 0 
L 1.24483996 -2.02016004 1.33443002 -2.02016004 0 P 0 
L 1.24486004 -2.01916004 1.3344 -2.01916004 0 P 0 
L 1.24488002 -2.01816004 1.33436004 -2.01816004 0 P 0 
L 1.2449 -2.01716004 1.33433002 -2.01716004 0 P 0 
L 1.24491998 -2.01616004 1.33428996 -2.01616004 0 P 0 
L 1.24493996 -2.01516004 1.33426004 -2.01516004 0 P 0 
L 1.24496004 -2.01416004 1.33421998 -2.01416004 0 P 0 
L 1.24498002 -2.01316004 1.33418996 -2.01316004 0 P 0 
L 1.245 -2.01216004 1.33415 -2.01216004 0 P 0 
L 1.24501998 -2.01116004 1.33411998 -2.01116004 0 P 0 
L 1.24503996 -2.01016004 1.33408002 -2.01016004 0 P 0 
L 1.24506004 -2.00916004 1.33403996 -2.00916004 0 P 0 
L 1.24508002 -2.00816004 1.334 -2.00816004 0 P 0 
L 1.2451 -2.00716004 1.33396004 -2.00716004 0 P 0 
L 1.24511998 -2.00616004 1.33393002 -2.00616004 0 P 0 
L 1.24513996 -2.00516004 1.29098996 -2.00516004 0 P 0 
L 1.24513996 -2.00416004 1.29033002 -2.00416004 0 P 0 
L 1.24513996 -2.00316004 1.29005 -2.00316004 0 P 0 
L 1.24513996 -2.00216004 1.29005 -2.00216004 0 P 0 
L 1.24513996 -2.00116004 1.29005 -2.00116004 0 P 0 
L 1.24515 -2.00016004 1.29005 -2.00016004 0 P 0 
L 1.24515 -1.99916004 1.29005 -1.99916004 0 P 0 
L 1.24515 -1.99816004 1.29005 -1.99816004 0 P 0 
L 1.24515 -1.99716004 1.29005 -1.99716004 0 P 0 
L 1.24515 -1.99616004 1.29005 -1.99616004 0 P 0 
L 1.24515 -1.99516004 1.29005 -1.99516004 0 P 0 
L 1.16085 -2.02753002 1.1601 -2.04393002 0 P 0 
L 1.1601 -2.04393002 1.15928996 -2.05771998 0 P 0 
L 1.15928996 -2.05771998 1.15883996 -2.06228002 0 P 0 
L 1.15883996 -2.06228002 1.15818002 -2.06681998 0 P 0 
L 1.15818002 -2.06681998 1.15751004 -2.07006998 0 P 0 
L 1.15751004 -2.07006998 1.15661004 -2.07328996 0 P 0 
L 1.15661004 -2.07328996 1.15616004 -2.07453996 0 P 0 
L 1.15616004 -2.07453996 1.15563002 -2.07576998 0 P 0 
L 1.15563002 -2.07576998 1.15501998 -2.07696004 0 P 0 
L 1.15501998 -2.07696004 1.15433002 -2.0781 0 P 0 
L 1.15433002 -2.0781 1.1534 -2.07941998 0 P 0 
L 1.1534 -2.07941998 1.15236004 -2.08066004 0 P 0 
L 1.15236004 -2.08066004 1.15123002 -2.08181998 0 P 0 
L 1.15123002 -2.08181998 1.15001004 -2.08286998 0 P 0 
L 1.15001004 -2.08286998 1.14871004 -2.08383002 0 P 0 
L 1.14871004 -2.08383002 1.14733002 -2.08468002 0 P 0 
L 1.14733002 -2.08468002 1.14591004 -2.0854 0 P 0 
L 1.14591004 -2.0854 1.14443996 -2.086 0 P 0 
L 1.14443996 -2.086 1.14291004 -2.08648002 0 P 0 
L 1.14291004 -2.08648002 1.14136004 -2.08683002 0 P 0 
L 1.14136004 -2.08683002 1.13976998 -2.08703996 0 P 0 
L 1.13976998 -2.08703996 1.13816004 -2.08713002 0 P 0 
L 1.13816004 -2.08713002 1.13656998 -2.08708002 0 P 0 
L 1.13656998 -2.08708002 1.13498996 -2.0869 0 P 0 
L 1.13498996 -2.0869 1.13341998 -2.08658996 0 P 0 
L 1.13341998 -2.08658996 1.13188996 -2.08615 0 P 0 
L 1.13188996 -2.08615 1.1304 -2.08558996 0 P 0 
L 1.1304 -2.08558996 1.12895 -2.08488996 0 P 0 
L 1.12895 -2.08488996 1.12756998 -2.08408002 0 P 0 
L 1.12756998 -2.08408002 1.12625 -2.08315 0 P 0 
L 1.12625 -2.08315 1.12501004 -2.08211998 0 P 0 
L 1.12501004 -2.08211998 1.12386004 -2.081 0 P 0 
L 1.12386004 -2.081 1.12281004 -2.07978002 0 P 0 
L 1.12281004 -2.07978002 1.12183996 -2.07846998 0 P 0 
L 1.12183996 -2.07846998 1.1211 -2.07726004 0 P 0 
L 1.1211 -2.07726004 1.12046998 -2.07598996 0 P 0 
L 1.12046998 -2.07598996 1.11996004 -2.07466998 0 P 0 
L 1.11996004 -2.07466998 1.11955 -2.07331004 0 P 0 
L 1.11955 -2.07331004 1.11926998 -2.07191004 0 P 0 
L 1.11926998 -2.07191004 1.11868002 -2.06693996 0 P 0 
L 1.11868002 -2.06693996 1.11848002 -2.06191004 0 P 0 
L 1.11848002 -2.06191004 1.11871004 -2.05668002 0 P 0 
L 1.11871004 -2.05668002 1.11936004 -2.05148002 0 P 0 
L 1.11936004 -2.05148002 1.11978996 -2.04936998 0 P 0 
L 1.11978996 -2.04936998 1.12036998 -2.0473 0 P 0 
L 1.12036998 -2.0473 1.12108996 -2.04528002 0 P 0 
L 1.12108996 -2.04528002 1.12196004 -2.04331998 0 P 0 
L 1.12196004 -2.04331998 1.1229 -2.04153996 0 P 0 
L 1.1229 -2.04153996 1.12396998 -2.03985 0 P 0 
L 1.12396998 -2.03985 1.12516998 -2.03823002 0 P 0 
L 1.12516998 -2.03823002 1.12735 -2.03573996 0 P 0 
L 1.12735 -2.03573996 1.12973002 -2.03345 0 P 0 
L 1.12973002 -2.03345 1.13223996 -2.03141998 0 P 0 
L 1.13223996 -2.03141998 1.13491998 -2.02961004 0 P 0 
L 1.13491998 -2.02961004 1.13611004 -2.02893002 0 P 0 
L 1.13611004 -2.02893002 1.13735 -2.02833996 0 P 0 
L 1.13735 -2.02833996 1.13861998 -2.02781998 0 P 0 
L 1.13861998 -2.02781998 1.13993996 -2.0274 0 P 0 
L 1.13993996 -2.0274 1.14191004 -2.02693002 0 P 0 
L 1.14191004 -2.02693002 1.14391004 -2.02663002 0 P 0 
L 1.14391004 -2.02663002 1.14935 -2.02626004 0 P 0 
L 1.14935 -2.02626004 1.15471004 -2.0263 0 P 0 
L 1.15471004 -2.0263 1.15591004 -2.02638996 0 P 0 
L 1.15591004 -2.02638996 1.1571 -2.02656998 0 P 0 
L 1.1571 -2.02656998 1.15828002 -2.02683996 0 P 0 
L 1.15828002 -2.02683996 1.16085 -2.02753002 0 P 0 
L 1.13876998 -2.14783002 1.20233002 -2.14783002 0 P 0 
L 1.14236998 -2.14683002 1.20266004 -2.14683002 0 P 0 
L 1.14481004 -2.14583002 1.20296004 -2.14583002 0 P 0 
L 1.1467 -2.14483002 1.20325 -2.14483002 0 P 0 
L 1.14826004 -2.14383002 1.20353002 -2.14383002 0 P 0 
L 1.1496 -2.14283002 1.20373996 -2.14283002 0 P 0 
L 1.15078996 -2.14183002 1.20395 -2.14183002 0 P 0 
L 1.15186004 -2.14083002 1.20415 -2.14083002 0 P 0 
L 1.15278996 -2.13983002 1.20431998 -2.13983002 0 P 0 
L 1.15361998 -2.13883002 1.20446004 -2.13883002 0 P 0 
L 1.15436004 -2.13783002 1.20458002 -2.13783002 0 P 0 
L 1.155 -2.13683002 1.20466998 -2.13683002 0 P 0 
L 1.15556998 -2.13583002 1.20475 -2.13583002 0 P 0 
L 1.15608996 -2.13483002 1.20481998 -2.13483002 0 P 0 
L 1.15653996 -2.13383002 1.20488996 -2.13383002 0 P 0 
L 1.15691004 -2.13283002 1.20496004 -2.13283002 0 P 0 
L 1.15723996 -2.13183002 1.20503002 -2.13183002 0 P 0 
L 1.15751998 -2.13083002 1.2051 -2.13083002 0 P 0 
L 1.15773002 -2.12983002 1.20516004 -2.12983002 0 P 0 
L 1.15793002 -2.12883002 1.20523002 -2.12883002 0 P 0 
L 1.15806004 -2.12783002 1.2053 -2.12783002 0 P 0 
L 1.15816998 -2.12683002 1.20536998 -2.12683002 0 P 0 
L 1.15821004 -2.12583002 1.20543996 -2.12583002 0 P 0 
L 1.11716004 -2.12483002 1.12726004 -2.12483002 0 P 0 
L 1.15823996 -2.12483002 1.20551004 -2.12483002 0 P 0 
L 1.10911998 -2.12383002 1.1352 -2.12383002 0 P 0 
L 1.15821998 -2.12383002 1.20556998 -2.12383002 0 P 0 
L 1.10468996 -2.12283002 1.14018996 -2.12283002 0 P 0 
L 1.1582 -2.12283002 1.20563996 -2.12283002 0 P 0 
L 1.10131004 -2.12183002 1.14366998 -2.12183002 0 P 0 
L 1.15818002 -2.12183002 1.2057 -2.12183002 0 P 0 
L 1.15808996 -2.12083002 1.20576004 -2.12083002 0 P 0 
L 1.15781004 -2.11983002 1.20583002 -2.11983002 0 P 0 
L 1.15721004 -2.11883002 1.20588002 -2.11883002 0 P 0 
L 1.14146004 -2.08883002 1.20758002 -2.08883002 0 P 0 
L 1.14525 -2.08783002 1.20763002 -2.08783002 0 P 0 
L 1.14751004 -2.08683002 1.20768002 -2.08683002 0 P 0 
L 1.14928002 -2.08583002 1.20773002 -2.08583002 0 P 0 
L 1.15073002 -2.08483002 1.20778996 -2.08483002 0 P 0 
L 1.15196004 -2.08383002 1.20783996 -2.08383002 0 P 0 
L 1.13818996 -2.08913002 1.13826998 -2.08913002 0 P 0 
L 1.13826998 -2.08913002 1.13988002 -2.08903996 0 P 0 
L 1.13988002 -2.08903996 1.13996004 -2.08903996 0 P 0 
L 1.13996004 -2.08903996 1.14001004 -2.08903002 0 P 0 
L 1.14001004 -2.08903002 1.14005 -2.08901998 0 P 0 
L 1.14005 -2.08901998 1.14163002 -2.08881004 0 P 0 
L 1.14163002 -2.08881004 1.14166998 -2.0888 0 P 0 
L 1.14166998 -2.0888 1.14171004 -2.0888 0 P 0 
L 1.14171004 -2.0888 1.14178996 -2.08878002 0 P 0 
L 1.14178996 -2.08878002 1.14335 -2.08843002 0 P 0 
L 1.14335 -2.08843002 1.14351004 -2.08838996 0 P 0 
L 1.14351004 -2.08838996 1.14503002 -2.08791004 0 P 0 
L 1.14503002 -2.08791004 1.14511004 -2.08788996 0 P 0 
L 1.14511004 -2.08788996 1.14515 -2.08786998 0 P 0 
L 1.14515 -2.08786998 1.14518996 -2.08786004 0 P 0 
L 1.14518996 -2.08786004 1.14666004 -2.08725 0 P 0 
L 1.14666004 -2.08725 1.14673996 -2.08721998 0 P 0 
L 1.14673996 -2.08721998 1.14678002 -2.0872 0 P 0 
L 1.14678002 -2.0872 1.14681998 -2.08718996 0 P 0 
L 1.14681998 -2.08718996 1.14823996 -2.08646998 0 P 0 
L 1.14823996 -2.08646998 1.14826998 -2.08645 0 P 0 
L 1.14826998 -2.08645 1.14835 -2.08641004 0 P 0 
L 1.14835 -2.08641004 1.14838002 -2.08638002 0 P 0 
L 1.14838002 -2.08638002 1.14976004 -2.08553002 0 P 0 
L 1.14976004 -2.08553002 1.14978996 -2.08551004 0 P 0 
L 1.14978996 -2.08551004 1.14983002 -2.08548996 0 P 0 
L 1.14983002 -2.08548996 1.14988996 -2.08543996 0 P 0 
L 1.14988996 -2.08543996 1.1512 -2.08448996 0 P 0 
L 1.1512 -2.08448996 1.15126004 -2.08443996 0 P 0 
L 1.15126004 -2.08443996 1.15128996 -2.08441004 0 P 0 
L 1.15128996 -2.08441004 1.15131998 -2.08438996 0 P 0 
L 1.15131998 -2.08438996 1.15253996 -2.08333002 0 P 0 
L 1.15253996 -2.08333002 1.15256998 -2.0833 0 P 0 
L 1.15256998 -2.0833 1.1526 -2.08328002 0 P 0 
L 1.1526 -2.08328002 1.15263002 -2.08323996 0 P 0 
L 1.15263002 -2.08323996 1.15266004 -2.08321998 0 P 0 
L 1.15266004 -2.08321998 1.15378996 -2.08206004 0 P 0 
L 1.15378996 -2.08206004 1.15376004 -2.08203996 0 P 0 
L 1.15376004 -2.08203996 1.15381998 -2.08203996 0 P 0 
L 1.15381998 -2.08203996 1.15383996 -2.082 0 P 0 
L 1.15383996 -2.082 1.15386998 -2.08196998 0 P 0 
L 1.15386998 -2.08196998 1.1539 -2.08195 0 P 0 
L 1.1539 -2.08195 1.15493002 -2.08071004 0 P 0 
L 1.15493002 -2.08071004 1.15493002 -2.0807 0 P 0 
L 1.15493002 -2.0807 1.15496004 -2.08066998 0 P 0 
L 1.15496004 -2.08066998 1.15498002 -2.08063996 0 P 0 
L 1.15498002 -2.08063996 1.15501004 -2.08061004 0 P 0 
L 1.15501004 -2.08061004 1.15503002 -2.08058002 0 P 0 
L 1.15503002 -2.08058002 1.15596004 -2.07926004 0 P 0 
L 1.15596004 -2.07926004 1.15603996 -2.07913996 0 P 0 
L 1.15603996 -2.07913996 1.15673002 -2.07798996 0 P 0 
L 1.15673002 -2.07798996 1.15676998 -2.07793002 0 P 0 
L 1.15676998 -2.07793002 1.15678996 -2.07786998 0 P 0 
L 1.15678996 -2.07786998 1.15741004 -2.07668996 0 P 0 
L 1.15741004 -2.07668996 1.15743996 -2.07663002 0 P 0 
L 1.15743996 -2.07663002 1.15746004 -2.07656998 0 P 0 
L 1.15746004 -2.07656998 1.15746998 -2.07656998 0 P 0 
L 1.15746998 -2.07656998 1.158 -2.07533996 0 P 0 
L 1.158 -2.07533996 1.15801004 -2.07531004 0 P 0 
L 1.15801004 -2.07531004 1.15803002 -2.07528002 0 P 0 
L 1.15803002 -2.07528002 1.15805 -2.07521998 0 P 0 
L 1.15805 -2.07521998 1.15848996 -2.07396004 0 P 0 
L 1.15848996 -2.07396004 1.15841004 -2.07393002 0 P 0 
L 1.15841004 -2.07393002 1.15851004 -2.07393002 0 P 0 
L 1.15851004 -2.07393002 1.15851998 -2.0739 0 P 0 
L 1.15851998 -2.0739 1.15853002 -2.07386004 0 P 0 
L 1.15853002 -2.07386004 1.15853996 -2.07383002 0 P 0 
L 1.15853996 -2.07383002 1.15943996 -2.07061004 0 P 0 
L 1.15943996 -2.07061004 1.15945 -2.07058002 0 P 0 
L 1.15945 -2.07058002 1.15946004 -2.07053996 0 P 0 
L 1.15946004 -2.07053996 1.15946998 -2.07051004 0 P 0 
L 1.15946998 -2.07051004 1.15946998 -2.07046998 0 P 0 
L 1.15946998 -2.07046998 1.16013996 -2.06723002 0 P 0 
L 1.16013996 -2.06723002 1.16013996 -2.0672 0 P 0 
L 1.16013996 -2.0672 1.16016004 -2.06713996 0 P 0 
L 1.16016004 -2.06713996 1.16016004 -2.06711004 0 P 0 
L 1.16016004 -2.06711004 1.16081998 -2.06256004 0 P 0 
L 1.16081998 -2.06256004 1.16081998 -2.06253996 0 P 0 
L 1.16081998 -2.06253996 1.16083002 -2.0625 0 P 0 
L 1.16083002 -2.0625 1.16083002 -2.06246998 0 P 0 
L 1.16083002 -2.06246998 1.16126998 -2.05791004 0 P 0 
L 1.16126998 -2.05791004 1.16128002 -2.0579 0 P 0 
L 1.16128002 -2.0579 1.16128002 -2.05783996 0 P 0 
L 1.16128002 -2.05783996 1.1621 -2.04405 0 P 0 
L 1.1621 -2.04405 1.1621 -2.04401998 0 P 0 
L 1.1621 -2.04401998 1.16285 -2.02761998 0 P 0 
L 1.16285 -2.02761998 1.16136998 -2.0256 0 P 0 
L 1.16136998 -2.0256 1.15878996 -2.02491004 0 P 0 
L 1.15878996 -2.02491004 1.15878002 -2.0249 0 P 0 
L 1.15878002 -2.0249 1.15871998 -2.02488996 0 P 0 
L 1.15871998 -2.02488996 1.15755 -2.02461998 0 P 0 
L 1.15755 -2.02461998 1.15746998 -2.0246 0 P 0 
L 1.15746998 -2.0246 1.1574 -2.0246 0 P 0 
L 1.1574 -2.0246 1.15621004 -2.02441004 0 P 0 
L 1.15621004 -2.02441004 1.15616998 -2.02441004 0 P 0 
L 1.15616998 -2.02441004 1.1561 -2.0244 0 P 0 
L 1.1561 -2.0244 1.15606004 -2.02438996 0 P 0 
L 1.15606004 -2.02438996 1.15486004 -2.0243 0 P 0 
L 1.15486004 -2.0243 1.15471998 -2.0243 0 P 0 
L 1.15471998 -2.0243 1.14936004 -2.02426004 0 P 0 
L 1.14936004 -2.02426004 1.14928996 -2.02426004 0 P 0 
L 1.14928996 -2.02426004 1.14925 -2.02426998 0 P 0 
L 1.14925 -2.02426998 1.14921004 -2.02426998 0 P 0 
L 1.14921004 -2.02426998 1.14376998 -2.02463996 0 P 0 
L 1.14376998 -2.02463996 1.1437 -2.02463996 0 P 0 
L 1.1437 -2.02463996 1.14365 -2.02465 0 P 0 
L 1.14365 -2.02465 1.14361004 -2.02465 0 P 0 
L 1.14361004 -2.02465 1.14161998 -2.02495 0 P 0 
L 1.14161998 -2.02495 1.14161004 -2.02495 0 P 0 
L 1.14161004 -2.02495 1.14153002 -2.02496998 0 P 0 
L 1.14153002 -2.02496998 1.14148996 -2.02496998 0 P 0 
L 1.14148996 -2.02496998 1.14143996 -2.02498996 0 P 0 
L 1.14143996 -2.02498996 1.13946998 -2.02545 0 P 0 
L 1.13946998 -2.02545 1.13943996 -2.02546998 0 P 0 
L 1.13943996 -2.02546998 1.1394 -2.02546998 0 P 0 
L 1.1394 -2.02546998 1.13933002 -2.0255 0 P 0 
L 1.13933002 -2.0255 1.13801004 -2.02591998 0 P 0 
L 1.13801004 -2.02591998 1.13798002 -2.02593002 0 P 0 
L 1.13798002 -2.02593002 1.13793996 -2.02593996 0 P 0 
L 1.13793996 -2.02593996 1.13788002 -2.02596998 0 P 0 
L 1.13788002 -2.02596998 1.1366 -2.02648002 0 P 0 
L 1.1366 -2.02648002 1.13653996 -2.0265 0 P 0 
L 1.13653996 -2.0265 1.13648002 -2.02653002 0 P 0 
L 1.13648002 -2.02653002 1.13523996 -2.02713002 0 P 0 
L 1.13523996 -2.02713002 1.13518002 -2.02716004 0 P 0 
L 1.13518002 -2.02716004 1.13515 -2.02716998 0 P 0 
L 1.13515 -2.02716998 1.13511998 -2.02718996 0 P 0 
L 1.13511998 -2.02718996 1.13393002 -2.02786998 0 P 0 
L 1.13393002 -2.02786998 1.13388996 -2.02788996 0 P 0 
L 1.13388996 -2.02788996 1.1338 -2.02795 0 P 0 
L 1.1338 -2.02795 1.13111998 -2.02976004 0 P 0 
L 1.13111998 -2.02976004 1.13105 -2.02981004 0 P 0 
L 1.13105 -2.02981004 1.13101004 -2.02983996 0 P 0 
L 1.13101004 -2.02983996 1.13098002 -2.02986004 0 P 0 
L 1.13098002 -2.02986004 1.12846998 -2.03188996 0 P 0 
L 1.12846998 -2.03188996 1.12838002 -2.03198002 0 P 0 
L 1.12838002 -2.03198002 1.12833996 -2.03201004 0 P 0 
L 1.12833996 -2.03201004 1.12596004 -2.0343 0 P 0 
L 1.12596004 -2.0343 1.12593996 -2.03433002 0 P 0 
L 1.12593996 -2.03433002 1.1259 -2.03436004 0 P 0 
L 1.1259 -2.03436004 1.12588002 -2.03438996 0 P 0 
L 1.12588002 -2.03438996 1.12585 -2.03443002 0 P 0 
L 1.12585 -2.03443002 1.12366998 -2.03691004 0 P 0 
L 1.12366998 -2.03691004 1.12363996 -2.03695 0 P 0 
L 1.12363996 -2.03695 1.12361998 -2.03698002 0 P 0 
L 1.12361998 -2.03698002 1.12358996 -2.03701004 0 P 0 
L 1.12358996 -2.03701004 1.12356998 -2.03703996 0 P 0 
L 1.12356998 -2.03703996 1.12236998 -2.03865 0 P 0 
L 1.12236998 -2.03865 1.12233996 -2.03868996 0 P 0 
L 1.12233996 -2.03868996 1.12233002 -2.03871004 0 P 0 
L 1.12233002 -2.03871004 1.12228996 -2.03878002 0 P 0 
L 1.12228996 -2.03878002 1.12121004 -2.04046998 0 P 0 
L 1.12121004 -2.04046998 1.12118996 -2.0405 0 P 0 
L 1.12118996 -2.0405 1.12116998 -2.04053996 0 P 0 
L 1.12116998 -2.04053996 1.12115 -2.04056998 0 P 0 
L 1.12115 -2.04056998 1.12113996 -2.04061004 0 P 0 
L 1.12113996 -2.04061004 1.12018996 -2.04238002 0 P 0 
L 1.12018996 -2.04238002 1.12016004 -2.04245 0 P 0 
L 1.12016004 -2.04245 1.12013996 -2.04248002 0 P 0 
L 1.12013996 -2.04248002 1.12013002 -2.04251004 0 P 0 
L 1.12013002 -2.04251004 1.11926004 -2.04446998 0 P 0 
L 1.11926004 -2.04446998 1.11925 -2.0445 0 P 0 
L 1.11925 -2.0445 1.11923002 -2.04453996 0 P 0 
L 1.11923002 -2.04453996 1.11921998 -2.04458002 0 P 0 
L 1.11921998 -2.04458002 1.11921004 -2.04461004 0 P 0 
L 1.11921004 -2.04461004 1.11848002 -2.04663002 0 P 0 
L 1.11848002 -2.04663002 1.11846998 -2.04666004 0 P 0 
L 1.11846998 -2.04666004 1.11846004 -2.0467 0 P 0 
L 1.11846004 -2.0467 1.11843996 -2.04676998 0 P 0 
L 1.11843996 -2.04676998 1.11786004 -2.04883996 0 P 0 
L 1.11786004 -2.04883996 1.11785 -2.04886998 0 P 0 
L 1.11785 -2.04886998 1.11783996 -2.04891004 0 P 0 
L 1.11783996 -2.04891004 1.11783996 -2.04893996 0 P 0 
L 1.11783996 -2.04893996 1.11783002 -2.04896998 0 P 0 
L 1.11783002 -2.04896998 1.11783002 -2.04898002 0 P 0 
L 1.11783002 -2.04898002 1.1174 -2.05108002 0 P 0 
L 1.1174 -2.05108002 1.1174 -2.05111998 0 P 0 
L 1.1174 -2.05111998 1.11738996 -2.05116004 0 P 0 
L 1.11738996 -2.05116004 1.11738002 -2.05118996 0 P 0 
L 1.11738002 -2.05118996 1.11738002 -2.05123002 0 P 0 
L 1.11738002 -2.05123002 1.11673002 -2.05643002 0 P 0 
L 1.11673002 -2.05643002 1.11671998 -2.05646998 0 P 0 
L 1.11671998 -2.05646998 1.11671998 -2.05655 0 P 0 
L 1.11671998 -2.05655 1.11671004 -2.05658996 0 P 0 
L 1.11671004 -2.05658996 1.11648996 -2.06181998 0 P 0 
L 1.11648996 -2.06181998 1.11648002 -2.06186998 0 P 0 
L 1.11648002 -2.06186998 1.11648002 -2.06195 0 P 0 
L 1.11648002 -2.06195 1.11648996 -2.06198996 0 P 0 
L 1.11648996 -2.06198996 1.11668002 -2.06696998 0 P 0 
L 1.11668002 -2.06696998 1.11768002 -2.06696998 0 P 0 
L 1.11768002 -2.06696998 1.11668002 -2.06701004 0 P 0 
L 1.11668002 -2.06701004 1.11668002 -2.06713002 0 P 0 
L 1.11668002 -2.06713002 1.11668996 -2.06716998 0 P 0 
L 1.11668996 -2.06716998 1.11728002 -2.07215 0 P 0 
L 1.11728002 -2.07215 1.11728996 -2.07218996 0 P 0 
L 1.11728996 -2.07218996 1.11728996 -2.07223002 0 P 0 
L 1.11728996 -2.07223002 1.11731004 -2.07231004 0 P 0 
L 1.11731004 -2.07231004 1.11758996 -2.07371004 0 P 0 
L 1.11758996 -2.07371004 1.1176 -2.07375 0 P 0 
L 1.1176 -2.07375 1.11761004 -2.0738 0 P 0 
L 1.11761004 -2.0738 1.11761998 -2.07383996 0 P 0 
L 1.11761998 -2.07383996 1.11763996 -2.07388002 0 P 0 
L 1.11763996 -2.07388002 1.11803996 -2.07523996 0 P 0 
L 1.11803996 -2.07523996 1.11806004 -2.07531998 0 P 0 
L 1.11806004 -2.07531998 1.11808002 -2.07536004 0 P 0 
L 1.11808002 -2.07536004 1.11808996 -2.07541004 0 P 0 
L 1.11808996 -2.07541004 1.11861004 -2.07673002 0 P 0 
L 1.11861004 -2.07673002 1.11863996 -2.07681004 0 P 0 
L 1.11863996 -2.07681004 1.11866004 -2.07683996 0 P 0 
L 1.11866004 -2.07683996 1.11868002 -2.07688002 0 P 0 
L 1.11868002 -2.07688002 1.11931004 -2.07815 0 P 0 
L 1.11931004 -2.07815 1.11935 -2.07823002 0 P 0 
L 1.11935 -2.07823002 1.1194 -2.0783 0 P 0 
L 1.1194 -2.0783 1.12013996 -2.07951998 0 P 0 
L 1.12013996 -2.07951998 1.12021004 -2.07961998 0 P 0 
L 1.12021004 -2.07961998 1.12023002 -2.07965 0 P 0 
L 1.12023002 -2.07965 1.12023002 -2.07966004 0 P 0 
L 1.12023002 -2.07966004 1.1212 -2.08096998 0 P 0 
L 1.1212 -2.08096998 1.12123996 -2.08103002 0 P 0 
L 1.12123996 -2.08103002 1.12126998 -2.08106004 0 P 0 
L 1.12126998 -2.08106004 1.12128996 -2.08108996 0 P 0 
L 1.12128996 -2.08108996 1.12235 -2.08231004 0 P 0 
L 1.12235 -2.08231004 1.12238002 -2.08233996 0 P 0 
L 1.12238002 -2.08233996 1.1224 -2.08236998 0 P 0 
L 1.1224 -2.08236998 1.12246004 -2.08243002 0 P 0 
L 1.12246004 -2.08243002 1.12361004 -2.08355 0 P 0 
L 1.12361004 -2.08355 1.12366998 -2.08361004 0 P 0 
L 1.12366998 -2.08361004 1.1237 -2.08363002 0 P 0 
L 1.1237 -2.08363002 1.12373002 -2.08366004 0 P 0 
L 1.12373002 -2.08366004 1.12496998 -2.08468996 0 P 0 
L 1.12496998 -2.08468996 1.125 -2.08471004 0 P 0 
L 1.125 -2.08471004 1.12503002 -2.08473996 0 P 0 
L 1.12503002 -2.08473996 1.12506998 -2.08476004 0 P 0 
L 1.12506998 -2.08476004 1.1251 -2.08478996 0 P 0 
L 1.1251 -2.08478996 1.12641998 -2.08571004 0 P 0 
L 1.12641998 -2.08571004 1.12645 -2.08573002 0 P 0 
L 1.12645 -2.08573002 1.12648002 -2.08576004 0 P 0 
L 1.12648002 -2.08576004 1.12651004 -2.08578002 0 P 0 
L 1.12651004 -2.08578002 1.12655 -2.0858 0 P 0 
L 1.12655 -2.0858 1.12793996 -2.08661004 0 P 0 
L 1.12793996 -2.08661004 1.12801004 -2.08665 0 P 0 
L 1.12801004 -2.08665 1.12805 -2.08666998 0 P 0 
L 1.12805 -2.08666998 1.12808002 -2.08668996 0 P 0 
L 1.12808002 -2.08668996 1.12808996 -2.08668996 0 P 0 
L 1.12808996 -2.08668996 1.12953996 -2.08738996 0 P 0 
L 1.12953996 -2.08738996 1.12961998 -2.08743002 0 P 0 
L 1.12961998 -2.08743002 1.12965 -2.08743996 0 P 0 
L 1.12965 -2.08743996 1.1297 -2.08746004 0 P 0 
L 1.1297 -2.08746004 1.13118002 -2.08801998 0 P 0 
L 1.13118002 -2.08801998 1.13133996 -2.08808002 0 P 0 
L 1.13133996 -2.08808002 1.13286998 -2.08851004 0 P 0 
L 1.13286998 -2.08851004 1.13295 -2.08853996 0 P 0 
L 1.13295 -2.08853996 1.13303996 -2.08855 0 P 0 
L 1.13303996 -2.08855 1.1346 -2.08886004 0 P 0 
L 1.1346 -2.08886004 1.13471998 -2.08888996 0 P 0 
L 1.13471998 -2.08888996 1.13476004 -2.08888996 0 P 0 
L 1.13476004 -2.08888996 1.13633996 -2.08906998 0 P 0 
L 1.13633996 -2.08906998 1.13638996 -2.08908002 0 P 0 
L 1.13638996 -2.08908002 1.13651004 -2.08908002 0 P 0 
L 1.13651004 -2.08908002 1.1381 -2.08913002 0 P 0 
L 1.1381 -2.08913002 1.13818996 -2.08913002 0 P 0 
L 1.31623996 -1.98923996 1.3135 -1.98988002 0 P 0 
L 1.3135 -1.98988002 1.31078996 -1.99071004 0 P 0 
L 1.31078996 -1.99071004 1.30813002 -1.99175 0 P 0 
L 1.30813002 -1.99175 1.30553996 -1.99296998 0 P 0 
L 1.30553996 -1.99296998 1.30308996 -1.99431998 0 P 0 
L 1.30308996 -1.99431998 1.30073996 -1.99585 0 P 0 
L 1.30073996 -1.99585 1.29863996 -1.99746004 0 P 0 
L 1.29863996 -1.99746004 1.29666004 -1.99923996 0 P 0 
L 1.29666004 -1.99923996 1.29205 -2.00375 0 P 0 
L 1.29205 -2.00375 1.29205 -1.99243996 0 P 0 
L 1.29205 -1.99243996 1.24316004 -1.99243996 0 P 0 
L 1.24316004 -1.99243996 1.24313996 -2.00521004 0 P 0 
L 1.24313996 -2.00521004 1.24261004 -2.03151004 0 P 0 
L 1.24261004 -2.03151004 1.24086998 -2.07046004 0 P 0 
L 1.24086998 -2.07046004 1.23873996 -2.10921004 0 P 0 
L 1.23873996 -2.10921004 1.23811998 -2.11641998 0 P 0 
L 1.23811998 -2.11641998 1.23711998 -2.12361998 0 P 0 
L 1.23711998 -2.12361998 1.23655 -2.12716004 0 P 0 
L 1.23655 -2.12716004 1.29205 -2.12716004 0 P 0 
L 1.29205 -2.12716004 1.29206998 -2.11766004 0 P 0 
L 1.29206998 -2.11766004 1.29238996 -2.10283996 0 P 0 
L 1.29238996 -2.10283996 1.29336004 -2.08431004 0 P 0 
L 1.29336004 -2.08431004 1.29463996 -2.06673002 0 P 0 
L 1.29463996 -2.06673002 1.29511004 -2.06253002 0 P 0 
L 1.29511004 -2.06253002 1.29583996 -2.05836004 0 P 0 
L 1.29583996 -2.05836004 1.29683002 -2.05446998 0 P 0 
L 1.29683002 -2.05446998 1.29813996 -2.05068996 0 P 0 
L 1.29813996 -2.05068996 1.29978002 -2.04701998 0 P 0 
L 1.29978002 -2.04701998 1.30056998 -2.04556998 0 P 0 
L 1.30056998 -2.04556998 1.30146998 -2.04418996 0 P 0 
L 1.30146998 -2.04418996 1.30246998 -2.04288002 0 P 0 
L 1.30246998 -2.04288002 1.30356998 -2.04165 0 P 0 
L 1.30356998 -2.04165 1.30475 -2.0405 0 P 0 
L 1.30475 -2.0405 1.30603996 -2.03945 0 P 0 
L 1.30603996 -2.03945 1.30773996 -2.03826004 0 P 0 
L 1.30773996 -2.03826004 1.30953002 -2.03723002 0 P 0 
L 1.30953002 -2.03723002 1.31141004 -2.03635 0 P 0 
L 1.31141004 -2.03635 1.31335 -2.03563002 0 P 0 
L 1.31335 -2.03563002 1.31535 -2.03508002 0 P 0 
L 1.31535 -2.03508002 1.31973996 -2.03423002 0 P 0 
L 1.31973996 -2.03423002 1.32416004 -2.03366998 0 P 0 
L 1.32416004 -2.03366998 1.32863002 -2.0334 0 P 0 
L 1.32863002 -2.0334 1.33688002 -2.03318002 0 P 0 
L 1.33688002 -2.03318002 1.33613002 -2.01151004 0 P 0 
L 1.33613002 -2.01151004 1.33581004 -2.00315 0 P 0 
L 1.33581004 -2.00315 1.33543996 -1.99596004 0 P 0 
L 1.33543996 -1.99596004 1.33508002 -1.98971004 0 P 0 
L 1.33508002 -1.98971004 1.33503996 -1.98945 0 P 0 
L 1.33503996 -1.98945 1.335 -1.98931998 0 P 0 
L 1.335 -1.98931998 1.33496004 -1.9892 0 P 0 
L 1.33496004 -1.9892 1.3349 -1.98908002 0 P 0 
L 1.3349 -1.98908002 1.33483996 -1.98896998 0 P 0 
L 1.33483996 -1.98896998 1.33476998 -1.98886004 0 P 0 
L 1.33476998 -1.98886004 1.33468996 -1.98876004 0 P 0 
L 1.33468996 -1.98876004 1.3346 -1.98866998 0 P 0 
L 1.3346 -1.98866998 1.33451004 -1.98858996 0 P 0 
L 1.33451004 -1.98858996 1.3344 -1.98851998 0 P 0 
L 1.3344 -1.98851998 1.3343 -1.98845 0 P 0 
L 1.3343 -1.98845 1.33418002 -1.98838996 0 P 0 
L 1.33418002 -1.98838996 1.33406998 -1.98833996 0 P 0 
L 1.33406998 -1.98833996 1.33395 -1.9883 0 P 0 
L 1.33395 -1.9883 1.33383002 -1.98828002 0 P 0 
L 1.33383002 -1.98828002 1.3337 -1.98826004 0 P 0 
L 1.3337 -1.98826004 1.33356998 -1.98825 0 P 0 
L 1.33356998 -1.98825 1.32756998 -1.98823002 0 P 0 
L 1.32756998 -1.98823002 1.32135 -1.98853996 0 P 0 
L 1.32135 -1.98853996 1.31878996 -1.98881998 0 P 0 
L 1.31878996 -1.98881998 1.31623996 -1.98923996 0 P 0 
L 1.2389 -2.12516004 1.29006004 -2.12516004 0 P 0 
L 1.23906998 -2.12416004 1.29006004 -2.12416004 0 P 0 
L 1.23921004 -2.12316004 1.29006004 -2.12316004 0 P 0 
L 1.23933996 -2.12216004 1.29006004 -2.12216004 0 P 0 
L 1.23948996 -2.12116004 1.29006004 -2.12116004 0 P 0 
L 1.23961998 -2.12016004 1.29006998 -2.12016004 0 P 0 
L 1.23976004 -2.11916004 1.29006998 -2.11916004 0 P 0 
L 1.2399 -2.11816004 1.29006998 -2.11816004 0 P 0 
L 1.24003996 -2.11716004 1.29008002 -2.11716004 0 P 0 
L 1.24015 -2.11616004 1.2901 -2.11616004 0 P 0 
L 1.24023996 -2.11516004 1.29011998 -2.11516004 0 P 0 
L 1.24033002 -2.11416004 1.29013996 -2.11416004 0 P 0 
L 1.24041004 -2.11316004 1.29016004 -2.11316004 0 P 0 
L 1.24048996 -2.11216004 1.29018996 -2.11216004 0 P 0 
L 1.24058002 -2.11116004 1.29021004 -2.11116004 0 P 0 
L 1.24066998 -2.11016004 1.29023002 -2.11016004 0 P 0 
L 1.24075 -2.10916004 1.29025 -2.10916004 0 P 0 
L 1.2408 -2.10816004 1.29026998 -2.10816004 0 P 0 
L 1.24086004 -2.10716004 1.29028996 -2.10716004 0 P 0 
L 1.24091004 -2.10616004 1.29031998 -2.10616004 0 P 0 
L 1.24096998 -2.10516004 1.29033996 -2.10516004 0 P 0 
L 1.24101998 -2.10416004 1.29036004 -2.10416004 0 P 0 
L 1.24108002 -2.10316004 1.29038002 -2.10316004 0 P 0 
L 1.24113002 -2.10216004 1.29041998 -2.10216004 0 P 0 
L 1.24118002 -2.10116004 1.29046998 -2.10116004 0 P 0 
L 1.24123996 -2.10016004 1.29053002 -2.10016004 0 P 0 
L 1.24128996 -2.09916004 1.29058002 -2.09916004 0 P 0 
L 1.24135 -2.09816004 1.29063002 -2.09816004 0 P 0 
L 1.2414 -2.09716004 1.29068002 -2.09716004 0 P 0 
L 1.24146004 -2.09616004 1.29073996 -2.09616004 0 P 0 
L 1.24151004 -2.09516004 1.29078996 -2.09516004 0 P 0 
L 1.24156998 -2.09416004 1.29083996 -2.09416004 0 P 0 
L 1.24161998 -2.09316004 1.2909 -2.09316004 0 P 0 
L 1.24168002 -2.09216004 1.29095 -2.09216004 0 P 0 
L 1.24173002 -2.09116004 1.291 -2.09116004 0 P 0 
L 1.24178996 -2.09016004 1.29105 -2.09016004 0 P 0 
L 1.24183996 -2.08916004 1.2911 -2.08916004 0 P 0 
L 1.2419 -2.08816004 1.29116004 -2.08816004 0 P 0 
L 1.24196004 -2.08716004 1.29121004 -2.08716004 0 P 0 
L 1.24201004 -2.08616004 1.29126998 -2.08616004 0 P 0 
L 1.24206998 -2.08516004 1.29131998 -2.08516004 0 P 0 
L 1.24211998 -2.08416004 1.29136998 -2.08416004 0 P 0 
L 1.2389 -2.12516004 1.2391 -2.12393002 0 P 0 
L 1.2391 -2.12393002 1.2391 -2.1239 0 P 0 
L 1.2391 -2.1239 1.24011004 -2.11665 0 P 0 
L 1.24011004 -2.11665 1.24073002 -2.10935 0 P 0 
L 1.24073002 -2.10935 1.24073996 -2.10931998 0 P 0 
L 1.24073996 -2.10931998 1.24286004 -2.07056004 0 P 0 
L 1.24286004 -2.07056004 1.24461004 -2.03158002 0 P 0 
L 1.24461004 -2.03158002 1.24513996 -2.00523002 0 P 0 
L 1.24513996 -2.00523002 1.24515 -1.99443996 0 P 0 
L 1.24515 -1.99443996 1.29005 -1.99443996 0 P 0 
L 1.29005 -1.99443996 1.29005 -2.00375 0 P 0 
L 1.29005 -2.00375 1.29128002 -2.0056 0 P 0 
L 1.29128002 -2.0056 1.29345 -2.00518002 0 P 0 
L 1.29345 -2.00518002 1.29803002 -2.0007 0 P 0 
L 1.29803002 -2.0007 1.29991998 -1.999 0 P 0 
L 1.29991998 -1.999 1.30188996 -1.99748996 0 P 0 
L 1.30188996 -1.99748996 1.30411998 -1.99603996 0 P 0 
L 1.30411998 -1.99603996 1.30645 -1.99475 0 P 0 
L 1.30645 -1.99475 1.30891998 -1.99358996 0 P 0 
L 1.30891998 -1.99358996 1.31145 -1.9926 0 P 0 
L 1.31145 -1.9926 1.31401998 -1.99181004 0 P 0 
L 1.31401998 -1.99181004 1.31663996 -1.9912 0 P 0 
L 1.31663996 -1.9912 1.31906004 -1.9908 0 P 0 
L 1.31906004 -1.9908 1.32151004 -1.99053002 0 P 0 
L 1.32151004 -1.99053002 1.32761998 -1.99023002 0 P 0 
L 1.32761998 -1.99023002 1.3331 -1.99025 0 P 0 
L 1.3331 -1.99025 1.33345 -1.99608002 0 P 0 
L 1.33345 -1.99608002 1.33381004 -2.00323002 0 P 0 
L 1.33381004 -2.00323002 1.33413002 -2.01158996 0 P 0 
L 1.33413002 -2.01158996 1.33413002 -2.0116 0 P 0 
L 1.33413002 -2.0116 1.33481998 -2.03123002 0 P 0 
L 1.33481998 -2.03123002 1.32853996 -2.0314 0 P 0 
L 1.32853996 -2.0314 1.32398002 -2.03166998 0 P 0 
L 1.32398002 -2.03166998 1.31941998 -2.03225 0 P 0 
L 1.31941998 -2.03225 1.31488996 -2.03313002 0 P 0 
L 1.31488996 -2.03313002 1.31273996 -2.03373002 0 P 0 
L 1.31273996 -2.03373002 1.31063996 -2.0345 0 P 0 
L 1.31063996 -2.0345 1.3086 -2.03545 0 P 0 
L 1.3086 -2.03545 1.30666004 -2.03656998 0 P 0 
L 1.30666004 -2.03656998 1.30658996 -2.03661998 0 P 0 
L 1.30658996 -2.03661998 1.30483002 -2.03786004 0 P 0 
L 1.30483002 -2.03786004 1.30341998 -2.03901004 0 P 0 
L 1.30341998 -2.03901004 1.30336998 -2.03906004 0 P 0 
L 1.30336998 -2.03906004 1.30211998 -2.04026004 0 P 0 
L 1.30211998 -2.04026004 1.30093002 -2.0416 0 P 0 
L 1.30093002 -2.0416 1.29983002 -2.04303996 0 P 0 
L 1.29983002 -2.04303996 1.29978996 -2.0431 0 P 0 
L 1.29978996 -2.0431 1.29885 -2.04453996 0 P 0 
L 1.29885 -2.04453996 1.29798996 -2.04613002 0 P 0 
L 1.29798996 -2.04613002 1.29631998 -2.04986998 0 P 0 
L 1.29631998 -2.04986998 1.29628002 -2.04995 0 P 0 
L 1.29628002 -2.04995 1.29625 -2.05003002 0 P 0 
L 1.29625 -2.05003002 1.29491998 -2.0539 0 P 0 
L 1.29491998 -2.0539 1.29388996 -2.05793996 0 P 0 
L 1.29388996 -2.05793996 1.29386998 -2.05801998 0 P 0 
L 1.29386998 -2.05801998 1.29313996 -2.06221004 0 P 0 
L 1.29313996 -2.06221004 1.29313002 -2.06223996 0 P 0 
L 1.29313002 -2.06223996 1.29311998 -2.0623 0 P 0 
L 1.29311998 -2.0623 1.29265 -2.06655 0 P 0 
L 1.29265 -2.06655 1.29136998 -2.08418996 0 P 0 
L 1.29136998 -2.08418996 1.29038996 -2.10276998 0 P 0 
L 1.29038996 -2.10276998 1.29006998 -2.11763002 0 P 0 
L 1.29006998 -2.11763002 1.29006004 -2.12516004 0 P 0 
L 1.29006004 -2.12516004 1.2389 -2.12516004 0 P 0 
L 1.09846998 -2.00483002 1.21248002 -2.00483002 0 P 0 
L 1.09838002 -2.12083002 1.14708002 -2.12083002 0 P 0 
L 1.11933002 -2.18283002 1.15161998 -2.18283002 0 P 0 
L 1.11001998 -2.18183002 1.15838002 -2.18183002 0 P 0 
L 1.10246998 -2.18083002 1.16333996 -2.18083002 0 P 0 
L 1.04061004 -1.89731004 1.09978002 -1.89731004 0 P 0 
L 1.03565 -1.89631004 1.09821004 -1.89631004 0 P 0 
L 1.03068996 -1.89531004 1.09661004 -1.89531004 0 P 0 
L 1.02573002 -1.89431004 1.09475 -1.89431004 0 P 0 
L 1.019 -1.89331004 1.09288002 -1.89331004 0 P 0 
L 1.01163996 -1.89231004 1.09101998 -1.89231004 0 P 0 
L 0.99518996 -1.89131004 1.08916004 -1.89131004 0 P 0 
L 0.87011998 -1.88331004 1.07278996 -1.88331004 0 P 0 
L 0.86963996 -1.88231004 1.07053002 -1.88231004 0 P 0 
L 0.86916004 -1.88131004 1.06828002 -1.88131004 0 P 0 
L 0.86863002 -1.88031004 1.06603002 -1.88031004 0 P 0 
L 0.86806998 -1.87931004 1.06351004 -1.87931004 0 P 0 
L 0.8675 -1.87831004 1.06076998 -1.87831004 0 P 0 
L 0.86693002 -1.87731004 1.05803996 -1.87731004 0 P 0 
L 0.86631004 -1.87631004 1.05531004 -1.87631004 0 P 0 
L 0.86563996 -1.87531004 1.05256998 -1.87531004 0 P 0 
L 0.86498002 -1.87431004 1.04983996 -1.87431004 0 P 0 
L 0.86431998 -1.87331004 1.0471 -1.87331004 0 P 0 
L 0.86356004 -1.87231004 1.04376004 -1.87231004 0 P 0 
L 0.86278996 -1.87131004 1.04041998 -1.87131004 0 P 0 
L 0.86203002 -1.87031004 1.03708002 -1.87031004 0 P 0 
L 0.86118996 -1.86931004 1.03373996 -1.86931004 0 P 0 
L 0.8603 -1.86831004 1.0304 -1.86831004 0 P 0 
L 0.85941004 -1.86731004 1.02656998 -1.86731004 0 P 0 
L 0.8585 -1.86631004 1.02231998 -1.86631004 0 P 0 
L 0.85756998 -1.86531004 1.01806998 -1.86531004 0 P 0 
L 0.85663002 -1.86431004 1.01381998 -1.86431004 0 P 0 
L 0.85568996 -1.86331004 1.00931998 -1.86331004 0 P 0 
L 0.85481004 -1.86231004 1.00335 -1.86231004 0 P 0 
L 0.85916998 -1.86131004 0.99738002 -1.86131004 0 P 0 
L 0.86716998 -1.86031004 0.99141998 -1.86031004 0 P 0 
L 0.87476998 -1.89731004 0.89943002 -1.89731004 0 P 0 
L 0.87453996 -1.89631004 0.90426004 -1.89631004 0 P 0 
L 0.87431004 -1.89531004 0.9097 -1.89531004 0 P 0 
L 0.87406998 -1.89431004 0.91608002 -1.89431004 0 P 0 
L 0.87383002 -1.89331004 0.92246004 -1.89331004 0 P 0 
L 0.87355 -1.89231004 0.93086004 -1.89231004 0 P 0 
L 0.87323002 -1.89131004 0.95553002 -1.89131004 0 P 0 
L 0.87291004 -1.89031004 1.08728996 -1.89031004 0 P 0 
L 0.87258996 -1.88931004 1.08543002 -1.88931004 0 P 0 
L 0.87223002 -1.88831004 1.08356998 -1.88831004 0 P 0 
L 0.87183002 -1.88731004 1.0817 -1.88731004 0 P 0 
L 0.87143002 -1.88631004 1.07955 -1.88631004 0 P 0 
L 0.87103002 -1.88531004 1.07728996 -1.88531004 0 P 0 
L 0.8706 -1.88431004 1.07503996 -1.88431004 0 P 0 
L 0.87525 -1.85931004 0.98545 -1.85931004 0 P 0 
L 0.88421004 -1.85831004 0.97621004 -1.85831004 0 P 0 
L 0.89393002 -1.85731004 0.96606998 -1.85731004 0 P 0 
L 0.9106 -1.85631004 0.95203002 -1.85631004 0 P 0 
L 1.08716004 -1.91231004 1.12151004 -1.91231004 0 P 0 
L 1.08486004 -1.91131004 1.12018996 -1.91131004 0 P 0 
L 1.08256004 -1.91031004 1.11886004 -1.91031004 0 P 0 
L 1.08023002 -1.90931004 1.11753996 -1.90931004 0 P 0 
L 1.07738002 -1.90831004 1.11621004 -1.90831004 0 P 0 
L 1.07453002 -1.90731004 1.11488996 -1.90731004 0 P 0 
L 1.07168996 -1.90631004 1.11356998 -1.90631004 0 P 0 
L 1.06883996 -1.90531004 1.11223996 -1.90531004 0 P 0 
L 1.066 -1.90431004 1.11076998 -1.90431004 0 P 0 
L 1.06315 -1.90331004 1.1092 -1.90331004 0 P 0 
L 1.0599 -1.90231004 1.10763002 -1.90231004 0 P 0 
L 1.05611998 -1.90131004 1.10606004 -1.90131004 0 P 0 
L 1.05235 -1.90031004 1.10448996 -1.90031004 0 P 0 
L 1.04856998 -1.89931004 1.10291998 -1.89931004 0 P 0 
L 1.04478996 -1.89831004 1.10135 -1.89831004 0 P 0 
L 0.98815 -2.08316004 1.03726998 -2.08316004 0 P 0 
L 0.98818002 -2.08216004 1.03731004 -2.08216004 0 P 0 
L 0.98821998 -2.08116004 1.03735 -2.08116004 0 P 0 
L 0.98825 -2.08016004 1.03738996 -2.08016004 0 P 0 
L 0.98828002 -2.07916004 1.03743002 -2.07916004 0 P 0 
L 0.98831998 -2.07816004 1.03746998 -2.07816004 0 P 0 
L 0.98835 -2.07716004 1.03751004 -2.07716004 0 P 0 
L 0.98838002 -2.07616004 1.03755 -2.07616004 0 P 0 
L 0.98841998 -2.07516004 1.03758002 -2.07516004 0 P 0 
L 0.98845 -2.07416004 1.03761004 -2.07416004 0 P 0 
L 0.98848002 -2.07316004 1.03763996 -2.07316004 0 P 0 
L 0.98851004 -2.07216004 1.03768002 -2.07216004 0 P 0 
L 0.98855 -2.07116004 1.03771004 -2.07116004 0 P 0 
L 0.98858002 -2.07016004 1.03773996 -2.07016004 0 P 0 
L 0.98858996 -2.06916004 1.03776998 -2.06916004 0 P 0 
L 0.98858996 -2.06816004 1.0378 -2.06816004 0 P 0 
L 0.98858996 -2.06716004 1.03783002 -2.06716004 0 P 0 
L 0.98858002 -2.06616004 1.03786004 -2.06616004 0 P 0 
L 0.98856998 -2.06516004 1.0379 -2.06516004 0 P 0 
L 0.98856998 -2.06416004 1.03793002 -2.06416004 0 P 0 
L 0.98856998 -2.06316004 1.03796004 -2.06316004 0 P 0 
L 0.98856004 -2.06216004 1.03798996 -2.06216004 0 P 0 
L 0.98855 -2.06116004 1.03801998 -2.06116004 0 P 0 
L 0.98855 -2.06016004 1.03805 -2.06016004 0 P 0 
L 0.98853996 -2.05916004 1.03808002 -2.05916004 0 P 0 
L 0.98853996 -2.05816004 1.0381 -2.05816004 0 P 0 
L 0.98853002 -2.05716004 1.03811998 -2.05716004 0 P 0 
L 0.98848002 -2.05616004 1.03815 -2.05616004 0 P 0 
L 0.98841004 -2.05516004 1.03818002 -2.05516004 0 P 0 
L 0.98835 -2.05416004 1.0382 -2.05416004 0 P 0 
L 0.98828002 -2.05316004 1.03821998 -2.05316004 0 P 0 
L 0.98821004 -2.05216004 1.03825 -2.05216004 0 P 0 
L 0.98815 -2.05116004 1.03826998 -2.05116004 0 P 0 
L 0.98808996 -2.05016004 1.03828996 -2.05016004 0 P 0 
L 0.98801998 -2.04916004 1.03831998 -2.04916004 0 P 0 
L 0.98796004 -2.04816004 1.03833996 -2.04816004 0 P 0 
L 0.98788996 -2.04716004 1.03836004 -2.04716004 0 P 0 
L 0.98783002 -2.04616004 1.03838996 -2.04616004 0 P 0 
L 0.98768996 -2.04516004 1.0384 -2.04516004 0 P 0 
L 0.98756004 -2.04416004 1.03841004 -2.04416004 0 P 0 
L 0.98738002 -2.04316004 1.03841998 -2.04316004 0 P 0 
L 0.98716004 -2.04216004 1.03843002 -2.04216004 0 P 0 
L 0.98691998 -2.04116004 1.03843996 -2.04116004 0 P 0 
L 0.98661998 -2.04016004 1.03845 -2.04016004 0 P 0 
L 0.98631998 -2.03916004 1.03846004 -2.03916004 0 P 0 
L 0.98593996 -2.03816004 1.03846998 -2.03816004 0 P 0 
L 0.98546998 -2.03716004 1.03848002 -2.03716004 0 P 0 
L 0.98491004 -2.03616004 1.03846998 -2.03616004 0 P 0 
L 0.98425 -2.03516004 1.03846004 -2.03516004 0 P 0 
L 0.98346004 -2.03416004 1.03846004 -2.03416004 0 P 0 
L 0.98251998 -2.03316004 1.03843996 -2.03316004 0 P 0 
L 0.98138002 -2.03216004 1.03843002 -2.03216004 0 P 0 
L 0.97998996 -2.03116004 1.03841998 -2.03116004 0 P 0 
L 0.97813996 -2.03016004 1.03841004 -2.03016004 0 P 0 
L 0.97491004 -2.02916004 1.0384 -2.02916004 0 P 0 
L 0.94763996 -2.00716004 1.03293996 -2.00716004 0 P 0 
L 0.94978996 -2.00616004 1.03231998 -2.00616004 0 P 0 
L 0.95081004 -2.00516004 1.0317 -2.00516004 0 P 0 
L 0.95183002 -2.00416004 1.03098002 -2.00416004 0 P 0 
L 0.95285 -2.00316004 1.03023002 -2.00316004 0 P 0 
L 0.95388996 -2.00216004 1.02936004 -2.00216004 0 P 0 
L 0.95498002 -2.00116004 1.02841998 -2.00116004 0 P 0 
L 0.95621998 -2.00016004 1.02738996 -2.00016004 0 P 0 
L 0.95761998 -1.99916004 1.0262 -1.99916004 0 P 0 
L 0.9592 -1.99816004 1.02486004 -1.99816004 0 P 0 
L 0.96083996 -1.99716004 1.02335 -1.99716004 0 P 0 
L 0.9627 -1.99616004 1.02161004 -1.99616004 0 P 0 
L 0.96468996 -1.99516004 1.01951998 -1.99516004 0 P 0 
L 0.96685 -1.99416004 1.01683002 -1.99416004 0 P 0 
L 0.96936998 -1.99316004 1.01378002 -1.99316004 0 P 0 
L 0.97236998 -1.99216004 1.00981004 -1.99216004 0 P 0 
L 0.97676004 -1.99116004 1.00456998 -1.99116004 0 P 0 
L 1.06713996 -2.08283002 1.12288002 -2.08283002 0 P 0 
L 1.06698996 -2.08183002 1.12193996 -2.08183002 0 P 0 
L 1.06686004 -2.08083002 1.12108996 -2.08083002 0 P 0 
L 1.06673996 -2.07983002 1.12036004 -2.07983002 0 P 0 
L 1.06661998 -2.07883002 1.11971998 -2.07883002 0 P 0 
L 1.06653002 -2.07783002 1.11916004 -2.07783002 0 P 0 
L 1.06648002 -2.07683002 1.11866004 -2.07683002 0 P 0 
L 1.06641998 -2.07583002 1.11826004 -2.07583002 0 P 0 
L 1.06636998 -2.07483002 1.11791998 -2.07483002 0 P 0 
L 1.06631998 -2.07383002 1.11761998 -2.07383002 0 P 0 
L 1.06626004 -2.07283002 1.11741998 -2.07283002 0 P 0 
L 1.06621004 -2.07183002 1.11723996 -2.07183002 0 P 0 
L 1.06616004 -2.07083002 1.11711998 -2.07083002 0 P 0 
L 1.06616004 -2.06983002 1.11701004 -2.06983002 0 P 0 
L 1.06616004 -2.06883002 1.11688996 -2.06883002 0 P 0 
L 1.06616998 -2.06783002 1.11676998 -2.06783002 0 P 0 
L 1.06618002 -2.06683002 1.11666998 -2.06683002 0 P 0 
L 1.06618996 -2.06583002 1.11663002 -2.06583002 0 P 0 
L 1.0662 -2.06483002 1.11658996 -2.06483002 0 P 0 
L 1.06621004 -2.06383002 1.11656004 -2.06383002 0 P 0 
L 1.06623002 -2.06283002 1.11651998 -2.06283002 0 P 0 
L 1.06631004 -2.06183002 1.11648996 -2.06183002 0 P 0 
L 1.06638002 -2.06083002 1.11653002 -2.06083002 0 P 0 
L 1.06645 -2.05983002 1.11656998 -2.05983002 0 P 0 
L 1.06651998 -2.05883002 1.11661998 -2.05883002 0 P 0 
L 1.06658996 -2.05783002 1.11666004 -2.05783002 0 P 0 
L 1.06666998 -2.05683002 1.11671004 -2.05683002 0 P 0 
L 1.06673996 -2.05583002 1.11681004 -2.05583002 0 P 0 
L 1.06686004 -2.05483002 1.11693002 -2.05483002 0 P 0 
L 1.067 -2.05383002 1.11705 -2.05383002 0 P 0 
L 1.06713996 -2.05283002 1.11718002 -2.05283002 0 P 0 
L 1.06728002 -2.05183002 1.11731004 -2.05183002 0 P 0 
L 1.06741998 -2.05083002 1.11746004 -2.05083002 0 P 0 
L 1.06756004 -2.04983002 1.11766004 -2.04983002 0 P 0 
L 1.0677 -2.04883002 1.11786004 -2.04883002 0 P 0 
L 1.06786004 -2.04783002 1.11813996 -2.04783002 0 P 0 
L 1.06806998 -2.04683002 1.11841998 -2.04683002 0 P 0 
L 1.06828002 -2.04583002 1.11876998 -2.04583002 0 P 0 
L 1.06848996 -2.04483002 1.11913002 -2.04483002 0 P 0 
L 1.06871004 -2.04383002 1.11955 -2.04383002 0 P 0 
L 1.06898996 -2.04283002 1.11998996 -2.04283002 0 P 0 
L 1.06928002 -2.04183002 1.12048002 -2.04183002 0 P 0 
L 1.06956004 -2.04083002 1.12101004 -2.04083002 0 P 0 
L 1.06985 -2.03983002 1.12161998 -2.03983002 0 P 0 
L 1.07021004 -2.03883002 1.12225 -2.03883002 0 P 0 
L 1.07056998 -2.03783002 1.12298002 -2.03783002 0 P 0 
L 1.07093002 -2.03683002 1.12373996 -2.03683002 0 P 0 
L 1.07128996 -2.03583002 1.12461998 -2.03583002 0 P 0 
L 1.07173002 -2.03483002 1.12548996 -2.03483002 0 P 0 
L 1.07216998 -2.03383002 1.12646004 -2.03383002 0 P 0 
L 1.07261998 -2.03283002 1.12748996 -2.03283002 0 P 0 
L 1.07308002 -2.03183002 1.12855 -2.03183002 0 P 0 
L 1.07361998 -2.03083002 1.12978996 -2.03083002 0 P 0 
L 1.09761004 -1.91731004 1.12756998 -1.91731004 0 P 0 
L 1.09566004 -1.91631004 1.12645 -1.91631004 0 P 0 
L 1.09371004 -1.91531004 1.12533002 -1.91531004 0 P 0 
L 1.09176004 -1.91431004 1.12416004 -1.91431004 0 P 0 
L 1.08946004 -1.91331004 1.12283996 -1.91331004 0 P 0 
L 1.07415 -2.02983002 1.13101998 -2.02983002 0 P 0 
L 1.07468996 -2.02883002 1.13248996 -2.02883002 0 P 0 
L 1.07528996 -2.02783002 1.134 -2.02783002 0 P 0 
L 1.07591998 -2.02683002 1.13586004 -2.02683002 0 P 0 
L 1.07656004 -2.02583002 1.13828996 -2.02583002 0 P 0 
L 1.07721004 -2.02483002 1.14243002 -2.02483002 0 P 0 
L 1.07795 -2.02383002 1.21126998 -2.02383002 0 P 0 
L 1.07868002 -2.02283002 1.21133002 -2.02283002 0 P 0 
L 1.07941998 -2.02183002 1.2114 -2.02183002 0 P 0 
L 1.08021004 -2.02083002 1.21146004 -2.02083002 0 P 0 
L 1.08103996 -2.01983002 1.21153002 -2.01983002 0 P 0 
L 1.08186998 -2.01883002 1.2116 -2.01883002 0 P 0 
L 1.08273002 -2.01783002 1.21166004 -2.01783002 0 P 0 
L 1.08366998 -2.01683002 1.21173002 -2.01683002 0 P 0 
L 1.0846 -2.01583002 1.2118 -2.01583002 0 P 0 
L 1.08555 -2.01483002 1.21186004 -2.01483002 0 P 0 
L 1.08661004 -2.01383002 1.21193002 -2.01383002 0 P 0 
L 1.08766998 -2.01283002 1.21198996 -2.01283002 0 P 0 
L 1.08873002 -2.01183002 1.21205 -2.01183002 0 P 0 
L 1.0898 -2.01083002 1.21211998 -2.01083002 0 P 0 
L 1.09098996 -2.00983002 1.21218002 -2.00983002 0 P 0 
L 1.09225 -2.00883002 1.21223996 -2.00883002 0 P 0 
L 1.09358996 -2.00783002 1.2123 -2.00783002 0 P 0 
L 1.09506998 -2.00683002 1.21236004 -2.00683002 0 P 0 
L 1.09668996 -2.00583002 1.21241998 -2.00583002 0 P 0 
L 0.98546998 -2.12516004 1.03548996 -2.12516004 0 P 0 
L 0.98558996 -2.12416004 1.03553996 -2.12416004 0 P 0 
L 0.9857 -2.12316004 1.03558002 -2.12316004 0 P 0 
L 0.98581004 -2.12216004 1.03561998 -2.12216004 0 P 0 
L 0.98591004 -2.12116004 1.03566998 -2.12116004 0 P 0 
L 0.98598996 -2.12016004 1.03571004 -2.12016004 0 P 0 
L 0.98608002 -2.11916004 1.03575 -2.11916004 0 P 0 
L 0.98616998 -2.11816004 1.0358 -2.11816004 0 P 0 
L 0.98625 -2.11716004 1.03583996 -2.11716004 0 P 0 
L 0.98633996 -2.11616004 1.03588002 -2.11616004 0 P 0 
L 0.98641998 -2.11516004 1.03593002 -2.11516004 0 P 0 
L 0.98651004 -2.11416004 1.03596998 -2.11416004 0 P 0 
L 0.9866 -2.11316004 1.03601004 -2.11316004 0 P 0 
L 0.98668002 -2.11216004 1.03605 -2.11216004 0 P 0 
L 0.98676998 -2.11116004 1.0361 -2.11116004 0 P 0 
L 0.98685 -2.11016004 1.03613996 -2.11016004 0 P 0 
L 0.98693996 -2.10916004 1.03618002 -2.10916004 0 P 0 
L 0.987 -2.10816004 1.03623002 -2.10816004 0 P 0 
L 0.98705 -2.10716004 1.03626998 -2.10716004 0 P 0 
L 0.9871 -2.10616004 1.03631004 -2.10616004 0 P 0 
L 0.98716004 -2.10516004 1.03636004 -2.10516004 0 P 0 
L 0.9872 -2.10416004 1.0364 -2.10416004 0 P 0 
L 0.98725 -2.10316004 1.03643996 -2.10316004 0 P 0 
L 0.98731004 -2.10216004 1.03648002 -2.10216004 0 P 0 
L 0.98735 -2.10116004 1.03653002 -2.10116004 0 P 0 
L 0.9874 -2.10016004 1.03656998 -2.10016004 0 P 0 
L 0.98746004 -2.09916004 1.03661004 -2.09916004 0 P 0 
L 0.98751004 -2.09816004 1.03666004 -2.09816004 0 P 0 
L 0.98755 -2.09716004 1.0367 -2.09716004 0 P 0 
L 0.9876 -2.09616004 1.03673996 -2.09616004 0 P 0 
L 0.98766004 -2.09516004 1.03678996 -2.09516004 0 P 0 
L 0.9877 -2.09416004 1.03683002 -2.09416004 0 P 0 
L 0.98775 -2.09316004 1.03686998 -2.09316004 0 P 0 
L 0.98781004 -2.09216004 1.03691998 -2.09216004 0 P 0 
L 0.98785 -2.09116004 1.03696004 -2.09116004 0 P 0 
L 0.9879 -2.09016004 1.037 -2.09016004 0 P 0 
L 0.98796004 -2.08916004 1.03703996 -2.08916004 0 P 0 
L 0.98798996 -2.08816004 1.03706998 -2.08816004 0 P 0 
L 0.98801998 -2.08716004 1.03711004 -2.08716004 0 P 0 
L 0.98805 -2.08616004 1.03715 -2.08616004 0 P 0 
L 0.98808996 -2.08516004 1.03718996 -2.08516004 0 P 0 
L 0.98811998 -2.08416004 1.03723002 -2.08416004 0 P 0 
L 1.08216998 -2.15683002 1.19803996 -2.15683002 0 P 0 
L 1.0821 -2.15583002 1.19861004 -2.15583002 0 P 0 
L 1.08201998 -2.15483002 1.19918002 -2.15483002 0 P 0 
L 1.08195 -2.15383002 1.1997 -2.15383002 0 P 0 
L 1.08188996 -2.15283002 1.20018002 -2.15283002 0 P 0 
L 1.08183002 -2.15183002 1.20066004 -2.15183002 0 P 0 
L 1.08176998 -2.15083002 1.20113996 -2.15083002 0 P 0 
L 1.08171998 -2.14983002 1.20153996 -2.14983002 0 P 0 
L 1.08166004 -2.14883002 1.20193002 -2.14883002 0 P 0 
L 1.0816 -2.14783002 1.11538996 -2.14783002 0 P 0 
L 1.08155 -2.14683002 1.10903002 -2.14683002 0 P 0 
L 1.0815 -2.14583002 1.10415 -2.14583002 0 P 0 
L 1.08146004 -2.14483002 1.09953002 -2.14483002 0 P 0 
L 1.08141004 -2.14383002 1.09563996 -2.14383002 0 P 0 
L 1.08136004 -2.14283002 1.09183996 -2.14283002 0 P 0 
L 1.08131004 -2.14183002 1.08821004 -2.14183002 0 P 0 
L 1.08133002 -2.14083002 1.08471998 -2.14083002 0 P 0 
L 1.09586998 -2.11983002 1.14965 -2.11983002 0 P 0 
L 1.09361998 -2.11883002 1.15221998 -2.11883002 0 P 0 
L 1.09158996 -2.11783002 1.20595 -2.11783002 0 P 0 
L 1.08988002 -2.11683002 1.20601004 -2.11683002 0 P 0 
L 1.08823996 -2.11583002 1.20606998 -2.11583002 0 P 0 
L 1.08678996 -2.11483002 1.20613002 -2.11483002 0 P 0 
L 1.08541004 -2.11383002 1.20618996 -2.11383002 0 P 0 
L 1.08416998 -2.11283002 1.20625 -2.11283002 0 P 0 
L 1.08295 -2.11183002 1.20631004 -2.11183002 0 P 0 
L 1.08188002 -2.11083002 1.20638002 -2.11083002 0 P 0 
L 1.08081998 -2.10983002 1.20643996 -2.10983002 0 P 0 
L 1.07986004 -2.10883002 1.2065 -2.10883002 0 P 0 
L 1.07895 -2.10783002 1.20656004 -2.10783002 0 P 0 
L 1.07803002 -2.10683002 1.20661998 -2.10683002 0 P 0 
L 1.07723996 -2.10583002 1.20666998 -2.10583002 0 P 0 
L 1.07646004 -2.10483002 1.20671998 -2.10483002 0 P 0 
L 1.07568002 -2.10383002 1.20678002 -2.10383002 0 P 0 
L 1.075 -2.10283002 1.20683002 -2.10283002 0 P 0 
L 1.07433002 -2.10183002 1.20688002 -2.10183002 0 P 0 
L 1.07366998 -2.10083002 1.20693996 -2.10083002 0 P 0 
L 1.07308996 -2.09983002 1.20698996 -2.09983002 0 P 0 
L 1.07253002 -2.09883002 1.20705 -2.09883002 0 P 0 
L 1.07198002 -2.09783002 1.2071 -2.09783002 0 P 0 
L 1.07146998 -2.09683002 1.20715 -2.09683002 0 P 0 
L 1.07101998 -2.09583002 1.2072 -2.09583002 0 P 0 
L 1.07056998 -2.09483002 1.20726004 -2.09483002 0 P 0 
L 1.07013002 -2.09383002 1.20731004 -2.09383002 0 P 0 
L 1.06976998 -2.09283002 1.20736004 -2.09283002 0 P 0 
L 1.06941998 -2.09183002 1.20741998 -2.09183002 0 P 0 
L 1.06906004 -2.09083002 1.20746998 -2.09083002 0 P 0 
L 1.06876004 -2.08983002 1.20753002 -2.08983002 0 P 0 
L 1.06848996 -2.08883002 1.13443002 -2.08883002 0 P 0 
L 1.06821998 -2.08783002 1.13068002 -2.08783002 0 P 0 
L 1.06795 -2.08683002 1.12836998 -2.08683002 0 P 0 
L 1.06771998 -2.08583002 1.1266 -2.08583002 0 P 0 
L 1.06753002 -2.08483002 1.12516004 -2.08483002 0 P 0 
L 1.06733002 -2.08383002 1.12393996 -2.08383002 0 P 0 
L 0.90273996 -1.85456998 0.89068996 -1.85558002 0 P 0 
L 0.89068996 -1.85558002 0.87421004 -1.85741998 0 P 0 
L 0.87421004 -1.85741998 0.85783002 -1.85946998 0 P 0 
L 0.85783002 -1.85946998 0.85526998 -1.8599 0 P 0 
L 0.85526998 -1.8599 0.85276004 -1.86055 0 P 0 
L 0.85276004 -1.86055 0.85255 -1.86063996 0 P 0 
L 0.85255 -1.86063996 0.85248996 -1.86068996 0 P 0 
L 0.85248996 -1.86068996 0.85243002 -1.86073002 0 P 0 
L 0.85243002 -1.86073002 0.85238002 -1.86078002 0 P 0 
L 0.85238002 -1.86078002 0.85233002 -1.86083996 0 P 0 
L 0.85233002 -1.86083996 0.85225 -1.86096004 0 P 0 
L 0.85225 -1.86096004 0.85218002 -1.8611 0 P 0 
L 0.85218002 -1.8611 0.85216004 -1.86116998 0 P 0 
L 0.85216004 -1.86116998 0.85215 -1.86123996 0 P 0 
L 0.85215 -1.86123996 0.85213996 -1.86136998 0 P 0 
L 0.85213996 -1.86136998 0.85213002 -1.86148996 0 P 0 
L 0.85213002 -1.86148996 0.85213996 -1.86161998 0 P 0 
L 0.85213996 -1.86161998 0.85215 -1.86173996 0 P 0 
L 0.85215 -1.86173996 0.85218002 -1.86186998 0 P 0 
L 0.85218002 -1.86186998 0.85221004 -1.86198996 0 P 0 
L 0.85221004 -1.86198996 0.85225 -1.8621 0 P 0 
L 0.85225 -1.8621 0.85231004 -1.86221998 0 P 0 
L 0.85231004 -1.86221998 0.85236998 -1.86233002 0 P 0 
L 0.85236998 -1.86233002 0.85281998 -1.863 0 P 0 
L 0.85281998 -1.863 0.8533 -1.86363996 0 P 0 
L 0.8533 -1.86363996 0.85383002 -1.86425 0 P 0 
L 0.85383002 -1.86425 0.85736004 -1.86801998 0 P 0 
L 0.85736004 -1.86801998 0.86013002 -1.87113002 0 P 0 
L 0.86013002 -1.87113002 0.86266004 -1.87443002 0 P 0 
L 0.86266004 -1.87443002 0.86501004 -1.87798996 0 P 0 
L 0.86501004 -1.87798996 0.86711998 -1.88171004 0 P 0 
L 0.86711998 -1.88171004 0.86896998 -1.88553996 0 P 0 
L 0.86896998 -1.88553996 0.87055 -1.8895 0 P 0 
L 0.87055 -1.8895 0.8718 -1.89343002 0 P 0 
L 0.8718 -1.89343002 0.87276004 -1.89745 0 P 0 
L 0.87276004 -1.89745 0.87371004 -1.90195 0 P 0 
L 0.87371004 -1.90195 0.87383002 -1.90236004 0 P 0 
L 0.87383002 -1.90236004 0.87396998 -1.90276004 0 P 0 
L 0.87396998 -1.90276004 0.87416004 -1.90313996 0 P 0 
L 0.87416004 -1.90313996 0.87436998 -1.90351004 0 P 0 
L 0.87436998 -1.90351004 0.87443002 -1.9036 0 P 0 
L 0.87443002 -1.9036 0.87456998 -1.90376004 0 P 0 
L 0.87456998 -1.90376004 0.87465 -1.90381998 0 P 0 
L 0.87465 -1.90381998 0.87473002 -1.90388996 0 P 0 
L 0.87473002 -1.90388996 0.87481998 -1.90393996 0 P 0 
L 0.87481998 -1.90393996 0.87491998 -1.90398996 0 P 0 
L 0.87491998 -1.90398996 0.87501004 -1.90403002 0 P 0 
L 0.87501004 -1.90403002 0.87521004 -1.90408996 0 P 0 
L 0.87521004 -1.90408996 0.87531998 -1.9041 0 P 0 
L 0.87531998 -1.9041 0.87573002 -1.90413002 0 P 0 
L 0.87573002 -1.90413002 0.87613996 -1.90411998 0 P 0 
L 0.87613996 -1.90411998 0.87653996 -1.90408002 0 P 0 
L 0.87653996 -1.90408002 0.87695 -1.90401004 0 P 0 
L 0.87695 -1.90401004 0.90756004 -1.89766998 0 P 0 
L 0.90756004 -1.89766998 0.92603996 -1.89478002 0 P 0 
L 0.92603996 -1.89478002 0.93486004 -1.89393996 0 P 0 
L 0.93486004 -1.89393996 0.94371004 -1.8935 0 P 0 
L 0.94371004 -1.8935 0.97045 -1.89308002 0 P 0 
L 0.97045 -1.89308002 0.99468996 -1.89328996 0 P 0 
L 0.99468996 -1.89328996 1.01021004 -1.89413996 0 P 0 
L 1.01021004 -1.89413996 1.0241 -1.89601998 0 P 0 
L 1.0241 -1.89601998 1.04188002 -1.89961004 0 P 0 
L 1.04188002 -1.89961004 1.06095 -1.90466004 0 P 0 
L 1.06095 -1.90466004 1.07963996 -1.91123002 0 P 0 
L 1.07963996 -1.91123002 1.09093996 -1.91613002 0 P 0 
L 1.09093996 -1.91613002 1.10186998 -1.92175 0 P 0 
L 1.10186998 -1.92175 1.11243996 -1.92806998 0 P 0 
L 1.11243996 -1.92806998 1.12163002 -1.93446998 0 P 0 
L 1.12163002 -1.93446998 1.13033002 -1.94148996 0 P 0 
L 1.13033002 -1.94148996 1.1385 -1.94911004 0 P 0 
L 1.1385 -1.94911004 1.14358996 -1.9546 0 P 0 
L 1.14358996 -1.9546 1.14825 -1.96045 0 P 0 
L 1.14825 -1.96045 1.15246998 -1.96663002 0 P 0 
L 1.15246998 -1.96663002 1.15623002 -1.97316004 0 P 0 
L 1.15623002 -1.97316004 1.15895 -1.97831004 0 P 0 
L 1.15895 -1.97831004 1.17358996 -1.97831004 0 P 0 
L 1.17358996 -1.97831004 1.17135 -1.9726 0 P 0 
L 1.17135 -1.9726 1.16696004 -1.96266998 0 P 0 
L 1.16696004 -1.96266998 1.16171998 -1.95313002 0 P 0 
L 1.16171998 -1.95313002 1.1557 -1.94406998 0 P 0 
L 1.1557 -1.94406998 1.14885 -1.93548002 0 P 0 
L 1.14885 -1.93548002 1.13778996 -1.92378002 0 P 0 
L 1.13778996 -1.92378002 1.12576998 -1.91301998 0 P 0 
L 1.12576998 -1.91301998 1.11283996 -1.90326004 0 P 0 
L 1.11283996 -1.90326004 1.09783002 -1.89368996 0 P 0 
L 1.09783002 -1.89368996 1.08213002 -1.88526998 0 P 0 
L 1.08213002 -1.88526998 1.06576998 -1.87801004 0 P 0 
L 1.06576998 -1.87801004 1.04776004 -1.87141998 0 P 0 
L 1.04776004 -1.87141998 1.02938002 -1.86591998 0 P 0 
L 1.02938002 -1.86591998 1.01058002 -1.8615 0 P 0 
L 1.01058002 -1.8615 0.98441998 -1.85711004 0 P 0 
L 0.98441998 -1.85711004 0.95781004 -1.85448996 0 P 0 
L 0.95781004 -1.85448996 0.93061004 -1.85366004 0 P 0 
L 0.93061004 -1.85366004 0.90273996 -1.85456998 0 P 0 
L 1.16015 -1.97631004 1.15798002 -1.97218996 0 P 0 
L 1.15798002 -1.97218996 1.15796004 -1.97216004 0 P 0 
L 1.15796004 -1.97216004 1.15416004 -1.96556998 0 P 0 
L 1.15416004 -1.96556998 1.15411998 -1.96551004 0 P 0 
L 1.15411998 -1.96551004 1.14986004 -1.95926004 0 P 0 
L 1.14986004 -1.95926004 1.14981998 -1.95921004 0 P 0 
L 1.14981998 -1.95921004 1.14511004 -1.9533 0 P 0 
L 1.14511004 -1.9533 1.13991998 -1.9477 0 P 0 
L 1.13991998 -1.9477 1.13986004 -1.94765 0 P 0 
L 1.13986004 -1.94765 1.13163996 -1.93998002 0 P 0 
L 1.13163996 -1.93998002 1.12283002 -1.93286004 0 P 0 
L 1.12283002 -1.93286004 1.11351998 -1.92638996 0 P 0 
L 1.11351998 -1.92638996 1.10283996 -1.92 0 P 0 
L 1.10283996 -1.92 1.0918 -1.91433002 0 P 0 
L 1.0918 -1.91433002 1.08036998 -1.90936004 0 P 0 
L 1.08036998 -1.90936004 1.06153002 -1.90273996 0 P 0 
L 1.06153002 -1.90273996 1.06146004 -1.90273002 0 P 0 
L 1.06146004 -1.90273002 1.04233002 -1.89766004 0 P 0 
L 1.04233002 -1.89766004 1.02443002 -1.89405 0 P 0 
L 1.02443002 -1.89405 1.0104 -1.89213996 0 P 0 
L 1.0104 -1.89213996 0.99475 -1.89128996 0 P 0 
L 0.99475 -1.89128996 0.97045 -1.89108002 0 P 0 
L 0.97045 -1.89108002 0.94365 -1.8915 0 P 0 
L 0.94365 -1.8915 0.94361998 -1.8915 0 P 0 
L 0.94361998 -1.8915 0.93471998 -1.89195 0 P 0 
L 0.93471998 -1.89195 0.92578996 -1.89278996 0 P 0 
L 0.92578996 -1.89278996 0.9072 -1.89571004 0 P 0 
L 0.9072 -1.89571004 0.87656998 -1.90203996 0 P 0 
L 0.87656998 -1.90203996 0.87626998 -1.9021 0 P 0 
L 0.87626998 -1.9021 0.87601998 -1.90211998 0 P 0 
L 0.87601998 -1.90211998 0.87588996 -1.90213002 0 P 0 
L 0.87588996 -1.90213002 0.87583002 -1.90198996 0 P 0 
L 0.87583002 -1.90198996 0.87573002 -1.90175 0 P 0 
L 0.87573002 -1.90175 0.87566004 -1.90146998 0 P 0 
L 0.87566004 -1.90146998 0.87471004 -1.89701004 0 P 0 
L 0.87471004 -1.89701004 0.8747 -1.89698996 0 P 0 
L 0.8747 -1.89698996 0.87373002 -1.89288996 0 P 0 
L 0.87373002 -1.89288996 0.87243002 -1.88881998 0 P 0 
L 0.87243002 -1.88881998 0.8724 -1.88876004 0 P 0 
L 0.8724 -1.88876004 0.8708 -1.88473996 0 P 0 
L 0.8708 -1.88473996 0.8689 -1.88078002 0 P 0 
L 0.8689 -1.88078002 0.86671998 -1.87693996 0 P 0 
L 0.86671998 -1.87693996 0.86428996 -1.87326004 0 P 0 
L 0.86428996 -1.87326004 0.86166998 -1.86985 0 P 0 
L 0.86166998 -1.86985 0.85883996 -1.86668002 0 P 0 
L 0.85883996 -1.86668002 0.85883002 -1.86666004 0 P 0 
L 0.85883002 -1.86666004 0.85531998 -1.86291004 0 P 0 
L 0.85531998 -1.86291004 0.85486004 -1.86238002 0 P 0 
L 0.85486004 -1.86238002 0.85466004 -1.86211998 0 P 0 
L 0.85466004 -1.86211998 0.8557 -1.86186004 0 P 0 
L 0.8557 -1.86186004 0.85811998 -1.86145 0 P 0 
L 0.85811998 -1.86145 0.87443996 -1.85941004 0 P 0 
L 0.87443996 -1.85941004 0.89088996 -1.85756998 0 P 0 
L 0.89088996 -1.85756998 0.90286004 -1.85656998 0 P 0 
L 0.90286004 -1.85656998 0.93061004 -1.85566004 0 P 0 
L 0.93061004 -1.85566004 0.95768002 -1.85648996 0 P 0 
L 0.95768002 -1.85648996 0.98416004 -1.8591 0 P 0 
L 0.98416004 -1.8591 1.01018996 -1.86346004 0 P 0 
L 1.01018996 -1.86346004 1.02886004 -1.86785 0 P 0 
L 1.02886004 -1.86785 1.04711998 -1.87331998 0 P 0 
L 1.04711998 -1.87331998 1.06501004 -1.87986004 0 P 0 
L 1.06501004 -1.87986004 1.08125 -1.88706998 0 P 0 
L 1.08125 -1.88706998 1.09681004 -1.89541998 0 P 0 
L 1.09681004 -1.89541998 1.1117 -1.9049 0 P 0 
L 1.1117 -1.9049 1.1245 -1.91456998 0 P 0 
L 1.1245 -1.91456998 1.13638996 -1.92521004 0 P 0 
L 1.13638996 -1.92521004 1.14733996 -1.93678996 0 P 0 
L 1.14733996 -1.93678996 1.15408002 -1.94525 0 P 0 
L 1.15408002 -1.94525 1.16001004 -1.95416998 0 P 0 
L 1.16001004 -1.95416998 1.16516004 -1.96355 0 P 0 
L 1.16516004 -1.96355 1.1695 -1.97336998 0 P 0 
L 1.1695 -1.97336998 1.17066004 -1.97631004 0 P 0 
L 1.17066004 -1.97631004 1.16015 -1.97631004 0 P 0 
L 0.87563002 -1.90131004 0.8801 -1.90131004 0 P 0 
L 0.87541004 -1.90031004 0.88493996 -1.90031004 0 P 0 
L 0.8752 -1.89931004 0.88976998 -1.89931004 0 P 0 
L 0.87498996 -1.89831004 0.8946 -1.89831004 0 P 0 
L 0.89423002 -2.08316004 0.94355 -2.08316004 0 P 0 
L 0.89428996 -2.08216004 0.9436 -2.08216004 0 P 0 
L 0.89435 -2.08116004 0.94365 -2.08116004 0 P 0 
L 0.89441004 -2.08016004 0.9437 -2.08016004 0 P 0 
L 0.89446004 -2.07916004 0.94375 -2.07916004 0 P 0 
L 0.89451998 -2.07816004 0.94378996 -2.07816004 0 P 0 
L 0.89458002 -2.07716004 0.94383996 -2.07716004 0 P 0 
L 0.89463996 -2.07616004 0.94388996 -2.07616004 0 P 0 
L 0.8947 -2.07516004 0.94393996 -2.07516004 0 P 0 
L 0.89475 -2.07416004 0.94398002 -2.07416004 0 P 0 
L 0.89481004 -2.07316004 0.94403002 -2.07316004 0 P 0 
L 0.89486998 -2.07216004 0.94408002 -2.07216004 0 P 0 
L 0.89493002 -2.07116004 0.94415 -2.07116004 0 P 0 
L 0.89498996 -2.07016004 0.94426004 -2.07016004 0 P 0 
L 0.89505 -2.06916004 0.94436998 -2.06916004 0 P 0 
L 0.8951 -2.06816004 0.94448002 -2.06816004 0 P 0 
L 0.89516004 -2.06716004 0.94458996 -2.06716004 0 P 0 
L 0.89521998 -2.06616004 0.9447 -2.06616004 0 P 0 
L 0.89526998 -2.06516004 0.94481004 -2.06516004 0 P 0 
L 0.89531004 -2.06416004 0.94491998 -2.06416004 0 P 0 
L 0.89535 -2.06316004 0.94503002 -2.06316004 0 P 0 
L 0.8954 -2.06216004 0.94513996 -2.06216004 0 P 0 
L 0.89543996 -2.06116004 0.94531998 -2.06116004 0 P 0 
L 0.89548996 -2.06016004 0.94551004 -2.06016004 0 P 0 
L 0.89553002 -2.05916004 0.9457 -2.05916004 0 P 0 
L 0.89558002 -2.05816004 0.94588996 -2.05816004 0 P 0 
L 0.89561998 -2.05716004 0.94608002 -2.05716004 0 P 0 
L 0.89566998 -2.05616004 0.94626998 -2.05616004 0 P 0 
L 0.89571004 -2.05516004 0.94646998 -2.05516004 0 P 0 
L 0.89575 -2.05416004 0.94666004 -2.05416004 0 P 0 
L 0.8958 -2.05316004 0.94685 -2.05316004 0 P 0 
L 0.89583996 -2.05216004 0.94708002 -2.05216004 0 P 0 
L 0.89588996 -2.05116004 0.94735 -2.05116004 0 P 0 
L 0.89593996 -2.05016004 0.94761998 -2.05016004 0 P 0 
L 0.89598002 -2.04916004 0.9479 -2.04916004 0 P 0 
L 0.89601998 -2.04816004 0.94825 -2.04816004 0 P 0 
L 0.89606998 -2.04716004 0.94858996 -2.04716004 0 P 0 
L 0.89611004 -2.04616004 0.94893002 -2.04616004 0 P 0 
L 0.89616004 -2.04516004 0.94935 -2.04516004 0 P 0 
L 0.8962 -2.04416004 0.94976998 -2.04416004 0 P 0 
L 0.89625 -2.04316004 0.9502 -2.04316004 0 P 0 
L 0.89628002 -2.04216004 0.95068996 -2.04216004 0 P 0 
L 0.89631004 -2.04116004 0.95118996 -2.04116004 0 P 0 
L 0.89633996 -2.04016004 0.95168996 -2.04016004 0 P 0 
L 0.89638002 -2.03916004 0.95228002 -2.03916004 0 P 0 
L 0.89641004 -2.03816004 0.95291004 -2.03816004 0 P 0 
L 0.89643996 -2.03716004 0.95363002 -2.03716004 0 P 0 
L 0.89646998 -2.03616004 0.95445 -2.03616004 0 P 0 
L 0.89651004 -2.03516004 0.95535 -2.03516004 0 P 0 
L 0.89653996 -2.03416004 0.95636998 -2.03416004 0 P 0 
L 0.89656998 -2.03316004 0.95756998 -2.03316004 0 P 0 
L 0.8966 -2.03216004 0.95893996 -2.03216004 0 P 0 
L 0.89663996 -2.03116004 0.96055 -2.03116004 0 P 0 
L 0.89666998 -2.03016004 0.96278002 -2.03016004 0 P 0 
L 0.8967 -2.02916004 0.96676004 -2.02916004 0 P 0 
L 0.89673996 -2.02816004 1.03838996 -2.02816004 0 P 0 
L 0.89676998 -2.02716004 1.03838002 -2.02716004 0 P 0 
L 0.8968 -2.02616004 1.03833996 -2.02616004 0 P 0 
L 0.89683996 -2.02516004 1.03828996 -2.02516004 0 P 0 
L 0.89686998 -2.02416004 1.03823002 -2.02416004 0 P 0 
L 0.8969 -2.02316004 1.03816004 -2.02316004 0 P 0 
L 0.89693996 -2.02216004 1.0381 -2.02216004 0 P 0 
L 0.89696998 -2.02116004 1.03803996 -2.02116004 0 P 0 
L 0.897 -2.02016004 1.0379 -2.02016004 0 P 0 
L 0.89703002 -2.01916004 1.03773996 -2.01916004 0 P 0 
L 0.89706004 -2.01816004 1.03751998 -2.01816004 0 P 0 
L 0.89708996 -2.01716004 1.03728002 -2.01716004 0 P 0 
L 0.89711998 -2.01616004 1.03698996 -2.01616004 0 P 0 
L 0.89713996 -2.01516004 1.03668002 -2.01516004 0 P 0 
L 0.89716998 -2.01416004 1.03631004 -2.01416004 0 P 0 
L 0.8972 -2.01316004 1.03591998 -2.01316004 0 P 0 
L 0.89721998 -2.01216004 1.03548996 -2.01216004 0 P 0 
L 0.89725 -2.01116004 1.03505 -2.01116004 0 P 0 
L 0.89726998 -2.01016004 1.03458002 -2.01016004 0 P 0 
L 0.8973 -2.00916004 1.03405 -2.00916004 0 P 0 
L 0.89733002 -2.00816004 1.03351998 -2.00816004 0 P 0 
L 0.89736004 -2.00716004 0.94676004 -2.00716004 0 P 0 
L 0.89738002 -2.00616004 0.9461 -2.00616004 0 P 0 
L 0.89741004 -2.00516004 0.94563996 -2.00516004 0 P 0 
L 0.89743996 -2.00416004 0.94563996 -2.00416004 0 P 0 
L 0.89746004 -2.00316004 0.94563996 -2.00316004 0 P 0 
L 0.89748996 -2.00216004 0.94563996 -2.00216004 0 P 0 
L 0.89751004 -2.00116004 0.94563996 -2.00116004 0 P 0 
L 0.89753996 -2.00016004 0.94563996 -2.00016004 0 P 0 
L 0.89756998 -1.99916004 0.94563996 -1.99916004 0 P 0 
L 0.8976 -1.99816004 0.94563996 -1.99816004 0 P 0 
L 0.89761998 -1.99716004 0.94563996 -1.99716004 0 P 0 
L 0.89765 -1.99616004 0.94563996 -1.99616004 0 P 0 
L 0.89768002 -1.99516004 0.94563996 -1.99516004 0 P 0 
L 0.97546998 -1.98933996 0.97236998 -1.99006004 0 P 0 
L 0.97236998 -1.99006004 0.96931998 -1.99103002 0 P 0 
L 0.96931998 -1.99103002 0.96603002 -1.99233002 0 P 0 
L 0.96603002 -1.99233002 0.96281004 -1.99383002 0 P 0 
L 0.96281004 -1.99383002 0.95976004 -1.99546998 0 P 0 
L 0.95976004 -1.99546998 0.95681004 -1.99728996 0 P 0 
L 0.95681004 -1.99728996 0.95521004 -1.99841004 0 P 0 
L 0.95521004 -1.99841004 0.95368996 -1.99963002 0 P 0 
L 0.95368996 -1.99963002 0.95223996 -2.00095 0 P 0 
L 0.95223996 -2.00095 0.94763996 -2.00546998 0 P 0 
L 0.94763996 -2.00546998 0.94763996 -1.99243996 0 P 0 
L 0.94763996 -1.99243996 0.89575 -1.99243996 0 P 0 
L 0.89575 -1.99243996 0.89505 -2.01878002 0 P 0 
L 0.89505 -2.01878002 0.89423996 -2.04316004 0 P 0 
L 0.89423996 -2.04316004 0.89321998 -2.0661 0 P 0 
L 0.89321998 -2.0661 0.89198996 -2.08728996 0 P 0 
L 0.89198996 -2.08728996 0.89055 -2.1063 0 P 0 
L 0.89055 -2.1063 0.88993996 -2.11358002 0 P 0 
L 0.88993996 -2.11358002 0.88943002 -2.11988002 0 P 0 
L 0.88943002 -2.11988002 0.88898996 -2.12533996 0 P 0 
L 0.88898996 -2.12533996 0.88896004 -2.12613002 0 P 0 
L 0.88896004 -2.12613002 0.88896998 -2.12621004 0 P 0 
L 0.88896998 -2.12621004 0.88898002 -2.12625 0 P 0 
L 0.88898002 -2.12625 0.88898996 -2.12628002 0 P 0 
L 0.88898996 -2.12628002 0.88901998 -2.12636004 0 P 0 
L 0.88901998 -2.12636004 0.88903996 -2.12638996 0 P 0 
L 0.88903996 -2.12638996 0.88906998 -2.12641998 0 P 0 
L 0.88906998 -2.12641998 0.88908996 -2.12645 0 P 0 
L 0.88908996 -2.12645 0.88911998 -2.12646998 0 P 0 
L 0.88911998 -2.12646998 0.88915 -2.1265 0 P 0 
L 0.88915 -2.1265 0.88921004 -2.12653996 0 P 0 
L 0.88921004 -2.12653996 0.88925 -2.12655 0 P 0 
L 0.88925 -2.12655 0.88928002 -2.12656004 0 P 0 
L 0.88928002 -2.12656004 0.88931998 -2.12658002 0 P 0 
L 0.88931998 -2.12658002 0.8894 -2.12658002 0 P 0 
L 0.8894 -2.12658002 0.89648002 -2.12686998 0 P 0 
L 0.89648002 -2.12686998 0.90518996 -2.1271 0 P 0 
L 0.90518996 -2.1271 0.9165 -2.12716004 0 P 0 
L 0.9165 -2.12716004 0.94403996 -2.12716004 0 P 0 
L 0.94403996 -2.12716004 0.94468996 -2.10135 0 P 0 
L 0.94468996 -2.10135 0.9461 -2.07171998 0 P 0 
L 0.9461 -2.07171998 0.94713002 -2.06233002 0 P 0 
L 0.94713002 -2.06233002 0.9489 -2.05308002 0 P 0 
L 0.9489 -2.05308002 0.94975 -2.04995 0 P 0 
L 0.94975 -2.04995 0.9508 -2.04688996 0 P 0 
L 0.9508 -2.04688996 0.95205 -2.0439 0 P 0 
L 0.95205 -2.0439 0.95351004 -2.041 0 P 0 
L 0.95351004 -2.041 0.9544 -2.03951004 0 P 0 
L 0.9544 -2.03951004 0.95541998 -2.03811004 0 P 0 
L 0.95541998 -2.03811004 0.95655 -2.03678996 0 P 0 
L 0.95655 -2.03678996 0.95778996 -2.03556998 0 P 0 
L 0.95778996 -2.03556998 0.95911998 -2.03446998 0 P 0 
L 0.95911998 -2.03446998 0.96056998 -2.03346998 0 P 0 
L 0.96056998 -2.03346998 0.96151004 -2.03291004 0 P 0 
L 0.96151004 -2.03291004 0.96248996 -2.03243002 0 P 0 
L 0.96248996 -2.03243002 0.96351004 -2.03201998 0 P 0 
L 0.96351004 -2.03201998 0.96455 -2.03168996 0 P 0 
L 0.96455 -2.03168996 0.96613002 -2.0313 0 P 0 
L 0.96613002 -2.0313 0.96773002 -2.03101998 0 P 0 
L 0.96773002 -2.03101998 0.96935 -2.03086004 0 P 0 
L 0.96935 -2.03086004 0.97095 -2.03081004 0 P 0 
L 0.97095 -2.03081004 0.97255 -2.03086998 0 P 0 
L 0.97255 -2.03086998 0.97413002 -2.03105 0 P 0 
L 0.97413002 -2.03105 0.97513002 -2.03123996 0 P 0 
L 0.97513002 -2.03123996 0.9761 -2.03151004 0 P 0 
L 0.9761 -2.03151004 0.97706004 -2.03186004 0 P 0 
L 0.97706004 -2.03186004 0.97796998 -2.0323 0 P 0 
L 0.97796998 -2.0323 0.97885 -2.0328 0 P 0 
L 0.97885 -2.0328 0.97968002 -2.03336998 0 P 0 
L 0.97968002 -2.03336998 0.98046998 -2.03398996 0 P 0 
L 0.98046998 -2.03398996 0.98121998 -2.03468002 0 P 0 
L 0.98121998 -2.03468002 0.98191004 -2.03541998 0 P 0 
L 0.98191004 -2.03541998 0.98253996 -2.0362 0 P 0 
L 0.98253996 -2.0362 0.9831 -2.03703002 0 P 0 
L 0.9831 -2.03703002 0.9836 -2.03788996 0 P 0 
L 0.9836 -2.03788996 0.98403996 -2.0388 0 P 0 
L 0.98403996 -2.0388 0.9844 -2.03973996 0 P 0 
L 0.9844 -2.03973996 0.98505 -2.04188996 0 P 0 
L 0.98505 -2.04188996 0.98553002 -2.04408002 0 P 0 
L 0.98553002 -2.04408002 0.98583002 -2.0463 0 P 0 
L 0.98583002 -2.0463 0.98653002 -2.05705 0 P 0 
L 0.98653002 -2.05705 0.9866 -2.06961004 0 P 0 
L 0.9866 -2.06961004 0.98596004 -2.08908002 0 P 0 
L 0.98596004 -2.08908002 0.98498002 -2.10858002 0 P 0 
L 0.98498002 -2.10858002 0.98388002 -2.12146998 0 P 0 
L 0.98388002 -2.12146998 0.98323002 -2.12716004 0 P 0 
L 0.98323002 -2.12716004 1.03741004 -2.12716004 0 P 0 
L 1.03741004 -2.12716004 1.03896004 -2.09103002 0 P 0 
L 1.03896004 -2.09103002 1.03956004 -2.0759 0 P 0 
L 1.03956004 -2.0759 1.04005 -2.06025 0 P 0 
L 1.04005 -2.06025 1.04038996 -2.04626004 0 P 0 
L 1.04038996 -2.04626004 1.04048002 -2.03698996 0 P 0 
L 1.04048002 -2.03698996 1.04036998 -2.02651998 0 P 0 
L 1.04036998 -2.02651998 1.04003996 -2.02096998 0 P 0 
L 1.04003996 -2.02096998 1.03975 -2.01895 0 P 0 
L 1.03975 -2.01895 1.0393 -2.01693996 0 P 0 
L 1.0393 -2.01693996 1.03868996 -2.01483996 0 P 0 
L 1.03868996 -2.01483996 1.03793996 -2.01278002 0 P 0 
L 1.03793996 -2.01278002 1.03658996 -2.00968002 0 P 0 
L 1.03658996 -2.00968002 1.03501004 -2.00668996 0 P 0 
L 1.03501004 -2.00668996 1.0332 -2.0038 0 P 0 
L 1.0332 -2.0038 1.03186998 -2.002 0 P 0 
L 1.03186998 -2.002 1.0304 -2.0003 0 P 0 
L 1.0304 -2.0003 1.0288 -1.99873002 0 P 0 
L 1.0288 -1.99873002 1.02708002 -1.99728996 0 P 0 
L 1.02708002 -1.99728996 1.02518002 -1.99593002 0 P 0 
L 1.02518002 -1.99593002 1.02318002 -1.99471998 0 P 0 
L 1.02318002 -1.99471998 1.0211 -1.99365 0 P 0 
L 1.0211 -1.99365 1.01893002 -1.99273996 0 P 0 
L 1.01893002 -1.99273996 1.01358996 -1.99098996 0 P 0 
L 1.01358996 -1.99098996 1.0081 -1.98971004 0 P 0 
L 1.0081 -1.98971004 1.00428996 -1.98908996 0 P 0 
L 1.00428996 -1.98908996 1.00043996 -1.98868002 0 P 0 
L 1.00043996 -1.98868002 0.99138002 -1.98826004 0 P 0 
L 0.99138002 -1.98826004 0.98251998 -1.98846998 0 P 0 
L 0.98251998 -1.98846998 0.97898996 -1.98878996 0 P 0 
L 0.97898996 -1.98878996 0.97546998 -1.98933996 0 P 0 
L 0.91651004 -2.12516004 0.94208996 -2.12516004 0 P 0 
L 0.8911 -2.12416004 0.94211004 -2.12416004 0 P 0 
L 0.89118002 -2.12316004 0.94213996 -2.12316004 0 P 0 
L 0.89125 -2.12216004 0.94216004 -2.12216004 0 P 0 
L 0.89133002 -2.12116004 0.94218996 -2.12116004 0 P 0 
L 0.89141004 -2.12016004 0.94221004 -2.12016004 0 P 0 
L 0.89148996 -2.11916004 0.94223996 -2.11916004 0 P 0 
L 0.89156998 -2.11816004 0.94226998 -2.11816004 0 P 0 
L 0.89166004 -2.11716004 0.94228996 -2.11716004 0 P 0 
L 0.89173996 -2.11616004 0.94231004 -2.11616004 0 P 0 
L 0.89181998 -2.11516004 0.94233996 -2.11516004 0 P 0 
L 0.8919 -2.11416004 0.94236004 -2.11416004 0 P 0 
L 0.89198002 -2.11316004 0.94238996 -2.11316004 0 P 0 
L 0.89206998 -2.11216004 0.94241998 -2.11216004 0 P 0 
L 0.89215 -2.11116004 0.94243996 -2.11116004 0 P 0 
L 0.89223002 -2.11016004 0.94246998 -2.11016004 0 P 0 
L 0.89231998 -2.10916004 0.94248996 -2.10916004 0 P 0 
L 0.8924 -2.10816004 0.94251998 -2.10816004 0 P 0 
L 0.89248002 -2.10716004 0.94255 -2.10716004 0 P 0 
L 0.89256998 -2.10616004 0.94256998 -2.10616004 0 P 0 
L 0.89263996 -2.10516004 0.94258996 -2.10516004 0 P 0 
L 0.89271004 -2.10416004 0.94261998 -2.10416004 0 P 0 
L 0.89278996 -2.10316004 0.94263996 -2.10316004 0 P 0 
L 0.89286998 -2.10216004 0.94266998 -2.10216004 0 P 0 
L 0.89293996 -2.10116004 0.9427 -2.10116004 0 P 0 
L 0.89301998 -2.10016004 0.94275 -2.10016004 0 P 0 
L 0.89308996 -2.09916004 0.94278996 -2.09916004 0 P 0 
L 0.89316998 -2.09816004 0.94283996 -2.09816004 0 P 0 
L 0.89325 -2.09716004 0.94288996 -2.09716004 0 P 0 
L 0.89331998 -2.09616004 0.94293996 -2.09616004 0 P 0 
L 0.8934 -2.09516004 0.94298002 -2.09516004 0 P 0 
L 0.89346998 -2.09416004 0.94303002 -2.09416004 0 P 0 
L 0.89355 -2.09316004 0.94308002 -2.09316004 0 P 0 
L 0.89361998 -2.09216004 0.94313002 -2.09216004 0 P 0 
L 0.8937 -2.09116004 0.94318002 -2.09116004 0 P 0 
L 0.89378002 -2.09016004 0.94321998 -2.09016004 0 P 0 
L 0.89385 -2.08916004 0.94326998 -2.08916004 0 P 0 
L 0.89393002 -2.08816004 0.94331998 -2.08816004 0 P 0 
L 0.894 -2.08716004 0.94336004 -2.08716004 0 P 0 
L 0.89406004 -2.08616004 0.94341004 -2.08616004 0 P 0 
L 0.89411998 -2.08516004 0.94346004 -2.08516004 0 P 0 
L 0.89418002 -2.08416004 0.94351004 -2.08416004 0 P 0 
L 0.91651004 -2.12516004 0.90521998 -2.1251 0 P 0 
L 0.90521998 -2.1251 0.89655 -2.12486998 0 P 0 
L 0.89655 -2.12486998 0.89106004 -2.12465 0 P 0 
L 0.89106004 -2.12465 0.89141998 -2.12003996 0 P 0 
L 0.89141998 -2.12003996 0.89193996 -2.11373996 0 P 0 
L 0.89193996 -2.11373996 0.89253996 -2.10645 0 P 0 
L 0.89253996 -2.10645 0.89398002 -2.08741998 0 P 0 
L 0.89398002 -2.08741998 0.89521998 -2.06621998 0 P 0 
L 0.89521998 -2.06621998 0.89521998 -2.06618996 0 P 0 
L 0.89521998 -2.06618996 0.89623996 -2.04323002 0 P 0 
L 0.89623996 -2.04323002 0.89703996 -2.01883002 0 P 0 
L 0.89703996 -2.01883002 0.8977 -1.99443996 0 P 0 
L 0.8977 -1.99443996 0.94563996 -1.99443996 0 P 0 
L 0.94563996 -1.99443996 0.94563996 -2.00546998 0 P 0 
L 0.94563996 -2.00546998 0.94686004 -2.00731004 0 P 0 
L 0.94686004 -2.00731004 0.94903002 -2.00688996 0 P 0 
L 0.94903002 -2.00688996 0.95361998 -2.00241004 0 P 0 
L 0.95361998 -2.00241004 0.95498996 -2.00115 0 P 0 
L 0.95498996 -2.00115 0.95641998 -2.00001004 0 P 0 
L 0.95641998 -2.00001004 0.9579 -1.99896004 0 P 0 
L 0.9579 -1.99896004 0.96076004 -1.9972 0 P 0 
L 0.96076004 -1.9972 0.9637 -1.99561998 0 P 0 
L 0.9637 -1.99561998 0.96683002 -1.99416998 0 P 0 
L 0.96683002 -1.99416998 0.96998996 -1.99291998 0 P 0 
L 0.96998996 -1.99291998 0.9729 -1.99198996 0 P 0 
L 0.9729 -1.99198996 0.97586004 -1.9913 0 P 0 
L 0.97586004 -1.9913 0.97923002 -1.99076998 0 P 0 
L 0.97923002 -1.99076998 0.98263002 -1.99046998 0 P 0 
L 0.98263002 -1.99046998 0.99136004 -1.99026004 0 P 0 
L 0.99136004 -1.99026004 1.00028996 -1.99066998 0 P 0 
L 1.00028996 -1.99066998 1.00403002 -1.99108002 0 P 0 
L 1.00403002 -1.99108002 1.00771004 -1.99166998 0 P 0 
L 1.00771004 -1.99166998 1.01305 -1.99291998 0 P 0 
L 1.01305 -1.99291998 1.01823002 -1.99461998 0 P 0 
L 1.01823002 -1.99461998 1.02026004 -1.99546998 0 P 0 
L 1.02026004 -1.99546998 1.02221004 -1.99646998 0 P 0 
L 1.02221004 -1.99646998 1.02408002 -1.9976 0 P 0 
L 1.02408002 -1.9976 1.02585 -1.99886998 0 P 0 
L 1.02585 -1.99886998 1.02746004 -2.00021004 0 P 0 
L 1.02746004 -2.00021004 1.02893996 -2.00166998 0 P 0 
L 1.02893996 -2.00166998 1.03031004 -2.00325 0 P 0 
L 1.03031004 -2.00325 1.03155 -2.00493002 0 P 0 
L 1.03155 -2.00493002 1.03326998 -2.00768002 0 P 0 
L 1.03326998 -2.00768002 1.03478002 -2.01055 0 P 0 
L 1.03478002 -2.01055 1.03608002 -2.01351998 0 P 0 
L 1.03608002 -2.01351998 1.03678996 -2.01546998 0 P 0 
L 1.03678996 -2.01546998 1.03736004 -2.01743002 0 P 0 
L 1.03736004 -2.01743002 1.03778002 -2.0193 0 P 0 
L 1.03778002 -2.0193 1.03805 -2.02116998 0 P 0 
L 1.03805 -2.02116998 1.03836998 -2.02658996 0 P 0 
L 1.03836998 -2.02658996 1.03848002 -2.03698996 0 P 0 
L 1.03848002 -2.03698996 1.03838996 -2.04623002 0 P 0 
L 1.03838996 -2.04623002 1.03805 -2.06018996 0 P 0 
L 1.03805 -2.06018996 1.03756004 -2.07583002 0 P 0 
L 1.03756004 -2.07583002 1.03696998 -2.09095 0 P 0 
L 1.03696998 -2.09095 1.03548996 -2.12516004 0 P 0 
L 1.03548996 -2.12516004 0.98546998 -2.12516004 0 P 0 
L 0.98546998 -2.12516004 0.98586998 -2.12166004 0 P 0 
L 0.98586998 -2.12166004 0.98696998 -2.10871998 0 P 0 
L 0.98696998 -2.10871998 0.98796004 -2.08916004 0 P 0 
L 0.98796004 -2.08916004 0.9886 -2.06963002 0 P 0 
L 0.9886 -2.06963002 0.98853002 -2.05698002 0 P 0 
L 0.98853002 -2.05698002 0.98781998 -2.0461 0 P 0 
L 0.98781998 -2.0461 0.9875 -2.04373002 0 P 0 
L 0.9875 -2.04373002 0.98748002 -2.04365 0 P 0 
L 0.98748002 -2.04365 0.98698996 -2.04138996 0 P 0 
L 0.98698996 -2.04138996 0.9863 -2.03908002 0 P 0 
L 0.9863 -2.03908002 0.98588002 -2.038 0 P 0 
L 0.98588002 -2.038 0.98538002 -2.03696004 0 P 0 
L 0.98538002 -2.03696004 0.9848 -2.03596004 0 P 0 
L 0.9848 -2.03596004 0.98413996 -2.03501004 0 P 0 
L 0.98413996 -2.03501004 0.98341998 -2.03411004 0 P 0 
L 0.98341998 -2.03411004 0.98336998 -2.03405 0 P 0 
L 0.98336998 -2.03405 0.98263002 -2.03326004 0 P 0 
L 0.98263002 -2.03326004 0.98176998 -2.03246998 0 P 0 
L 0.98176998 -2.03246998 0.98086998 -2.03175 0 P 0 
L 0.98086998 -2.03175 0.97991004 -2.0311 0 P 0 
L 0.97991004 -2.0311 0.9789 -2.03051998 0 P 0 
L 0.9789 -2.03051998 0.97783002 -2.03001998 0 P 0 
L 0.97783002 -2.03001998 0.97673002 -2.02961004 0 P 0 
L 0.97673002 -2.02961004 0.97663996 -2.02958002 0 P 0 
L 0.97663996 -2.02958002 0.97558996 -2.02928996 0 P 0 
L 0.97558996 -2.02928996 0.97443002 -2.02906998 0 P 0 
L 0.97443002 -2.02906998 0.9727 -2.02888002 0 P 0 
L 0.9727 -2.02888002 0.97261998 -2.02886998 0 P 0 
L 0.97261998 -2.02886998 0.97096004 -2.02881004 0 P 0 
L 0.97096004 -2.02881004 0.96921004 -2.02886004 0 P 0 
L 0.96921004 -2.02886004 0.96745 -2.02903996 0 P 0 
L 0.96745 -2.02903996 0.96571004 -2.02933996 0 P 0 
L 0.96571004 -2.02933996 0.964 -2.02976004 0 P 0 
L 0.964 -2.02976004 0.96283002 -2.03013996 0 P 0 
L 0.96283002 -2.03013996 0.96168002 -2.0306 0 P 0 
L 0.96168002 -2.0306 0.96056998 -2.03115 0 P 0 
L 0.96056998 -2.03115 0.95948996 -2.03178002 0 P 0 
L 0.95948996 -2.03178002 0.95791004 -2.03286998 0 P 0 
L 0.95791004 -2.03286998 0.95645 -2.03408996 0 P 0 
L 0.95645 -2.03408996 0.95508996 -2.03541998 0 P 0 
L 0.95508996 -2.03541998 0.95383996 -2.03686998 0 P 0 
L 0.95383996 -2.03686998 0.9538 -2.03693002 0 P 0 
L 0.9538 -2.03693002 0.95273002 -2.03841004 0 P 0 
L 0.95273002 -2.03841004 0.95175 -2.04003996 0 P 0 
L 0.95175 -2.04003996 0.95023002 -2.04306004 0 P 0 
L 0.95023002 -2.04306004 0.94896004 -2.04611004 0 P 0 
L 0.94896004 -2.04611004 0.94893002 -2.04616998 0 P 0 
L 0.94893002 -2.04616998 0.94783002 -2.04936004 0 P 0 
L 0.94783002 -2.04936004 0.94695 -2.05263002 0 P 0 
L 0.94695 -2.05263002 0.94515 -2.06203002 0 P 0 
L 0.94515 -2.06203002 0.9441 -2.07156004 0 P 0 
L 0.9441 -2.07156004 0.9427 -2.10128002 0 P 0 
L 0.9427 -2.10128002 0.94208996 -2.12516004 0 P 0 
L 0.94208996 -2.12516004 0.91651004 -2.12516004 0 P 0 
L 0.93143002 -2.21261998 1.00578996 -2.21261998 0 P 0 
L 0.94051004 -2.21161998 1.00803002 -2.21161998 0 P 0 
L 0.94941998 -2.21061998 1.01026004 -2.21061998 0 P 0 
L 0.9555 -2.20961998 1.0125 -2.20961998 0 P 0 
L 0.96158002 -2.20861998 1.01473996 -2.20861998 0 P 0 
L 0.96766004 -2.20761998 1.01696998 -2.20761998 0 P 0 
L 0.97373002 -2.20661998 1.01921004 -2.20661998 0 P 0 
L 0.97981004 -2.20561998 1.02145 -2.20561998 0 P 0 
L 0.98498996 -2.20461998 1.02368996 -2.20461998 0 P 0 
L 0.98973996 -2.20361998 1.02591998 -2.20361998 0 P 0 
L 0.99448996 -2.20261998 1.02816004 -2.20261998 0 P 0 
L 0.99923996 -2.20161998 1.0304 -2.20161998 0 P 0 
L 1.00398996 -2.20061998 1.03243996 -2.20061998 0 P 0 
L 1.00875 -2.19961998 1.0344 -2.19961998 0 P 0 
L 1.01348996 -2.19861998 1.03636998 -2.19861998 0 P 0 
L 1.0178 -2.19761998 1.03833996 -2.19761998 0 P 0 
L 1.02168996 -2.19661998 1.04031004 -2.19661998 0 P 0 
L 1.02558002 -2.19561998 1.04228002 -2.19561998 0 P 0 
L 1.02946998 -2.19461998 1.04415 -2.19461998 0 P 0 
L 1.03336004 -2.19361998 1.04596998 -2.19361998 0 P 0 
L 1.03725 -2.19261998 1.04778996 -2.19261998 0 P 0 
L 1.04113996 -2.19161998 1.0496 -2.19161998 0 P 0 
L 1.14356998 -1.98926998 1.13261004 -1.99086004 0 P 0 
L 1.13261004 -1.99086004 1.12165 -1.9934 0 P 0 
L 1.12165 -1.9934 1.11125 -1.99673002 0 P 0 
L 1.11125 -1.99673002 1.10658002 -1.99858996 0 P 0 
L 1.10658002 -1.99858996 1.10198996 -2.00071004 0 P 0 
L 1.10198996 -2.00071004 1.09653002 -2.00358996 0 P 0 
L 1.09653002 -2.00358996 1.09436998 -2.00488996 0 P 0 
L 1.09436998 -2.00488996 1.09226004 -2.00631004 0 P 0 
L 1.09226004 -2.00631004 1.09028002 -2.00781004 0 P 0 
L 1.09028002 -2.00781004 1.08836998 -2.00941998 0 P 0 
L 1.08836998 -2.00941998 1.08405 -2.0135 0 P 0 
L 1.08405 -2.0135 1.08096998 -2.01678996 0 P 0 
L 1.08096998 -2.01678996 1.07808002 -2.02026998 0 P 0 
L 1.07808002 -2.02026998 1.0754 -2.02393002 0 P 0 
L 1.0754 -2.02393002 1.07313996 -2.02748002 0 P 0 
L 1.07313996 -2.02748002 1.07116004 -2.03118996 0 P 0 
L 1.07116004 -2.03118996 1.06943996 -2.03505 0 P 0 
L 1.06943996 -2.03505 1.06795 -2.03918996 0 P 0 
L 1.06795 -2.03918996 1.06673996 -2.04343996 0 P 0 
L 1.06673996 -2.04343996 1.06583002 -2.04778002 0 P 0 
L 1.06583002 -2.04778002 1.06476998 -2.05538996 0 P 0 
L 1.06476998 -2.05538996 1.06421004 -2.06306004 0 P 0 
L 1.06421004 -2.06306004 1.06415 -2.07076004 0 P 0 
L 1.06415 -2.07076004 1.06456998 -2.0785 0 P 0 
L 1.06456998 -2.0785 1.06508996 -2.08276004 0 P 0 
L 1.06508996 -2.08276004 1.06591004 -2.08696004 0 P 0 
L 1.06591004 -2.08696004 1.06703002 -2.09108002 0 P 0 
L 1.06703002 -2.09108002 1.06833002 -2.09473002 0 P 0 
L 1.06833002 -2.09473002 1.06991998 -2.09823996 0 P 0 
L 1.06991998 -2.09823996 1.0718 -2.10161998 0 P 0 
L 1.0718 -2.10161998 1.07398002 -2.10491998 0 P 0 
L 1.07398002 -2.10491998 1.07641998 -2.10803002 0 P 0 
L 1.07641998 -2.10803002 1.07908996 -2.11095 0 P 0 
L 1.07908996 -2.11095 1.08175 -2.11345 0 P 0 
L 1.08175 -2.11345 1.08458996 -2.11573996 0 P 0 
L 1.08458996 -2.11573996 1.08758996 -2.1178 0 P 0 
L 1.08758996 -2.1178 1.09073002 -2.11963996 0 P 0 
L 1.09073002 -2.11963996 1.094 -2.12123996 0 P 0 
L 1.094 -2.12123996 1.0986 -2.12306998 0 P 0 
L 1.0986 -2.12306998 1.10331004 -2.12456004 0 P 0 
L 1.10331004 -2.12456004 1.10811004 -2.12568996 0 P 0 
L 1.10811004 -2.12568996 1.11298002 -2.12646998 0 P 0 
L 1.11298002 -2.12646998 1.1182 -2.12693002 0 P 0 
L 1.1182 -2.12693002 1.12343996 -2.12703002 0 P 0 
L 1.12343996 -2.12703002 1.12866998 -2.12676004 0 P 0 
L 1.12866998 -2.12676004 1.13388002 -2.12613002 0 P 0 
L 1.13388002 -2.12613002 1.14086004 -2.12473996 0 P 0 
L 1.14086004 -2.12473996 1.1477 -2.12273996 0 P 0 
L 1.1477 -2.12273996 1.15433996 -2.12015 0 P 0 
L 1.15433996 -2.12015 1.1545 -2.12008996 0 P 0 
L 1.1545 -2.12008996 1.15466004 -2.12003996 0 P 0 
L 1.15466004 -2.12003996 1.15483002 -2.12001004 0 P 0 
L 1.15483002 -2.12001004 1.15498996 -2.11998996 0 P 0 
L 1.15498996 -2.11998996 1.15533002 -2.11998996 0 P 0 
L 1.15533002 -2.11998996 1.15538996 -2.12 0 P 0 
L 1.15538996 -2.12 1.15545 -2.12001998 0 P 0 
L 1.15545 -2.12001998 1.15551004 -2.12003002 0 P 0 
L 1.15551004 -2.12003002 1.15556004 -2.12006004 0 P 0 
L 1.15556004 -2.12006004 1.15561004 -2.12008002 0 P 0 
L 1.15561004 -2.12008002 1.15566004 -2.12011004 0 P 0 
L 1.15566004 -2.12011004 1.15571004 -2.12015 0 P 0 
L 1.15571004 -2.12015 1.15575 -2.12018996 0 P 0 
L 1.15575 -2.12018996 1.15578996 -2.12023996 0 P 0 
L 1.15578996 -2.12023996 1.15583002 -2.12028002 0 P 0 
L 1.15583002 -2.12028002 1.15586004 -2.12033996 0 P 0 
L 1.15586004 -2.12033996 1.15588002 -2.12038996 0 P 0 
L 1.15588002 -2.12038996 1.15591004 -2.12043996 0 P 0 
L 1.15591004 -2.12043996 1.15601998 -2.12076004 0 P 0 
L 1.15601998 -2.12076004 1.1561 -2.12108002 0 P 0 
L 1.1561 -2.12108002 1.15616004 -2.12141998 0 P 0 
L 1.15616004 -2.12141998 1.15618002 -2.12175 0 P 0 
L 1.15618002 -2.12175 1.15623996 -2.12505 0 P 0 
L 1.15623996 -2.12505 1.15616004 -2.12688002 0 P 0 
L 1.15616004 -2.12688002 1.15593002 -2.12871004 0 P 0 
L 1.15593002 -2.12871004 1.15553996 -2.13051998 0 P 0 
L 1.15553996 -2.13051998 1.15516004 -2.1318 0 P 0 
L 1.15516004 -2.1318 1.1547 -2.13305 0 P 0 
L 1.1547 -2.13305 1.15415 -2.13426004 0 P 0 
L 1.15415 -2.13426004 1.15351004 -2.13545 0 P 0 
L 1.15351004 -2.13545 1.15278996 -2.1366 0 P 0 
L 1.15278996 -2.1366 1.15198002 -2.13768996 0 P 0 
L 1.15198002 -2.13768996 1.15111004 -2.13873002 0 P 0 
L 1.15111004 -2.13873002 1.15016004 -2.13971004 0 P 0 
L 1.15016004 -2.13971004 1.14876004 -2.14096004 0 P 0 
L 1.14876004 -2.14096004 1.14726004 -2.1421 0 P 0 
L 1.14726004 -2.1421 1.14566998 -2.14311004 0 P 0 
L 1.14566998 -2.14311004 1.144 -2.144 0 P 0 
L 1.144 -2.144 1.14226004 -2.14476004 0 P 0 
L 1.14226004 -2.14476004 1.14046004 -2.14536998 0 P 0 
L 1.14046004 -2.14536998 1.13863002 -2.14583002 0 P 0 
L 1.13863002 -2.14583002 1.13676004 -2.14613996 0 P 0 
L 1.13676004 -2.14613996 1.13041998 -2.14663996 0 P 0 
L 1.13041998 -2.14663996 1.12403996 -2.1466 0 P 0 
L 1.12403996 -2.1466 1.11621998 -2.14593996 0 P 0 
L 1.11621998 -2.14593996 1.10843996 -2.14471004 0 P 0 
L 1.10843996 -2.14471004 1.09946998 -2.14276998 0 P 0 
L 1.09946998 -2.14276998 1.0905 -2.14041004 0 P 0 
L 1.0905 -2.14041004 1.07963996 -2.13728996 0 P 0 
L 1.07963996 -2.13728996 1.07936004 -2.1401 0 P 0 
L 1.07936004 -2.1401 1.07931004 -2.14103996 0 P 0 
L 1.07931004 -2.14103996 1.07931998 -2.14198002 0 P 0 
L 1.07931998 -2.14198002 1.07956998 -2.14735 0 P 0 
L 1.07956998 -2.14735 1.07993996 -2.15375 0 P 0 
L 1.07993996 -2.15375 1.08045 -2.16081998 0 P 0 
L 1.08045 -2.16081998 1.08181004 -2.17873002 0 P 0 
L 1.08181004 -2.17873002 1.08996004 -2.18061004 0 P 0 
L 1.08996004 -2.18061004 1.09951004 -2.18246004 0 P 0 
L 1.09951004 -2.18246004 1.11243996 -2.18416998 0 P 0 
L 1.11243996 -2.18416998 1.1254 -2.18543002 0 P 0 
L 1.1254 -2.18543002 1.13508002 -2.18583002 0 P 0 
L 1.13508002 -2.18583002 1.14765 -2.18528996 0 P 0 
L 1.14765 -2.18528996 1.15368002 -2.18461004 0 P 0 
L 1.15368002 -2.18461004 1.15971004 -2.18363996 0 P 0 
L 1.15971004 -2.18363996 1.16521004 -2.18248002 0 P 0 
L 1.16521004 -2.18248002 1.17063996 -2.18103002 0 P 0 
L 1.17063996 -2.18103002 1.17528996 -2.17946998 0 P 0 
L 1.17528996 -2.17946998 1.17978002 -2.17753996 0 P 0 
L 1.17978002 -2.17753996 1.18216998 -2.1763 0 P 0 
L 1.18216998 -2.1763 1.18446004 -2.17488996 0 P 0 
L 1.18446004 -2.17488996 1.18663996 -2.17331004 0 P 0 
L 1.18663996 -2.17331004 1.18871004 -2.17156004 0 P 0 
L 1.18871004 -2.17156004 1.19161004 -2.16871998 0 P 0 
L 1.19161004 -2.16871998 1.19431004 -2.16568996 0 P 0 
L 1.19431004 -2.16568996 1.19678996 -2.16246998 0 P 0 
L 1.19678996 -2.16246998 1.19908996 -2.15901998 0 P 0 
L 1.19908996 -2.15901998 1.20113996 -2.15543996 0 P 0 
L 1.20113996 -2.15543996 1.20295 -2.15171004 0 P 0 
L 1.20295 -2.15171004 1.20435 -2.14815 0 P 0 
L 1.20435 -2.14815 1.20543996 -2.14448996 0 P 0 
L 1.20543996 -2.14448996 1.20621004 -2.14073996 0 P 0 
L 1.20621004 -2.14073996 1.20651998 -2.13855 0 P 0 
L 1.20651998 -2.13855 1.20671998 -2.13633996 0 P 0 
L 1.20671998 -2.13633996 1.20761998 -2.12321004 0 P 0 
L 1.20761998 -2.12321004 1.20858002 -2.10753996 0 P 0 
L 1.20858002 -2.10753996 1.20951004 -2.09021998 0 P 0 
L 1.20951004 -2.09021998 1.21048002 -2.07166004 0 P 0 
L 1.21048002 -2.07166004 1.21156004 -2.05228002 0 P 0 
L 1.21156004 -2.05228002 1.21258002 -2.03478996 0 P 0 
L 1.21258002 -2.03478996 1.21333002 -2.02286004 0 P 0 
L 1.21333002 -2.02286004 1.21393996 -2.01373996 0 P 0 
L 1.21393996 -2.01373996 1.21443996 -2.00568996 0 P 0 
L 1.21443996 -2.00568996 1.21485 -1.99883996 0 P 0 
L 1.21485 -1.99883996 1.2149 -1.99721004 0 P 0 
L 1.2149 -1.99721004 1.21488996 -1.99703996 0 P 0 
L 1.21488996 -1.99703996 1.21486998 -1.99686004 0 P 0 
L 1.21486998 -1.99686004 1.21483996 -1.99668996 0 P 0 
L 1.21483996 -1.99668996 1.21478996 -1.99653002 0 P 0 
L 1.21478996 -1.99653002 1.21473002 -1.99636998 0 P 0 
L 1.21473002 -1.99636998 1.21466004 -1.99621004 0 P 0 
L 1.21466004 -1.99621004 1.21458002 -1.99606004 0 P 0 
L 1.21458002 -1.99606004 1.21448002 -1.99591004 0 P 0 
L 1.21448002 -1.99591004 1.21433002 -1.99571998 0 P 0 
L 1.21433002 -1.99571998 1.21416998 -1.99553996 0 P 0 
L 1.21416998 -1.99553996 1.21398996 -1.99538002 0 P 0 
L 1.21398996 -1.99538002 1.21378996 -1.99523996 0 P 0 
L 1.21378996 -1.99523996 1.21358002 -1.99511004 0 P 0 
L 1.21358002 -1.99511004 1.21336004 -1.995 0 P 0 
L 1.21336004 -1.995 1.21261004 -1.99468996 0 P 0 
L 1.21261004 -1.99468996 1.21183996 -1.99443996 0 P 0 
L 1.21183996 -1.99443996 1.21105 -1.99423002 0 P 0 
L 1.21105 -1.99423002 1.20593996 -1.99318002 0 P 0 
L 1.20593996 -1.99318002 1.18996998 -1.99065 0 P 0 
L 1.18996998 -1.99065 1.17318996 -1.98908002 0 P 0 
L 1.17318996 -1.98908002 1.15718996 -1.98858002 0 P 0 
L 1.15718996 -1.98858002 1.1504 -1.98876004 0 P 0 
L 1.1504 -1.98876004 1.14356998 -1.98926998 0 P 0 
L 1.04503996 -2.19061998 1.05141998 -2.19061998 0 P 0 
L 1.04893002 -2.18961998 1.05323002 -2.18961998 0 P 0 
L 1.05263002 -2.18861998 1.05503996 -2.18861998 0 P 0 
L 1.05628996 -2.18761998 1.05676004 -2.18761998 0 P 0 
L 1.09645 -2.17983002 1.16738002 -2.17983002 0 P 0 
L 1.09126004 -2.17883002 1.17091004 -2.17883002 0 P 0 
L 1.0868 -2.17783002 1.17386998 -2.17783002 0 P 0 
L 1.08368002 -2.17683002 1.17636004 -2.17683002 0 P 0 
L 1.0836 -2.17583002 1.1787 -2.17583002 0 P 0 
L 1.08351998 -2.17483002 1.18066998 -2.17483002 0 P 0 
L 1.08345 -2.17383002 1.18236998 -2.17383002 0 P 0 
L 1.08336998 -2.17283002 1.1839 -2.17283002 0 P 0 
L 1.08328996 -2.17183002 1.18526998 -2.17183002 0 P 0 
L 1.08321998 -2.17083002 1.18646998 -2.17083002 0 P 0 
L 1.08313996 -2.16983002 1.18761998 -2.16983002 0 P 0 
L 1.08306998 -2.16883002 1.18863996 -2.16883002 0 P 0 
L 1.08298996 -2.16783002 1.18966004 -2.16783002 0 P 0 
L 1.08291998 -2.16683002 1.19061004 -2.16683002 0 P 0 
L 1.08283996 -2.16583002 1.1915 -2.16583002 0 P 0 
L 1.08276004 -2.16483002 1.19238996 -2.16483002 0 P 0 
L 1.08268996 -2.16383002 1.19321004 -2.16383002 0 P 0 
L 1.08261004 -2.16283002 1.19398002 -2.16283002 0 P 0 
L 1.08253002 -2.16183002 1.19476004 -2.16183002 0 P 0 
L 1.08246004 -2.16083002 1.19548002 -2.16083002 0 P 0 
L 1.08238002 -2.15983002 1.19613996 -2.15983002 0 P 0 
L 1.08231004 -2.15883002 1.19681004 -2.15883002 0 P 0 
L 1.08223996 -2.15783002 1.19746004 -2.15783002 0 P 0 
L 1.13506998 -2.18383002 1.12553002 -2.18343996 0 P 0 
L 1.12553002 -2.18343996 1.11266004 -2.18218002 0 P 0 
L 1.11266004 -2.18218002 1.09983002 -2.18048002 0 P 0 
L 1.09983002 -2.18048002 1.09036998 -2.17866004 0 P 0 
L 1.09036998 -2.17866004 1.0837 -2.17711004 0 P 0 
L 1.0837 -2.17711004 1.08245 -2.16066998 0 P 0 
L 1.08245 -2.16066998 1.08193996 -2.15361998 0 P 0 
L 1.08193996 -2.15361998 1.08156998 -2.14726004 0 P 0 
L 1.08156998 -2.14726004 1.08131998 -2.14191004 0 P 0 
L 1.08131998 -2.14191004 1.08131004 -2.14108996 0 P 0 
L 1.08131004 -2.14108996 1.08136004 -2.14026004 0 P 0 
L 1.08136004 -2.14026004 1.0814 -2.13986998 0 P 0 
L 1.0814 -2.13986998 1.08996004 -2.14233002 0 P 0 
L 1.08996004 -2.14233002 1.08996998 -2.14233996 0 P 0 
L 1.08996998 -2.14233996 1.08998996 -2.14233996 0 P 0 
L 1.08998996 -2.14233996 1.099 -2.14471998 0 P 0 
L 1.099 -2.14471998 1.10806998 -2.14668002 0 P 0 
L 1.10806998 -2.14668002 1.11598002 -2.14791998 0 P 0 
L 1.11598002 -2.14791998 1.12395 -2.1486 0 P 0 
L 1.12395 -2.1486 1.13048996 -2.14863996 0 P 0 
L 1.13048996 -2.14863996 1.137 -2.14811998 0 P 0 
L 1.137 -2.14811998 1.13903002 -2.14778996 0 P 0 
L 1.13903002 -2.14778996 1.14103002 -2.14728996 0 P 0 
L 1.14103002 -2.14728996 1.14298002 -2.14661998 0 P 0 
L 1.14298002 -2.14661998 1.14486998 -2.14581004 0 P 0 
L 1.14486998 -2.14581004 1.14668002 -2.14483996 0 P 0 
L 1.14668002 -2.14483996 1.1484 -2.14373996 0 P 0 
L 1.1484 -2.14373996 1.15003002 -2.1425 0 P 0 
L 1.15003002 -2.1425 1.15155 -2.14115 0 P 0 
L 1.15155 -2.14115 1.1526 -2.14006998 0 P 0 
L 1.1526 -2.14006998 1.15263996 -2.14001998 0 P 0 
L 1.15263996 -2.14001998 1.15356004 -2.13893002 0 P 0 
L 1.15356004 -2.13893002 1.15443996 -2.13771998 0 P 0 
L 1.15443996 -2.13771998 1.15523002 -2.13646004 0 P 0 
L 1.15523002 -2.13646004 1.15593996 -2.13515 0 P 0 
L 1.15593996 -2.13515 1.15655 -2.13381004 0 P 0 
L 1.15655 -2.13381004 1.15706004 -2.13243002 0 P 0 
L 1.15706004 -2.13243002 1.15748002 -2.13101004 0 P 0 
L 1.15748002 -2.13101004 1.1579 -2.12905 0 P 0 
L 1.1579 -2.12905 1.15816004 -2.12706004 0 P 0 
L 1.15816004 -2.12706004 1.15825 -2.12506998 0 P 0 
L 1.15825 -2.12506998 1.15818002 -2.12165 0 P 0 
L 1.15818002 -2.12165 1.15813996 -2.12118002 0 P 0 
L 1.15813996 -2.12118002 1.15813002 -2.1211 0 P 0 
L 1.15813002 -2.1211 1.15806004 -2.12068002 0 P 0 
L 1.15806004 -2.12068002 1.15793996 -2.12018996 0 P 0 
L 1.15793996 -2.12018996 1.15778002 -2.11973002 0 P 0 
L 1.15778002 -2.11973002 1.1577 -2.11953002 0 P 0 
L 1.1577 -2.11953002 1.15758996 -2.11933002 0 P 0 
L 1.15758996 -2.11933002 1.15746998 -2.11913996 0 P 0 
L 1.15746998 -2.11913996 1.15733002 -2.11895 0 P 0 
L 1.15733002 -2.11895 1.15716998 -2.11878002 0 P 0 
L 1.15716998 -2.11878002 1.157 -2.11863002 0 P 0 
L 1.157 -2.11863002 1.15681998 -2.11848996 0 P 0 
L 1.15681998 -2.11848996 1.15663002 -2.11836004 0 P 0 
L 1.15663002 -2.11836004 1.15641998 -2.11825 0 P 0 
L 1.15641998 -2.11825 1.15621004 -2.11816004 0 P 0 
L 1.15621004 -2.11816004 1.15598996 -2.11808996 0 P 0 
L 1.15598996 -2.11808996 1.15576998 -2.11803996 0 P 0 
L 1.15576998 -2.11803996 1.15553002 -2.118 0 P 0 
L 1.15553002 -2.118 1.15518002 -2.11798002 0 P 0 
L 1.15518002 -2.11798002 1.15483996 -2.11798996 0 P 0 
L 1.15483996 -2.11798996 1.15451004 -2.11803002 0 P 0 
L 1.15451004 -2.11803002 1.15418002 -2.1181 0 P 0 
L 1.15418002 -2.1181 1.15386004 -2.1182 0 P 0 
L 1.15386004 -2.1182 1.15361004 -2.11828996 0 P 0 
L 1.15361004 -2.11828996 1.14705 -2.12083996 0 P 0 
L 1.14705 -2.12083996 1.14038996 -2.12278996 0 P 0 
L 1.14038996 -2.12278996 1.13356004 -2.12416004 0 P 0 
L 1.13356004 -2.12416004 1.1285 -2.12476998 0 P 0 
L 1.1285 -2.12476998 1.12341004 -2.12501998 0 P 0 
L 1.12341004 -2.12501998 1.11831004 -2.12493002 0 P 0 
L 1.11831004 -2.12493002 1.11323002 -2.12448996 0 P 0 
L 1.11323002 -2.12448996 1.10848996 -2.12373002 0 P 0 
L 1.10848996 -2.12373002 1.10383996 -2.12263002 0 P 0 
L 1.10383996 -2.12263002 1.09926998 -2.12118996 0 P 0 
L 1.09926998 -2.12118996 1.09481004 -2.11941004 0 P 0 
L 1.09481004 -2.11941004 1.09168002 -2.11788002 0 P 0 
L 1.09168002 -2.11788002 1.08866004 -2.11611998 0 P 0 
L 1.08866004 -2.11611998 1.08578002 -2.11413002 0 P 0 
L 1.08578002 -2.11413002 1.08306998 -2.11193996 0 P 0 
L 1.08306998 -2.11193996 1.08051998 -2.10955 0 P 0 
L 1.08051998 -2.10955 1.07793996 -2.10673002 0 P 0 
L 1.07793996 -2.10673002 1.07561004 -2.10373996 0 P 0 
L 1.07561004 -2.10373996 1.07351004 -2.10058002 0 P 0 
L 1.07351004 -2.10058002 1.07171004 -2.09733996 0 P 0 
L 1.07171004 -2.09733996 1.07018002 -2.09396998 0 P 0 
L 1.07018002 -2.09396998 1.06893996 -2.09048002 0 P 0 
L 1.06893996 -2.09048002 1.06786004 -2.0865 0 P 0 
L 1.06786004 -2.0865 1.06706004 -2.08243996 0 P 0 
L 1.06706004 -2.08243996 1.06656004 -2.07833002 0 P 0 
L 1.06656004 -2.07833002 1.06615 -2.07071004 0 P 0 
L 1.06615 -2.07071004 1.06621004 -2.06313996 0 P 0 
L 1.06621004 -2.06313996 1.06675 -2.0556 0 P 0 
L 1.06675 -2.0556 1.0678 -2.04813002 0 P 0 
L 1.0678 -2.04813002 1.06868996 -2.04391998 0 P 0 
L 1.06868996 -2.04391998 1.06985 -2.03981004 0 P 0 
L 1.06985 -2.03981004 1.0713 -2.03578996 0 P 0 
L 1.0713 -2.03578996 1.07296004 -2.03206998 0 P 0 
L 1.07296004 -2.03206998 1.07486998 -2.02848996 0 P 0 
L 1.07486998 -2.02848996 1.07705 -2.02506004 0 P 0 
L 1.07705 -2.02506004 1.07966004 -2.0215 0 P 0 
L 1.07966004 -2.0215 1.08246998 -2.01811004 0 P 0 
L 1.08246998 -2.01811004 1.08546998 -2.01491004 0 P 0 
L 1.08546998 -2.01491004 1.0897 -2.01091004 0 P 0 
L 1.0897 -2.01091004 1.09153002 -2.00936998 0 P 0 
L 1.09153002 -2.00936998 1.09341998 -2.00793996 0 P 0 
L 1.09341998 -2.00793996 1.09545 -2.00658002 0 P 0 
L 1.09545 -2.00658002 1.09751004 -2.00533996 0 P 0 
L 1.09751004 -2.00533996 1.10288002 -2.0025 0 P 0 
L 1.10288002 -2.0025 1.10736998 -2.00043002 0 P 0 
L 1.10736998 -2.00043002 1.11193002 -1.99861004 0 P 0 
L 1.11193002 -1.99861004 1.12218002 -1.99533002 0 P 0 
L 1.12218002 -1.99533002 1.13298002 -1.99281998 0 P 0 
L 1.13298002 -1.99281998 1.14378996 -1.99126004 0 P 0 
L 1.14378996 -1.99126004 1.1505 -1.99075 0 P 0 
L 1.1505 -1.99075 1.15718002 -1.99058996 0 P 0 
L 1.15718002 -1.99058996 1.17306998 -1.99108002 0 P 0 
L 1.17306998 -1.99108002 1.18971998 -1.99263002 0 P 0 
L 1.18971998 -1.99263002 1.20558002 -1.99515 0 P 0 
L 1.20558002 -1.99515 1.21058996 -1.99618002 0 P 0 
L 1.21058996 -1.99618002 1.21126998 -1.99636004 0 P 0 
L 1.21126998 -1.99636004 1.21191998 -1.99656998 0 P 0 
L 1.21191998 -1.99656998 1.21253002 -1.99681998 0 P 0 
L 1.21253002 -1.99681998 1.21261004 -1.99686004 0 P 0 
L 1.21261004 -1.99686004 1.21266004 -1.99688996 0 P 0 
L 1.21266004 -1.99688996 1.21271998 -1.99693002 0 P 0 
L 1.21271998 -1.99693002 1.21281998 -1.99703002 0 P 0 
L 1.21281998 -1.99703002 1.21286004 -1.99708996 0 P 0 
L 1.21286004 -1.99708996 1.21288002 -1.99711004 0 P 0 
L 1.21288002 -1.99711004 1.21288002 -1.99711998 0 P 0 
L 1.21288002 -1.99711998 1.21288996 -1.99715 0 P 0 
L 1.21288996 -1.99715 1.2129 -1.99716998 0 P 0 
L 1.2129 -1.99716998 1.2129 -1.99721998 0 P 0 
L 1.2129 -1.99721998 1.21285 -1.99875 0 P 0 
L 1.21285 -1.99875 1.21243996 -2.00556998 0 P 0 
L 1.21243996 -2.00556998 1.21193996 -2.01361004 0 P 0 
L 1.21193996 -2.01361004 1.21133996 -2.02273002 0 P 0 
L 1.21133996 -2.02273002 1.21133996 -2.02273996 0 P 0 
L 1.21133996 -2.02273996 1.21058996 -2.03468002 0 P 0 
L 1.21058996 -2.03468002 1.20956004 -2.05216998 0 P 0 
L 1.20956004 -2.05216998 1.20848996 -2.07156004 0 P 0 
L 1.20848996 -2.07156004 1.20848996 -2.07156998 0 P 0 
L 1.20848996 -2.07156998 1.20751004 -2.09011004 0 P 0 
L 1.20751004 -2.09011004 1.20658996 -2.10743996 0 P 0 
L 1.20658996 -2.10743996 1.20561998 -2.12308996 0 P 0 
L 1.20561998 -2.12308996 1.20473002 -2.13618996 0 P 0 
L 1.20473002 -2.13618996 1.20453002 -2.13831998 0 P 0 
L 1.20453002 -2.13831998 1.20423996 -2.14041004 0 P 0 
L 1.20423996 -2.14041004 1.2035 -2.144 0 P 0 
L 1.2035 -2.144 1.20246004 -2.1475 0 P 0 
L 1.20246004 -2.1475 1.20111998 -2.1509 0 P 0 
L 1.20111998 -2.1509 1.19936998 -2.1545 0 P 0 
L 1.19936998 -2.1545 1.19738002 -2.15796998 0 P 0 
L 1.19738002 -2.15796998 1.19516004 -2.1613 0 P 0 
L 1.19516004 -2.1613 1.19276998 -2.16441004 0 P 0 
L 1.19276998 -2.16441004 1.19016004 -2.16733996 0 P 0 
L 1.19016004 -2.16733996 1.18736004 -2.17008002 0 P 0 
L 1.18736004 -2.17008002 1.1854 -2.17173996 0 P 0 
L 1.1854 -2.17173996 1.18335 -2.17323002 0 P 0 
L 1.18335 -2.17323002 1.18118002 -2.17456004 0 P 0 
L 1.18118002 -2.17456004 1.17893002 -2.17573002 0 P 0 
L 1.17893002 -2.17573002 1.17456998 -2.1776 0 P 0 
L 1.17456998 -2.1776 1.17006998 -2.17911998 0 P 0 
L 1.17006998 -2.17911998 1.16473996 -2.18053002 0 P 0 
L 1.16473996 -2.18053002 1.15935 -2.18166998 0 P 0 
L 1.15935 -2.18166998 1.15341998 -2.18263002 0 P 0 
L 1.15341998 -2.18263002 1.1475 -2.18328996 0 P 0 
L 1.1475 -2.18328996 1.13506998 -2.18383002 0 P 0 
L 0.90491998 -2.21461998 1.00131004 -2.21461998 0 P 0 
L 0.92235 -2.21361998 1.00355 -2.21361998 0 P 0 
L 0.76925 -1.8965 0.85586998 -1.8965 0 P 0 
L 0.76958996 -1.8955 0.85556004 -1.8955 0 P 0 
L 0.76995 -1.8945 0.85521004 -1.8945 0 P 0 
L 0.77031004 -1.8935 0.85486004 -1.8935 0 P 0 
L 0.77071004 -1.8925 0.85443996 -1.8925 0 P 0 
L 0.77115 -1.8915 0.85401004 -1.8915 0 P 0 
L 0.7716 -1.8905 0.85355 -1.8905 0 P 0 
L 0.77206004 -1.8895 0.85303002 -1.8895 0 P 0 
L 0.7726 -1.8885 0.85251004 -1.8885 0 P 0 
L 0.77313996 -1.8875 0.85198996 -1.8875 0 P 0 
L 0.77368996 -1.8865 0.85138002 -1.8865 0 P 0 
L 0.77433002 -1.8855 0.85073996 -1.8855 0 P 0 
L 0.77496004 -1.8845 0.85011004 -1.8845 0 P 0 
L 0.77561998 -1.8835 0.84943002 -1.8835 0 P 0 
L 0.77636004 -1.8825 0.84866998 -1.8825 0 P 0 
L 0.77711004 -1.8815 0.84791004 -1.8815 0 P 0 
L 0.7779 -1.8805 0.84713002 -1.8805 0 P 0 
L 0.77876998 -1.8795 0.84623002 -1.8795 0 P 0 
L 0.77963996 -1.8785 0.84533002 -1.8785 0 P 0 
L 0.7806 -1.8775 0.8444 -1.8775 0 P 0 
L 0.78161004 -1.8765 0.84335 -1.8765 0 P 0 
L 0.78265 -1.8755 0.84228996 -1.8755 0 P 0 
L 0.78381998 -1.8745 0.84108996 -1.8745 0 P 0 
L 0.78498996 -1.8735 0.83986998 -1.8735 0 P 0 
L 0.78635 -1.8725 0.83848002 -1.8725 0 P 0 
L 0.78773002 -1.8715 0.83706004 -1.8715 0 P 0 
L 0.78933002 -1.8705 0.83541998 -1.8705 0 P 0 
L 0.791 -1.8695 0.83366004 -1.8695 0 P 0 
L 0.793 -1.8685 0.83171998 -1.8685 0 P 0 
L 0.79525 -1.8675 0.82941998 -1.8675 0 P 0 
L 0.79791998 -1.8665 0.82671004 -1.8665 0 P 0 
L 0.80143996 -1.8655 0.82328996 -1.8655 0 P 0 
L 0.80705 -1.8645 0.81776004 -1.8645 0 P 0 
L 0.74543002 -1.89661998 0.75033002 -1.89661998 0 P 0 
L 0.74751004 -1.89561998 0.75058996 -1.89561998 0 P 0 
L 0.74958996 -1.89461998 0.75086004 -1.89461998 0 P 0 
L 0.76733996 -1.9125 0.85751998 -1.9125 0 P 0 
L 0.76728996 -1.9115 0.85756004 -1.9115 0 P 0 
L 0.76723996 -1.9105 0.85758996 -1.9105 0 P 0 
L 0.76721998 -1.9095 0.85763002 -1.9095 0 P 0 
L 0.76725 -1.9085 0.85761004 -1.9085 0 P 0 
L 0.76728002 -1.9075 0.85756998 -1.9075 0 P 0 
L 0.76731004 -1.9065 0.85753002 -1.9065 0 P 0 
L 0.76741998 -1.9055 0.85748996 -1.9055 0 P 0 
L 0.76753996 -1.9045 0.85738002 -1.9045 0 P 0 
L 0.76766004 -1.9035 0.85726004 -1.9035 0 P 0 
L 0.76781998 -1.9025 0.85713996 -1.9025 0 P 0 
L 0.76801998 -1.9015 0.85701004 -1.9015 0 P 0 
L 0.76821004 -1.9005 0.85683002 -1.9005 0 P 0 
L 0.76841998 -1.8995 0.85661998 -1.8995 0 P 0 
L 0.7687 -1.8985 0.85641004 -1.8985 0 P 0 
L 0.76896998 -1.8975 0.85613996 -1.8975 0 P 0 
L 0.76751004 -2.08325 0.8416 -2.08325 0 P 0 
L 0.76761998 -2.08225 0.84161998 -2.08225 0 P 0 
L 0.76773996 -2.08125 0.84166998 -2.08125 0 P 0 
L 0.76786004 -2.08025 0.84171998 -2.08025 0 P 0 
L 0.76796998 -2.07925 0.84176998 -2.07925 0 P 0 
L 0.76808002 -2.07825 0.84181004 -2.07825 0 P 0 
L 0.76818002 -2.07725 0.84186004 -2.07725 0 P 0 
L 0.76828996 -2.07625 0.8419 -2.07625 0 P 0 
L 0.76838996 -2.07525 0.84195 -2.07525 0 P 0 
L 0.76848996 -2.07425 0.842 -2.07425 0 P 0 
L 0.7686 -2.07325 0.84205 -2.07325 0 P 0 
L 0.7687 -2.07225 0.84208996 -2.07225 0 P 0 
L 0.7688 -2.07125 0.84213996 -2.07125 0 P 0 
L 0.7689 -2.07025 0.84218002 -2.07025 0 P 0 
L 0.76901004 -2.06925 0.84223002 -2.06925 0 P 0 
L 0.76911004 -2.06825 0.84228002 -2.06825 0 P 0 
L 0.76921004 -2.06725 0.84233002 -2.06725 0 P 0 
L 0.76931998 -2.06625 0.84236998 -2.06625 0 P 0 
L 0.76941998 -2.06525 0.84241998 -2.06525 0 P 0 
L 0.76948996 -2.06425 0.84246004 -2.06425 0 P 0 
L 0.76956004 -2.06325 0.84251004 -2.06325 0 P 0 
L 0.76963002 -2.06225 0.84256004 -2.06225 0 P 0 
L 0.7697 -2.06125 0.8426 -2.06125 0 P 0 
L 0.76976998 -2.06025 0.84265 -2.06025 0 P 0 
L 0.76983996 -2.05925 0.8427 -2.05925 0 P 0 
L 0.76991004 -2.05825 0.84273996 -2.05825 0 P 0 
L 0.76996998 -2.05725 0.84278996 -2.05725 0 P 0 
L 0.77001004 -2.05625 0.84283996 -2.05625 0 P 0 
L 0.77003996 -2.05525 0.84288002 -2.05525 0 P 0 
L 0.77008002 -2.05425 0.84295 -2.05425 0 P 0 
L 0.77011998 -2.05325 0.84303996 -2.05325 0 P 0 
L 0.77016004 -2.05225 0.84311998 -2.05225 0 P 0 
L 0.77018996 -2.05125 0.84321004 -2.05125 0 P 0 
L 0.77023002 -2.05025 0.8433 -2.05025 0 P 0 
L 0.77026998 -2.04925 0.84338002 -2.04925 0 P 0 
L 0.77031004 -2.04825 0.84346998 -2.04825 0 P 0 
L 0.77033996 -2.04725 0.84356004 -2.04725 0 P 0 
L 0.77038002 -2.04625 0.84363996 -2.04625 0 P 0 
L 0.77041004 -2.04525 0.84373002 -2.04525 0 P 0 
L 0.77043996 -2.04425 0.84381004 -2.04425 0 P 0 
L 0.77046004 -2.04325 0.8439 -2.04325 0 P 0 
L 0.77048002 -2.04225 0.84398996 -2.04225 0 P 0 
L 0.77051004 -2.04125 0.84406998 -2.04125 0 P 0 
L 0.77053002 -2.04025 0.84416004 -2.04025 0 P 0 
L 0.77055 -2.03925 0.84425 -2.03925 0 P 0 
L 0.77058002 -2.03825 0.84433002 -2.03825 0 P 0 
L 0.7706 -2.03725 0.84441998 -2.03725 0 P 0 
L 0.77061998 -2.03625 0.84451004 -2.03625 0 P 0 
L 0.77065 -2.03525 0.84458996 -2.03525 0 P 0 
L 0.77066998 -2.03425 0.84468002 -2.03425 0 P 0 
L 0.7707 -2.03325 0.84476998 -2.03325 0 P 0 
L 0.77071998 -2.03225 0.84485 -2.03225 0 P 0 
L 0.77073002 -2.03125 0.84493996 -2.03125 0 P 0 
L 0.77073996 -2.03025 0.84503002 -2.03025 0 P 0 
L 0.79986004 -1.8638 0.79643996 -1.86486998 0 P 0 
L 0.79643996 -1.86486998 0.79311998 -1.86621004 0 P 0 
L 0.79311998 -1.86621004 0.78991004 -1.86781004 0 P 0 
L 0.78991004 -1.86781004 0.78683996 -1.86966998 0 P 0 
L 0.78683996 -1.86966998 0.78391998 -1.87178002 0 P 0 
L 0.78391998 -1.87178002 0.78111998 -1.87416998 0 P 0 
L 0.78111998 -1.87416998 0.7785 -1.87676004 0 P 0 
L 0.7785 -1.87676004 0.77608002 -1.87953996 0 P 0 
L 0.77608002 -1.87953996 0.77386998 -1.8825 0 P 0 
L 0.77386998 -1.8825 0.77188002 -1.88561998 0 P 0 
L 0.77188002 -1.88561998 0.77013996 -1.88886004 0 P 0 
L 0.77013996 -1.88886004 0.76863996 -1.89221004 0 P 0 
L 0.76863996 -1.89221004 0.7674 -1.89566998 0 P 0 
L 0.7674 -1.89566998 0.76643002 -1.89921004 0 P 0 
L 0.76643002 -1.89921004 0.76571004 -1.90283996 0 P 0 
L 0.76571004 -1.90283996 0.76531004 -1.90636004 0 P 0 
L 0.76531004 -1.90636004 0.7652 -1.90991004 0 P 0 
L 0.7652 -1.90991004 0.76538996 -1.91345 0 P 0 
L 0.76538996 -1.91345 0.76586998 -1.91696998 0 P 0 
L 0.76586998 -1.91696998 0.76663996 -1.92046004 0 P 0 
L 0.76663996 -1.92046004 0.76803002 -1.92493996 0 P 0 
L 0.76803002 -1.92493996 0.76978002 -1.9293 0 P 0 
L 0.76978002 -1.9293 0.77106998 -1.93193996 0 P 0 
L 0.77106998 -1.93193996 0.77253002 -1.93448002 0 P 0 
L 0.77253002 -1.93448002 0.77416004 -1.93693996 0 P 0 
L 0.77416004 -1.93693996 0.77593002 -1.93923002 0 P 0 
L 0.77593002 -1.93923002 0.77783996 -1.94141004 0 P 0 
L 0.77783996 -1.94141004 0.77988996 -1.94345 0 P 0 
L 0.77988996 -1.94345 0.78216004 -1.94545 0 P 0 
L 0.78216004 -1.94545 0.78453996 -1.9473 0 P 0 
L 0.78453996 -1.9473 0.78703002 -1.94901998 0 P 0 
L 0.78703002 -1.94901998 0.79016998 -1.95088002 0 P 0 
L 0.79016998 -1.95088002 0.79343996 -1.95248996 0 P 0 
L 0.79343996 -1.95248996 0.79683002 -1.95383996 0 P 0 
L 0.79683002 -1.95383996 0.80031998 -1.95491998 0 P 0 
L 0.80031998 -1.95491998 0.80391004 -1.95573996 0 P 0 
L 0.80391004 -1.95573996 0.80751998 -1.95626004 0 P 0 
L 0.80751998 -1.95626004 0.81116004 -1.9565 0 P 0 
L 0.81116004 -1.9565 0.81481004 -1.95646004 0 P 0 
L 0.81481004 -1.95646004 0.81843996 -1.95613002 0 P 0 
L 0.81843996 -1.95613002 0.82205 -1.95551004 0 P 0 
L 0.82205 -1.95551004 0.82561998 -1.95461004 0 P 0 
L 0.82561998 -1.95461004 0.82911004 -1.95345 0 P 0 
L 0.82911004 -1.95345 0.83248996 -1.95201004 0 P 0 
L 0.83248996 -1.95201004 0.83576004 -1.95031998 0 P 0 
L 0.83576004 -1.95031998 0.83891998 -1.94836004 0 P 0 
L 0.83891998 -1.94836004 0.84191998 -1.94616998 0 P 0 
L 0.84191998 -1.94616998 0.84475 -1.94375 0 P 0 
L 0.84475 -1.94375 0.84738996 -1.94113996 0 P 0 
L 0.84738996 -1.94113996 0.84983002 -1.93833996 0 P 0 
L 0.84983002 -1.93833996 0.85206998 -1.93533996 0 P 0 
L 0.85206998 -1.93533996 0.8536 -1.93291998 0 P 0 
L 0.8536 -1.93291998 0.85496004 -1.93041004 0 P 0 
L 0.85496004 -1.93041004 0.85613996 -1.9278 0 P 0 
L 0.85613996 -1.9278 0.85711998 -1.92511004 0 P 0 
L 0.85711998 -1.92511004 0.85823002 -1.92123002 0 P 0 
L 0.85823002 -1.92123002 0.85901998 -1.91726998 0 P 0 
L 0.85901998 -1.91726998 0.85948996 -1.91323996 0 P 0 
L 0.85948996 -1.91323996 0.85963996 -1.90918002 0 P 0 
L 0.85963996 -1.90918002 0.85946998 -1.90513002 0 P 0 
L 0.85946998 -1.90513002 0.85898002 -1.9011 0 P 0 
L 0.85898002 -1.9011 0.85841998 -1.89826004 0 P 0 
L 0.85841998 -1.89826004 0.85766004 -1.89546004 0 P 0 
L 0.85766004 -1.89546004 0.85671004 -1.89273002 0 P 0 
L 0.85671004 -1.89273002 0.85556998 -1.89006004 0 P 0 
L 0.85556998 -1.89006004 0.85361998 -1.88631004 0 P 0 
L 0.85361998 -1.88631004 0.85136004 -1.88273996 0 P 0 
L 0.85136004 -1.88273996 0.84881004 -1.87938002 0 P 0 
L 0.84881004 -1.87938002 0.84596998 -1.87623002 0 P 0 
L 0.84596998 -1.87623002 0.84355 -1.87393996 0 P 0 
L 0.84355 -1.87393996 0.84096998 -1.87181998 0 P 0 
L 0.84096998 -1.87181998 0.83826004 -1.86988996 0 P 0 
L 0.83826004 -1.86988996 0.83541004 -1.86815 0 P 0 
L 0.83541004 -1.86815 0.83243996 -1.86661004 0 P 0 
L 0.83243996 -1.86661004 0.82938996 -1.86531004 0 P 0 
L 0.82938996 -1.86531004 0.82625 -1.86423002 0 P 0 
L 0.82625 -1.86423002 0.82303996 -1.86336004 0 P 0 
L 0.82303996 -1.86336004 0.81978002 -1.86273002 0 P 0 
L 0.81978002 -1.86273002 0.81646998 -1.86233002 0 P 0 
L 0.81646998 -1.86233002 0.81228996 -1.86215 0 P 0 
L 0.81228996 -1.86215 0.80811004 -1.86233996 0 P 0 
L 0.80811004 -1.86233996 0.80396004 -1.86288996 0 P 0 
L 0.80396004 -1.86288996 0.79986004 -1.8638 0 P 0 
L 0.80308996 -1.9535 0.82186004 -1.9535 0 P 0 
L 0.79926004 -1.9525 0.82563996 -1.9525 0 P 0 
L 0.79636004 -1.9515 0.82856998 -1.9515 0 P 0 
L 0.79393002 -1.9505 0.83093996 -1.9505 0 P 0 
L 0.7919 -1.9495 0.83298996 -1.9495 0 P 0 
L 0.79008002 -1.9485 0.8349 -1.9485 0 P 0 
L 0.78838996 -1.9475 0.83651004 -1.9475 0 P 0 
L 0.7869 -1.9465 0.83806998 -1.9465 0 P 0 
L 0.78548002 -1.9455 0.83943996 -1.9455 0 P 0 
L 0.7842 -1.9445 0.84078996 -1.9445 0 P 0 
L 0.78298002 -1.9435 0.84196998 -1.9435 0 P 0 
L 0.78183996 -1.9425 0.84313996 -1.9425 0 P 0 
L 0.78076998 -1.9415 0.84418996 -1.9415 0 P 0 
L 0.77976004 -1.9405 0.8452 -1.9405 0 P 0 
L 0.77883002 -1.9395 0.84616998 -1.9395 0 P 0 
L 0.77793996 -1.9385 0.84703996 -1.9385 0 P 0 
L 0.77711998 -1.9375 0.84791004 -1.9375 0 P 0 
L 0.77635 -1.9365 0.84871004 -1.9365 0 P 0 
L 0.77561004 -1.9355 0.84945 -1.9355 0 P 0 
L 0.77493996 -1.9345 0.8502 -1.9345 0 P 0 
L 0.77428002 -1.9335 0.85086998 -1.9335 0 P 0 
L 0.7737 -1.9325 0.8515 -1.9325 0 P 0 
L 0.77311998 -1.9315 0.8521 -1.9315 0 P 0 
L 0.77258996 -1.9305 0.85263996 -1.9305 0 P 0 
L 0.7721 -1.9295 0.85318002 -1.9295 0 P 0 
L 0.77161004 -1.9285 0.85363002 -1.9285 0 P 0 
L 0.77121004 -1.9275 0.85408002 -1.9275 0 P 0 
L 0.77081004 -1.9265 0.85448002 -1.9265 0 P 0 
L 0.77041004 -1.9255 0.85485 -1.9255 0 P 0 
L 0.77001004 -1.9245 0.85521998 -1.9245 0 P 0 
L 0.76968002 -1.9235 0.8555 -1.9235 0 P 0 
L 0.76936998 -1.9225 0.85578996 -1.9225 0 P 0 
L 0.76906004 -1.9215 0.85606998 -1.9215 0 P 0 
L 0.76875 -1.9205 0.85633002 -1.9205 0 P 0 
L 0.76848002 -1.9195 0.85653002 -1.9195 0 P 0 
L 0.76826004 -1.9185 0.85673002 -1.9185 0 P 0 
L 0.76803002 -1.9175 0.85693002 -1.9175 0 P 0 
L 0.76783002 -1.9165 0.85708996 -1.9165 0 P 0 
L 0.76768996 -1.9155 0.85721004 -1.9155 0 P 0 
L 0.76755 -1.9145 0.85733002 -1.9145 0 P 0 
L 0.76741998 -1.9135 0.85745 -1.9135 0 P 0 
L 0.81121004 -1.9545 0.80773002 -1.95426998 0 P 0 
L 0.80773002 -1.95426998 0.80426998 -1.95376998 0 P 0 
L 0.80426998 -1.95376998 0.80083996 -1.95298996 0 P 0 
L 0.80083996 -1.95298996 0.7975 -1.95195 0 P 0 
L 0.7975 -1.95195 0.79426004 -1.95066004 0 P 0 
L 0.79426004 -1.95066004 0.79111998 -1.94911998 0 P 0 
L 0.79111998 -1.94911998 0.78811004 -1.94733002 0 P 0 
L 0.78811004 -1.94733002 0.78573002 -1.94568996 0 P 0 
L 0.78573002 -1.94568996 0.78343996 -1.9439 0 P 0 
L 0.78343996 -1.9439 0.78126004 -1.94198996 0 P 0 
L 0.78126004 -1.94198996 0.7793 -1.94003996 0 P 0 
L 0.7793 -1.94003996 0.77746998 -1.93796004 0 P 0 
L 0.77746998 -1.93796004 0.77578996 -1.93576998 0 P 0 
L 0.77578996 -1.93576998 0.77423002 -1.93343002 0 P 0 
L 0.77423002 -1.93343002 0.77283996 -1.931 0 P 0 
L 0.77283996 -1.931 0.77161004 -1.92848996 0 P 0 
L 0.77161004 -1.92848996 0.76991998 -1.92426998 0 P 0 
L 0.76991998 -1.92426998 0.76858002 -1.91993996 0 P 0 
L 0.76858002 -1.91993996 0.76783996 -1.91661998 0 P 0 
L 0.76783996 -1.91661998 0.76738002 -1.91326998 0 P 0 
L 0.76738002 -1.91326998 0.76721004 -1.90988996 0 P 0 
L 0.76721004 -1.90988996 0.76731004 -1.90651004 0 P 0 
L 0.76731004 -1.90651004 0.7677 -1.90315 0 P 0 
L 0.7677 -1.90315 0.76838002 -1.89966998 0 P 0 
L 0.76838002 -1.89966998 0.76931004 -1.89626998 0 P 0 
L 0.76931004 -1.89626998 0.7705 -1.89296004 0 P 0 
L 0.7705 -1.89296004 0.77193996 -1.88973996 0 P 0 
L 0.77193996 -1.88973996 0.7736 -1.88663996 0 P 0 
L 0.7736 -1.88663996 0.77551004 -1.88363996 0 P 0 
L 0.77551004 -1.88363996 0.77763002 -1.8808 0 P 0 
L 0.77763002 -1.8808 0.77996004 -1.87813002 0 P 0 
L 0.77996004 -1.87813002 0.78246998 -1.87565 0 P 0 
L 0.78246998 -1.87565 0.78516004 -1.87336004 0 P 0 
L 0.78516004 -1.87336004 0.78795 -1.87133996 0 P 0 
L 0.78795 -1.87133996 0.79088002 -1.86956004 0 P 0 
L 0.79088002 -1.86956004 0.79393996 -1.86803002 0 P 0 
L 0.79393996 -1.86803002 0.79711004 -1.86675 0 P 0 
L 0.79711004 -1.86675 0.80038002 -1.86573002 0 P 0 
L 0.80038002 -1.86573002 0.80431004 -1.86486004 0 P 0 
L 0.80431004 -1.86486004 0.80828996 -1.86433996 0 P 0 
L 0.80828996 -1.86433996 0.8123 -1.86416004 0 P 0 
L 0.8123 -1.86416004 0.81631004 -1.86431998 0 P 0 
L 0.81631004 -1.86431998 0.81946998 -1.86471004 0 P 0 
L 0.81946998 -1.86471004 0.82258996 -1.86531004 0 P 0 
L 0.82258996 -1.86531004 0.82566004 -1.86613996 0 P 0 
L 0.82566004 -1.86613996 0.82866998 -1.86718002 0 P 0 
L 0.82866998 -1.86718002 0.83158996 -1.86843002 0 P 0 
L 0.83158996 -1.86843002 0.83443002 -1.86988996 0 P 0 
L 0.83443002 -1.86988996 0.83716004 -1.87156004 0 P 0 
L 0.83716004 -1.87156004 0.83976004 -1.87341004 0 P 0 
L 0.83976004 -1.87341004 0.84223002 -1.87543996 0 P 0 
L 0.84223002 -1.87543996 0.84453996 -1.87763002 0 P 0 
L 0.84453996 -1.87763002 0.84726998 -1.88065 0 P 0 
L 0.84726998 -1.88065 0.84971998 -1.88388002 0 P 0 
L 0.84971998 -1.88388002 0.85188996 -1.88731004 0 P 0 
L 0.85188996 -1.88731004 0.85376004 -1.89091004 0 P 0 
L 0.85376004 -1.89091004 0.85483996 -1.89345 0 P 0 
L 0.85483996 -1.89345 0.85575 -1.89605 0 P 0 
L 0.85575 -1.89605 0.85646998 -1.89871004 0 P 0 
L 0.85646998 -1.89871004 0.857 -1.90141004 0 P 0 
L 0.857 -1.90141004 0.85748002 -1.9053 0 P 0 
L 0.85748002 -1.9053 0.85763996 -1.90918996 0 P 0 
L 0.85763996 -1.90918996 0.8575 -1.91308002 0 P 0 
L 0.8575 -1.91308002 0.85703996 -1.91696004 0 P 0 
L 0.85703996 -1.91696004 0.85628002 -1.92076004 0 P 0 
L 0.85628002 -1.92076004 0.85521998 -1.92448996 0 P 0 
L 0.85521998 -1.92448996 0.85428002 -1.92705 0 P 0 
L 0.85428002 -1.92705 0.85316998 -1.92951998 0 P 0 
L 0.85316998 -1.92951998 0.85188002 -1.93191004 0 P 0 
L 0.85188002 -1.93191004 0.85041998 -1.9342 0 P 0 
L 0.85041998 -1.9342 0.84826998 -1.93708002 0 P 0 
L 0.84826998 -1.93708002 0.84593002 -1.93976998 0 P 0 
L 0.84593002 -1.93976998 0.8434 -1.94228002 0 P 0 
L 0.8434 -1.94228002 0.84068002 -1.9446 0 P 0 
L 0.84068002 -1.9446 0.8378 -1.9467 0 P 0 
L 0.8378 -1.9467 0.83476998 -1.94858002 0 P 0 
L 0.83476998 -1.94858002 0.83163996 -1.9502 0 P 0 
L 0.83163996 -1.9502 0.8284 -1.95158002 0 P 0 
L 0.8284 -1.95158002 0.82506004 -1.95268996 0 P 0 
L 0.82506004 -1.95268996 0.82163996 -1.95356004 0 P 0 
L 0.82163996 -1.95356004 0.81818002 -1.95413996 0 P 0 
L 0.81818002 -1.95413996 0.8147 -1.95446004 0 P 0 
L 0.8147 -1.95446004 0.81121004 -1.9545 0 P 0 
L 0.77075 -2.02925 0.84511004 -2.02925 0 P 0 
L 0.77076004 -2.02825 0.8452 -2.02825 0 P 0 
L 0.77076998 -2.02725 0.84528996 -2.02725 0 P 0 
L 0.77078002 -2.02625 0.84536998 -2.02625 0 P 0 
L 0.77078996 -2.02525 0.84548996 -2.02525 0 P 0 
L 0.7708 -2.02425 0.84561998 -2.02425 0 P 0 
L 0.77081004 -2.02325 0.84575 -2.02325 0 P 0 
L 0.77081998 -2.02225 0.84588002 -2.02225 0 P 0 
L 0.77083002 -2.02125 0.84601004 -2.02125 0 P 0 
L 0.77083996 -2.02025 0.84613996 -2.02025 0 P 0 
L 0.77085 -2.01925 0.84626004 -2.01925 0 P 0 
L 0.77085 -2.01825 0.84638996 -2.01825 0 P 0 
L 0.77085 -2.01725 0.84651998 -2.01725 0 P 0 
L 0.77086004 -2.01625 0.84663996 -2.01625 0 P 0 
L 0.77086004 -2.01525 0.84676998 -2.01525 0 P 0 
L 0.77086004 -2.01425 0.8469 -2.01425 0 P 0 
L 0.77086004 -2.01325 0.84703002 -2.01325 0 P 0 
L 0.77086004 -2.01225 0.84716004 -2.01225 0 P 0 
L 0.77086004 -2.01125 0.84728996 -2.01125 0 P 0 
L 0.77086004 -2.01025 0.84741004 -2.01025 0 P 0 
L 0.77086998 -2.00925 0.84753996 -2.00925 0 P 0 
L 0.77086998 -2.00825 0.84766998 -2.00825 0 P 0 
L 0.77086998 -2.00725 0.84778996 -2.00725 0 P 0 
L 0.77086998 -2.00625 0.84791998 -2.00625 0 P 0 
L 0.77086998 -2.00525 0.84805 -2.00525 0 P 0 
L 0.77086998 -2.00425 0.84818002 -2.00425 0 P 0 
L 0.77088002 -2.00325 0.84831004 -2.00325 0 P 0 
L 0.77088002 -2.00225 0.84843996 -2.00225 0 P 0 
L 0.77088002 -2.00125 0.84856004 -2.00125 0 P 0 
L 0.77088002 -2.00025 0.84868996 -2.00025 0 P 0 
L 0.77088002 -1.99925 0.84881998 -1.99925 0 P 0 
L 0.77088002 -1.99825 0.84896004 -1.99825 0 P 0 
L 0.77088002 -1.99725 0.84911004 -1.99725 0 P 0 
L 0.77088996 -1.99625 0.84926998 -1.99625 0 P 0 
L 0.77088996 -1.99525 0.84941998 -1.99525 0 P 0 
L 0.77088996 -1.99425 0.84956998 -1.99425 0 P 0 
L 0.77088996 -1.99325 0.84971998 -1.99325 0 P 0 
L 0.77088996 -1.99225 0.84986998 -1.99225 0 P 0 
L 0.77088996 -1.99125 0.85003002 -1.99125 0 P 0 
L 0.7709 -1.99025 0.85018002 -1.99025 0 P 0 
L 0.7709 -1.98925 0.85033002 -1.98925 0 P 0 
L 0.76885 -2.01878002 0.76871998 -2.03201998 0 P 0 
L 0.76871998 -2.03201998 0.7684 -2.04553996 0 P 0 
L 0.7684 -2.04553996 0.76796004 -2.05751004 0 P 0 
L 0.76796004 -2.05751004 0.76741004 -2.06523002 0 P 0 
L 0.76741004 -2.06523002 0.76596004 -2.07933996 0 P 0 
L 0.76596004 -2.07933996 0.7636 -2.09918002 0 P 0 
L 0.7636 -2.09918002 0.76116004 -2.119 0 P 0 
L 0.76116004 -2.119 0.76011998 -2.12526004 0 P 0 
L 0.76011998 -2.12526004 0.75948996 -2.12825 0 P 0 
L 0.75948996 -2.12825 0.84418002 -2.12825 0 P 0 
L 0.84418002 -2.12825 0.84361998 -2.10788002 0 P 0 
L 0.84361998 -2.10788002 0.8436 -2.08276004 0 P 0 
L 0.8436 -2.08276004 0.8449 -2.05491998 0 P 0 
L 0.8449 -2.05491998 0.84736004 -2.02641004 0 P 0 
L 0.84736004 -2.02641004 0.85083996 -1.99923002 0 P 0 
L 0.85083996 -1.99923002 0.85268996 -1.987 0 P 0 
L 0.85268996 -1.987 0.7689 -1.987 0 P 0 
L 0.7689 -1.987 0.76885 -2.01878002 0 P 0 
L 0.76195 -2.12625 0.84211998 -2.12625 0 P 0 
L 0.76213996 -2.12525 0.8421 -2.12525 0 P 0 
L 0.76231004 -2.12425 0.84206998 -2.12425 0 P 0 
L 0.76248002 -2.12325 0.84203996 -2.12325 0 P 0 
L 0.76263996 -2.12225 0.84201004 -2.12225 0 P 0 
L 0.76281004 -2.12125 0.84198996 -2.12125 0 P 0 
L 0.76296998 -2.12025 0.84196004 -2.12025 0 P 0 
L 0.76313996 -2.11925 0.84193002 -2.11925 0 P 0 
L 0.76326998 -2.11825 0.8419 -2.11825 0 P 0 
L 0.76338996 -2.11725 0.84188002 -2.11725 0 P 0 
L 0.76351004 -2.11625 0.84185 -2.11625 0 P 0 
L 0.76363996 -2.11525 0.84181998 -2.11525 0 P 0 
L 0.76376004 -2.11425 0.84178996 -2.11425 0 P 0 
L 0.76388002 -2.11325 0.84176998 -2.11325 0 P 0 
L 0.76401004 -2.11225 0.84173996 -2.11225 0 P 0 
L 0.76413002 -2.11125 0.84171004 -2.11125 0 P 0 
L 0.76425 -2.11025 0.84168002 -2.11025 0 P 0 
L 0.76438002 -2.10925 0.84166004 -2.10925 0 P 0 
L 0.7645 -2.10825 0.84163002 -2.10825 0 P 0 
L 0.76461998 -2.10725 0.84161998 -2.10725 0 P 0 
L 0.76475 -2.10625 0.84161998 -2.10625 0 P 0 
L 0.76486998 -2.10525 0.84161998 -2.10525 0 P 0 
L 0.76498996 -2.10425 0.84161998 -2.10425 0 P 0 
L 0.76511998 -2.10325 0.84161998 -2.10325 0 P 0 
L 0.76523996 -2.10225 0.84161998 -2.10225 0 P 0 
L 0.76536004 -2.10125 0.84161998 -2.10125 0 P 0 
L 0.76548996 -2.10025 0.84161998 -2.10025 0 P 0 
L 0.76561004 -2.09925 0.84161998 -2.09925 0 P 0 
L 0.76573002 -2.09825 0.84161004 -2.09825 0 P 0 
L 0.76583996 -2.09725 0.84161004 -2.09725 0 P 0 
L 0.76596998 -2.09625 0.84161004 -2.09625 0 P 0 
L 0.76608996 -2.09525 0.84161004 -2.09525 0 P 0 
L 0.7662 -2.09425 0.84161004 -2.09425 0 P 0 
L 0.76631998 -2.09325 0.84161004 -2.09325 0 P 0 
L 0.76643996 -2.09225 0.84161004 -2.09225 0 P 0 
L 0.76656004 -2.09125 0.84161004 -2.09125 0 P 0 
L 0.76668002 -2.09025 0.84161004 -2.09025 0 P 0 
L 0.76678996 -2.08925 0.84161004 -2.08925 0 P 0 
L 0.76691998 -2.08825 0.84161004 -2.08825 0 P 0 
L 0.76703002 -2.08725 0.84161004 -2.08725 0 P 0 
L 0.76715 -2.08625 0.8416 -2.08625 0 P 0 
L 0.76726998 -2.08525 0.8416 -2.08525 0 P 0 
L 0.76738996 -2.08425 0.8416 -2.08425 0 P 0 
L 0.76195 -2.12625 0.76208002 -2.12561998 0 P 0 
L 0.76208002 -2.12561998 0.76313996 -2.11928996 0 P 0 
L 0.76313996 -2.11928996 0.76558996 -2.09941998 0 P 0 
L 0.76558996 -2.09941998 0.76558996 -2.09941004 0 P 0 
L 0.76558996 -2.09941004 0.76793996 -2.07956004 0 P 0 
L 0.76793996 -2.07956004 0.7694 -2.0654 0 P 0 
L 0.7694 -2.0654 0.76941004 -2.06536004 0 P 0 
L 0.76941004 -2.06536004 0.76996004 -2.05761998 0 P 0 
L 0.76996004 -2.05761998 0.76996004 -2.05758996 0 P 0 
L 0.76996004 -2.05758996 0.7704 -2.0456 0 P 0 
L 0.7704 -2.0456 0.77071998 -2.03206004 0 P 0 
L 0.77071998 -2.03206004 0.77085 -2.01878002 0 P 0 
L 0.77085 -2.01878002 0.7709 -1.989 0 P 0 
L 0.7709 -1.989 0.85036004 -1.989 0 P 0 
L 0.85036004 -1.989 0.84886004 -1.99895 0 P 0 
L 0.84886004 -1.99895 0.84538002 -2.02618996 0 P 0 
L 0.84538002 -2.02618996 0.8429 -2.05478996 0 P 0 
L 0.8429 -2.05478996 0.8416 -2.08271004 0 P 0 
L 0.8416 -2.08271004 0.84161998 -2.10791004 0 P 0 
L 0.84161998 -2.10791004 0.84211998 -2.12625 0 P 0 
L 0.84211998 -2.12625 0.76195 -2.12625 0 P 0 
L 0.71628996 -1.91261998 0.74938002 -1.91261998 0 P 0 
L 0.71783002 -1.91161998 0.74933002 -1.91161998 0 P 0 
L 0.71953002 -1.91061998 0.74931004 -1.91061998 0 P 0 
L 0.72133002 -1.90961998 0.74928996 -1.90961998 0 P 0 
L 0.72313996 -1.90861998 0.74926998 -1.90861998 0 P 0 
L 0.72493996 -1.90761998 0.74928996 -1.90761998 0 P 0 
L 0.72673996 -1.90661998 0.74931998 -1.90661998 0 P 0 
L 0.72855 -1.90561998 0.74935 -1.90561998 0 P 0 
L 0.73035 -1.90461998 0.74938996 -1.90461998 0 P 0 
L 0.73215 -1.90361998 0.74946998 -1.90361998 0 P 0 
L 0.73396004 -1.90261998 0.74953996 -1.90261998 0 P 0 
L 0.73576004 -1.90161998 0.74961998 -1.90161998 0 P 0 
L 0.73756998 -1.90061998 0.74973996 -1.90061998 0 P 0 
L 0.73943002 -1.89961998 0.74986004 -1.89961998 0 P 0 
L 0.74141998 -1.89861998 0.74998996 -1.89861998 0 P 0 
L 0.74341004 -1.89761998 0.75015 -1.89761998 0 P 0 
L 0.59843002 -2.08361998 0.6754 -2.08361998 0 P 0 
L 0.59846004 -2.08261998 0.67538996 -2.08261998 0 P 0 
L 0.59848002 -2.08161998 0.67538002 -2.08161998 0 P 0 
L 0.59851004 -2.08061998 0.67538002 -2.08061998 0 P 0 
L 0.59853002 -2.07961998 0.67546004 -2.07961998 0 P 0 
L 0.59856004 -2.07861998 0.67553996 -2.07861998 0 P 0 
L 0.59861998 -2.07761998 0.67561004 -2.07761998 0 P 0 
L 0.5987 -2.07661998 0.67568996 -2.07661998 0 P 0 
L 0.59878002 -2.07561998 0.67576004 -2.07561998 0 P 0 
L 0.59885 -2.07461998 0.67583996 -2.07461998 0 P 0 
L 0.59893002 -2.07361998 0.67591998 -2.07361998 0 P 0 
L 0.59901004 -2.07261998 0.67598996 -2.07261998 0 P 0 
L 0.59908002 -2.07161998 0.67606998 -2.07161998 0 P 0 
L 0.59916004 -2.07061998 0.67613996 -2.07061998 0 P 0 
L 0.59923002 -2.06961998 0.67621004 -2.06961998 0 P 0 
L 0.59936004 -2.06861998 0.6763 -2.06861998 0 P 0 
L 0.59948996 -2.06761998 0.67645 -2.06761998 0 P 0 
L 0.59963002 -2.06661998 0.6766 -2.06661998 0 P 0 
L 0.59976998 -2.06561998 0.67676004 -2.06561998 0 P 0 
L 0.5999 -2.06461998 0.67691998 -2.06461998 0 P 0 
L 0.60003002 -2.06361998 0.67706998 -2.06361998 0 P 0 
L 0.60016998 -2.06261998 0.6773 -2.06261998 0 P 0 
L 0.60031004 -2.06161998 0.67753002 -2.06161998 0 P 0 
L 0.60051004 -2.06061998 0.67776004 -2.06061998 0 P 0 
L 0.60071004 -2.05961998 0.67798996 -2.05961998 0 P 0 
L 0.60091998 -2.05861998 0.67823002 -2.05861998 0 P 0 
L 0.60111998 -2.05761998 0.67853002 -2.05761998 0 P 0 
L 0.60133002 -2.05661998 0.67883996 -2.05661998 0 P 0 
L 0.60153996 -2.05561998 0.67913996 -2.05561998 0 P 0 
L 0.60173996 -2.05461998 0.67945 -2.05461998 0 P 0 
L 0.60195 -2.05361998 0.67975 -2.05361998 0 P 0 
L 0.60223002 -2.05261998 0.68006004 -2.05261998 0 P 0 
L 0.60251004 -2.05161998 0.68036004 -2.05161998 0 P 0 
L 0.60278996 -2.05061998 0.68066998 -2.05061998 0 P 0 
L 0.60306004 -2.04961998 0.68096998 -2.04961998 0 P 0 
L 0.60333996 -2.04861998 0.68135 -2.04861998 0 P 0 
L 0.60361998 -2.04761998 0.68173002 -2.04761998 0 P 0 
L 0.6039 -2.04661998 0.68211004 -2.04661998 0 P 0 
L 0.60418002 -2.04561998 0.68248996 -2.04561998 0 P 0 
L 0.60453002 -2.04461998 0.68288002 -2.04461998 0 P 0 
L 0.60488002 -2.04361998 0.68326004 -2.04361998 0 P 0 
L 0.60523002 -2.04261998 0.68363996 -2.04261998 0 P 0 
L 0.60556998 -2.04161998 0.68401998 -2.04161998 0 P 0 
L 0.60591998 -2.04061998 0.6844 -2.04061998 0 P 0 
L 0.60626998 -2.03961998 0.68486004 -2.03961998 0 P 0 
L 0.60661998 -2.03861998 0.68531998 -2.03861998 0 P 0 
L 0.60698996 -2.03761998 0.68578002 -2.03761998 0 P 0 
L 0.60743002 -2.03661998 0.68623996 -2.03661998 0 P 0 
L 0.60786004 -2.03561998 0.6867 -2.03561998 0 P 0 
L 0.60828996 -2.03461998 0.68716004 -2.03461998 0 P 0 
L 0.60873002 -2.03361998 0.68761998 -2.03361998 0 P 0 
L 0.60916004 -2.03261998 0.68808996 -2.03261998 0 P 0 
L 0.60958996 -2.03161998 0.68856998 -2.03161998 0 P 0 
L 0.61003002 -2.03061998 0.68911004 -2.03061998 0 P 0 
L 0.61046004 -2.02961998 0.68965 -2.02961998 0 P 0 
L 0.61088996 -2.02861998 0.69018996 -2.02861998 0 P 0 
L 0.61133002 -2.02761998 0.69073002 -2.02761998 0 P 0 
L 0.61176004 -2.02661998 0.69126998 -2.02661998 0 P 0 
L 0.6122 -2.02561998 0.69181004 -2.02561998 0 P 0 
L 0.61263002 -2.02461998 0.69235 -2.02461998 0 P 0 
L 0.61306004 -2.02361998 0.69288002 -2.02361998 0 P 0 
L 0.61348996 -2.02261998 0.69346998 -2.02261998 0 P 0 
L 0.61393002 -2.02161998 0.69408996 -2.02161998 0 P 0 
L 0.61436004 -2.02061998 0.6947 -2.02061998 0 P 0 
L 0.61478996 -2.01961998 0.69531998 -2.01961998 0 P 0 
L 0.61531004 -2.01861998 0.69593996 -2.01861998 0 P 0 
L 0.61583996 -2.01761998 0.69656004 -2.01761998 0 P 0 
L 0.61636004 -2.01661998 0.69718002 -2.01661998 0 P 0 
L 0.61688002 -2.01561998 0.69778996 -2.01561998 0 P 0 
L 0.6174 -2.01461998 0.69841998 -2.01461998 0 P 0 
L 0.61791998 -2.01361998 0.69911998 -2.01361998 0 P 0 
L 0.61843996 -2.01261998 0.69981998 -2.01261998 0 P 0 
L 0.61896004 -2.01161998 0.70051998 -2.01161998 0 P 0 
L 0.61948002 -2.01061998 0.70123002 -2.01061998 0 P 0 
L 0.62 -2.00961998 0.70193002 -2.00961998 0 P 0 
L 0.62051998 -2.00861998 0.70263002 -2.00861998 0 P 0 
L 0.62103996 -2.00761998 0.70333002 -2.00761998 0 P 0 
L 0.62163996 -2.00661998 0.70403996 -2.00661998 0 P 0 
L 0.62225 -2.00561998 0.70483002 -2.00561998 0 P 0 
L 0.62285 -2.00461998 0.70565 -2.00461998 0 P 0 
L 0.62346004 -2.00361998 0.70646004 -2.00361998 0 P 0 
L 0.62406004 -2.00261998 0.70726998 -2.00261998 0 P 0 
L 0.62466004 -2.00161998 0.70808996 -2.00161998 0 P 0 
L 0.62526998 -2.00061998 0.7089 -2.00061998 0 P 0 
L 0.62586998 -1.99961998 0.70971004 -1.99961998 0 P 0 
L 0.62648002 -1.99861998 0.71053002 -1.99861998 0 P 0 
L 0.62708002 -1.99761998 0.71133996 -1.99761998 0 P 0 
L 0.62768996 -1.99661998 0.71216004 -1.99661998 0 P 0 
L 0.62831998 -1.99561998 0.71296998 -1.99561998 0 P 0 
L 0.62901004 -1.99461998 0.71378996 -1.99461998 0 P 0 
L 0.62971004 -1.99361998 0.71466004 -1.99361998 0 P 0 
L 0.6304 -1.99261998 0.71561004 -1.99261998 0 P 0 
L 0.6311 -1.99161998 0.71656998 -1.99161998 0 P 0 
L 0.63178996 -1.99061998 0.71753002 -1.99061998 0 P 0 
L 0.63248996 -1.98961998 0.71848996 -1.98961998 0 P 0 
L 0.63318002 -1.98861998 0.71945 -1.98861998 0 P 0 
L 0.63388002 -1.98761998 0.72041004 -1.98761998 0 P 0 
L 0.63456998 -1.98661998 0.72136998 -1.98661998 0 P 0 
L 0.63526998 -1.98561998 0.72233002 -1.98561998 0 P 0 
L 0.63598002 -1.98461998 0.72328996 -1.98461998 0 P 0 
L 0.63678996 -1.98361998 0.72425 -1.98361998 0 P 0 
L 0.6376 -1.98261998 0.72521004 -1.98261998 0 P 0 
L 0.63841004 -1.98161998 0.72628002 -1.98161998 0 P 0 
L 0.63921998 -1.98061998 0.72738996 -1.98061998 0 P 0 
L 0.64003002 -1.97961998 0.7285 -1.97961998 0 P 0 
L 0.64083996 -1.97861998 0.72961004 -1.97861998 0 P 0 
L 0.64165 -1.97761998 0.73071004 -1.97761998 0 P 0 
L 0.64246004 -1.97661998 0.73181998 -1.97661998 0 P 0 
L 0.64326998 -1.97561998 0.73293002 -1.97561998 0 P 0 
L 0.64406998 -1.97461998 0.73403996 -1.97461998 0 P 0 
L 0.64488002 -1.97361998 0.73515 -1.97361998 0 P 0 
L 0.64568996 -1.97261998 0.73625 -1.97261998 0 P 0 
L 0.6465 -1.97161998 0.73736004 -1.97161998 0 P 0 
L 0.64731004 -1.97061998 0.73848002 -1.97061998 0 P 0 
L 0.64811998 -1.96961998 0.73973002 -1.96961998 0 P 0 
L 0.64893002 -1.96861998 0.74098996 -1.96861998 0 P 0 
L 0.64981004 -1.96761998 0.74225 -1.96761998 0 P 0 
L 0.65076004 -1.96661998 0.74351004 -1.96661998 0 P 0 
L 0.65171004 -1.96561998 0.74476998 -1.96561998 0 P 0 
L 0.65266998 -1.96461998 0.74603002 -1.96461998 0 P 0 
L 0.65361998 -1.96361998 0.74728996 -1.96361998 0 P 0 
L 0.65458002 -1.96261998 0.74855 -1.96261998 0 P 0 
L 0.65553002 -1.96161998 0.74981004 -1.96161998 0 P 0 
L 0.65648996 -1.96061998 0.75106004 -1.96061998 0 P 0 
L 0.65743996 -1.95961998 0.75233996 -1.95961998 0 P 0 
L 0.6584 -1.95861998 0.7537 -1.95861998 0 P 0 
L 0.65935 -1.95761998 0.75506004 -1.95761998 0 P 0 
L 0.66031004 -1.95661998 0.75641998 -1.95661998 0 P 0 
L 0.66126004 -1.95561998 0.75778996 -1.95561998 0 P 0 
L 0.66221004 -1.95461998 0.75916004 -1.95461998 0 P 0 
L 0.66316998 -1.95361998 0.76053996 -1.95361998 0 P 0 
L 0.66411998 -1.95261998 0.76193996 -1.95261998 0 P 0 
L 0.66523002 -1.95161998 0.76333996 -1.95161998 0 P 0 
L 0.66636004 -1.95061998 0.76406998 -1.95061998 0 P 0 
L 0.66746998 -1.94961998 0.76355 -1.94961998 0 P 0 
L 0.6686 -1.94861998 0.76291998 -1.94861998 0 P 0 
L 0.66971004 -1.94761998 0.76226998 -1.94761998 0 P 0 
L 0.67083996 -1.94661998 0.76161998 -1.94661998 0 P 0 
L 0.67196004 -1.94561998 0.76096998 -1.94561998 0 P 0 
L 0.67306998 -1.94461998 0.76033002 -1.94461998 0 P 0 
L 0.6742 -1.94361998 0.75968996 -1.94361998 0 P 0 
L 0.67531004 -1.94261998 0.75905 -1.94261998 0 P 0 
L 0.67643996 -1.94161998 0.75846004 -1.94161998 0 P 0 
L 0.67755 -1.94061998 0.75788996 -1.94061998 0 P 0 
L 0.67868002 -1.93961998 0.75731998 -1.93961998 0 P 0 
L 0.67978996 -1.93861998 0.75676998 -1.93861998 0 P 0 
L 0.68091998 -1.93761998 0.75626998 -1.93761998 0 P 0 
L 0.68221004 -1.93661998 0.75576998 -1.93661998 0 P 0 
L 0.68353002 -1.93561998 0.75528002 -1.93561998 0 P 0 
L 0.68483996 -1.93461998 0.75483996 -1.93461998 0 P 0 
L 0.68616004 -1.93361998 0.75441004 -1.93361998 0 P 0 
L 0.68746998 -1.93261998 0.75398002 -1.93261998 0 P 0 
L 0.68878002 -1.93161998 0.7536 -1.93161998 0 P 0 
L 0.6901 -1.93061998 0.75323996 -1.93061998 0 P 0 
L 0.69141004 -1.92961998 0.75286998 -1.92961998 0 P 0 
L 0.69271998 -1.92861998 0.75253996 -1.92861998 0 P 0 
L 0.69403002 -1.92761998 0.75223002 -1.92761998 0 P 0 
L 0.69535 -1.92661998 0.75193002 -1.92661998 0 P 0 
L 0.69666004 -1.92561998 0.75163002 -1.92561998 0 P 0 
L 0.69796998 -1.92461998 0.75138002 -1.92461998 0 P 0 
L 0.69936998 -1.92361998 0.75113996 -1.92361998 0 P 0 
L 0.70091004 -1.92261998 0.75088996 -1.92261998 0 P 0 
L 0.70243996 -1.92161998 0.75066004 -1.92161998 0 P 0 
L 0.70398002 -1.92061998 0.75046004 -1.92061998 0 P 0 
L 0.70551998 -1.91961998 0.75026004 -1.91961998 0 P 0 
L 0.70706004 -1.91861998 0.75006998 -1.91861998 0 P 0 
L 0.7086 -1.91761998 0.7499 -1.91761998 0 P 0 
L 0.71013996 -1.91661998 0.74976998 -1.91661998 0 P 0 
L 0.71166998 -1.91561998 0.74961998 -1.91561998 0 P 0 
L 0.71321004 -1.91461998 0.74951998 -1.91461998 0 P 0 
L 0.71475 -1.91361998 0.74945 -1.91361998 0 P 0 
L 0.61556998 -2.15661998 0.70655 -2.15661998 0 P 0 
L 0.61503002 -2.15561998 0.7056 -2.15561998 0 P 0 
L 0.61448996 -2.15461998 0.70465 -2.15461998 0 P 0 
L 0.61395 -2.15361998 0.7037 -2.15361998 0 P 0 
L 0.61341004 -2.15261998 0.70273996 -2.15261998 0 P 0 
L 0.61286998 -2.15161998 0.70178996 -2.15161998 0 P 0 
L 0.61233002 -2.15061998 0.70095 -2.15061998 0 P 0 
L 0.61188002 -2.14961998 0.70015 -2.14961998 0 P 0 
L 0.61143002 -2.14861998 0.69935 -2.14861998 0 P 0 
L 0.61098002 -2.14761998 0.69855 -2.14761998 0 P 0 
L 0.61053002 -2.14661998 0.69775 -2.14661998 0 P 0 
L 0.61008002 -2.14561998 0.69695 -2.14561998 0 P 0 
L 0.60963002 -2.14461998 0.69615 -2.14461998 0 P 0 
L 0.60918002 -2.14361998 0.69535 -2.14361998 0 P 0 
L 0.60873002 -2.14261998 0.69455 -2.14261998 0 P 0 
L 0.60831004 -2.14161998 0.69381998 -2.14161998 0 P 0 
L 0.60793996 -2.14061998 0.69315 -2.14061998 0 P 0 
L 0.60756998 -2.13961998 0.69248002 -2.13961998 0 P 0 
L 0.60721004 -2.13861998 0.69181004 -2.13861998 0 P 0 
L 0.60683996 -2.13761998 0.69115 -2.13761998 0 P 0 
L 0.60646998 -2.13661998 0.69048002 -2.13661998 0 P 0 
L 0.60611004 -2.13561998 0.68981004 -2.13561998 0 P 0 
L 0.60573996 -2.13461998 0.68918002 -2.13461998 0 P 0 
L 0.60538002 -2.13361998 0.68863002 -2.13361998 0 P 0 
L 0.60503996 -2.13261998 0.68808002 -2.13261998 0 P 0 
L 0.60476004 -2.13161998 0.68753002 -2.13161998 0 P 0 
L 0.60446998 -2.13061998 0.68698002 -2.13061998 0 P 0 
L 0.60418002 -2.12961998 0.68643002 -2.12961998 0 P 0 
L 0.6039 -2.12861998 0.68588002 -2.12861998 0 P 0 
L 0.60361004 -2.12761998 0.68533002 -2.12761998 0 P 0 
L 0.60331998 -2.12661998 0.68486004 -2.12661998 0 P 0 
L 0.60303002 -2.12561998 0.68441998 -2.12561998 0 P 0 
L 0.60275 -2.12461998 0.68396998 -2.12461998 0 P 0 
L 0.60246004 -2.12361998 0.68353002 -2.12361998 0 P 0 
L 0.60218002 -2.12261998 0.68308996 -2.12261998 0 P 0 
L 0.60188996 -2.12161998 0.68263996 -2.12161998 0 P 0 
L 0.60166998 -2.12061998 0.6822 -2.12061998 0 P 0 
L 0.60145 -2.11961998 0.68176004 -2.11961998 0 P 0 
L 0.60123002 -2.11861998 0.68138996 -2.11861998 0 P 0 
L 0.60101004 -2.11761998 0.68105 -2.11761998 0 P 0 
L 0.60078002 -2.11661998 0.68071004 -2.11661998 0 P 0 
L 0.6006 -2.11561998 0.68036004 -2.11561998 0 P 0 
L 0.60043002 -2.11461998 0.68001998 -2.11461998 0 P 0 
L 0.60025 -2.11361998 0.67968002 -2.11361998 0 P 0 
L 0.60008002 -2.11261998 0.67933002 -2.11261998 0 P 0 
L 0.59991004 -2.11161998 0.67898996 -2.11161998 0 P 0 
L 0.59976004 -2.11061998 0.6787 -2.11061998 0 P 0 
L 0.59963996 -2.10961998 0.67845 -2.10961998 0 P 0 
L 0.59951004 -2.10861998 0.6782 -2.10861998 0 P 0 
L 0.59938002 -2.10761998 0.67795 -2.10761998 0 P 0 
L 0.59925 -2.10661998 0.6777 -2.10661998 0 P 0 
L 0.59913002 -2.10561998 0.67746004 -2.10561998 0 P 0 
L 0.59905 -2.10461998 0.67721004 -2.10461998 0 P 0 
L 0.59896998 -2.10361998 0.67696004 -2.10361998 0 P 0 
L 0.59888002 -2.10261998 0.67671004 -2.10261998 0 P 0 
L 0.5988 -2.10161998 0.67653996 -2.10161998 0 P 0 
L 0.59871998 -2.10061998 0.67638002 -2.10061998 0 P 0 
L 0.59866998 -2.09961998 0.67621004 -2.09961998 0 P 0 
L 0.59863996 -2.09861998 0.67605 -2.09861998 0 P 0 
L 0.59861004 -2.09761998 0.67588996 -2.09761998 0 P 0 
L 0.59858996 -2.09661998 0.6758 -2.09661998 0 P 0 
L 0.59856004 -2.09561998 0.67571004 -2.09561998 0 P 0 
L 0.59853002 -2.09461998 0.67563002 -2.09461998 0 P 0 
L 0.5985 -2.09361998 0.67553996 -2.09361998 0 P 0 
L 0.59846998 -2.09261998 0.67546004 -2.09261998 0 P 0 
L 0.59843996 -2.09161998 0.67546004 -2.09161998 0 P 0 
L 0.59841998 -2.09061998 0.67545 -2.09061998 0 P 0 
L 0.59838002 -2.08961998 0.67543996 -2.08961998 0 P 0 
L 0.59836004 -2.08861998 0.67543002 -2.08861998 0 P 0 
L 0.59833002 -2.08761998 0.67543002 -2.08761998 0 P 0 
L 0.59835 -2.08661998 0.67541998 -2.08661998 0 P 0 
L 0.59836998 -2.08561998 0.67541004 -2.08561998 0 P 0 
L 0.5984 -2.08461998 0.67541004 -2.08461998 0 P 0 
L 0.80005 -2.25161998 0.85543996 -2.25161998 0 P 0 
L 0.78651998 -2.25061998 0.86596004 -2.25061998 0 P 0 
L 0.77878996 -2.24961998 0.87636004 -2.24961998 0 P 0 
L 0.77106004 -2.24861998 0.88285 -2.24861998 0 P 0 
L 0.76398996 -2.24761998 0.88933996 -2.24761998 0 P 0 
L 0.75891998 -2.24661998 0.89583996 -2.24661998 0 P 0 
L 0.73781004 -1.8982 0.71738996 -1.90951998 0 P 0 
L 0.71738996 -1.90951998 0.69766998 -1.92233996 0 P 0 
L 0.69766998 -1.92233996 0.67971004 -1.93601998 0 P 0 
L 0.67971004 -1.93601998 0.66278996 -1.95113002 0 P 0 
L 0.66278996 -1.95113002 0.64786998 -1.96675 0 P 0 
L 0.64786998 -1.96675 0.63423996 -1.98358996 0 P 0 
L 0.63423996 -1.98358996 0.62643996 -1.99483002 0 P 0 
L 0.62643996 -1.99483002 0.61933996 -2.00655 0 P 0 
L 0.61933996 -2.00655 0.61298996 -2.01873996 0 P 0 
L 0.61298996 -2.01873996 0.60503002 -2.03713002 0 P 0 
L 0.60503002 -2.03713002 0.60225 -2.04506004 0 P 0 
L 0.60225 -2.04506004 0.59998996 -2.05323002 0 P 0 
L 0.59998996 -2.05323002 0.59833996 -2.0612 0 P 0 
L 0.59833996 -2.0612 0.59725 -2.06928996 0 P 0 
L 0.59725 -2.06928996 0.59656998 -2.07833996 0 P 0 
L 0.59656998 -2.07833996 0.59633002 -2.0875 0 P 0 
L 0.59633002 -2.0875 0.59668996 -2.10036998 0 P 0 
L 0.59668996 -2.10036998 0.59715 -2.10596004 0 P 0 
L 0.59715 -2.10596004 0.59786004 -2.11151004 0 P 0 
L 0.59786004 -2.11151004 0.59878996 -2.11686998 0 P 0 
L 0.59878996 -2.11686998 0.59996998 -2.1222 0 P 0 
L 0.59996998 -2.1222 0.60326998 -2.13368996 0 P 0 
L 0.60326998 -2.13368996 0.60656998 -2.1427 0 P 0 
L 0.60656998 -2.1427 0.6105 -2.15143996 0 P 0 
L 0.6105 -2.15143996 0.61505 -2.15988002 0 P 0 
L 0.61505 -2.15988002 0.62023996 -2.16803996 0 P 0 
L 0.62023996 -2.16803996 0.62828996 -2.17873002 0 P 0 
L 0.62828996 -2.17873002 0.63718996 -2.18871004 0 P 0 
L 0.63718996 -2.18871004 0.64693002 -2.19795 0 P 0 
L 0.64693002 -2.19795 0.6582 -2.20701998 0 P 0 
L 0.6582 -2.20701998 0.67011004 -2.21518996 0 P 0 
L 0.67011004 -2.21518996 0.68261004 -2.22243002 0 P 0 
L 0.68261004 -2.22243002 0.69673996 -2.22936004 0 P 0 
L 0.69673996 -2.22936004 0.71123002 -2.23543996 0 P 0 
L 0.71123002 -2.23543996 0.72611998 -2.24066998 0 P 0 
L 0.72611998 -2.24066998 0.74536004 -2.24598996 0 P 0 
L 0.74536004 -2.24598996 0.76493002 -2.24985 0 P 0 
L 0.76493002 -2.24985 0.78671998 -2.25266998 0 P 0 
L 0.78671998 -2.25266998 0.80863002 -2.25425 0 P 0 
L 0.80863002 -2.25425 0.83146004 -2.25463002 0 P 0 
L 0.83146004 -2.25463002 0.85418002 -2.25375 0 P 0 
L 0.85418002 -2.25375 0.87641004 -2.25163996 0 P 0 
L 0.87641004 -2.25163996 0.89853002 -2.24823002 0 P 0 
L 0.89853002 -2.24823002 0.93045 -2.24101998 0 P 0 
L 0.93045 -2.24101998 0.96466004 -2.23063002 0 P 0 
L 0.96466004 -2.23063002 0.99911004 -2.2178 0 P 0 
L 0.99911004 -2.2178 1.03183002 -2.20318002 0 P 0 
L 1.03183002 -2.20318002 1.04391998 -2.19703002 0 P 0 
L 1.04391998 -2.19703002 1.05581004 -2.19048996 0 P 0 
L 1.05581004 -2.19048996 1.06676004 -2.18411998 0 P 0 
L 1.06676004 -2.18411998 1.06681004 -2.18408996 0 P 0 
L 1.06681004 -2.18408996 1.06685 -2.18405 0 P 0 
L 1.06685 -2.18405 1.0669 -2.18401004 0 P 0 
L 1.0669 -2.18401004 1.06693996 -2.18396998 0 P 0 
L 1.06693996 -2.18396998 1.06696998 -2.18391998 0 P 0 
L 1.06696998 -2.18391998 1.06701004 -2.18386998 0 P 0 
L 1.06701004 -2.18386998 1.06703002 -2.18381998 0 P 0 
L 1.06703002 -2.18381998 1.06706004 -2.18376004 0 P 0 
L 1.06706004 -2.18376004 1.06706998 -2.18371004 0 P 0 
L 1.06706998 -2.18371004 1.06708996 -2.18365 0 P 0 
L 1.06708996 -2.18365 1.06708996 -2.18358996 0 P 0 
L 1.06708996 -2.18358996 1.0671 -2.18353002 0 P 0 
L 1.0671 -2.18353002 1.0671 -2.18346998 0 P 0 
L 1.0671 -2.18346998 1.06708996 -2.18341004 0 P 0 
L 1.06708996 -2.18341004 1.06706998 -2.18336004 0 P 0 
L 1.06706998 -2.18336004 1.06706004 -2.1833 0 P 0 
L 1.06706004 -2.1833 1.06703002 -2.18323996 0 P 0 
L 1.06703002 -2.18323996 1.06701004 -2.18318996 0 P 0 
L 1.06701004 -2.18318996 1.06696998 -2.18313996 0 P 0 
L 1.06696998 -2.18313996 1.06693996 -2.18308996 0 P 0 
L 1.06693996 -2.18308996 1.06688002 -2.18303002 0 P 0 
L 1.06688002 -2.18303002 1.06678996 -2.18296998 0 P 0 
L 1.06678996 -2.18296998 1.06673002 -2.18295 0 P 0 
L 1.06673002 -2.18295 1.0667 -2.18295 0 P 0 
L 1.0667 -2.18295 1.06666004 -2.18293996 0 P 0 
L 1.06666004 -2.18293996 1.0666 -2.18293996 0 P 0 
L 1.0666 -2.18293996 1.06656998 -2.18295 0 P 0 
L 1.06656998 -2.18295 1.06653002 -2.18295 0 P 0 
L 1.06653002 -2.18295 1.06153002 -2.1842 0 P 0 
L 1.06153002 -2.1842 1.05583996 -2.18566998 0 P 0 
L 1.05583996 -2.18566998 1.04916998 -2.1875 0 P 0 
L 1.04916998 -2.1875 1.0153 -2.1962 0 P 0 
L 1.0153 -2.1962 0.9814 -2.20333996 0 P 0 
L 0.9814 -2.20333996 0.94881998 -2.2087 0 P 0 
L 0.94881998 -2.2087 0.9189 -2.21198996 0 P 0 
L 0.9189 -2.21198996 0.90113996 -2.21278996 0 P 0 
L 0.90113996 -2.21278996 0.87738002 -2.21265 0 P 0 
L 0.87738002 -2.21265 0.854 -2.21183002 0 P 0 
L 0.854 -2.21183002 0.83788996 -2.21033996 0 P 0 
L 0.83788996 -2.21033996 0.8174 -2.20693002 0 P 0 
L 0.8174 -2.20693002 0.79708996 -2.2023 0 P 0 
L 0.79708996 -2.2023 0.7769 -2.19641004 0 P 0 
L 0.7769 -2.19641004 0.76433002 -2.19183996 0 P 0 
L 0.76433002 -2.19183996 0.75208996 -2.18638002 0 P 0 
L 0.75208996 -2.18638002 0.74026998 -2.18006998 0 P 0 
L 0.74026998 -2.18006998 0.72886998 -2.17291004 0 P 0 
L 0.72886998 -2.17291004 0.71961998 -2.16603002 0 P 0 
L 0.71961998 -2.16603002 0.71098996 -2.15838996 0 P 0 
L 0.71098996 -2.15838996 0.70303002 -2.15003002 0 P 0 
L 0.70303002 -2.15003002 0.6958 -2.14098996 0 P 0 
L 0.6958 -2.14098996 0.69106998 -2.1339 0 P 0 
L 0.69106998 -2.1339 0.68696004 -2.12643002 0 P 0 
L 0.68696004 -2.12643002 0.68351004 -2.11863002 0 P 0 
L 0.68351004 -2.11863002 0.68073996 -2.11056004 0 P 0 
L 0.68073996 -2.11056004 0.67866004 -2.10218996 0 P 0 
L 0.67866004 -2.10218996 0.67788002 -2.09741998 0 P 0 
L 0.67788002 -2.09741998 0.67746004 -2.0926 0 P 0 
L 0.67746004 -2.0926 0.67738002 -2.08076004 0 P 0 
L 0.67738002 -2.08076004 0.67828002 -2.06891004 0 P 0 
L 0.67828002 -2.06891004 0.67903002 -2.06403996 0 P 0 
L 0.67903002 -2.06403996 0.68013002 -2.05923996 0 P 0 
L 0.68013002 -2.05923996 0.68288002 -2.05021998 0 P 0 
L 0.68288002 -2.05021998 0.68623996 -2.04141004 0 P 0 
L 0.68623996 -2.04141004 0.69018002 -2.03286004 0 P 0 
L 0.69018002 -2.03286004 0.69486004 -2.02418002 0 P 0 
L 0.69486004 -2.02418002 0.70003996 -2.0158 0 P 0 
L 0.70003996 -2.0158 0.70573002 -2.00768996 0 P 0 
L 0.70573002 -2.00768996 0.7158 -1.99531998 0 P 0 
L 0.7158 -1.99531998 0.72681004 -1.98385 0 P 0 
L 0.72681004 -1.98385 0.73971004 -1.9722 0 P 0 
L 0.73971004 -1.9722 0.7533 -1.9614 0 P 0 
L 0.7533 -1.9614 0.75753996 -1.95828002 0 P 0 
L 0.75753996 -1.95828002 0.76138002 -1.95548002 0 P 0 
L 0.76138002 -1.95548002 0.76463002 -1.95316004 0 P 0 
L 0.76463002 -1.95316004 0.76516004 -1.95281004 0 P 0 
L 0.76516004 -1.95281004 0.7657 -1.95248996 0 P 0 
L 0.7657 -1.95248996 0.76578002 -1.95243996 0 P 0 
L 0.76578002 -1.95243996 0.76586004 -1.95238002 0 P 0 
L 0.76586004 -1.95238002 0.76593002 -1.95231998 0 P 0 
L 0.76593002 -1.95231998 0.766 -1.95223996 0 P 0 
L 0.766 -1.95223996 0.76606004 -1.95216998 0 P 0 
L 0.76606004 -1.95216998 0.76616004 -1.95201004 0 P 0 
L 0.76616004 -1.95201004 0.7662 -1.95191998 0 P 0 
L 0.7662 -1.95191998 0.76626004 -1.95173996 0 P 0 
L 0.76626004 -1.95173996 0.76628002 -1.95163996 0 P 0 
L 0.76628002 -1.95163996 0.7663 -1.95143002 0 P 0 
L 0.7663 -1.95143002 0.7663 -1.95121004 0 P 0 
L 0.7663 -1.95121004 0.76628996 -1.951 0 P 0 
L 0.76628996 -1.951 0.76625 -1.95078996 0 P 0 
L 0.76625 -1.95078996 0.7662 -1.95058002 0 P 0 
L 0.7662 -1.95058002 0.76613002 -1.95036998 0 P 0 
L 0.76613002 -1.95036998 0.76583002 -1.94966998 0 P 0 
L 0.76583002 -1.94966998 0.76548996 -1.94896998 0 P 0 
L 0.76548996 -1.94896998 0.76508996 -1.9483 0 P 0 
L 0.76508996 -1.9483 0.76253002 -1.94436004 0 P 0 
L 0.76253002 -1.94436004 0.76056998 -1.94126998 0 P 0 
L 0.76056998 -1.94126998 0.75871998 -1.93806004 0 P 0 
L 0.75871998 -1.93806004 0.75716998 -1.93496998 0 P 0 
L 0.75716998 -1.93496998 0.7558 -1.93178002 0 P 0 
L 0.7558 -1.93178002 0.7546 -1.92853996 0 P 0 
L 0.7546 -1.92853996 0.75358996 -1.92521004 0 P 0 
L 0.75358996 -1.92521004 0.7527 -1.92161998 0 P 0 
L 0.7527 -1.92161998 0.75196998 -1.91796004 0 P 0 
L 0.75196998 -1.91796004 0.75155 -1.91496004 0 P 0 
L 0.75155 -1.91496004 0.75133002 -1.91193002 0 P 0 
L 0.75133002 -1.91193002 0.75126998 -1.9085 0 P 0 
L 0.75126998 -1.9085 0.75136004 -1.90506004 0 P 0 
L 0.75136004 -1.90506004 0.75161004 -1.90181998 0 P 0 
L 0.75161004 -1.90181998 0.752 -1.8986 0 P 0 
L 0.752 -1.8986 0.75228996 -1.89701998 0 P 0 
L 0.75228996 -1.89701998 0.75268996 -1.89546998 0 P 0 
L 0.75268996 -1.89546998 0.7532 -1.89395 0 P 0 
L 0.7532 -1.89395 0.75358996 -1.89281998 0 P 0 
L 0.75358996 -1.89281998 0.75373002 -1.89231998 0 P 0 
L 0.75373002 -1.89231998 0.75383996 -1.8918 0 P 0 
L 0.75383996 -1.8918 0.75391998 -1.89138996 0 P 0 
L 0.75391998 -1.89138996 0.75396998 -1.89098996 0 P 0 
L 0.75396998 -1.89098996 0.75396998 -1.89086004 0 P 0 
L 0.75396998 -1.89086004 0.75393996 -1.89076998 0 P 0 
L 0.75393996 -1.89076998 0.7539 -1.89071004 0 P 0 
L 0.7539 -1.89071004 0.75386004 -1.89066998 0 P 0 
L 0.75386004 -1.89066998 0.75381004 -1.89063002 0 P 0 
L 0.75381004 -1.89063002 0.75378996 -1.89061004 0 P 0 
L 0.75378996 -1.89061004 0.75373002 -1.89058996 0 P 0 
L 0.75373002 -1.89058996 0.75368002 -1.89056998 0 P 0 
L 0.75368002 -1.89056998 0.75356004 -1.89056998 0 P 0 
L 0.75356004 -1.89056998 0.75346998 -1.8906 0 P 0 
L 0.75346998 -1.8906 0.74898002 -1.8927 0 P 0 
L 0.74898002 -1.8927 0.74383002 -1.89518002 0 P 0 
L 0.74383002 -1.89518002 0.73781004 -1.8982 0 P 0 
L 0.69776998 -2.22761998 0.96701004 -2.22761998 0 P 0 
L 0.6957 -2.22661998 0.96968996 -2.22661998 0 P 0 
L 0.69366998 -2.22561998 0.97238002 -2.22561998 0 P 0 
L 0.69163002 -2.22461998 0.97506004 -2.22461998 0 P 0 
L 0.68958996 -2.22361998 0.97775 -2.22361998 0 P 0 
L 0.68756004 -2.22261998 0.98043002 -2.22261998 0 P 0 
L 0.68551998 -2.22161998 0.98311004 -2.22161998 0 P 0 
L 0.68348996 -2.22061998 0.9858 -2.22061998 0 P 0 
L 0.68176998 -2.21961998 0.98848002 -2.21961998 0 P 0 
L 0.68003996 -2.21861998 0.99116998 -2.21861998 0 P 0 
L 0.67831004 -2.21761998 0.99385 -2.21761998 0 P 0 
L 0.67658002 -2.21661998 0.99653996 -2.21661998 0 P 0 
L 0.67485 -2.21561998 0.99908002 -2.21561998 0 P 0 
L 0.67311998 -2.21461998 0.87665 -2.21461998 0 P 0 
L 0.6714 -2.21361998 0.85166004 -2.21361998 0 P 0 
L 0.6699 -2.21261998 0.84083002 -2.21261998 0 P 0 
L 0.66845 -2.21161998 0.8334 -2.21161998 0 P 0 
L 0.66698996 -2.21061998 0.8274 -2.21061998 0 P 0 
L 0.66553002 -2.20961998 0.82138996 -2.20961998 0 P 0 
L 0.66406998 -2.20861998 0.81583002 -2.20861998 0 P 0 
L 0.66261998 -2.20761998 0.81143996 -2.20761998 0 P 0 
L 0.66116004 -2.20661998 0.80706004 -2.20661998 0 P 0 
L 0.6597 -2.20561998 0.80266998 -2.20561998 0 P 0 
L 0.65841004 -2.20461998 0.79828996 -2.20461998 0 P 0 
L 0.65716998 -2.20361998 0.79448996 -2.20361998 0 P 0 
L 0.65593002 -2.20261998 0.79106004 -2.20261998 0 P 0 
L 0.65468996 -2.20161998 0.78763996 -2.20161998 0 P 0 
L 0.83143002 -2.25261998 0.80871998 -2.25225 0 P 0 
L 0.80871998 -2.25225 0.78691998 -2.25066998 0 P 0 
L 0.78691998 -2.25066998 0.76525 -2.24786998 0 P 0 
L 0.76525 -2.24786998 0.74581998 -2.24403996 0 P 0 
L 0.74581998 -2.24403996 0.72671004 -2.23876004 0 P 0 
L 0.72671004 -2.23876004 0.71196004 -2.23356998 0 P 0 
L 0.71196004 -2.23356998 0.69756998 -2.22753996 0 P 0 
L 0.69756998 -2.22753996 0.68355 -2.22066004 0 P 0 
L 0.68355 -2.22066004 0.67118002 -2.2135 0 P 0 
L 0.67118002 -2.2135 0.65938996 -2.20541004 0 P 0 
L 0.65938996 -2.20541004 0.64825 -2.19643996 0 P 0 
L 0.64825 -2.19643996 0.63861998 -2.18731998 0 P 0 
L 0.63861998 -2.18731998 0.62983002 -2.17746998 0 P 0 
L 0.62983002 -2.17746998 0.62188996 -2.1669 0 P 0 
L 0.62188996 -2.1669 0.61678002 -2.15886998 0 P 0 
L 0.61678002 -2.15886998 0.6123 -2.15056004 0 P 0 
L 0.6123 -2.15056004 0.60841998 -2.14193996 0 P 0 
L 0.60841998 -2.14193996 0.60516998 -2.13306998 0 P 0 
L 0.60516998 -2.13306998 0.60191004 -2.12171004 0 P 0 
L 0.60191004 -2.12171004 0.60075 -2.11648002 0 P 0 
L 0.60075 -2.11648002 0.59983996 -2.11121004 0 P 0 
L 0.59983996 -2.11121004 0.59913996 -2.10576004 0 P 0 
L 0.59913996 -2.10576004 0.59868996 -2.10026004 0 P 0 
L 0.59868996 -2.10026004 0.59833002 -2.0875 0 P 0 
L 0.59833002 -2.0875 0.59856998 -2.07843996 0 P 0 
L 0.59856998 -2.07843996 0.59923996 -2.0695 0 P 0 
L 0.59923996 -2.0695 0.60031998 -2.06153996 0 P 0 
L 0.60031998 -2.06153996 0.60193002 -2.05368996 0 P 0 
L 0.60193002 -2.05368996 0.60416004 -2.04566004 0 P 0 
L 0.60416004 -2.04566004 0.60688996 -2.03786004 0 P 0 
L 0.60688996 -2.03786004 0.6148 -2.01961004 0 P 0 
L 0.6148 -2.01961004 0.62108996 -2.00753002 0 P 0 
L 0.62108996 -2.00753002 0.62811998 -1.99591998 0 P 0 
L 0.62811998 -1.99591998 0.63583996 -1.98478996 0 P 0 
L 0.63583996 -1.98478996 0.64936998 -1.96808002 0 P 0 
L 0.64936998 -1.96808002 0.66418002 -1.95256998 0 P 0 
L 0.66418002 -1.95256998 0.68098002 -1.93756004 0 P 0 
L 0.68098002 -1.93756004 0.69881998 -1.92398002 0 P 0 
L 0.69881998 -1.92398002 0.71841998 -1.91123996 0 P 0 
L 0.71841998 -1.91123996 0.73875 -1.89996998 0 P 0 
L 0.73875 -1.89996998 0.74471004 -1.89696998 0 P 0 
L 0.74471004 -1.89696998 0.74983002 -1.89451004 0 P 0 
L 0.74983002 -1.89451004 0.7511 -1.89391004 0 P 0 
L 0.7511 -1.89391004 0.75076998 -1.89488996 0 P 0 
L 0.75076998 -1.89488996 0.75033996 -1.89658996 0 P 0 
L 0.75033996 -1.89658996 0.75003002 -1.8983 0 P 0 
L 0.75003002 -1.8983 0.74961998 -1.90161998 0 P 0 
L 0.74961998 -1.90161998 0.74936004 -1.90496004 0 P 0 
L 0.74936004 -1.90496004 0.74926998 -1.9085 0 P 0 
L 0.74926998 -1.9085 0.74933002 -1.91201998 0 P 0 
L 0.74933002 -1.91201998 0.74956004 -1.91516998 0 P 0 
L 0.74956004 -1.91516998 0.75 -1.91828996 0 P 0 
L 0.75 -1.91828996 0.75075 -1.92205 0 P 0 
L 0.75075 -1.92205 0.75166004 -1.92573996 0 P 0 
L 0.75166004 -1.92573996 0.7527 -1.92916998 0 P 0 
L 0.7527 -1.92916998 0.75393996 -1.93253002 0 P 0 
L 0.75393996 -1.93253002 0.75536004 -1.93581998 0 P 0 
L 0.75536004 -1.93581998 0.75696004 -1.939 0 P 0 
L 0.75696004 -1.939 0.75885 -1.94231004 0 P 0 
L 0.75885 -1.94231004 0.76083996 -1.94543996 0 P 0 
L 0.76083996 -1.94543996 0.76338996 -1.94933996 0 P 0 
L 0.76338996 -1.94933996 0.76371998 -1.94991998 0 P 0 
L 0.76371998 -1.94991998 0.76401004 -1.9505 0 P 0 
L 0.76401004 -1.9505 0.76423996 -1.95103002 0 P 0 
L 0.76423996 -1.95103002 0.76408996 -1.95111004 0 P 0 
L 0.76408996 -1.95111004 0.76348996 -1.95151004 0 P 0 
L 0.76348996 -1.95151004 0.76021004 -1.95386004 0 P 0 
L 0.76021004 -1.95386004 0.7602 -1.95386998 0 P 0 
L 0.7602 -1.95386998 0.75636998 -1.95666004 0 P 0 
L 0.75636998 -1.95666004 0.75636004 -1.95666998 0 P 0 
L 0.75636004 -1.95666998 0.75635 -1.95666998 0 P 0 
L 0.75635 -1.95666998 0.75208996 -1.95981004 0 P 0 
L 0.75208996 -1.95981004 0.73841004 -1.97066998 0 P 0 
L 0.73841004 -1.97066998 0.72541004 -1.98241004 0 P 0 
L 0.72541004 -1.98241004 0.7143 -1.994 0 P 0 
L 0.7143 -1.994 0.71425 -1.99406004 0 P 0 
L 0.71425 -1.99406004 0.70413996 -2.00648002 0 P 0 
L 0.70413996 -2.00648002 0.69836998 -2.01468996 0 P 0 
L 0.69836998 -2.01468996 0.69313002 -2.02318002 0 P 0 
L 0.69313002 -2.02318002 0.68838996 -2.03196004 0 P 0 
L 0.68838996 -2.03196004 0.68438996 -2.04063996 0 P 0 
L 0.68438996 -2.04063996 0.68098996 -2.04958002 0 P 0 
L 0.68098996 -2.04958002 0.6782 -2.05873002 0 P 0 
L 0.6782 -2.05873002 0.67706004 -2.06366004 0 P 0 
L 0.67706004 -2.06366004 0.67628996 -2.06866998 0 P 0 
L 0.67628996 -2.06866998 0.67538002 -2.08068996 0 P 0 
L 0.67538002 -2.08068996 0.67546004 -2.09268996 0 P 0 
L 0.67546004 -2.09268996 0.67588996 -2.09766998 0 P 0 
L 0.67588996 -2.09766998 0.6767 -2.10258996 0 P 0 
L 0.6767 -2.10258996 0.67881998 -2.11111998 0 P 0 
L 0.67881998 -2.11111998 0.68163996 -2.11936004 0 P 0 
L 0.68163996 -2.11936004 0.68516004 -2.12731998 0 P 0 
L 0.68516004 -2.12731998 0.68935 -2.13493996 0 P 0 
L 0.68935 -2.13493996 0.69418002 -2.14216998 0 P 0 
L 0.69418002 -2.14216998 0.70153002 -2.15135 0 P 0 
L 0.70153002 -2.15135 0.7096 -2.15983002 0 P 0 
L 0.7096 -2.15983002 0.71836004 -2.16758996 0 P 0 
L 0.71836004 -2.16758996 0.71843002 -2.16763996 0 P 0 
L 0.71843002 -2.16763996 0.72773996 -2.17456004 0 P 0 
L 0.72773996 -2.17456004 0.73926998 -2.1818 0 P 0 
L 0.73926998 -2.1818 0.75121004 -2.18818002 0 P 0 
L 0.75121004 -2.18818002 0.75128002 -2.18821004 0 P 0 
L 0.75128002 -2.18821004 0.76358002 -2.19368996 0 P 0 
L 0.76358002 -2.19368996 0.77628002 -2.19831004 0 P 0 
L 0.77628002 -2.19831004 0.79658996 -2.20423996 0 P 0 
L 0.79658996 -2.20423996 0.81701004 -2.20888996 0 P 0 
L 0.81701004 -2.20888996 0.83763996 -2.21233002 0 P 0 
L 0.83763996 -2.21233002 0.85388002 -2.21383002 0 P 0 
L 0.85388002 -2.21383002 0.87733996 -2.21465 0 P 0 
L 0.87733996 -2.21465 0.90118002 -2.21478996 0 P 0 
L 0.90118002 -2.21478996 0.91906004 -2.21398996 0 P 0 
L 0.91906004 -2.21398996 0.94908996 -2.21068002 0 P 0 
L 0.94908996 -2.21068002 0.98176998 -2.2053 0 P 0 
L 0.98176998 -2.2053 1.01575 -2.19815 0 P 0 
L 1.01575 -2.19815 1.04968002 -2.18943002 0 P 0 
L 1.04968002 -2.18943002 1.05633996 -2.18761004 0 P 0 
L 1.05633996 -2.18761004 1.05713996 -2.1874 0 P 0 
L 1.05713996 -2.1874 1.05483002 -2.18875 0 P 0 
L 1.05483002 -2.18875 1.04298996 -2.19526004 0 P 0 
L 1.04298996 -2.19526004 1.03096998 -2.20136998 0 P 0 
L 1.03096998 -2.20136998 0.99835 -2.21595 0 P 0 
L 0.99835 -2.21595 0.96401998 -2.22873996 0 P 0 
L 0.96401998 -2.22873996 0.92993996 -2.23908002 0 P 0 
L 0.92993996 -2.23908002 0.89816004 -2.24626004 0 P 0 
L 0.89816004 -2.24626004 0.87616004 -2.24965 0 P 0 
L 0.87616004 -2.24965 0.85405 -2.25176004 0 P 0 
L 0.85405 -2.25176004 0.83143002 -2.25261998 0 P 0 
L 0.65345 -2.20061998 0.78421004 -2.20061998 0 P 0 
L 0.65221004 -2.19961998 0.78078002 -2.19961998 0 P 0 
L 0.65096004 -2.19861998 0.77735 -2.19861998 0 P 0 
L 0.64971998 -2.19761998 0.77438996 -2.19761998 0 P 0 
L 0.64848002 -2.19661998 0.77163996 -2.19661998 0 P 0 
L 0.64738996 -2.19561998 0.76888996 -2.19561998 0 P 0 
L 0.64633996 -2.19461998 0.76613996 -2.19461998 0 P 0 
L 0.64528002 -2.19361998 0.76343002 -2.19361998 0 P 0 
L 0.64421998 -2.19261998 0.76118996 -2.19261998 0 P 0 
L 0.64316998 -2.19161998 0.75893996 -2.19161998 0 P 0 
L 0.64211004 -2.19061998 0.7567 -2.19061998 0 P 0 
L 0.64106004 -2.18961998 0.75446004 -2.18961998 0 P 0 
L 0.64 -2.18861998 0.75221004 -2.18861998 0 P 0 
L 0.63895 -2.18761998 0.75018002 -2.18761998 0 P 0 
L 0.63801004 -2.18661998 0.74831004 -2.18661998 0 P 0 
L 0.63711004 -2.18561998 0.74643002 -2.18561998 0 P 0 
L 0.63621998 -2.18461998 0.74456004 -2.18461998 0 P 0 
L 0.63533002 -2.18361998 0.74268002 -2.18361998 0 P 0 
L 0.63443996 -2.18261998 0.74081004 -2.18261998 0 P 0 
L 0.63353996 -2.18161998 0.73898996 -2.18161998 0 P 0 
L 0.63265 -2.18061998 0.73738996 -2.18061998 0 P 0 
L 0.63176004 -2.17961998 0.7358 -2.17961998 0 P 0 
L 0.63086998 -2.17861998 0.73421004 -2.17861998 0 P 0 
L 0.62996998 -2.17761998 0.73261998 -2.17761998 0 P 0 
L 0.6292 -2.17661998 0.73103002 -2.17661998 0 P 0 
L 0.62845 -2.17561998 0.72943996 -2.17561998 0 P 0 
L 0.6277 -2.17461998 0.72783996 -2.17461998 0 P 0 
L 0.62693996 -2.17361998 0.72648002 -2.17361998 0 P 0 
L 0.62618996 -2.17261998 0.72513996 -2.17261998 0 P 0 
L 0.62543996 -2.17161998 0.72378996 -2.17161998 0 P 0 
L 0.62468996 -2.17061998 0.72245 -2.17061998 0 P 0 
L 0.62393996 -2.16961998 0.7211 -2.16961998 0 P 0 
L 0.62318002 -2.16861998 0.71976004 -2.16861998 0 P 0 
L 0.62243996 -2.16761998 0.71841004 -2.16761998 0 P 0 
L 0.62171004 -2.16661998 0.71726998 -2.16661998 0 P 0 
L 0.62108002 -2.16561998 0.71613996 -2.16561998 0 P 0 
L 0.62043996 -2.16461998 0.71501004 -2.16461998 0 P 0 
L 0.61981004 -2.16361998 0.71388002 -2.16361998 0 P 0 
L 0.61916998 -2.16261998 0.71276004 -2.16261998 0 P 0 
L 0.61853002 -2.16161998 0.71163002 -2.16161998 0 P 0 
L 0.6179 -2.16061998 0.7105 -2.16061998 0 P 0 
L 0.61726004 -2.15961998 0.7094 -2.15961998 0 P 0 
L 0.61665 -2.15861998 0.70845 -2.15861998 0 P 0 
L 0.61611004 -2.15761998 0.7075 -2.15761998 0 P 0 
L 0.75383996 -2.24561998 0.901 -2.24561998 0 P 0 
L 0.74876998 -2.24461998 0.90541998 -2.24461998 0 P 0 
L 0.74431004 -2.24361998 0.90985 -2.24361998 0 P 0 
L 0.7407 -2.24261998 0.91426998 -2.24261998 0 P 0 
L 0.73708002 -2.24161998 0.9187 -2.24161998 0 P 0 
L 0.73346998 -2.24061998 0.92311998 -2.24061998 0 P 0 
L 0.72986004 -2.23961998 0.92753996 -2.23961998 0 P 0 
L 0.72633996 -2.23861998 0.93145 -2.23861998 0 P 0 
L 0.72348996 -2.23761998 0.93473996 -2.23761998 0 P 0 
L 0.72063996 -2.23661998 0.93803996 -2.23661998 0 P 0 
L 0.7178 -2.23561998 0.94133002 -2.23561998 0 P 0 
L 0.71495 -2.23461998 0.94461998 -2.23461998 0 P 0 
L 0.7121 -2.23361998 0.94791998 -2.23361998 0 P 0 
L 0.70968996 -2.23261998 0.95121004 -2.23261998 0 P 0 
L 0.70731004 -2.23161998 0.95451004 -2.23161998 0 P 0 
L 0.70491998 -2.23061998 0.9578 -2.23061998 0 P 0 
L 0.70253996 -2.22961998 0.9611 -2.22961998 0 P 0 
L 0.70015 -2.22861998 0.96431998 -2.22861998 0 P 0 
P 6.60051998 4.9574 9 P 0 0;1,3=25
P 6.64186004 4.9574 9 P 0 0;1,3=25
P 6.60051998 4.8767 9 P 0 0;1,3=25
P 6.64186004 4.8767 9 P 0 0;1,3=25
P 6.60051998 4.91705 24 P 0 0;1,3=26
P 6.64186004 4.91705 24 P 0 0;1,3=26
L 0.0349 -2.3038 0.0349 -1.0038 3 P 0 
L 0.0349 -1.0038 4.5349 -1.0038 3 P 0 
L 4.5349 -1.0038 4.5349 -2.3038 3 P 0 
L 4.5349 -2.3038 0.0349 -2.3038 3 P 0 
L 0.0349 -1.6038 4.5349 -1.6038 3 P 0 
L 0.0349 -1.8038 4.5349 -1.8038 3 P 0 
L 2.4349 -2.1038 4.0349 -2.1038 3 P 0 
L 2.4349 -2.3038 2.4349 -1.8038 3 P 0 
L 3.2349 -2.1038 3.2349 -1.8038 3 P 0 
L 4.0349 -2.3038 4.0349 -1.8038 3 P 0 
L 0.0723999 -1.6844687 0.07906663 -1.69030079 2 P 0 ;0,4=27,6=0.000000
L 0.07906663 -1.69030079 0.08656654 -1.6938 2 P 0 ;0,4=27,6=0.000000
L 0.08656654 -1.6938 0.09323337 -1.6938 2 P 0 ;0,4=27,6=0.000000
L 0.09323337 -1.6938 0.0999001 -1.69030079 2 P 0 ;0,4=27,6=0.000000
L 0.0999001 -1.69030079 0.10490059 -1.6844687 2 P 0 ;0,4=27,6=0.000000
L 0.10490059 -1.6844687 0.1074 -1.67629951 2 P 0 ;0,4=27,6=0.000000
L 0.1074 -1.67629951 0.10573376 -1.66813455 2 P 0 ;0,4=27,6=0.000000
L 0.10573376 -1.66813455 0.10156644 -1.66113396 2 P 0 ;0,4=27,6=0.000000
L 0.10156644 -1.66113396 0.09406654 -1.65646614 2 P 0 ;0,4=27,6=0.000000
L 0.09406654 -1.65646614 0.08406713 -1.65413327 2 P 0 ;0,4=27,6=0.000000
L 0.08406713 -1.65413327 0.07823346 -1.64946762 2 P 0 ;0,4=27,6=0.000000
L 0.07823346 -1.64946762 0.07573248 -1.64130059 2 P 0 ;0,4=27,6=0.000000
L 0.07573248 -1.64130059 0.0774003 -1.63313356 2 P 0 ;0,4=27,6=0.000000
L 0.0774003 -1.63313356 0.08156614 -1.62730148 2 P 0 ;0,4=27,6=0.000000
L 0.08156614 -1.62730148 0.0873997 -1.6238 2 P 0 ;0,4=27,6=0.000000
L 0.0873997 -1.6238 0.09323337 -1.6238 2 P 0 ;0,4=27,6=0.000000
L 0.09323337 -1.6238 0.09906693 -1.62613287 2 P 0 ;0,4=27,6=0.000000
L 0.09906693 -1.62613287 0.10406742 -1.63196713 2 P 0 ;0,4=27,6=0.000000
L 0.1383999 -1.6938 0.1383999 -1.6238 2 P 0 ;0,4=27,6=0.000000
L 0.1734 -1.6238 0.1734 -1.6938 2 P 0 ;0,4=27,6=0.000000
L 0.1734 -1.65880108 0.1383999 -1.65880108 2 P 0 ;0,4=27,6=0.000000
L 0.23856683 -1.6938 0.20523307 -1.6938 2 P 0 ;0,4=27,6=0.000000
L 0.20523307 -1.6938 0.20523307 -1.6238 2 P 0 ;0,4=27,6=0.000000
L 0.20523307 -1.6238 0.23856683 -1.6238 2 P 0 ;0,4=27,6=0.000000
L 0.22523337 -1.65763258 0.20523307 -1.65763258 2 P 0 ;0,4=27,6=0.000000
L 0.30456683 -1.6938 0.27123307 -1.6938 2 P 0 ;0,4=27,6=0.000000
L 0.27123307 -1.6938 0.27123307 -1.6238 2 P 0 ;0,4=27,6=0.000000
L 0.27123307 -1.6238 0.30456683 -1.6238 2 P 0 ;0,4=27,6=0.000000
L 0.29123337 -1.65763258 0.27123307 -1.65763258 2 P 0 ;0,4=27,6=0.000000
L 0.35389921 -1.6238 0.35389921 -1.6938 2 P 0 ;0,4=27,6=0.000000
L 0.33473356 -1.6238 0.37306634 -1.6238 2 P 0 ;0,4=27,6=0.000000
L 0.09489921 -1.7188 0.09489921 -1.7888 2 P 0 ;0,4=28,6=0.000000
L 0.07573356 -1.7188 0.11406634 -1.7188 2 P 0 ;0,4=28,6=0.000000
L 0.1508998 -1.7188 0.17089862 -1.7188 2 P 0 ;0,4=28,6=0.000000
L 0.16089921 -1.7188 0.16089921 -1.7888 2 P 0 ;0,4=28,6=0.000000
L 0.1508998 -1.7888 0.17089862 -1.7888 2 P 0 ;0,4=28,6=0.000000
L 0.22689921 -1.7188 0.22689921 -1.7888 2 P 0 ;0,4=28,6=0.000000
L 0.20773356 -1.7188 0.24606634 -1.7188 2 P 0 ;0,4=28,6=0.000000
L 0.27623307 -1.7188 0.27623307 -1.7888 2 P 0 ;0,4=28,6=0.000000
L 0.27623307 -1.7888 0.30956683 -1.7888 2 P 0 ;0,4=28,6=0.000000
L 0.37556683 -1.7888 0.34223307 -1.7888 2 P 0 ;0,4=28,6=0.000000
L 0.34223307 -1.7888 0.34223307 -1.7188 2 P 0 ;0,4=28,6=0.000000
L 0.34223307 -1.7188 0.37556683 -1.7188 2 P 0 ;0,4=28,6=0.000000
L 0.36223337 -1.75263258 0.34223307 -1.75263258 2 P 0 ;0,4=28,6=0.000000
L 2.5438999 -1.96813563 2.5519 -1.97480089 2 P 0 ;0,4=29,6=0.000000
L 2.5519 -1.97480089 2.5608999 -1.9788 2 P 0 ;0,4=29,6=0.000000
L 2.5608999 -1.9788 2.5689 -1.9788 2 P 0 ;0,4=29,6=0.000000
L 2.5689 -1.9788 2.5769001 -1.97480089 2 P 0 ;0,4=29,6=0.000000
L 2.5769001 -1.97480089 2.58290069 -1.96813563 2 P 0 ;0,4=29,6=0.000000
L 2.58290069 -1.96813563 2.5859 -1.95879941 2 P 0 ;0,4=29,6=0.000000
L 2.5859 -1.95879941 2.58390049 -1.94946811 2 P 0 ;0,4=29,6=0.000000
L 2.58390049 -1.94946811 2.5788997 -1.94146732 2 P 0 ;0,4=29,6=0.000000
L 2.5788997 -1.94146732 2.5698998 -1.93613278 2 P 0 ;0,4=29,6=0.000000
L 2.5698998 -1.93613278 2.55790049 -1.93346663 2 P 0 ;0,4=29,6=0.000000
L 2.55790049 -1.93346663 2.5509002 -1.92813445 2 P 0 ;0,4=29,6=0.000000
L 2.5509002 -1.92813445 2.54789902 -1.91880069 2 P 0 ;0,4=29,6=0.000000
L 2.54789902 -1.91880069 2.54990039 -1.90946683 2 P 0 ;0,4=29,6=0.000000
L 2.54990039 -1.90946683 2.55489931 -1.90280167 2 P 0 ;0,4=29,6=0.000000
L 2.55489931 -1.90280167 2.5618997 -1.8988 2 P 0 ;0,4=29,6=0.000000
L 2.5618997 -1.8988 2.5689 -1.8988 2 P 0 ;0,4=29,6=0.000000
L 2.5689 -1.8988 2.57590039 -1.90146614 2 P 0 ;0,4=29,6=0.000000
L 2.57590039 -1.90146614 2.58190089 -1.90813386 2 P 0 ;0,4=29,6=0.000000
L 2.6648998 -1.90546772 2.65889931 -1.90146614 2 P 0 ;0,4=29,6=0.000000
L 2.65889931 -1.90146614 2.65190079 -1.8988 2 P 0 ;0,4=29,6=0.000000
L 2.65190079 -1.8988 2.64390069 -1.8988 2 P 0 ;0,4=29,6=0.000000
L 2.64390069 -1.8988 2.63489892 -1.90280167 2 P 0 ;0,4=29,6=0.000000
L 2.63489892 -1.90280167 2.62790039 -1.90946683 2 P 0 ;0,4=29,6=0.000000
L 2.62790039 -1.90946683 2.62289961 -1.91746762 2 P 0 ;0,4=29,6=0.000000
L 2.62289961 -1.91746762 2.61889862 -1.93080049 2 P 0 ;0,4=29,6=0.000000
L 2.61889862 -1.93080049 2.61789892 -1.94280039 2 P 0 ;0,4=29,6=0.000000
L 2.61789892 -1.94280039 2.6199003 -1.9548003 2 P 0 ;0,4=29,6=0.000000
L 2.6199003 -1.9548003 2.62289961 -1.96280098 2 P 0 ;0,4=29,6=0.000000
L 2.62289961 -1.96280098 2.6289002 -1.97080177 2 P 0 ;0,4=29,6=0.000000
L 2.6289002 -1.97080177 2.63590049 -1.97613396 2 P 0 ;0,4=29,6=0.000000
L 2.63590049 -1.97613396 2.64289902 -1.9788 2 P 0 ;0,4=29,6=0.000000
L 2.64289902 -1.9788 2.64989941 -1.9788 2 P 0 ;0,4=29,6=0.000000
L 2.64989941 -1.9788 2.6568997 -1.97613396 2 P 0 ;0,4=29,6=0.000000
L 2.6568997 -1.97613396 2.6629003 -1.97213484 2 P 0 ;0,4=29,6=0.000000
L 2.6629003 -1.97213484 2.66790098 -1.96680266 2 P 0 ;0,4=29,6=0.000000
L 2.69589892 -1.9788 2.72089902 -1.8988 2 P 0 ;0,4=29,6=0.000000
L 2.72089902 -1.8988 2.74590098 -1.9788 2 P 0 ;0,4=29,6=0.000000
L 2.73689931 -1.95080118 2.70489882 -1.95080118 2 P 0 ;0,4=29,6=0.000000
L 2.77889961 -1.8988 2.77889961 -1.9788 2 P 0 ;0,4=29,6=0.000000
L 2.77889961 -1.9788 2.8189003 -1.9788 2 P 0 ;0,4=29,6=0.000000
L 2.8969003 -1.9788 2.85689961 -1.9788 2 P 0 ;0,4=29,6=0.000000
L 2.85689961 -1.9788 2.85689961 -1.8988 2 P 0 ;0,4=29,6=0.000000
L 2.85689961 -1.8988 2.8969003 -1.8988 2 P 0 ;0,4=29,6=0.000000
L 2.8809 -1.93746575 2.85689961 -1.93746575 2 P 0 ;0,4=29,6=0.000000
L 3.03289902 -1.9788 3.03289902 -1.8988 2 P 0 ;0,4=29,6=0.000000
L 3.03289902 -1.8988 3.0208998 -1.91479911 2 P 0 ;0,4=29,6=0.000000
L 3.0208998 -1.9788 3.04489833 -1.9788 2 P 0 ;0,4=29,6=0.000000
L 3.11089902 -1.98146604 3.10889951 -1.98013297 2 P 0 ;0,4=29,6=0.000000
L 3.10889951 -1.98013297 3.10889951 -1.97746703 2 P 0 ;0,4=29,6=0.000000
L 3.10889951 -1.97746703 3.11089902 -1.97613396 2 P 0 ;0,4=29,6=0.000000
L 3.11089902 -1.97613396 3.11290039 -1.97746703 2 P 0 ;0,4=29,6=0.000000
L 3.11290039 -1.97746703 3.11290039 -1.98013297 2 P 0 ;0,4=29,6=0.000000
L 3.11290039 -1.98013297 3.11089902 -1.98146604 2 P 0 ;0,4=29,6=0.000000
L 3.11089902 -1.945469 3.10889951 -1.94413346 2 P 0 ;0,4=29,6=0.000000
L 3.10889951 -1.94413346 3.10889951 -1.94146732 2 P 0 ;0,4=29,6=0.000000
L 3.10889951 -1.94146732 3.11089902 -1.94013435 2 P 0 ;0,4=29,6=0.000000
L 3.11089902 -1.94013435 3.11290039 -1.94146732 2 P 0 ;0,4=29,6=0.000000
L 3.11290039 -1.94146732 3.11290039 -1.94413346 2 P 0 ;0,4=29,6=0.000000
L 3.11290039 -1.94413346 3.11089902 -1.945469 2 P 0 ;0,4=29,6=0.000000
L 3.18889902 -1.9788 3.18889902 -1.8988 2 P 0 ;0,4=29,6=0.000000
L 3.18889902 -1.8988 3.1768998 -1.91479911 2 P 0 ;0,4=29,6=0.000000
L 3.1768998 -1.9788 3.20089833 -1.9788 2 P 0 ;0,4=29,6=0.000000
L 2.5138999 -2.23313563 2.5219 -2.23980089 2 P 0 ;0,4=27,6=0.000000
L 2.5219 -2.23980089 2.5308999 -2.2438 2 P 0 ;0,4=27,6=0.000000
L 2.5308999 -2.2438 2.5389 -2.2438 2 P 0 ;0,4=27,6=0.000000
L 2.5389 -2.2438 2.5469001 -2.23980089 2 P 0 ;0,4=27,6=0.000000
L 2.5469001 -2.23980089 2.55290069 -2.23313563 2 P 0 ;0,4=27,6=0.000000
L 2.55290069 -2.23313563 2.5559 -2.22379941 2 P 0 ;0,4=27,6=0.000000
L 2.5559 -2.22379941 2.55390049 -2.21446811 2 P 0 ;0,4=27,6=0.000000
L 2.55390049 -2.21446811 2.5488997 -2.20646732 2 P 0 ;0,4=27,6=0.000000
L 2.5488997 -2.20646732 2.5398998 -2.20113278 2 P 0 ;0,4=27,6=0.000000
L 2.5398998 -2.20113278 2.52790049 -2.19846663 2 P 0 ;0,4=27,6=0.000000
L 2.52790049 -2.19846663 2.5209002 -2.19313445 2 P 0 ;0,4=27,6=0.000000
L 2.5209002 -2.19313445 2.51789902 -2.18380069 2 P 0 ;0,4=27,6=0.000000
L 2.51789902 -2.18380069 2.51990039 -2.17446683 2 P 0 ;0,4=27,6=0.000000
L 2.51990039 -2.17446683 2.52489931 -2.16780167 2 P 0 ;0,4=27,6=0.000000
L 2.52489931 -2.16780167 2.5318997 -2.1638 2 P 0 ;0,4=27,6=0.000000
L 2.5318997 -2.1638 2.5389 -2.1638 2 P 0 ;0,4=27,6=0.000000
L 2.5389 -2.1638 2.54590039 -2.16646614 2 P 0 ;0,4=27,6=0.000000
L 2.54590039 -2.16646614 2.55190089 -2.17313386 2 P 0 ;0,4=27,6=0.000000
L 2.5918999 -2.2438 2.5918999 -2.1638 2 P 0 ;0,4=27,6=0.000000
L 2.6339 -2.1638 2.6339 -2.2438 2 P 0 ;0,4=27,6=0.000000
L 2.6339 -2.20380128 2.5918999 -2.20380128 2 P 0 ;0,4=27,6=0.000000
L 2.7109003 -2.2438 2.67089961 -2.2438 2 P 0 ;0,4=27,6=0.000000
L 2.67089961 -2.2438 2.67089961 -2.1638 2 P 0 ;0,4=27,6=0.000000
L 2.67089961 -2.1638 2.7109003 -2.1638 2 P 0 ;0,4=27,6=0.000000
L 2.6949 -2.20246575 2.67089961 -2.20246575 2 P 0 ;0,4=27,6=0.000000
L 2.7889003 -2.2438 2.74889961 -2.2438 2 P 0 ;0,4=27,6=0.000000
L 2.74889961 -2.2438 2.74889961 -2.1638 2 P 0 ;0,4=27,6=0.000000
L 2.74889961 -2.1638 2.7889003 -2.1638 2 P 0 ;0,4=27,6=0.000000
L 2.7729 -2.20246575 2.74889961 -2.20246575 2 P 0 ;0,4=27,6=0.000000
L 2.84689902 -2.1638 2.84689902 -2.2438 2 P 0 ;0,4=27,6=0.000000
L 2.8239003 -2.1638 2.86989961 -2.1638 2 P 0 ;0,4=27,6=0.000000
L 3.29489961 -1.9238 3.29489961 -2.0038 2 P 0 ;0,4=30,6=0.000000
L 3.29489961 -2.0038 3.3349003 -2.0038 2 P 0 ;0,4=30,6=0.000000
L 3.36789892 -2.0038 3.39289902 -1.9238 2 P 0 ;0,4=30,6=0.000000
L 3.39289902 -1.9238 3.41790098 -2.0038 2 P 0 ;0,4=30,6=0.000000
L 3.40889931 -1.97580118 3.37689882 -1.97580118 2 P 0 ;0,4=30,6=0.000000
L 3.47089902 -2.0038 3.47089902 -1.96780039 2 P 0 ;0,4=30,6=0.000000
L 3.47089902 -1.96780039 3.45089961 -1.9238 2 P 0 ;0,4=30,6=0.000000
L 3.4909003 -1.9238 3.47089902 -1.96780039 2 P 0 ;0,4=30,6=0.000000
L 3.5689003 -2.0038 3.52889961 -2.0038 2 P 0 ;0,4=30,6=0.000000
L 3.52889961 -2.0038 3.52889961 -1.9238 2 P 0 ;0,4=30,6=0.000000
L 3.52889961 -1.9238 3.5689003 -1.9238 2 P 0 ;0,4=30,6=0.000000
L 3.5529 -1.96246575 3.52889961 -1.96246575 2 P 0 ;0,4=30,6=0.000000
L 3.60689961 -2.0038 3.60689961 -1.9238 2 P 0 ;0,4=30,6=0.000000
L 3.60689961 -1.9238 3.6318998 -1.9238 2 P 0 ;0,4=30,6=0.000000
L 3.6318998 -1.9238 3.6398999 -1.92780167 2 P 0 ;0,4=30,6=0.000000
L 3.6398999 -1.92780167 3.64490069 -1.93313386 2 P 0 ;0,4=30,6=0.000000
L 3.64490069 -1.93313386 3.6469003 -1.94380069 2 P 0 ;0,4=30,6=0.000000
L 3.6469003 -1.94380069 3.64490069 -1.95446752 2 P 0 ;0,4=30,6=0.000000
L 3.64490069 -1.95446752 3.6389001 -1.96113278 2 P 0 ;0,4=30,6=0.000000
L 3.6389001 -1.96113278 3.6318998 -1.96513435 2 P 0 ;0,4=30,6=0.000000
L 3.6318998 -1.96513435 3.60689961 -1.96513435 2 P 0 ;0,4=30,6=0.000000
L 3.6318998 -1.96513435 3.6469003 -2.0038 2 P 0 ;0,4=30,6=0.000000
L 3.33989902 -2.2538 3.33189892 -2.25246703 2 P 0 ;0,4=31,6=0.000000
L 3.33189892 -2.25246703 3.32490039 -2.24713484 2 P 0 ;0,4=31,6=0.000000
L 3.32490039 -2.24713484 3.3188999 -2.23913406 2 P 0 ;0,4=31,6=0.000000
L 3.3188999 -2.23913406 3.31489892 -2.2298003 2 P 0 ;0,4=31,6=0.000000
L 3.31489892 -2.2298003 3.31289931 -2.21913346 2 P 0 ;0,4=31,6=0.000000
L 3.31289931 -2.21913346 3.31289931 -2.20846663 2 P 0 ;0,4=31,6=0.000000
L 3.31289931 -2.20846663 3.31489892 -2.1977998 2 P 0 ;0,4=31,6=0.000000
L 3.31489892 -2.1977998 3.3188999 -2.18846604 2 P 0 ;0,4=31,6=0.000000
L 3.3188999 -2.18846604 3.32490039 -2.18046772 2 P 0 ;0,4=31,6=0.000000
L 3.32490039 -2.18046772 3.33189892 -2.17513307 2 P 0 ;0,4=31,6=0.000000
L 3.33189892 -2.17513307 3.33989902 -2.1738 2 P 0 ;0,4=31,6=0.000000
L 3.33989902 -2.1738 3.34789911 -2.17513307 2 P 0 ;0,4=31,6=0.000000
L 3.34789911 -2.17513307 3.35489951 -2.18046772 2 P 0 ;0,4=31,6=0.000000
L 3.35489951 -2.18046772 3.3609 -2.18846604 2 P 0 ;0,4=31,6=0.000000
L 3.3609 -2.18846604 3.36490098 -2.1977998 2 P 0 ;0,4=31,6=0.000000
L 3.36490098 -2.1977998 3.36690059 -2.20846663 2 P 0 ;0,4=31,6=0.000000
L 3.36690059 -2.20846663 3.36690059 -2.21913346 2 P 0 ;0,4=31,6=0.000000
L 3.36690059 -2.21913346 3.36490098 -2.2298003 2 P 0 ;0,4=31,6=0.000000
L 3.36490098 -2.2298003 3.3609 -2.23913406 2 P 0 ;0,4=31,6=0.000000
L 3.3609 -2.23913406 3.35489951 -2.24713484 2 P 0 ;0,4=31,6=0.000000
L 3.35489951 -2.24713484 3.34789911 -2.25246703 2 P 0 ;0,4=31,6=0.000000
L 3.34789911 -2.25246703 3.33989902 -2.2538 2 P 0 ;0,4=31,6=0.000000
L 3.39889941 -2.2538 3.39889941 -2.1738 2 P 0 ;0,4=31,6=0.000000
L 3.39889941 -2.1738 3.43690049 -2.1738 2 P 0 ;0,4=31,6=0.000000
L 3.4228998 -2.21246575 3.39889941 -2.21246575 2 P 0 ;0,4=31,6=0.000000
L 0.16489872 -1.0538 0.16489872 -1.1538 2 P 0 ;0,4=28,6=0.000000
L 0.13423376 -1.0538 0.19556614 -1.0538 2 P 0 ;0,4=28,6=0.000000
L 0.2588997 -1.0538 0.29089774 -1.0538 2 P 0 ;0,4=28,6=0.000000
L 0.27489872 -1.0538 0.27489872 -1.1538 2 P 0 ;0,4=28,6=0.000000
L 0.2588997 -1.1538 0.29089774 -1.1538 2 P 0 ;0,4=28,6=0.000000
L 0.38489872 -1.0538 0.38489872 -1.1538 2 P 0 ;0,4=28,6=0.000000
L 0.35423376 -1.0538 0.41556614 -1.0538 2 P 0 ;0,4=28,6=0.000000
L 0.46823287 -1.0538 0.46823287 -1.1538 2 P 0 ;0,4=28,6=0.000000
L 0.46823287 -1.1538 0.52156703 -1.1538 2 P 0 ;0,4=28,6=0.000000
L 0.63156703 -1.1538 0.57823287 -1.1538 2 P 0 ;0,4=28,6=0.000000
L 0.57823287 -1.1538 0.57823287 -1.0538 2 P 0 ;0,4=28,6=0.000000
L 0.57823287 -1.0538 0.63156703 -1.0538 2 P 0 ;0,4=28,6=0.000000
L 0.61023337 -1.10213219 0.57823287 -1.10213219 2 P 0 ;0,4=28,6=0.000000
L 4.18989892 -1.9538 4.21489902 -1.8738 2 P 0 ;0,4=32,6=0.000000
L 4.21489902 -1.8738 4.23990098 -1.9538 2 P 0 ;0,4=32,6=0.000000
L 4.23089931 -1.92580118 4.19889882 -1.92580118 2 P 0 ;0,4=32,6=0.000000
L 4.27289961 -1.9538 4.27289961 -1.8738 2 P 0 ;0,4=32,6=0.000000
L 4.27289961 -1.8738 4.2978998 -1.8738 2 P 0 ;0,4=32,6=0.000000
L 4.2978998 -1.8738 4.3058999 -1.87780167 2 P 0 ;0,4=32,6=0.000000
L 4.3058999 -1.87780167 4.31090069 -1.88313386 2 P 0 ;0,4=32,6=0.000000
L 4.31090069 -1.88313386 4.3129003 -1.89380069 2 P 0 ;0,4=32,6=0.000000
L 4.3129003 -1.89380069 4.31090069 -1.90446752 2 P 0 ;0,4=32,6=0.000000
L 4.31090069 -1.90446752 4.3049001 -1.91113278 2 P 0 ;0,4=32,6=0.000000
L 4.3049001 -1.91113278 4.2978998 -1.91513435 2 P 0 ;0,4=32,6=0.000000
L 4.2978998 -1.91513435 4.27289961 -1.91513435 2 P 0 ;0,4=32,6=0.000000
L 4.2978998 -1.91513435 4.3129003 -1.9538 2 P 0 ;0,4=32,6=0.000000
L 4.37089902 -1.8738 4.37089902 -1.9538 2 P 0 ;0,4=32,6=0.000000
L 4.3479003 -1.8738 4.39389961 -1.8738 2 P 0 ;0,4=32,6=0.000000
L 3.72973337 -1.97380098 3.76006654 -1.97380098 2 P 0 ;0,4=33,6=0.000000
L 3.06989892 -2.2538 3.06989892 -2.1638 2 P 0 ;0,4=34,6=0.000000
L 3.06989892 -2.1638 3.0558997 -2.18179892 2 P 0 ;0,4=34,6=0.000000
L 3.0558997 -2.2538 3.08389803 -2.2538 2 P 0 ;0,4=34,6=0.000000
L 3.64489892 -2.2538 3.64489892 -2.1638 2 P 0 ;0,4=34,6=0.000000
L 3.64489892 -2.1638 3.6308997 -2.18179892 2 P 0 ;0,4=34,6=0.000000
L 3.6308997 -2.2538 3.65889803 -2.2538 2 P 0 ;0,4=34,6=0.000000
L 0.5453998 -1.74180266 0.55473337 -1.74930098 2 P 0 ;0,4=35,6=0.000000
L 0.55473337 -1.74930098 0.56523317 -1.7538 2 P 0 ;0,4=35,6=0.000000
L 0.56523317 -1.7538 0.57456673 -1.7538 2 P 0 ;0,4=35,6=0.000000
L 0.57456673 -1.7538 0.5839002 -1.74930098 2 P 0 ;0,4=35,6=0.000000
L 0.5839002 -1.74930098 0.59090079 -1.74180266 2 P 0 ;0,4=35,6=0.000000
L 0.59090079 -1.74180266 0.5944001 -1.73129941 2 P 0 ;0,4=35,6=0.000000
L 0.5944001 -1.73129941 0.59206722 -1.72080157 2 P 0 ;0,4=35,6=0.000000
L 0.59206722 -1.72080157 0.58623297 -1.71180079 2 P 0 ;0,4=35,6=0.000000
L 0.58623297 -1.71180079 0.57573307 -1.70579931 2 P 0 ;0,4=35,6=0.000000
L 0.57573307 -1.70579931 0.56173396 -1.7028 2 P 0 ;0,4=35,6=0.000000
L 0.56173396 -1.7028 0.55356693 -1.69680128 2 P 0 ;0,4=35,6=0.000000
L 0.55356693 -1.69680128 0.55006555 -1.68630069 2 P 0 ;0,4=35,6=0.000000
L 0.55006555 -1.68630069 0.55240049 -1.6758002 2 P 0 ;0,4=35,6=0.000000
L 0.55240049 -1.6758002 0.55823258 -1.66830187 2 P 0 ;0,4=35,6=0.000000
L 0.55823258 -1.66830187 0.56639961 -1.6638 2 P 0 ;0,4=35,6=0.000000
L 0.56639961 -1.6638 0.57456673 -1.6638 2 P 0 ;0,4=35,6=0.000000
L 0.57456673 -1.6638 0.58273376 -1.66679941 2 P 0 ;0,4=35,6=0.000000
L 0.58273376 -1.66679941 0.58973435 -1.67430059 2 P 0 ;0,4=35,6=0.000000
L 0.65989892 -1.7538 0.65056545 -1.75230039 2 P 0 ;0,4=35,6=0.000000
L 0.65056545 -1.75230039 0.64240049 -1.74630167 2 P 0 ;0,4=35,6=0.000000
L 0.64240049 -1.74630167 0.6353998 -1.73730079 2 P 0 ;0,4=35,6=0.000000
L 0.6353998 -1.73730079 0.63073209 -1.7268003 2 P 0 ;0,4=35,6=0.000000
L 0.63073209 -1.7268003 0.62839921 -1.7148001 2 P 0 ;0,4=35,6=0.000000
L 0.62839921 -1.7148001 0.62839921 -1.7028 2 P 0 ;0,4=35,6=0.000000
L 0.62839921 -1.7028 0.63073209 -1.6907998 2 P 0 ;0,4=35,6=0.000000
L 0.63073209 -1.6907998 0.6353998 -1.68029931 2 P 0 ;0,4=35,6=0.000000
L 0.6353998 -1.68029931 0.64240049 -1.67130118 2 P 0 ;0,4=35,6=0.000000
L 0.64240049 -1.67130118 0.65056545 -1.6652997 2 P 0 ;0,4=35,6=0.000000
L 0.65056545 -1.6652997 0.65989892 -1.6638 2 P 0 ;0,4=35,6=0.000000
L 0.65989892 -1.6638 0.66923238 -1.6652997 2 P 0 ;0,4=35,6=0.000000
L 0.66923238 -1.6652997 0.67739941 -1.67130118 2 P 0 ;0,4=35,6=0.000000
L 0.67739941 -1.67130118 0.6844001 -1.68029931 2 P 0 ;0,4=35,6=0.000000
L 0.6844001 -1.68029931 0.68906782 -1.6907998 2 P 0 ;0,4=35,6=0.000000
L 0.68906782 -1.6907998 0.69140069 -1.7028 2 P 0 ;0,4=35,6=0.000000
L 0.69140069 -1.7028 0.69140069 -1.7148001 2 P 0 ;0,4=35,6=0.000000
L 0.69140069 -1.7148001 0.68906782 -1.7268003 2 P 0 ;0,4=35,6=0.000000
L 0.68906782 -1.7268003 0.6844001 -1.73730079 2 P 0 ;0,4=35,6=0.000000
L 0.6844001 -1.73730079 0.67739941 -1.74630167 2 P 0 ;0,4=35,6=0.000000
L 0.67739941 -1.74630167 0.66923238 -1.75230039 2 P 0 ;0,4=35,6=0.000000
L 0.66923238 -1.75230039 0.65989892 -1.7538 2 P 0 ;0,4=35,6=0.000000
L 0.72656624 -1.6638 0.72656624 -1.7538 2 P 0 ;0,4=35,6=0.000000
L 0.72656624 -1.7538 0.77323366 -1.7538 2 P 0 ;0,4=35,6=0.000000
L 0.81423346 -1.7538 0.81423346 -1.6638 2 P 0 ;0,4=35,6=0.000000
L 0.81423346 -1.6638 0.83756604 -1.6638 2 P 0 ;0,4=35,6=0.000000
L 0.83756604 -1.6638 0.84689951 -1.66830187 2 P 0 ;0,4=35,6=0.000000
L 0.84689951 -1.66830187 0.8539002 -1.67430059 2 P 0 ;0,4=35,6=0.000000
L 0.8539002 -1.67430059 0.85973435 -1.68329862 2 P 0 ;0,4=35,6=0.000000
L 0.85973435 -1.68329862 0.8644001 -1.69380187 2 P 0 ;0,4=35,6=0.000000
L 0.8644001 -1.69380187 0.86556644 -1.70880138 2 P 0 ;0,4=35,6=0.000000
L 0.86556644 -1.70880138 0.8644001 -1.72380098 2 P 0 ;0,4=35,6=0.000000
L 0.8644001 -1.72380098 0.85973435 -1.73430148 2 P 0 ;0,4=35,6=0.000000
L 0.85973435 -1.73430148 0.8539002 -1.74330226 2 P 0 ;0,4=35,6=0.000000
L 0.8539002 -1.74330226 0.84689951 -1.74930098 2 P 0 ;0,4=35,6=0.000000
L 0.84689951 -1.74930098 0.83756604 -1.7538 2 P 0 ;0,4=35,6=0.000000
L 0.83756604 -1.7538 0.81423346 -1.7538 2 P 0 ;0,4=35,6=0.000000
L 0.95323366 -1.7538 0.90656624 -1.7538 2 P 0 ;0,4=35,6=0.000000
L 0.90656624 -1.7538 0.90656624 -1.6638 2 P 0 ;0,4=35,6=0.000000
L 0.90656624 -1.6638 0.95323366 -1.6638 2 P 0 ;0,4=35,6=0.000000
L 0.93456673 -1.70729902 0.90656624 -1.70729902 2 P 0 ;0,4=35,6=0.000000
L 0.99656624 -1.7538 0.99656624 -1.6638 2 P 0 ;0,4=35,6=0.000000
L 0.99656624 -1.6638 1.02573307 -1.6638 2 P 0 ;0,4=35,6=0.000000
L 1.02573307 -1.6638 1.03506654 -1.66830187 2 P 0 ;0,4=35,6=0.000000
L 1.03506654 -1.66830187 1.04090079 -1.67430059 2 P 0 ;0,4=35,6=0.000000
L 1.04090079 -1.67430059 1.04323366 -1.68630069 2 P 0 ;0,4=35,6=0.000000
L 1.04323366 -1.68630069 1.04090079 -1.69830089 2 P 0 ;0,4=35,6=0.000000
L 1.04090079 -1.69830089 1.0339002 -1.70579931 2 P 0 ;0,4=35,6=0.000000
L 1.0339002 -1.70579931 1.02573307 -1.71030108 2 P 0 ;0,4=35,6=0.000000
L 1.02573307 -1.71030108 0.99656624 -1.71030108 2 P 0 ;0,4=35,6=0.000000
L 1.02573307 -1.71030108 1.04323366 -1.7538 2 P 0 ;0,4=35,6=0.000000
L 1.17656624 -1.7538 1.17656624 -1.6638 2 P 0 ;0,4=35,6=0.000000
L 1.17656624 -1.6638 1.20456673 -1.6638 2 P 0 ;0,4=35,6=0.000000
L 1.20456673 -1.6638 1.2139002 -1.66830187 2 P 0 ;0,4=35,6=0.000000
L 1.2139002 -1.66830187 1.22090079 -1.67879961 2 P 0 ;0,4=35,6=0.000000
L 1.22090079 -1.67879961 1.22323366 -1.6907998 2 P 0 ;0,4=35,6=0.000000
L 1.22323366 -1.6907998 1.22090079 -1.7028 2 P 0 ;0,4=35,6=0.000000
L 1.22090079 -1.7028 1.21506654 -1.71180079 2 P 0 ;0,4=35,6=0.000000
L 1.21506654 -1.71180079 1.20456673 -1.71630256 2 P 0 ;0,4=35,6=0.000000
L 1.20456673 -1.71630256 1.17656624 -1.71630256 2 P 0 ;0,4=35,6=0.000000
L 1.26073209 -1.7538 1.28989892 -1.6638 2 P 0 ;0,4=35,6=0.000000
L 1.28989892 -1.6638 1.31906782 -1.7538 2 P 0 ;0,4=35,6=0.000000
L 1.30856585 -1.72230128 1.27123189 -1.72230128 2 P 0 ;0,4=35,6=0.000000
L 1.3553998 -1.74180266 1.36473337 -1.74930098 2 P 0 ;0,4=35,6=0.000000
L 1.36473337 -1.74930098 1.37523317 -1.7538 2 P 0 ;0,4=35,6=0.000000
L 1.37523317 -1.7538 1.38456673 -1.7538 2 P 0 ;0,4=35,6=0.000000
L 1.38456673 -1.7538 1.3939002 -1.74930098 2 P 0 ;0,4=35,6=0.000000
L 1.3939002 -1.74930098 1.40090079 -1.74180266 2 P 0 ;0,4=35,6=0.000000
L 1.40090079 -1.74180266 1.4044001 -1.73129941 2 P 0 ;0,4=35,6=0.000000
L 1.4044001 -1.73129941 1.40206722 -1.72080157 2 P 0 ;0,4=35,6=0.000000
L 1.40206722 -1.72080157 1.39623297 -1.71180079 2 P 0 ;0,4=35,6=0.000000
L 1.39623297 -1.71180079 1.38573307 -1.70579931 2 P 0 ;0,4=35,6=0.000000
L 1.38573307 -1.70579931 1.37173396 -1.7028 2 P 0 ;0,4=35,6=0.000000
L 1.37173396 -1.7028 1.36356693 -1.69680128 2 P 0 ;0,4=35,6=0.000000
L 1.36356693 -1.69680128 1.36006555 -1.68630069 2 P 0 ;0,4=35,6=0.000000
L 1.36006555 -1.68630069 1.36240049 -1.6758002 2 P 0 ;0,4=35,6=0.000000
L 1.36240049 -1.6758002 1.36823258 -1.66830187 2 P 0 ;0,4=35,6=0.000000
L 1.36823258 -1.66830187 1.37639961 -1.6638 2 P 0 ;0,4=35,6=0.000000
L 1.37639961 -1.6638 1.38456673 -1.6638 2 P 0 ;0,4=35,6=0.000000
L 1.38456673 -1.6638 1.39273376 -1.66679941 2 P 0 ;0,4=35,6=0.000000
L 1.39273376 -1.66679941 1.39973435 -1.67430059 2 P 0 ;0,4=35,6=0.000000
L 1.46989892 -1.6638 1.46989892 -1.7538 2 P 0 ;0,4=35,6=0.000000
L 1.44306703 -1.6638 1.49673287 -1.6638 2 P 0 ;0,4=35,6=0.000000
L 1.58323366 -1.7538 1.53656624 -1.7538 2 P 0 ;0,4=35,6=0.000000
L 1.53656624 -1.7538 1.53656624 -1.6638 2 P 0 ;0,4=35,6=0.000000
L 1.53656624 -1.6638 1.58323366 -1.6638 2 P 0 ;0,4=35,6=0.000000
L 1.56456673 -1.70729902 1.53656624 -1.70729902 2 P 0 ;0,4=35,6=0.000000
L 1.73406683 -1.78379902 1.72240049 -1.76879951 2 P 0 ;0,4=35,6=0.000000
L 1.72240049 -1.76879951 1.71656624 -1.7538 2 P 0 ;0,4=35,6=0.000000
L 1.71656624 -1.7538 1.71656624 -1.69380187 2 P 0 ;0,4=35,6=0.000000
L 1.71656624 -1.69380187 1.72240049 -1.67879961 2 P 0 ;0,4=35,6=0.000000
L 1.72240049 -1.67879961 1.73406683 -1.6638 2 P 0 ;0,4=35,6=0.000000
L 1.82989892 -1.6638 1.82989892 -1.7538 2 P 0 ;0,4=35,6=0.000000
L 1.80306703 -1.6638 1.85673287 -1.6638 2 P 0 ;0,4=35,6=0.000000
L 1.91989892 -1.7538 1.91056545 -1.75230039 2 P 0 ;0,4=35,6=0.000000
L 1.91056545 -1.75230039 1.90240049 -1.74630167 2 P 0 ;0,4=35,6=0.000000
L 1.90240049 -1.74630167 1.8953998 -1.73730079 2 P 0 ;0,4=35,6=0.000000
L 1.8953998 -1.73730079 1.89073209 -1.7268003 2 P 0 ;0,4=35,6=0.000000
L 1.89073209 -1.7268003 1.88839921 -1.7148001 2 P 0 ;0,4=35,6=0.000000
L 1.88839921 -1.7148001 1.88839921 -1.7028 2 P 0 ;0,4=35,6=0.000000
L 1.88839921 -1.7028 1.89073209 -1.6907998 2 P 0 ;0,4=35,6=0.000000
L 1.89073209 -1.6907998 1.8953998 -1.68029931 2 P 0 ;0,4=35,6=0.000000
L 1.8953998 -1.68029931 1.90240049 -1.67130118 2 P 0 ;0,4=35,6=0.000000
L 1.90240049 -1.67130118 1.91056545 -1.6652997 2 P 0 ;0,4=35,6=0.000000
L 1.91056545 -1.6652997 1.91989892 -1.6638 2 P 0 ;0,4=35,6=0.000000
L 1.91989892 -1.6638 1.92923238 -1.6652997 2 P 0 ;0,4=35,6=0.000000
L 1.92923238 -1.6652997 1.93739941 -1.67130118 2 P 0 ;0,4=35,6=0.000000
L 1.93739941 -1.67130118 1.9444001 -1.68029931 2 P 0 ;0,4=35,6=0.000000
L 1.9444001 -1.68029931 1.94906782 -1.6907998 2 P 0 ;0,4=35,6=0.000000
L 1.94906782 -1.6907998 1.95140069 -1.7028 2 P 0 ;0,4=35,6=0.000000
L 1.95140069 -1.7028 1.95140069 -1.7148001 2 P 0 ;0,4=35,6=0.000000
L 1.95140069 -1.7148001 1.94906782 -1.7268003 2 P 0 ;0,4=35,6=0.000000
L 1.94906782 -1.7268003 1.9444001 -1.73730079 2 P 0 ;0,4=35,6=0.000000
L 1.9444001 -1.73730079 1.93739941 -1.74630167 2 P 0 ;0,4=35,6=0.000000
L 1.93739941 -1.74630167 1.92923238 -1.75230039 2 P 0 ;0,4=35,6=0.000000
L 1.92923238 -1.75230039 1.91989892 -1.7538 2 P 0 ;0,4=35,6=0.000000
L 1.98656624 -1.7538 1.98656624 -1.6638 2 P 0 ;0,4=35,6=0.000000
L 1.98656624 -1.6638 2.01456673 -1.6638 2 P 0 ;0,4=35,6=0.000000
L 2.01456673 -1.6638 2.0239002 -1.66830187 2 P 0 ;0,4=35,6=0.000000
L 2.0239002 -1.66830187 2.03090079 -1.67879961 2 P 0 ;0,4=35,6=0.000000
L 2.03090079 -1.67879961 2.03323366 -1.6907998 2 P 0 ;0,4=35,6=0.000000
L 2.03323366 -1.6907998 2.03090079 -1.7028 2 P 0 ;0,4=35,6=0.000000
L 2.03090079 -1.7028 2.02506654 -1.71180079 2 P 0 ;0,4=35,6=0.000000
L 2.02506654 -1.71180079 2.01456673 -1.71630256 2 P 0 ;0,4=35,6=0.000000
L 2.01456673 -1.71630256 1.98656624 -1.71630256 2 P 0 ;0,4=35,6=0.000000
L 2.10573307 -1.78379902 2.11739941 -1.76879951 2 P 0 ;0,4=35,6=0.000000
L 2.11739941 -1.76879951 2.12323366 -1.7538 2 P 0 ;0,4=35,6=0.000000
L 2.12323366 -1.7538 2.12323366 -1.69380187 2 P 0 ;0,4=35,6=0.000000
L 2.12323366 -1.69380187 2.11739941 -1.67879961 2 P 0 ;0,4=35,6=0.000000
L 2.11739941 -1.67879961 2.10573307 -1.6638 2 P 0 ;0,4=35,6=0.000000
L 0.59099833 -1.36499882 0.5990003 -1.35750039 2 P 0 ;0,4=36,6=0.000000
L 0.5990003 -1.35750039 0.60499902 -1.34500315 2 P 0 ;0,4=36,6=0.000000
L 0.60499902 -1.34500315 0.60900187 -1.32749764 2 P 0 ;0,4=36,6=0.000000
L 0.60900187 -1.32749764 0.60499902 -1.31250089 2 P 0 ;0,4=36,6=0.000000
L 0.60499902 -1.31250089 0.59700079 -1.30250305 2 P 0 ;0,4=36,6=0.000000
L 0.59700079 -1.30250305 0.5830001 -1.295 2 P 0 ;0,4=36,6=0.000000
L 0.5830001 -1.295 0.52900059 -1.295 2 P 0 ;0,4=36,6=0.000000
L 0.52900059 -1.295 0.52900059 -1.445 2 P 0 ;0,4=36,6=0.000000
L 0.52900059 -1.445 0.59500118 -1.445 2 P 0 ;0,4=36,6=0.000000
L 0.59500118 -1.445 0.60900187 -1.43500217 2 P 0 ;0,4=36,6=0.000000
L 0.60900187 -1.43500217 0.6170001 -1.42000079 2 P 0 ;0,4=36,6=0.000000
L 0.6170001 -1.42000079 0.62099931 -1.4025 2 P 0 ;0,4=36,6=0.000000
L 0.62099931 -1.4025 0.6170001 -1.38500374 2 P 0 ;0,4=36,6=0.000000
L 0.6170001 -1.38500374 0.60499902 -1.37000236 2 P 0 ;0,4=36,6=0.000000
L 0.60499902 -1.37000236 0.59099833 -1.36499882 2 P 0 ;0,4=36,6=0.000000
L 0.59099833 -1.36499882 0.52900059 -1.36499882 2 P 0 ;0,4=36,6=0.000000
L 0.77100138 -1.445 0.77100138 -1.34500315 2 P 0 ;0,4=36,6=0.000000
L 0.77100138 -1.36249941 0.76299951 -1.35250148 2 P 0 ;0,4=36,6=0.000000
L 0.76299951 -1.35250148 0.75099833 -1.34750256 2 P 0 ;0,4=36,6=0.000000
L 0.75099833 -1.34750256 0.73700138 -1.34500315 2 P 0 ;0,4=36,6=0.000000
L 0.73700138 -1.34500315 0.72300069 -1.35000207 2 P 0 ;0,4=36,6=0.000000
L 0.72300069 -1.35000207 0.71099961 -1.3599999 2 P 0 ;0,4=36,6=0.000000
L 0.71099961 -1.3599999 0.70299764 -1.37500128 2 P 0 ;0,4=36,6=0.000000
L 0.70299764 -1.37500128 0.69899852 -1.39500157 2 P 0 ;0,4=36,6=0.000000
L 0.69899852 -1.39500157 0.70299764 -1.41500187 2 P 0 ;0,4=36,6=0.000000
L 0.70299764 -1.41500187 0.71099961 -1.43000325 2 P 0 ;0,4=36,6=0.000000
L 0.71099961 -1.43000325 0.72300069 -1.44000108 2 P 0 ;0,4=36,6=0.000000
L 0.72300069 -1.44000108 0.73700138 -1.445 2 P 0 ;0,4=36,6=0.000000
L 0.73700138 -1.445 0.75099833 -1.44250059 2 P 0 ;0,4=36,6=0.000000
L 0.75099833 -1.44250059 0.76299951 -1.43500217 2 P 0 ;0,4=36,6=0.000000
L 0.76299951 -1.43500217 0.77100138 -1.42500433 2 P 0 ;0,4=36,6=0.000000
L 0.86700039 -1.445 0.86700039 -1.34500315 2 P 0 ;0,4=36,6=0.000000
L 0.86700039 -1.36499882 0.87699833 -1.35500098 2 P 0 ;0,4=36,6=0.000000
L 0.87699833 -1.35500098 0.8869998 -1.34750256 2 P 0 ;0,4=36,6=0.000000
L 0.8869998 -1.34750256 0.90100049 -1.34500315 2 P 0 ;0,4=36,6=0.000000
L 0.90100049 -1.34500315 0.91099833 -1.34750256 2 P 0 ;0,4=36,6=0.000000
L 0.91099833 -1.34750256 0.92299951 -1.35500098 2 P 0 ;0,4=36,6=0.000000
L 1.02700039 -1.445 1.02700039 -1.34500315 2 P 0 ;0,4=36,6=0.000000
L 1.02700039 -1.36499882 1.03699833 -1.35500098 2 P 0 ;0,4=36,6=0.000000
L 1.03699833 -1.35500098 1.0469998 -1.34750256 2 P 0 ;0,4=36,6=0.000000
L 1.0469998 -1.34750256 1.06100049 -1.34500315 2 P 0 ;0,4=36,6=0.000000
L 1.06100049 -1.34500315 1.07099833 -1.34750256 2 P 0 ;0,4=36,6=0.000000
L 1.07099833 -1.34750256 1.08299951 -1.35500098 2 P 0 ;0,4=36,6=0.000000
L 1.18500089 -1.37750069 1.24900187 -1.37750069 2 P 0 ;0,4=36,6=0.000000
L 1.24900187 -1.37750069 1.24299951 -1.3599999 2 P 0 ;0,4=36,6=0.000000
L 1.24299951 -1.3599999 1.23300157 -1.35000207 2 P 0 ;0,4=36,6=0.000000
L 1.23300157 -1.35000207 1.21900089 -1.34500315 2 P 0 ;0,4=36,6=0.000000
L 1.21900089 -1.34500315 1.2050003 -1.34750256 2 P 0 ;0,4=36,6=0.000000
L 1.2050003 -1.34750256 1.19299911 -1.35500098 2 P 0 ;0,4=36,6=0.000000
L 1.19299911 -1.35500098 1.18500089 -1.37250177 2 P 0 ;0,4=36,6=0.000000
L 1.18500089 -1.37250177 1.18099803 -1.38750315 2 P 0 ;0,4=36,6=0.000000
L 1.18099803 -1.38750315 1.18099803 -1.4025 2 P 0 ;0,4=36,6=0.000000
L 1.18099803 -1.4025 1.18500089 -1.41750138 2 P 0 ;0,4=36,6=0.000000
L 1.18500089 -1.41750138 1.19499872 -1.43250276 2 P 0 ;0,4=36,6=0.000000
L 1.19499872 -1.43250276 1.2069998 -1.44250059 2 P 0 ;0,4=36,6=0.000000
L 1.2069998 -1.44250059 1.22100049 -1.445 2 P 0 ;0,4=36,6=0.000000
L 1.22100049 -1.445 1.23500118 -1.44000108 2 P 0 ;0,4=36,6=0.000000
L 1.23500118 -1.44000108 1.24900187 -1.42500433 2 P 0 ;0,4=36,6=0.000000
L 1.37499813 -1.445 1.37499813 -1.295 2 P 0 ;0,4=36,6=0.000000
L 1.50500089 -1.37750069 1.56900187 -1.37750069 2 P 0 ;0,4=36,6=0.000000
L 1.56900187 -1.37750069 1.56299951 -1.3599999 2 P 0 ;0,4=36,6=0.000000
L 1.56299951 -1.3599999 1.55300157 -1.35000207 2 P 0 ;0,4=36,6=0.000000
L 1.55300157 -1.35000207 1.53900089 -1.34500315 2 P 0 ;0,4=36,6=0.000000
L 1.53900089 -1.34500315 1.5250003 -1.34750256 2 P 0 ;0,4=36,6=0.000000
L 1.5250003 -1.34750256 1.51299911 -1.35500098 2 P 0 ;0,4=36,6=0.000000
L 1.51299911 -1.35500098 1.50500089 -1.37250177 2 P 0 ;0,4=36,6=0.000000
L 1.50500089 -1.37250177 1.50099803 -1.38750315 2 P 0 ;0,4=36,6=0.000000
L 1.50099803 -1.38750315 1.50099803 -1.4025 2 P 0 ;0,4=36,6=0.000000
L 1.50099803 -1.4025 1.50500089 -1.41750138 2 P 0 ;0,4=36,6=0.000000
L 1.50500089 -1.41750138 1.51499872 -1.43250276 2 P 0 ;0,4=36,6=0.000000
L 1.51499872 -1.43250276 1.5269998 -1.44250059 2 P 0 ;0,4=36,6=0.000000
L 1.5269998 -1.44250059 1.54100049 -1.445 2 P 0 ;0,4=36,6=0.000000
L 1.54100049 -1.445 1.55500118 -1.44000108 2 P 0 ;0,4=36,6=0.000000
L 1.55500118 -1.44000108 1.56900187 -1.42500433 2 P 0 ;0,4=36,6=0.000000
L 1.6529998 -1.48999951 1.66500089 -1.49499843 2 P 0 ;0,4=36,6=0.000000
L 1.66500089 -1.49499843 1.68100108 -1.48999951 2 P 0 ;0,4=36,6=0.000000
L 1.68100108 -1.48999951 1.69099902 -1.48000167 2 P 0 ;0,4=36,6=0.000000
L 1.69099902 -1.48000167 1.69900089 -1.4674997 2 P 0 ;0,4=36,6=0.000000
L 1.69900089 -1.4674997 1.71099833 -1.42750374 2 P 0 ;0,4=36,6=0.000000
L 1.71099833 -1.42750374 1.7370001 -1.34500315 2 P 0 ;0,4=36,6=0.000000
L 1.67299911 -1.34500315 1.71099833 -1.42750374 2 P 0 ;0,4=36,6=0.000000
L 1.82500089 -1.37750069 1.88900187 -1.37750069 2 P 0 ;0,4=36,6=0.000000
L 1.88900187 -1.37750069 1.88299951 -1.3599999 2 P 0 ;0,4=36,6=0.000000
L 1.88299951 -1.3599999 1.87300157 -1.35000207 2 P 0 ;0,4=36,6=0.000000
L 1.87300157 -1.35000207 1.85900089 -1.34500315 2 P 0 ;0,4=36,6=0.000000
L 1.85900089 -1.34500315 1.8450003 -1.34750256 2 P 0 ;0,4=36,6=0.000000
L 1.8450003 -1.34750256 1.83299911 -1.35500098 2 P 0 ;0,4=36,6=0.000000
L 1.83299911 -1.35500098 1.82500089 -1.37250177 2 P 0 ;0,4=36,6=0.000000
L 1.82500089 -1.37250177 1.82099803 -1.38750315 2 P 0 ;0,4=36,6=0.000000
L 1.82099803 -1.38750315 1.82099803 -1.4025 2 P 0 ;0,4=36,6=0.000000
L 1.82099803 -1.4025 1.82500089 -1.41750138 2 P 0 ;0,4=36,6=0.000000
L 1.82500089 -1.41750138 1.83499872 -1.43250276 2 P 0 ;0,4=36,6=0.000000
L 1.83499872 -1.43250276 1.8469998 -1.44250059 2 P 0 ;0,4=36,6=0.000000
L 1.8469998 -1.44250059 1.86100049 -1.445 2 P 0 ;0,4=36,6=0.000000
L 1.86100049 -1.445 1.87500118 -1.44000108 2 P 0 ;0,4=36,6=0.000000
L 1.87500118 -1.44000108 1.88900187 -1.42500433 2 P 0 ;0,4=36,6=0.000000
L 2.18699921 -1.37000236 2.22700167 -1.37000236 2 P 0 ;0,4=36,6=0.000000
L 2.22700167 -1.37000236 2.22700167 -1.41500187 2 P 0 ;0,4=36,6=0.000000
L 2.22700167 -1.41500187 2.21500059 -1.43000325 2 P 0 ;0,4=36,6=0.000000
L 2.21500059 -1.43000325 2.2009999 -1.44000108 2 P 0 ;0,4=36,6=0.000000
L 2.2009999 -1.44000108 2.18100049 -1.445 2 P 0 ;0,4=36,6=0.000000
L 2.18100049 -1.445 2.16100108 -1.44000108 2 P 0 ;0,4=36,6=0.000000
L 2.16100108 -1.44000108 2.14700039 -1.43000325 2 P 0 ;0,4=36,6=0.000000
L 2.14700039 -1.43000325 2.13499931 -1.41500187 2 P 0 ;0,4=36,6=0.000000
L 2.13499931 -1.41500187 2.12699734 -1.39750108 2 P 0 ;0,4=36,6=0.000000
L 2.12699734 -1.39750108 2.12299823 -1.37750069 2 P 0 ;0,4=36,6=0.000000
L 2.12299823 -1.37750069 2.12299823 -1.3599999 2 P 0 ;0,4=36,6=0.000000
L 2.12299823 -1.3599999 2.12699734 -1.34500315 2 P 0 ;0,4=36,6=0.000000
L 2.12699734 -1.34500315 2.13499931 -1.32749764 2 P 0 ;0,4=36,6=0.000000
L 2.13499931 -1.32749764 2.14700039 -1.31250089 2 P 0 ;0,4=36,6=0.000000
L 2.14700039 -1.31250089 2.15899783 -1.30250305 2 P 0 ;0,4=36,6=0.000000
L 2.15899783 -1.30250305 2.17499813 -1.295 2 P 0 ;0,4=36,6=0.000000
L 2.17499813 -1.295 2.18899882 -1.295 2 P 0 ;0,4=36,6=0.000000
L 2.18899882 -1.295 2.20499902 -1.29999902 2 P 0 ;0,4=36,6=0.000000
L 2.20499902 -1.29999902 2.2170001 -1.31000138 2 P 0 ;0,4=36,6=0.000000
L 2.29699892 -1.31999931 2.309 -1.30500246 2 P 0 ;0,4=36,6=0.000000
L 2.309 -1.30500246 2.32300069 -1.29749951 2 P 0 ;0,4=36,6=0.000000
L 2.32300069 -1.29749951 2.33900089 -1.295 2 P 0 ;0,4=36,6=0.000000
L 2.33900089 -1.295 2.3590003 -1.29999902 2 P 0 ;0,4=36,6=0.000000
L 2.3590003 -1.29999902 2.37300098 -1.31250089 2 P 0 ;0,4=36,6=0.000000
L 2.37300098 -1.31250089 2.3770001 -1.32749764 2 P 0 ;0,4=36,6=0.000000
L 2.3770001 -1.32749764 2.37500059 -1.34250364 2 P 0 ;0,4=36,6=0.000000
L 2.37500059 -1.34250364 2.36699862 -1.35500098 2 P 0 ;0,4=36,6=0.000000
L 2.36699862 -1.35500098 2.3269998 -1.3800002 2 P 0 ;0,4=36,6=0.000000
L 2.3269998 -1.3800002 2.309 -1.39750108 2 P 0 ;0,4=36,6=0.000000
L 2.309 -1.39750108 2.29699892 -1.42250482 2 P 0 ;0,4=36,6=0.000000
L 2.29699892 -1.42250482 2.2929998 -1.445 2 P 0 ;0,4=36,6=0.000000
L 2.2929998 -1.445 2.3770001 -1.445 2 P 0 ;0,4=36,6=0.000000
L 2.6129998 -1.42500433 2.629 -1.43750167 2 P 0 ;0,4=36,6=0.000000
L 2.629 -1.43750167 2.6469998 -1.445 2 P 0 ;0,4=36,6=0.000000
L 2.6469998 -1.445 2.6630001 -1.445 2 P 0 ;0,4=36,6=0.000000
L 2.6630001 -1.445 2.6790003 -1.43750167 2 P 0 ;0,4=36,6=0.000000
L 2.6790003 -1.43750167 2.69100138 -1.42500433 2 P 0 ;0,4=36,6=0.000000
L 2.69100138 -1.42500433 2.6970001 -1.40749892 2 P 0 ;0,4=36,6=0.000000
L 2.6970001 -1.40749892 2.69300098 -1.39000266 2 P 0 ;0,4=36,6=0.000000
L 2.69300098 -1.39000266 2.68299951 -1.37500128 2 P 0 ;0,4=36,6=0.000000
L 2.68299951 -1.37500128 2.66499961 -1.36499882 2 P 0 ;0,4=36,6=0.000000
L 2.66499961 -1.36499882 2.64100108 -1.3599999 2 P 0 ;0,4=36,6=0.000000
L 2.64100108 -1.3599999 2.62700039 -1.35000207 2 P 0 ;0,4=36,6=0.000000
L 2.62700039 -1.35000207 2.62099803 -1.33250118 2 P 0 ;0,4=36,6=0.000000
L 2.62099803 -1.33250118 2.62500089 -1.31500039 2 P 0 ;0,4=36,6=0.000000
L 2.62500089 -1.31500039 2.63499872 -1.30250305 2 P 0 ;0,4=36,6=0.000000
L 2.63499872 -1.30250305 2.64899941 -1.295 2 P 0 ;0,4=36,6=0.000000
L 2.64899941 -1.295 2.6630001 -1.295 2 P 0 ;0,4=36,6=0.000000
L 2.6630001 -1.295 2.67700079 -1.29999902 2 P 0 ;0,4=36,6=0.000000
L 2.67700079 -1.29999902 2.68900187 -1.31250089 2 P 0 ;0,4=36,6=0.000000
L 2.7729998 -1.445 2.8570001 -1.295 2 P 0 ;0,4=36,6=0.000000
L 2.7729998 -1.295 2.8570001 -1.445 2 P 0 ;0,4=36,6=0.000000
L 2.92299823 -1.445 2.92299823 -1.295 2 P 0 ;0,4=36,6=0.000000
L 2.92299823 -1.295 2.97499813 -1.42000079 2 P 0 ;0,4=36,6=0.000000
L 2.97499813 -1.42000079 3.02700167 -1.295 2 P 0 ;0,4=36,6=0.000000
L 3.02700167 -1.295 3.02700167 -1.445 2 P 0 ;0,4=36,6=0.000000
L 3.09699892 -1.31999931 3.109 -1.30500246 2 P 0 ;0,4=36,6=0.000000
L 3.109 -1.30500246 3.12300069 -1.29749951 2 P 0 ;0,4=36,6=0.000000
L 3.12300069 -1.29749951 3.13900089 -1.295 2 P 0 ;0,4=36,6=0.000000
L 3.13900089 -1.295 3.1590003 -1.29999902 2 P 0 ;0,4=36,6=0.000000
L 3.1590003 -1.29999902 3.17300098 -1.31250089 2 P 0 ;0,4=36,6=0.000000
L 3.17300098 -1.31250089 3.1770001 -1.32749764 2 P 0 ;0,4=36,6=0.000000
L 3.1770001 -1.32749764 3.17500059 -1.34250364 2 P 0 ;0,4=36,6=0.000000
L 3.17500059 -1.34250364 3.16699862 -1.35500098 2 P 0 ;0,4=36,6=0.000000
L 3.16699862 -1.35500098 3.1269998 -1.3800002 2 P 0 ;0,4=36,6=0.000000
L 3.1269998 -1.3800002 3.109 -1.39750108 2 P 0 ;0,4=36,6=0.000000
L 3.109 -1.39750108 3.09699892 -1.42250482 2 P 0 ;0,4=36,6=0.000000
L 3.09699892 -1.42250482 3.0929998 -1.445 2 P 0 ;0,4=36,6=0.000000
L 3.0929998 -1.445 3.1770001 -1.445 2 P 0 ;0,4=36,6=0.000000
L 3.269 -1.39500157 3.3209999 -1.39500157 2 P 0 ;0,4=36,6=0.000000
L 3.41499931 -1.445 3.41499931 -1.295 2 P 0 ;0,4=36,6=0.000000
L 3.41499931 -1.295 3.46499961 -1.295 2 P 0 ;0,4=36,6=0.000000
L 3.46499961 -1.295 3.4809999 -1.30250305 2 P 0 ;0,4=36,6=0.000000
L 3.4809999 -1.30250305 3.49100138 -1.31250089 2 P 0 ;0,4=36,6=0.000000
L 3.49100138 -1.31250089 3.49500059 -1.33250118 2 P 0 ;0,4=36,6=0.000000
L 3.49500059 -1.33250118 3.49100138 -1.35250148 2 P 0 ;0,4=36,6=0.000000
L 3.49100138 -1.35250148 3.4790003 -1.36499882 2 P 0 ;0,4=36,6=0.000000
L 3.4790003 -1.36499882 3.46499961 -1.37250177 2 P 0 ;0,4=36,6=0.000000
L 3.46499961 -1.37250177 3.41499931 -1.37250177 2 P 0 ;0,4=36,6=0.000000
L 3.46499961 -1.37250177 3.49500059 -1.445 2 P 0 ;0,4=36,6=0.000000
L 3.61499813 -1.34500315 3.61499813 -1.445 2 P 0 ;0,4=36,6=0.000000
L 3.61499813 -1.30500246 3.61099902 -1.30250305 2 P 0 ;0,4=36,6=0.000000
L 3.61099902 -1.30250305 3.61099902 -1.29749951 2 P 0 ;0,4=36,6=0.000000
L 3.61099902 -1.29749951 3.61499813 -1.295 2 P 0 ;0,4=36,6=0.000000
L 3.61499813 -1.295 3.61900089 -1.29749951 2 P 0 ;0,4=36,6=0.000000
L 3.61900089 -1.29749951 3.61900089 -1.30250305 2 P 0 ;0,4=36,6=0.000000
L 3.61900089 -1.30250305 3.61499813 -1.30500246 2 P 0 ;0,4=36,6=0.000000
L 3.74500089 -1.42750374 3.75499872 -1.43750167 2 P 0 ;0,4=36,6=0.000000
L 3.75499872 -1.43750167 3.76899941 -1.445 2 P 0 ;0,4=36,6=0.000000
L 3.76899941 -1.445 3.78100049 -1.445 2 P 0 ;0,4=36,6=0.000000
L 3.78100049 -1.445 3.79300157 -1.44000108 2 P 0 ;0,4=36,6=0.000000
L 3.79300157 -1.44000108 3.8009999 -1.43250276 2 P 0 ;0,4=36,6=0.000000
L 3.8009999 -1.43250276 3.80499902 -1.42250482 2 P 0 ;0,4=36,6=0.000000
L 3.80499902 -1.42250482 3.80299951 -1.40749892 2 P 0 ;0,4=36,6=0.000000
L 3.80299951 -1.40749892 3.79500118 -1.40000049 2 P 0 ;0,4=36,6=0.000000
L 3.79500118 -1.40000049 3.75899783 -1.38500374 2 P 0 ;0,4=36,6=0.000000
L 3.75899783 -1.38500374 3.75099961 -1.36749833 2 P 0 ;0,4=36,6=0.000000
L 3.75099961 -1.36749833 3.75499872 -1.35500098 2 P 0 ;0,4=36,6=0.000000
L 3.75499872 -1.35500098 3.76300069 -1.34750256 2 P 0 ;0,4=36,6=0.000000
L 3.76300069 -1.34750256 3.77499813 -1.34500315 2 P 0 ;0,4=36,6=0.000000
L 3.77499813 -1.34500315 3.78699921 -1.34750256 2 P 0 ;0,4=36,6=0.000000
L 3.78699921 -1.34750256 3.7990003 -1.35500098 2 P 0 ;0,4=36,6=0.000000
L 3.90500089 -1.37750069 3.96900187 -1.37750069 2 P 0 ;0,4=36,6=0.000000
L 3.96900187 -1.37750069 3.96299951 -1.3599999 2 P 0 ;0,4=36,6=0.000000
L 3.96299951 -1.3599999 3.95300157 -1.35000207 2 P 0 ;0,4=36,6=0.000000
L 3.95300157 -1.35000207 3.93900089 -1.34500315 2 P 0 ;0,4=36,6=0.000000
L 3.93900089 -1.34500315 3.9250003 -1.34750256 2 P 0 ;0,4=36,6=0.000000
L 3.9250003 -1.34750256 3.91299911 -1.35500098 2 P 0 ;0,4=36,6=0.000000
L 3.91299911 -1.35500098 3.90500089 -1.37250177 2 P 0 ;0,4=36,6=0.000000
L 3.90500089 -1.37250177 3.90099803 -1.38750315 2 P 0 ;0,4=36,6=0.000000
L 3.90099803 -1.38750315 3.90099803 -1.4025 2 P 0 ;0,4=36,6=0.000000
L 3.90099803 -1.4025 3.90500089 -1.41750138 2 P 0 ;0,4=36,6=0.000000
L 3.90500089 -1.41750138 3.91499872 -1.43250276 2 P 0 ;0,4=36,6=0.000000
L 3.91499872 -1.43250276 3.9269998 -1.44250059 2 P 0 ;0,4=36,6=0.000000
L 3.9269998 -1.44250059 3.94100049 -1.445 2 P 0 ;0,4=36,6=0.000000
L 3.94100049 -1.445 3.95500118 -1.44000108 2 P 0 ;0,4=36,6=0.000000
L 3.95500118 -1.44000108 3.96900187 -1.42500433 2 P 0 ;0,4=36,6=0.000000
L 4.06700039 -1.445 4.06700039 -1.34500315 2 P 0 ;0,4=36,6=0.000000
L 4.06700039 -1.36499882 4.07699833 -1.35500098 2 P 0 ;0,4=36,6=0.000000
L 4.07699833 -1.35500098 4.0869998 -1.34750256 2 P 0 ;0,4=36,6=0.000000
L 4.0869998 -1.34750256 4.10100049 -1.34500315 2 P 0 ;0,4=36,6=0.000000
L 4.10100049 -1.34500315 4.11099833 -1.34750256 2 P 0 ;0,4=36,6=0.000000
L 4.11099833 -1.34750256 4.12299951 -1.35500098 2 P 0 ;0,4=36,6=0.000000
L 4.16964783 -2.2038 4.21839813 -2.0478 2 P 0 ;0,4=37,6=0.000000
L 4.21839813 -2.0478 4.26715207 -2.2038 2 P 0 ;0,4=37,6=0.000000
L 4.24959862 -2.14920217 4.18719774 -2.14920217 2 P 0 ;0,4=37,6=0.000000
L 4.37939813 -2.2038 4.37939813 -2.0478 2 P 0 ;0,4=37,6=0.000000
L 4.37939813 -2.0478 4.35599961 -2.07899813 2 P 0 ;0,4=37,6=0.000000
L 4.35599961 -2.2038 4.40279675 -2.2038 2 P 0 ;0,4=37,6=0.000000
L 2.0009002 -0.9538 2.0009002 -0.8038 2 P 0 ;0,4=38,6=0.000000
L 2.0009002 -0.8038 2.04089902 -0.8038 2 P 0 ;0,4=38,6=0.000000
L 2.04089902 -0.8038 2.05689921 -0.81130305 2 P 0 ;0,4=38,6=0.000000
L 2.05689921 -0.81130305 2.0689003 -0.82130089 2 P 0 ;0,4=38,6=0.000000
L 2.0689003 -0.82130089 2.07890187 -0.83629764 2 P 0 ;0,4=38,6=0.000000
L 2.07890187 -0.83629764 2.0869001 -0.85380315 2 P 0 ;0,4=38,6=0.000000
L 2.0869001 -0.85380315 2.0888997 -0.87880236 2 P 0 ;0,4=38,6=0.000000
L 2.0888997 -0.87880236 2.0869001 -0.90380157 2 P 0 ;0,4=38,6=0.000000
L 2.0869001 -0.90380157 2.07890187 -0.92130246 2 P 0 ;0,4=38,6=0.000000
L 2.07890187 -0.92130246 2.0689003 -0.93630374 2 P 0 ;0,4=38,6=0.000000
L 2.0689003 -0.93630374 2.05689921 -0.94630167 2 P 0 ;0,4=38,6=0.000000
L 2.05689921 -0.94630167 2.04089902 -0.9538 2 P 0 ;0,4=38,6=0.000000
L 2.04089902 -0.9538 2.0009002 -0.9538 2 P 0 ;0,4=38,6=0.000000
L 2.15489783 -0.9538 2.20489813 -0.8038 2 P 0 ;0,4=38,6=0.000000
L 2.20489813 -0.8038 2.25490207 -0.9538 2 P 0 ;0,4=38,6=0.000000
L 2.23689862 -0.90130207 2.17289764 -0.90130207 2 P 0 ;0,4=38,6=0.000000
L 2.36489813 -0.8038 2.36489813 -0.9538 2 P 0 ;0,4=38,6=0.000000
L 2.31890059 -0.8038 2.41089931 -0.8038 2 P 0 ;0,4=38,6=0.000000
L 2.56490059 -0.9538 2.48489931 -0.9538 2 P 0 ;0,4=38,6=0.000000
L 2.48489931 -0.9538 2.48489931 -0.8038 2 P 0 ;0,4=38,6=0.000000
L 2.48489931 -0.8038 2.56490059 -0.8038 2 P 0 ;0,4=38,6=0.000000
L 2.5329001 -0.87629833 2.48489931 -0.87629833 2 P 0 ;0,4=38,6=0.000000
L 2.84489813 -0.9538 2.82889783 -0.95130059 2 P 0 ;0,4=38,6=0.000000
L 2.82889783 -0.95130059 2.81490089 -0.94130276 2 P 0 ;0,4=38,6=0.000000
L 2.81490089 -0.94130276 2.8028998 -0.92630138 2 P 0 ;0,4=38,6=0.000000
L 2.8028998 -0.92630138 2.79489783 -0.90880049 2 P 0 ;0,4=38,6=0.000000
L 2.79489783 -0.90880049 2.79089862 -0.8888002 2 P 0 ;0,4=38,6=0.000000
L 2.79089862 -0.8888002 2.79089862 -0.8687999 2 P 0 ;0,4=38,6=0.000000
L 2.79089862 -0.8687999 2.79489783 -0.84879961 2 P 0 ;0,4=38,6=0.000000
L 2.79489783 -0.84879961 2.8028998 -0.83129872 2 P 0 ;0,4=38,6=0.000000
L 2.8028998 -0.83129872 2.81490089 -0.81630197 2 P 0 ;0,4=38,6=0.000000
L 2.81490089 -0.81630197 2.82889783 -0.80629951 2 P 0 ;0,4=38,6=0.000000
L 2.82889783 -0.80629951 2.84489813 -0.8038 2 P 0 ;0,4=38,6=0.000000
L 2.84489813 -0.8038 2.86089833 -0.80629951 2 P 0 ;0,4=38,6=0.000000
L 2.86089833 -0.80629951 2.87489902 -0.81630197 2 P 0 ;0,4=38,6=0.000000
L 2.87489902 -0.81630197 2.8869001 -0.83129872 2 P 0 ;0,4=38,6=0.000000
L 2.8869001 -0.83129872 2.89490207 -0.84879961 2 P 0 ;0,4=38,6=0.000000
L 2.89490207 -0.84879961 2.89890128 -0.8687999 2 P 0 ;0,4=38,6=0.000000
L 2.89890128 -0.8687999 2.89890128 -0.8888002 2 P 0 ;0,4=38,6=0.000000
L 2.89890128 -0.8888002 2.89490207 -0.90880049 2 P 0 ;0,4=38,6=0.000000
L 2.89490207 -0.90880049 2.8869001 -0.92630138 2 P 0 ;0,4=38,6=0.000000
L 2.8869001 -0.92630138 2.87489902 -0.94130276 2 P 0 ;0,4=38,6=0.000000
L 2.87489902 -0.94130276 2.86089833 -0.95130059 2 P 0 ;0,4=38,6=0.000000
L 2.86089833 -0.95130059 2.84489813 -0.9538 2 P 0 ;0,4=38,6=0.000000
L 3.0488997 -0.81630197 3.03689862 -0.80879902 2 P 0 ;0,4=38,6=0.000000
L 3.03689862 -0.80879902 3.02290157 -0.8038 2 P 0 ;0,4=38,6=0.000000
L 3.02290157 -0.8038 3.00690138 -0.8038 2 P 0 ;0,4=38,6=0.000000
L 3.00690138 -0.8038 2.98889783 -0.81130305 2 P 0 ;0,4=38,6=0.000000
L 2.98889783 -0.81130305 2.97490089 -0.82380039 2 P 0 ;0,4=38,6=0.000000
L 2.97490089 -0.82380039 2.96489931 -0.83880177 2 P 0 ;0,4=38,6=0.000000
L 2.96489931 -0.83880177 2.95689734 -0.86380098 2 P 0 ;0,4=38,6=0.000000
L 2.95689734 -0.86380098 2.95489783 -0.88630069 2 P 0 ;0,4=38,6=0.000000
L 2.95489783 -0.88630069 2.95890059 -0.90880049 2 P 0 ;0,4=38,6=0.000000
L 2.95890059 -0.90880049 2.96489931 -0.92380187 2 P 0 ;0,4=38,6=0.000000
L 2.96489931 -0.92380187 2.97690039 -0.93880325 2 P 0 ;0,4=38,6=0.000000
L 2.97690039 -0.93880325 2.99090108 -0.94880108 2 P 0 ;0,4=38,6=0.000000
L 2.99090108 -0.94880108 3.00489813 -0.9538 2 P 0 ;0,4=38,6=0.000000
L 3.00489813 -0.9538 3.01889882 -0.9538 2 P 0 ;0,4=38,6=0.000000
L 3.01889882 -0.9538 3.03289951 -0.94880108 2 P 0 ;0,4=38,6=0.000000
L 3.03289951 -0.94880108 3.04490059 -0.94130276 2 P 0 ;0,4=38,6=0.000000
L 3.04490059 -0.94130276 3.05490207 -0.93130482 2 P 0 ;0,4=38,6=0.000000
L 3.16489813 -0.8038 3.16489813 -0.9538 2 P 0 ;0,4=38,6=0.000000
L 3.11890059 -0.8038 3.21089931 -0.8038 2 P 0 ;0,4=38,6=0.000000
L 3.28889852 -0.95879892 3.36090138 -0.8038 2 P 0 ;0,4=38,6=0.000000
L 3.44689892 -0.82879931 3.4589 -0.81380246 2 P 0 ;0,4=38,6=0.000000
L 3.4589 -0.81380246 3.47290069 -0.80629951 2 P 0 ;0,4=38,6=0.000000
L 3.47290069 -0.80629951 3.48890089 -0.8038 2 P 0 ;0,4=38,6=0.000000
L 3.48890089 -0.8038 3.5089003 -0.80879902 2 P 0 ;0,4=38,6=0.000000
L 3.5089003 -0.80879902 3.52290098 -0.82130089 2 P 0 ;0,4=38,6=0.000000
L 3.52290098 -0.82130089 3.5269001 -0.83629764 2 P 0 ;0,4=38,6=0.000000
L 3.5269001 -0.83629764 3.52490059 -0.85130364 2 P 0 ;0,4=38,6=0.000000
L 3.52490059 -0.85130364 3.51689862 -0.86380098 2 P 0 ;0,4=38,6=0.000000
L 3.51689862 -0.86380098 3.4768998 -0.8888002 2 P 0 ;0,4=38,6=0.000000
L 3.4768998 -0.8888002 3.4589 -0.90630108 2 P 0 ;0,4=38,6=0.000000
L 3.4589 -0.90630108 3.44689892 -0.93130482 2 P 0 ;0,4=38,6=0.000000
L 3.44689892 -0.93130482 3.4428998 -0.9538 2 P 0 ;0,4=38,6=0.000000
L 3.4428998 -0.9538 3.5269001 -0.9538 2 P 0 ;0,4=38,6=0.000000
L 3.64089902 -0.9538 3.64489813 -0.92130246 2 P 0 ;0,4=38,6=0.000000
L 3.64489813 -0.92130246 3.65090049 -0.89380374 2 P 0 ;0,4=38,6=0.000000
L 3.65090049 -0.89380374 3.65889882 -0.8687999 2 P 0 ;0,4=38,6=0.000000
L 3.65889882 -0.8687999 3.6689003 -0.84130118 2 P 0 ;0,4=38,6=0.000000
L 3.6689003 -0.84130118 3.68490059 -0.8038 2 P 0 ;0,4=38,6=0.000000
L 3.68490059 -0.8038 3.60489931 -0.8038 2 P 0 ;0,4=38,6=0.000000
L 3.76889852 -0.95879892 3.84090138 -0.8038 2 P 0 ;0,4=38,6=0.000000
L 3.92689892 -0.82879931 3.9389 -0.81380246 2 P 0 ;0,4=38,6=0.000000
L 3.9389 -0.81380246 3.95290069 -0.80629951 2 P 0 ;0,4=38,6=0.000000
L 3.95290069 -0.80629951 3.96890089 -0.8038 2 P 0 ;0,4=38,6=0.000000
L 3.96890089 -0.8038 3.9889003 -0.80879902 2 P 0 ;0,4=38,6=0.000000
L 3.9889003 -0.80879902 4.00290098 -0.82130089 2 P 0 ;0,4=38,6=0.000000
L 4.00290098 -0.82130089 4.0069001 -0.83629764 2 P 0 ;0,4=38,6=0.000000
L 4.0069001 -0.83629764 4.00490059 -0.85130364 2 P 0 ;0,4=38,6=0.000000
L 4.00490059 -0.85130364 3.99689862 -0.86380098 2 P 0 ;0,4=38,6=0.000000
L 3.99689862 -0.86380098 3.9568998 -0.8888002 2 P 0 ;0,4=38,6=0.000000
L 3.9568998 -0.8888002 3.9389 -0.90630108 2 P 0 ;0,4=38,6=0.000000
L 3.9389 -0.90630108 3.92689892 -0.93130482 2 P 0 ;0,4=38,6=0.000000
L 3.92689892 -0.93130482 3.9228998 -0.9538 2 P 0 ;0,4=38,6=0.000000
L 3.9228998 -0.9538 4.0069001 -0.9538 2 P 0 ;0,4=38,6=0.000000
L 4.12489813 -0.8038 4.10889783 -0.80879902 2 P 0 ;0,4=38,6=0.000000
L 4.10889783 -0.80879902 4.09690039 -0.82130089 2 P 0 ;0,4=38,6=0.000000
L 4.09690039 -0.82130089 4.08889852 -0.83629764 2 P 0 ;0,4=38,6=0.000000
L 4.08889852 -0.83629764 4.0828998 -0.85630256 2 P 0 ;0,4=38,6=0.000000
L 4.0828998 -0.85630256 4.0809002 -0.87880236 2 P 0 ;0,4=38,6=0.000000
L 4.0809002 -0.87880236 4.0828998 -0.90130207 2 P 0 ;0,4=38,6=0.000000
L 4.0828998 -0.90130207 4.08889852 -0.92130246 2 P 0 ;0,4=38,6=0.000000
L 4.08889852 -0.92130246 4.09690039 -0.93630374 2 P 0 ;0,4=38,6=0.000000
L 4.09690039 -0.93630374 4.10889783 -0.94880108 2 P 0 ;0,4=38,6=0.000000
L 4.10889783 -0.94880108 4.12489813 -0.9538 2 P 0 ;0,4=38,6=0.000000
L 4.12489813 -0.9538 4.14089833 -0.94880108 2 P 0 ;0,4=38,6=0.000000
L 4.14089833 -0.94880108 4.15289951 -0.93630374 2 P 0 ;0,4=38,6=0.000000
L 4.15289951 -0.93630374 4.16090138 -0.92130246 2 P 0 ;0,4=38,6=0.000000
L 4.16090138 -0.92130246 4.1669001 -0.90130207 2 P 0 ;0,4=38,6=0.000000
L 4.1669001 -0.90130207 4.1688997 -0.87880236 2 P 0 ;0,4=38,6=0.000000
L 4.1688997 -0.87880236 4.1669001 -0.85630256 2 P 0 ;0,4=38,6=0.000000
L 4.1669001 -0.85630256 4.16090138 -0.83629764 2 P 0 ;0,4=38,6=0.000000
L 4.16090138 -0.83629764 4.15289951 -0.82130089 2 P 0 ;0,4=38,6=0.000000
L 4.15289951 -0.82130089 4.14089833 -0.80879902 2 P 0 ;0,4=38,6=0.000000
L 4.14089833 -0.80879902 4.12489813 -0.8038 2 P 0 ;0,4=38,6=0.000000
L 4.28489813 -0.9538 4.28489813 -0.8038 2 P 0 ;0,4=38,6=0.000000
L 4.28489813 -0.8038 4.26089961 -0.83379823 2 P 0 ;0,4=38,6=0.000000
L 4.26089961 -0.9538 4.30889665 -0.9538 2 P 0 ;0,4=38,6=0.000000
L 4.44089902 -0.9538 4.44489813 -0.92130246 2 P 0 ;0,4=38,6=0.000000
L 4.44489813 -0.92130246 4.45090049 -0.89380374 2 P 0 ;0,4=38,6=0.000000
L 4.45090049 -0.89380374 4.45889882 -0.8687999 2 P 0 ;0,4=38,6=0.000000
L 4.45889882 -0.8687999 4.4689003 -0.84130118 2 P 0 ;0,4=38,6=0.000000
L 4.4689003 -0.84130118 4.48490059 -0.8038 2 P 0 ;0,4=38,6=0.000000
L 4.48490059 -0.8038 4.40489931 -0.8038 2 P 0 ;0,4=38,6=0.000000

### steps/drc/layers/drillo/features
#
#Feature symbol names
#
$0 r8
$1 r10
$2 r27.56
$3 r29.92
$4 r39.37
$5 r51.18
$6 r55.12
$7 r92.52
$8 r98.43
$9 r118.11
$10 r125
$11 r129.92
$12 r137.8
$13 r157.48
$14 r177.17
$15 r393.7

#
#Feature attribute names
#
@0 .geometry
@1 .drill

#
#Feature attribute text strings
#
&0 SP-8C5_2P0_254
&1 V20D10AT28SM14
&2 C3_5N
&3 C4N-B
&4 O5X3_5N
&5 C3_175N-A
&6 SP-9C5_7P0_254
&7 C4_5N-B
&8 C2_5N
&9 C10N
&10 C3_3N
&11 C1_3N
&12 C1_17P0_76TPM
&13 S1_9P1_4
&14 C1_9P1_4
&15 C3N
&16 C2_35N
&17 S1_11P0_7
&18 C1_11P0_7
&19 C1N
&20 S1_11P0_7TP
&21 C1_11P0_7TP
&22 TPB30V20D10AT28BPM
&23 V17D8AT30SM11
&24 V20D10AT28PG

#
#Layer features
#
P 6.11811004 1.39763996 1 P 2 0;0=0,1=2
P 6.02756004 1.43701004 1 P 2 0;0=1,1=2
P 5.98818996 1.52756004 1 P 2 0;0=1,1=2
P 6.02756004 1.61811004 1 P 2 0;0=1,1=2
P 6.11811004 1.65748002 1 P 2 0;0=0,1=2
P 6.20866004 1.61811004 1 P 2 0;0=1,1=2
P 6.24803002 1.52756004 1 P 2 0;0=1,1=2
P 6.20866004 1.43701004 1 P 2 0;0=1,1=2
P 4.83268002 1.37795 1 P 2 0;0=0,1=2
P 4.74081004 1.416 1 P 2 0;0=1,1=2
P 4.70276004 1.50786998 1 P 2 0;0=1,1=2
P 4.74081004 1.59975 1 P 2 0;0=1,1=2
P 4.83268002 1.6378 1 P 2 0;0=0,1=2
P 4.92455 1.59975 1 P 2 0;0=1,1=2
P 4.9626 1.50786998 1 P 2 0;0=1,1=2
P 4.92455 1.416 1 P 2 0;0=1,1=2
P 2.24606004 1.37795 1 P 2 0;0=0,1=2
P 2.15418996 1.416 1 P 2 0;0=1,1=2
P 2.11613996 1.50786998 1 P 2 0;0=1,1=2
P 2.15418996 1.59975 1 P 2 0;0=1,1=2
P 2.24606004 1.6378 1 P 2 0;0=0,1=2
P 2.33793002 1.59975 1 P 2 0;0=1,1=2
P 2.37598002 1.50786998 1 P 2 0;0=1,1=2
P 2.33793002 1.416 1 P 2 0;0=1,1=2
P 0.96063002 1.39763996 1 P 2 0;0=0,1=2
P 0.86876004 1.43568996 1 P 2 0;0=1,1=2
P 0.83071004 1.52756004 1 P 2 0;0=1,1=2
P 0.86876004 1.61943002 1 P 2 0;0=1,1=2
P 0.96063002 1.65748002 1 P 2 0;0=0,1=2
P 1.0525 1.61943002 1 P 2 0;0=1,1=2
P 1.09055 1.52756004 1 P 2 0;0=1,1=2
P 1.0525 1.43568996 1 P 2 0;0=1,1=2
P 0.96063002 4.0748 1 P 2 0;0=0,1=2
P 0.86876004 4.11286004 1 P 2 0;0=1,1=2
P 0.83071004 4.20473002 1 P 2 0;0=1,1=2
P 0.86876004 4.2966 1 P 2 0;0=1,1=2
P 0.96063002 4.33465 1 P 2 0;0=0,1=2
P 1.0525 4.2966 1 P 2 0;0=1,1=2
P 1.09055 4.20473002 1 P 2 0;0=1,1=2
P 1.0525 4.11286004 1 P 2 0;0=1,1=2
P 2.24606004 4.09448996 1 P 2 0;0=0,1=2
P 2.15418996 4.13253996 1 P 2 0;0=1,1=2
P 2.11613996 4.22441004 1 P 2 0;0=1,1=2
P 2.15418996 4.31628002 1 P 2 0;0=1,1=2
P 2.24606004 4.35433002 1 P 2 0;0=0,1=2
P 2.33793002 4.31628002 1 P 2 0;0=1,1=2
P 2.37598002 4.22441004 1 P 2 0;0=1,1=2
P 2.33793002 4.13253996 1 P 2 0;0=1,1=2
P 4.83268002 4.09448996 1 P 2 0;0=0,1=2
P 4.74081004 4.13253996 1 P 2 0;0=1,1=2
P 4.70276004 4.22441004 1 P 2 0;0=1,1=2
P 4.74081004 4.31628002 1 P 2 0;0=1,1=2
P 4.83268002 4.35433002 1 P 2 0;0=0,1=2
P 4.92455 4.31628002 1 P 2 0;0=1,1=2
P 4.9626 4.22441004 1 P 2 0;0=1,1=2
P 4.92455 4.13253996 1 P 2 0;0=1,1=2
P 6.11811004 4.0748 1 P 2 0;0=0,1=2
P 6.02623996 4.11286004 1 P 2 0;0=1,1=2
P 5.98818996 4.20473002 1 P 2 0;0=1,1=2
P 6.02623996 4.2966 1 P 2 0;0=1,1=2
P 6.11811004 4.33465 1 P 2 0;0=0,1=2
P 6.20998002 4.2966 1 P 2 0;0=1,1=2
P 6.24803002 4.20473002 1 P 2 0;0=1,1=2
P 6.20998002 4.11286004 1 P 2 0;0=1,1=2
P 6.04921004 2.58268002 12 P 14 0;0=2,1=1
P 2.24606004 1.50786998 13 P 16 0;0=3,1=1
P 2.24606004 4.22441004 13 P 16 0;0=3,1=1
P 4.83268002 1.50786998 13 P 16 0;0=3,1=1
P 4.83268002 4.22441004 13 P 16 0;0=3,1=1
P 6.11811004 1.52756004 13 P 16 0;0=3,1=1
P 6.11811004 4.20473002 13 P 16 0;0=3,1=1
P 0.96063002 1.52756004 13 P 16 0;0=3,1=1
P 0.96063002 4.20473002 13 P 16 0;0=3,1=1
L 1.029525 2.58268002 1.088575 2.58268002 12 P 15 ;0=4,1=1
P 12.12205 1.39763996 1 P 2 0;0=0,1=2
P 12.0315 1.43701004 1 P 2 0;0=1,1=2
P 11.99213002 1.52756004 1 P 2 0;0=1,1=2
P 12.0315 1.61811004 1 P 2 0;0=1,1=2
P 12.12205 1.65748002 1 P 2 0;0=0,1=2
P 12.2126 1.61811004 1 P 2 0;0=1,1=2
P 12.25196998 1.52756004 1 P 2 0;0=1,1=2
P 12.2126 1.43701004 1 P 2 0;0=1,1=2
P 10.83661998 1.37795 1 P 2 0;0=0,1=2
P 10.74475 1.416 1 P 2 0;0=1,1=2
P 10.7067 1.50786998 1 P 2 0;0=1,1=2
P 10.74475 1.59975 1 P 2 0;0=1,1=2
P 10.83661998 1.6378 1 P 2 0;0=0,1=2
P 10.92848996 1.59975 1 P 2 0;0=1,1=2
P 10.96653996 1.50786998 1 P 2 0;0=1,1=2
P 10.92848996 1.416 1 P 2 0;0=1,1=2
P 8.25 1.37795 1 P 2 0;0=0,1=2
P 8.15813002 1.416 1 P 2 0;0=1,1=2
P 8.12008002 1.50786998 1 P 2 0;0=1,1=2
P 8.15813002 1.59975 1 P 2 0;0=1,1=2
P 8.25 1.6378 1 P 2 0;0=0,1=2
P 8.34186998 1.59975 1 P 2 0;0=1,1=2
P 8.37991998 1.50786998 1 P 2 0;0=1,1=2
P 8.34186998 1.416 1 P 2 0;0=1,1=2
P 6.96456998 1.39763996 1 P 2 0;0=0,1=2
P 6.8727 1.43568996 1 P 2 0;0=1,1=2
P 6.83465 1.52756004 1 P 2 0;0=1,1=2
P 6.8727 1.61943002 1 P 2 0;0=1,1=2
P 6.96456998 1.65748002 1 P 2 0;0=0,1=2
P 7.05643996 1.61943002 1 P 2 0;0=1,1=2
P 7.09448996 1.52756004 1 P 2 0;0=1,1=2
P 7.05643996 1.43568996 1 P 2 0;0=1,1=2
P 6.96456998 4.0748 1 P 2 0;0=0,1=2
P 6.8727 4.11286004 1 P 2 0;0=1,1=2
P 6.83465 4.20473002 1 P 2 0;0=1,1=2
P 6.8727 4.2966 1 P 2 0;0=1,1=2
P 6.96456998 4.33465 1 P 2 0;0=0,1=2
P 7.05643996 4.2966 1 P 2 0;0=1,1=2
P 7.09448996 4.20473002 1 P 2 0;0=1,1=2
P 7.05643996 4.11286004 1 P 2 0;0=1,1=2
P 8.25 4.09448996 1 P 2 0;0=0,1=2
P 8.15813002 4.13253996 1 P 2 0;0=1,1=2
P 8.12008002 4.22441004 1 P 2 0;0=1,1=2
P 8.15813002 4.31628002 1 P 2 0;0=1,1=2
P 8.25 4.35433002 1 P 2 0;0=0,1=2
P 8.34186998 4.31628002 1 P 2 0;0=1,1=2
P 8.37991998 4.22441004 1 P 2 0;0=1,1=2
P 8.34186998 4.13253996 1 P 2 0;0=1,1=2
P 10.83661998 4.09448996 1 P 2 0;0=0,1=2
P 10.74475 4.13253996 1 P 2 0;0=1,1=2
P 10.7067 4.22441004 1 P 2 0;0=1,1=2
P 10.74475 4.31628002 1 P 2 0;0=1,1=2
P 10.83661998 4.35433002 1 P 2 0;0=0,1=2
P 10.92848996 4.31628002 1 P 2 0;0=1,1=2
P 10.96653996 4.22441004 1 P 2 0;0=1,1=2
P 10.92848996 4.13253996 1 P 2 0;0=1,1=2
P 12.12205 4.0748 1 P 2 0;0=0,1=2
P 12.03018002 4.11286004 1 P 2 0;0=1,1=2
P 11.99213002 4.20473002 1 P 2 0;0=1,1=2
P 12.03018002 4.2966 1 P 2 0;0=1,1=2
P 12.12205 4.33465 1 P 2 0;0=0,1=2
P 12.21391998 4.2966 1 P 2 0;0=1,1=2
P 12.25196998 4.20473002 1 P 2 0;0=1,1=2
P 12.21391998 4.11286004 1 P 2 0;0=1,1=2
P 12.05315 2.58268002 12 P 14 0;0=2,1=1
P 10.83661998 1.50786998 13 P 16 0;0=3,1=1
P 10.83661998 4.22441004 13 P 16 0;0=3,1=1
P 12.12205 1.52756004 13 P 16 0;0=3,1=1
P 12.12205 4.20473002 13 P 16 0;0=3,1=1
P 6.96456998 1.52756004 13 P 16 0;0=3,1=1
P 6.96456998 4.20473002 13 P 16 0;0=3,1=1
P 8.25 1.50786998 13 P 16 0;0=3,1=1
P 8.25 4.22441004 13 P 16 0;0=3,1=1
L 7.03346496 2.58268002 7.09251496 2.58268002 12 P 15 ;0=4,1=1
P 0.2 5.82361998 10 P 12 0;0=5,1=1
P 0.22245 0.8189 1 P 2 0;0=0,1=2
P 0.313 0.77953002 1 P 2 0;0=1,1=2
P 0.35236998 0.68898002 1 P 2 0;0=1,1=2
P 0.313 0.59843002 1 P 2 0;0=1,1=2
P 0.22245 0.55906004 1 P 2 0;0=0,1=2
P 0.1319 0.59843002 1 P 2 0;0=1,1=2
P 0.09253002 0.68898002 1 P 2 0;0=1,1=2
P 0.1319 0.77953002 1 P 2 0;0=1,1=2
P 0.22245 0.68898002 13 P 16 0;0=3,1=1
P 7.17716998 5.93306998 1 P 2 0;0=6,1=2
P 7.28016998 5.8904 1 P 2 0;0=1,1=2
P 7.32283996 5.7874 1 P 2 0;0=1,1=2
P 7.28016998 5.6844 1 P 2 0;0=1,1=2
P 7.17716998 5.64173002 1 P 2 0;0=6,1=2
P 7.07416998 5.6844 1 P 2 0;0=1,1=2
P 7.0315 5.7874 1 P 2 0;0=1,1=2
P 7.07416998 5.8904 1 P 2 0;0=1,1=2
P 7.17716998 5.7874 14 P 17 0;0=7,1=1
P 0.22245 5.24803002 1 P 2 0;0=0,1=2
P 0.313 5.20866004 1 P 2 0;0=1,1=2
P 0.35236998 5.11811004 1 P 2 0;0=1,1=2
P 0.313 5.02756004 1 P 2 0;0=1,1=2
P 0.22245 4.98818996 1 P 2 0;0=0,1=2
P 0.1319 5.02756004 1 P 2 0;0=1,1=2
P 0.09253002 5.11811004 1 P 2 0;0=1,1=2
P 0.1319 5.20866004 1 P 2 0;0=1,1=2
P 0.22245 5.11811004 13 P 16 0;0=3,1=1
P 7.17716998 0.38188996 1 P 2 0;0=6,1=2
P 7.28016998 0.33921998 1 P 2 0;0=1,1=2
P 7.32283996 0.23621998 1 P 2 0;0=1,1=2
P 7.28016998 0.13321998 1 P 2 0;0=1,1=2
P 7.17716998 0.09055 1 P 2 0;0=6,1=2
P 7.07416998 0.13321998 1 P 2 0;0=1,1=2
P 7.0315 0.23621998 1 P 2 0;0=1,1=2
P 7.07416998 0.33921998 1 P 2 0;0=1,1=2
P 7.17716998 0.23621998 14 P 17 0;0=7,1=1
P 12.68701998 5.2874 1 P 2 0;0=0,1=2
P 12.77756998 5.24803002 1 P 2 0;0=1,1=2
P 12.81693996 5.15748002 1 P 2 0;0=1,1=2
P 12.77756998 5.06693002 1 P 2 0;0=1,1=2
P 12.68701998 5.02756004 1 P 2 0;0=0,1=2
P 12.59646998 5.06693002 1 P 2 0;0=1,1=2
P 12.5571 5.15748002 1 P 2 0;0=1,1=2
P 12.59646998 5.24803002 1 P 2 0;0=1,1=2
P 12.68701998 5.15748002 13 P 16 0;0=3,1=1
P 12.68701998 0.85826998 1 P 2 0;0=0,1=2
P 12.77756998 0.8189 1 P 2 0;0=1,1=2
P 12.81693996 0.72835 1 P 2 0;0=1,1=2
P 12.77756998 0.6378 1 P 2 0;0=1,1=2
P 12.68701998 0.59843002 1 P 2 0;0=0,1=2
P 12.59646998 0.6378 1 P 2 0;0=1,1=2
P 12.5571 0.72835 1 P 2 0;0=1,1=2
P 12.59646998 0.8189 1 P 2 0;0=1,1=2
P 12.68701998 0.72835 13 P 16 0;0=3,1=1
P 12.68701998 0.97243996 8 P 10 0;0=8,1=1
P 0.22245 0.93306998 8 P 10 0;0=8,1=1
P 12.68701004 4.91338002 8 P 10 0;0=8,1=1
P 0.66 0.29 10 P 12 0;0=5,1=1
P 5.78346004 5.4441 15 P 18 0;0=9,1=1
P 10.20866004 5.4441 15 P 18 0;0=9,1=1
P 12.7252 -0.293 10 P 12 0;0=5,1=1
P 0.2 6.31661998 10 P 12 0;0=5,1=1
P 12.7252 6.31661998 10 P 12 0;0=5,1=1
P 0.22255 5.38583002 11 P 13 0;0=10,1=1
P 0.22245 0.42126004 11 P 13 0;0=10,1=1
P 12.68701998 5.4252 11 P 13 0;0=10,1=1
P 12.68701004 0.46063002 11 P 13 0;0=10,1=1
P 12.27 0.29 10 P 12 0;0=5,1=1
P 0.2 -0.293 10 P 12 0;0=5,1=1
P 0.22245 4.87401004 8 P 10 0;0=8,1=1
P 2.72091004 4.91851004 5 P 7 0;0=11,1=1
P 3.58311004 4.91851004 5 P 7 0;0=11,1=1
P 2.69925 5.05826998 3 P 5 0;0=12,1=0
P 3.60476998 5.05826998 3 P 5 0;0=12,1=0
P 2.67956998 4.77875 3 P 5 0;0=12,1=0
P 3.60476998 4.77875 3 P 5 0;0=12,1=0
P 1.55631004 4.91851004 5 P 7 0;0=11,1=1
P 2.41851004 4.91851004 5 P 7 0;0=11,1=1
P 1.53465 5.05826998 3 P 5 0;0=12,1=0
P 2.44016998 5.05826998 3 P 5 0;0=12,1=0
P 1.51496998 4.77875 3 P 5 0;0=12,1=0
P 2.45985 4.77875 3 P 5 0;0=12,1=0
P 8.72445 4.91851004 5 P 7 0;0=11,1=1
P 9.58665 4.91851004 5 P 7 0;0=11,1=1
P 8.70278996 5.05826998 3 P 5 0;0=12,1=0
P 9.60831004 5.05826998 3 P 5 0;0=12,1=0
P 8.68311004 4.77875 3 P 5 0;0=12,1=0
P 9.60831004 4.77875 3 P 5 0;0=12,1=0
P 7.55985 4.91851004 5 P 7 0;0=11,1=1
P 8.42205 4.91851004 5 P 7 0;0=11,1=1
P 7.53818996 5.05826998 3 P 5 0;0=12,1=0
P 8.44371004 5.05826998 3 P 5 0;0=12,1=0
P 7.51851004 4.77875 3 P 5 0;0=12,1=0
P 8.46338996 4.77875 3 P 5 0;0=12,1=0
P 12.14961004 5.49685 6 P 8 0;0=13,1=0
P 11.98425 5.49685 6 P 8 0;0=14,1=0
P 11.8189 5.49685 6 P 8 0;0=14,1=0
P 11.65353996 5.49685 6 P 8 0;0=14,1=0
P 11.48818996 5.49685 6 P 8 0;0=14,1=0
P 11.32283996 5.49685 6 P 8 0;0=14,1=0
P 11.15748002 5.49685 6 P 8 0;0=14,1=0
P 10.99213002 5.49685 6 P 8 0;0=14,1=0
P 10.82676998 5.49685 6 P 8 0;0=14,1=0
P 12.14961004 5.71338996 6 P 8 0;0=14,1=0
P 11.98425 5.71338996 6 P 8 0;0=14,1=0
P 11.8189 5.71338996 6 P 8 0;0=14,1=0
P 11.65353996 5.71338996 6 P 8 0;0=14,1=0
P 11.48818996 5.71338996 6 P 8 0;0=14,1=0
P 11.32283996 5.71338996 6 P 8 0;0=14,1=0
P 11.15748002 5.71338996 6 P 8 0;0=14,1=0
P 10.99213002 5.71338996 6 P 8 0;0=14,1=0
P 10.82676998 5.71338996 6 P 8 0;0=14,1=0
P 12.33465 5.69528002 9 P 11 0;0=15,1=1
P 0.22243996 1.79331004 7 P 9 0;0=16,1=1
P 0.22243996 4.67323002 7 P 9 0;0=16,1=1
P 0.17323002 1.33465 2 P 19 0;0=17,1=0
P 0.09448996 1.37401998 2 P 19 0;0=18,1=0
P 0.17323002 1.41338996 2 P 19 0;0=18,1=0
P 0.09448996 1.45276004 2 P 19 0;0=18,1=0
P 0.17323002 1.49213002 2 P 19 0;0=18,1=0
P 0.09448996 1.5315 2 P 19 0;0=18,1=0
P 0.17323002 1.57086998 2 P 19 0;0=18,1=0
P 0.09448996 1.61023996 2 P 19 0;0=18,1=0
P 0.17323002 1.64961004 2 P 19 0;0=18,1=0
P 0.09448996 1.68898002 2 P 19 0;0=18,1=0
P 0.17323002 1.72835 2 P 19 0;0=18,1=0
P 0.09448996 1.84646004 2 P 19 0;0=18,1=0
P 0.17323002 1.88583002 2 P 19 0;0=18,1=0
P 0.09448996 1.9252 2 P 19 0;0=18,1=0
P 0.17323002 1.96456998 2 P 19 0;0=18,1=0
P 0.09448996 2.00393996 2 P 19 0;0=18,1=0
P 0.17323002 2.04331004 2 P 19 0;0=18,1=0
P 0.09448996 2.08268002 2 P 19 0;0=18,1=0
P 0.17323002 2.12205 2 P 19 0;0=18,1=0
P 0.09448996 2.16141998 2 P 19 0;0=18,1=0
P 0.17323002 2.20078996 2 P 19 0;0=18,1=0
P 0.09448996 2.24016004 2 P 19 0;0=18,1=0
P 0.17323002 2.27953002 2 P 19 0;0=18,1=0
P 0.09448996 2.3189 2 P 19 0;0=18,1=0
P 0.17323002 2.35826998 2 P 19 0;0=18,1=0
P 0.09448996 2.39763996 2 P 19 0;0=18,1=0
P 0.17323002 2.43701004 2 P 19 0;0=18,1=0
P 0.09448996 2.47638002 2 P 19 0;0=18,1=0
P 0.17323002 2.51575 2 P 19 0;0=18,1=0
P 0.09448996 2.55511998 2 P 19 0;0=18,1=0
P 0.17323002 2.59448996 2 P 19 0;0=18,1=0
P 0.09448996 2.63386004 2 P 19 0;0=18,1=0
P 0.17323002 2.67323002 2 P 19 0;0=18,1=0
P 0.09448996 2.7126 2 P 19 0;0=18,1=0
P 0.17323002 2.75196998 2 P 19 0;0=18,1=0
P 0.09448996 2.79133996 2 P 19 0;0=18,1=0
P 0.17323002 2.83071004 2 P 19 0;0=18,1=0
P 0.09448996 2.87008002 2 P 19 0;0=18,1=0
P 0.17323002 2.90945 2 P 19 0;0=18,1=0
P 0.09448996 2.94881998 2 P 19 0;0=18,1=0
P 0.17323002 2.98818996 2 P 19 0;0=18,1=0
P 0.09448996 3.02756004 2 P 19 0;0=18,1=0
P 0.17323002 3.06693002 2 P 19 0;0=18,1=0
P 0.09448996 3.1063 2 P 19 0;0=18,1=0
P 0.17323002 3.14566998 2 P 19 0;0=18,1=0
P 0.09448996 3.18503996 2 P 19 0;0=18,1=0
P 0.17323002 3.22441004 2 P 19 0;0=18,1=0
P 0.09448996 3.26378002 2 P 19 0;0=18,1=0
P 0.17323002 3.30315 2 P 19 0;0=18,1=0
P 0.09448996 3.34251998 2 P 19 0;0=18,1=0
P 0.17323002 3.38188996 2 P 19 0;0=18,1=0
P 0.09448996 3.42126004 2 P 19 0;0=18,1=0
P 0.17323002 3.46063002 2 P 19 0;0=18,1=0
P 0.09448996 3.5 2 P 19 0;0=18,1=0
P 0.17323002 3.53936998 2 P 19 0;0=18,1=0
P 0.09448996 3.57873996 2 P 19 0;0=18,1=0
P 0.17323002 3.61811004 2 P 19 0;0=18,1=0
P 0.09448996 3.65748002 2 P 19 0;0=18,1=0
P 0.17323002 3.69685 2 P 19 0;0=18,1=0
P 0.09448996 3.73621998 2 P 19 0;0=18,1=0
P 0.17323002 3.77558996 2 P 19 0;0=18,1=0
P 0.09448996 3.81496004 2 P 19 0;0=18,1=0
P 0.17323002 3.85433002 2 P 19 0;0=18,1=0
P 0.09448996 3.8937 2 P 19 0;0=18,1=0
P 0.17323002 3.93306998 2 P 19 0;0=18,1=0
P 0.09448996 3.97243996 2 P 19 0;0=18,1=0
P 0.17323002 4.01181004 2 P 19 0;0=18,1=0
P 0.09448996 4.05118002 2 P 19 0;0=18,1=0
P 0.17323002 4.09055 2 P 19 0;0=18,1=0
P 0.09448996 4.12991998 2 P 19 0;0=18,1=0
P 0.17323002 4.16928996 2 P 19 0;0=18,1=0
P 0.09448996 4.20866004 2 P 19 0;0=18,1=0
P 0.17323002 4.24803002 2 P 19 0;0=18,1=0
P 0.09448996 4.2874 2 P 19 0;0=18,1=0
P 0.17323002 4.32676998 2 P 19 0;0=18,1=0
P 0.09448996 4.36613996 2 P 19 0;0=18,1=0
P 0.17323002 4.40551004 2 P 19 0;0=18,1=0
P 0.09448996 4.44488002 2 P 19 0;0=18,1=0
P 0.17323002 4.48425 2 P 19 0;0=18,1=0
P 0.09448996 4.52361998 2 P 19 0;0=18,1=0
P 0.17323002 4.563 2 P 19 0;0=18,1=0
P 0.09448996 4.60236998 2 P 19 0;0=18,1=0
P 0.27165 1.33465 2 P 19 0;0=17,1=0
P 0.35038996 1.37401998 2 P 19 0;0=18,1=0
P 0.27165 1.41338996 2 P 19 0;0=18,1=0
P 0.35038996 1.45276004 2 P 19 0;0=18,1=0
P 0.27165 1.49213002 2 P 19 0;0=18,1=0
P 0.35038996 1.5315 2 P 19 0;0=18,1=0
P 0.27165 1.57086998 2 P 19 0;0=18,1=0
P 0.35038996 1.61023996 2 P 19 0;0=18,1=0
P 0.27165 1.64961004 2 P 19 0;0=18,1=0
P 0.35038996 1.68898002 2 P 19 0;0=18,1=0
P 0.27165 1.72835 2 P 19 0;0=18,1=0
P 0.35038996 1.84646004 2 P 19 0;0=18,1=0
P 0.27165 1.88583002 2 P 19 0;0=18,1=0
P 0.35038996 1.9252 2 P 19 0;0=18,1=0
P 0.27165 1.96456998 2 P 19 0;0=18,1=0
P 0.35038996 2.00393996 2 P 19 0;0=18,1=0
P 0.27165 2.04331004 2 P 19 0;0=18,1=0
P 0.35038996 2.08268002 2 P 19 0;0=18,1=0
P 0.27165 2.12205 2 P 19 0;0=18,1=0
P 0.35038996 2.16141998 2 P 19 0;0=18,1=0
P 0.27165 2.20078996 2 P 19 0;0=18,1=0
P 0.35038996 2.24016004 2 P 19 0;0=18,1=0
P 0.27165 2.27953002 2 P 19 0;0=18,1=0
P 0.35038996 2.3189 2 P 19 0;0=18,1=0
P 0.27165 2.35826998 2 P 19 0;0=18,1=0
P 0.35038996 2.39763996 2 P 19 0;0=18,1=0
P 0.27165 2.43701004 2 P 19 0;0=18,1=0
P 0.35038996 2.47638002 2 P 19 0;0=18,1=0
P 0.27165 2.51575 2 P 19 0;0=18,1=0
P 0.35038996 2.55511998 2 P 19 0;0=18,1=0
P 0.27165 2.59448996 2 P 19 0;0=18,1=0
P 0.35038996 2.63386004 2 P 19 0;0=18,1=0
P 0.27165 2.67323002 2 P 19 0;0=18,1=0
P 0.35038996 2.7126 2 P 19 0;0=18,1=0
P 0.27165 2.75196998 2 P 19 0;0=18,1=0
P 0.35038996 2.79133996 2 P 19 0;0=18,1=0
P 0.27165 2.83071004 2 P 19 0;0=18,1=0
P 0.35038996 2.87008002 2 P 19 0;0=18,1=0
P 0.27165 2.90945 2 P 19 0;0=18,1=0
P 0.35038996 2.94881998 2 P 19 0;0=18,1=0
P 0.27165 2.98818996 2 P 19 0;0=18,1=0
P 0.35038996 3.02756004 2 P 19 0;0=18,1=0
P 0.27165 3.06693002 2 P 19 0;0=18,1=0
P 0.35038996 3.1063 2 P 19 0;0=18,1=0
P 0.27165 3.14566998 2 P 19 0;0=18,1=0
P 0.35038996 3.18503996 2 P 19 0;0=18,1=0
P 0.27165 3.22441004 2 P 19 0;0=18,1=0
P 0.35038996 3.26378002 2 P 19 0;0=18,1=0
P 0.27165 3.30315 2 P 19 0;0=18,1=0
P 0.35038996 3.34251998 2 P 19 0;0=18,1=0
P 0.27165 3.38188996 2 P 19 0;0=18,1=0
P 0.35038996 3.42126004 2 P 19 0;0=18,1=0
P 0.27165 3.46063002 2 P 19 0;0=18,1=0
P 0.35038996 3.5 2 P 19 0;0=18,1=0
P 0.27165 3.53936998 2 P 19 0;0=18,1=0
P 0.35038996 3.57873996 2 P 19 0;0=18,1=0
P 0.27165 3.61811004 2 P 19 0;0=18,1=0
P 0.35038996 3.65748002 2 P 19 0;0=18,1=0
P 0.27165 3.69685 2 P 19 0;0=18,1=0
P 0.35038996 3.73621998 2 P 19 0;0=18,1=0
P 0.27165 3.77558996 2 P 19 0;0=18,1=0
P 0.35038996 3.81496004 2 P 19 0;0=18,1=0
P 0.27165 3.85433002 2 P 19 0;0=18,1=0
P 0.35038996 3.8937 2 P 19 0;0=18,1=0
P 0.27165 3.93306998 2 P 19 0;0=18,1=0
P 0.35038996 3.97243996 2 P 19 0;0=18,1=0
P 0.27165 4.01181004 2 P 19 0;0=18,1=0
P 0.35038996 4.05118002 2 P 19 0;0=18,1=0
P 0.27165 4.09055 2 P 19 0;0=18,1=0
P 0.35038996 4.12991998 2 P 19 0;0=18,1=0
P 0.27165 4.16928996 2 P 19 0;0=18,1=0
P 0.35038996 4.20866004 2 P 19 0;0=18,1=0
P 0.27165 4.24803002 2 P 19 0;0=18,1=0
P 0.35038996 4.2874 2 P 19 0;0=18,1=0
P 0.27165 4.32676998 2 P 19 0;0=18,1=0
P 0.35038996 4.36613996 2 P 19 0;0=18,1=0
P 0.27165 4.40551004 2 P 19 0;0=18,1=0
P 0.35038996 4.44488002 2 P 19 0;0=18,1=0
P 0.27165 4.48425 2 P 19 0;0=18,1=0
P 0.35038996 4.52361998 2 P 19 0;0=18,1=0
P 0.27165 4.563 2 P 19 0;0=18,1=0
P 0.35038996 4.60236998 2 P 19 0;0=18,1=0
P 12.687 1.83268002 7 P 9 0;0=16,1=1
P 12.687 4.7126 7 P 9 0;0=16,1=1
P 12.63778996 1.37401998 2 P 19 0;0=17,1=0
P 12.55905 1.41338996 2 P 19 0;0=18,1=0
P 12.63778996 1.45276004 2 P 19 0;0=18,1=0
P 12.55905 1.49213002 2 P 19 0;0=18,1=0
P 12.63778996 1.5315 2 P 19 0;0=18,1=0
P 12.55905 1.57086998 2 P 19 0;0=18,1=0
P 12.63778996 1.61023996 2 P 19 0;0=18,1=0
P 12.55905 1.64961004 2 P 19 0;0=18,1=0
P 12.63778996 1.68898002 2 P 19 0;0=18,1=0
P 12.55905 1.72835 2 P 19 0;0=18,1=0
P 12.63778996 1.76771998 2 P 19 0;0=18,1=0
P 12.55905 1.88583002 2 P 19 0;0=18,1=0
P 12.63778996 1.9252 2 P 19 0;0=18,1=0
P 12.55905 1.96456998 2 P 19 0;0=18,1=0
P 12.63778996 2.00393996 2 P 19 0;0=18,1=0
P 12.55905 2.04331004 2 P 19 0;0=18,1=0
P 12.63778996 2.08268002 2 P 19 0;0=18,1=0
P 12.55905 2.12205 2 P 19 0;0=18,1=0
P 12.63778996 2.16141998 2 P 19 0;0=18,1=0
P 12.55905 2.20078996 2 P 19 0;0=18,1=0
P 12.63778996 2.24016004 2 P 19 0;0=18,1=0
P 12.55905 2.27953002 2 P 19 0;0=18,1=0
P 12.63778996 2.3189 2 P 19 0;0=18,1=0
P 12.55905 2.35826998 2 P 19 0;0=18,1=0
P 12.63778996 2.39763996 2 P 19 0;0=18,1=0
P 12.55905 2.43701004 2 P 19 0;0=18,1=0
P 12.63778996 2.47638002 2 P 19 0;0=18,1=0
P 12.55905 2.51575 2 P 19 0;0=18,1=0
P 12.63778996 2.55511998 2 P 19 0;0=18,1=0
P 12.55905 2.59448996 2 P 19 0;0=18,1=0
P 12.63778996 2.63386004 2 P 19 0;0=18,1=0
P 12.55905 2.67323002 2 P 19 0;0=18,1=0
P 12.63778996 2.7126 2 P 19 0;0=18,1=0
P 12.55905 2.75196998 2 P 19 0;0=18,1=0
P 12.63778996 2.79133996 2 P 19 0;0=18,1=0
P 12.55905 2.83071004 2 P 19 0;0=18,1=0
P 12.63778996 2.87008002 2 P 19 0;0=18,1=0
P 12.55905 2.90945 2 P 19 0;0=18,1=0
P 12.63778996 2.94881998 2 P 19 0;0=18,1=0
P 12.55905 2.98818996 2 P 19 0;0=18,1=0
P 12.63778996 3.02756004 2 P 19 0;0=18,1=0
P 12.55905 3.06693002 2 P 19 0;0=18,1=0
P 12.63778996 3.1063 2 P 19 0;0=18,1=0
P 12.55905 3.14566998 2 P 19 0;0=18,1=0
P 12.63778996 3.18503996 2 P 19 0;0=18,1=0
P 12.55905 3.22441004 2 P 19 0;0=18,1=0
P 12.63778996 3.26378002 2 P 19 0;0=18,1=0
P 12.55905 3.30315 2 P 19 0;0=18,1=0
P 12.63778996 3.34251998 2 P 19 0;0=18,1=0
P 12.55905 3.38188996 2 P 19 0;0=18,1=0
P 12.63778996 3.42126004 2 P 19 0;0=18,1=0
P 12.55905 3.46063002 2 P 19 0;0=18,1=0
P 12.63778996 3.5 2 P 19 0;0=18,1=0
P 12.55905 3.53936998 2 P 19 0;0=18,1=0
P 12.63778996 3.57873996 2 P 19 0;0=18,1=0
P 12.55905 3.61811004 2 P 19 0;0=18,1=0
P 12.63778996 3.65748002 2 P 19 0;0=18,1=0
P 12.55905 3.69685 2 P 19 0;0=18,1=0
P 12.63778996 3.73621998 2 P 19 0;0=18,1=0
P 12.55905 3.77558996 2 P 19 0;0=18,1=0
P 12.63778996 3.81496004 2 P 19 0;0=18,1=0
P 12.55905 3.85433002 2 P 19 0;0=18,1=0
P 12.63778996 3.8937 2 P 19 0;0=18,1=0
P 12.55905 3.93306998 2 P 19 0;0=18,1=0
P 12.63778996 3.97243996 2 P 19 0;0=18,1=0
P 12.55905 4.01181004 2 P 19 0;0=18,1=0
P 12.63778996 4.05118002 2 P 19 0;0=18,1=0
P 12.55905 4.09055 2 P 19 0;0=18,1=0
P 12.63778996 4.12991998 2 P 19 0;0=18,1=0
P 12.55905 4.16928996 2 P 19 0;0=18,1=0
P 12.63778996 4.20866004 2 P 19 0;0=18,1=0
P 12.55905 4.24803002 2 P 19 0;0=18,1=0
P 12.63778996 4.2874 2 P 19 0;0=18,1=0
P 12.55905 4.32676998 2 P 19 0;0=18,1=0
P 12.63778996 4.36613996 2 P 19 0;0=18,1=0
P 12.55905 4.40551004 2 P 19 0;0=18,1=0
P 12.63778996 4.44488002 2 P 19 0;0=18,1=0
P 12.55905 4.48425 2 P 19 0;0=18,1=0
P 12.63778996 4.52361998 2 P 19 0;0=18,1=0
P 12.55905 4.56298996 2 P 19 0;0=18,1=0
P 12.63778996 4.60236998 2 P 19 0;0=18,1=0
P 12.55905 4.64173996 2 P 19 0;0=18,1=0
P 12.73621004 1.37401998 2 P 19 0;0=17,1=0
P 12.81495 1.41338996 2 P 19 0;0=18,1=0
P 12.73621004 1.45276004 2 P 19 0;0=18,1=0
P 12.81495 1.49213002 2 P 19 0;0=18,1=0
P 12.73621004 1.5315 2 P 19 0;0=18,1=0
P 12.81495 1.57086998 2 P 19 0;0=18,1=0
P 12.73621004 1.61023996 2 P 19 0;0=18,1=0
P 12.81495 1.64961004 2 P 19 0;0=18,1=0
P 12.73621004 1.68898002 2 P 19 0;0=18,1=0
P 12.81495 1.72835 2 P 19 0;0=18,1=0
P 12.73621004 1.76771998 2 P 19 0;0=18,1=0
P 12.81495 1.88583002 2 P 19 0;0=18,1=0
P 12.73621004 1.9252 2 P 19 0;0=18,1=0
P 12.81495 1.96456998 2 P 19 0;0=18,1=0
P 12.73621004 2.00393996 2 P 19 0;0=18,1=0
P 12.81495 2.04331004 2 P 19 0;0=18,1=0
P 12.73621004 2.08268002 2 P 19 0;0=18,1=0
P 12.81495 2.12205 2 P 19 0;0=18,1=0
P 12.73621004 2.16141998 2 P 19 0;0=18,1=0
P 12.81495 2.20078996 2 P 19 0;0=18,1=0
P 12.73621004 2.24016004 2 P 19 0;0=18,1=0
P 12.81495 2.27953002 2 P 19 0;0=18,1=0
P 12.73621004 2.3189 2 P 19 0;0=18,1=0
P 12.81495 2.35826998 2 P 19 0;0=18,1=0
P 12.73621004 2.39763996 2 P 19 0;0=18,1=0
P 12.81495 2.43701004 2 P 19 0;0=18,1=0
P 12.73621004 2.47638002 2 P 19 0;0=18,1=0
P 12.81495 2.51575 2 P 19 0;0=18,1=0
P 12.73621004 2.55511998 2 P 19 0;0=18,1=0
P 12.81495 2.59448996 2 P 19 0;0=18,1=0
P 12.73621004 2.63386004 2 P 19 0;0=18,1=0
P 12.81495 2.67323002 2 P 19 0;0=18,1=0
P 12.73621004 2.7126 2 P 19 0;0=18,1=0
P 12.81495 2.75196998 2 P 19 0;0=18,1=0
P 12.73621004 2.79133996 2 P 19 0;0=18,1=0
P 12.81495 2.83071004 2 P 19 0;0=18,1=0
P 12.73621004 2.87008002 2 P 19 0;0=18,1=0
P 12.81495 2.90945 2 P 19 0;0=18,1=0
P 12.73621004 2.94881998 2 P 19 0;0=18,1=0
P 12.81495 2.98818996 2 P 19 0;0=18,1=0
P 12.73621004 3.02756004 2 P 19 0;0=18,1=0
P 12.81495 3.06693002 2 P 19 0;0=18,1=0
P 12.73621004 3.1063 2 P 19 0;0=18,1=0
P 12.81495 3.14566998 2 P 19 0;0=18,1=0
P 12.73621004 3.18503996 2 P 19 0;0=18,1=0
P 12.81495 3.22441004 2 P 19 0;0=18,1=0
P 12.73621004 3.26378002 2 P 19 0;0=18,1=0
P 12.81495 3.30315 2 P 19 0;0=18,1=0
P 12.73621004 3.34251998 2 P 19 0;0=18,1=0
P 12.81495 3.38188996 2 P 19 0;0=18,1=0
P 12.73621004 3.42126004 2 P 19 0;0=18,1=0
P 12.81495 3.46063002 2 P 19 0;0=18,1=0
P 12.73621004 3.5 2 P 19 0;0=18,1=0
P 12.81495 3.53936998 2 P 19 0;0=18,1=0
P 12.73621004 3.57873996 2 P 19 0;0=18,1=0
P 12.81495 3.61811004 2 P 19 0;0=18,1=0
P 12.73621004 3.65748002 2 P 19 0;0=18,1=0
P 12.81495 3.69685 2 P 19 0;0=18,1=0
P 12.73621004 3.73621998 2 P 19 0;0=18,1=0
P 12.81495 3.77558996 2 P 19 0;0=18,1=0
P 12.73621004 3.81496004 2 P 19 0;0=18,1=0
P 12.81495 3.85433002 2 P 19 0;0=18,1=0
P 12.73621004 3.8937 2 P 19 0;0=18,1=0
P 12.81495 3.93306998 2 P 19 0;0=18,1=0
P 12.73621004 3.97243996 2 P 19 0;0=18,1=0
P 12.81495 4.01181004 2 P 19 0;0=18,1=0
P 12.73621004 4.05118002 2 P 19 0;0=18,1=0
P 12.81495 4.09055 2 P 19 0;0=18,1=0
P 12.73621004 4.12991998 2 P 19 0;0=18,1=0
P 12.81495 4.16928996 2 P 19 0;0=18,1=0
P 12.73621004 4.20866004 2 P 19 0;0=18,1=0
P 12.81495 4.24803002 2 P 19 0;0=18,1=0
P 12.73621004 4.2874 2 P 19 0;0=18,1=0
P 12.81495 4.32676998 2 P 19 0;0=18,1=0
P 12.73621004 4.36613996 2 P 19 0;0=18,1=0
P 12.81495 4.40551004 2 P 19 0;0=18,1=0
P 12.73621004 4.44488002 2 P 19 0;0=18,1=0
P 12.81495 4.48425 2 P 19 0;0=18,1=0
P 12.73621004 4.52361998 2 P 19 0;0=18,1=0
P 12.81495 4.56298996 2 P 19 0;0=18,1=0
P 12.73621004 4.60236998 2 P 19 0;0=18,1=0
P 12.81495 4.64173996 2 P 19 0;0=18,1=0
P 1.47736004 5.62008002 4 P 6 0;0=19,1=1
P 0.7687 5.62008002 4 P 6 0;0=19,1=1
P 1.325 -0.35 2 P 4 0;0=20,1=0
P 1.325 -0.25 2 P 4 0;0=21,1=0
P 0.875 -0.35 2 P 4 0;0=20,1=0
P 0.875 -0.25 2 P 4 0;0=21,1=0
P 0.725 -0.35 2 P 4 0;0=20,1=0
P 0.725 -0.25 2 P 4 0;0=21,1=0
P 1.175 -0.35 2 P 4 0;0=20,1=0
P 1.175 -0.25 2 P 4 0;0=21,1=0
P 1.025 -0.35 2 P 4 0;0=20,1=0
P 1.025 -0.25 2 P 4 0;0=21,1=0
P 1.64 6.26 2 P 4 0;0=20,1=0
P 1.64 6.36 2 P 4 0;0=20,1=0
P 1.74 6.36 2 P 4 0;0=21,1=0
P 1.74 6.26 2 P 4 0;0=21,1=0
P 0.965 6.26 2 P 4 0;0=20,1=0
P 0.965 6.36 2 P 4 0;0=20,1=0
P 1.065 6.36 2 P 4 0;0=21,1=0
P 1.065 6.26 2 P 4 0;0=21,1=0
P 0.74 6.26 2 P 4 0;0=20,1=0
P 0.74 6.36 2 P 4 0;0=20,1=0
P 0.84 6.36 2 P 4 0;0=21,1=0
P 0.84 6.26 2 P 4 0;0=21,1=0
P 1.415 6.26 2 P 4 0;0=20,1=0
P 1.415 6.36 2 P 4 0;0=20,1=0
P 1.515 6.36 2 P 4 0;0=21,1=0
P 1.515 6.26 2 P 4 0;0=21,1=0
P 1.19 6.26 2 P 4 0;0=20,1=0
P 1.19 6.36 2 P 4 0;0=20,1=0
P 1.29 6.36 2 P 4 0;0=21,1=0
P 1.29 6.26 2 P 4 0;0=21,1=0
P 3.17146004 5.255 1 P 3 0;0=22,1=2
P 2.06646004 5.29 1 P 3 0;0=22,1=2
P 3.115 5.255 1 P 3 0;0=22,1=2
P 2.00146004 5.29 1 P 3 0;0=22,1=2
P 1.23906004 5.04351004 1 P 3 0;0=22,1=2
P 1.28906004 5.04351004 1 P 3 0;0=22,1=2
P 1.18906004 5.15351004 1 P 3 0;0=22,1=2
P 1.33906004 5.15351004 1 P 3 0;0=22,1=2
P 1.86 4.485 1 P 3 0;0=22,1=2
P 1.8 4.485 1 P 3 0;0=22,1=2
P 9.175 5.255 1 P 3 0;0=22,1=2
P 8.07 5.29 1 P 3 0;0=22,1=2
P 9.11853996 5.255 1 P 3 0;0=22,1=2
P 8.005 5.29 1 P 3 0;0=22,1=2
P 7.2426 5.04351004 1 P 3 0;0=22,1=2
P 7.2926 5.04351004 1 P 3 0;0=22,1=2
P 7.1926 5.15351004 1 P 3 0;0=22,1=2
P 7.3426 5.15351004 1 P 3 0;0=22,1=2
P 7.835 4.45 1 P 3 0;0=22,1=2
P 7.785 4.45 1 P 3 0;0=22,1=2
P 3.84 0.69 1 P 3 0;0=22,1=2
P 3.75998996 0.345 1 P 3 0;0=22,1=2
P 3.785 0.69 1 P 3 0;0=22,1=2
P 3.56 0.49 1 P 3 0;0=22,1=2
P 3.635 0.715 1 P 3 0;0=22,1=2
P 3.635 0.49 1 P 3 0;0=22,1=2
P 4.07408002 4.01978996 1 P 3 0;0=22,1=2
P 3.9099 5.395 1 P 3 0;0=22,1=2
P 4.06 4.86 1 P 3 0;0=22,1=2
P 4.02 4.42 1 P 3 0;0=22,1=2
P 9.64 0.71 1 P 3 0;0=22,1=2
P 9.55795 0.36633002 1 P 3 0;0=22,1=2
P 9.58296004 0.71133002 1 P 3 0;0=22,1=2
P 9.35796004 0.49133002 1 P 3 0;0=22,1=2
P 9.43296004 0.73633002 1 P 3 0;0=22,1=2
P 9.43296004 0.49133002 1 P 3 0;0=22,1=2
P 7.425 3.43 1 P 3 0;0=22,1=2
P 3.8899 4.765 1 P 3 0;0=22,1=2
P 3.985 4.88998996 1 P 3 0;0=22,1=2
P 4 5.29 1 P 3 0;0=22,1=2
P 10.38498996 4.9231 1 P 3 0;0=22,1=2
P 3.86 0.7751 1 P 3 0;0=22,1=2
P 0.66 2.045 1 P 3 0;0=22,1=2
P 0.7 5.267 1 P 3 0;0=22,1=2
P 7.78 2.4781 1 P 3 0;0=22,1=2
P 3.94 4.765 1 P 3 0;0=22,1=2
P 5.76 2.66 1 P 3 0;0=22,1=2
P 3.775 5.295 1 P 3 0;0=22,1=2
P 1.08 5.85 1 P 3 0;0=22,1=2
P 4.02 4.355 1 P 3 0;0=22,1=2
P 3.94 4.42 1 P 3 0;0=22,1=2
P 3.8399 4.765 1 P 3 0;0=22,1=2
P 1.16 5.85 1 P 3 0;0=22,1=2
P 4.105 4.985 1 P 3 0;0=22,1=2
P 9.91 4.433 1 P 3 0;0=22,1=2
P 3.88 4.545 1 P 3 0;0=22,1=2
P 5.815 0.925 1 P 3 0;0=22,1=2
P 0.96555 5.78055 1 P 3 0;0=22,1=2
P 0.72933002 5.463 1 P 3 0;0=22,1=2
P 1.28906004 4.69351004 1 P 3 0;0=22,1=2
P 1.33906004 4.69351004 1 P 3 0;0=22,1=2
P 7.2926 4.69351004 1 P 3 0;0=22,1=2
P 7.3426 4.69351004 1 P 3 0;0=22,1=2
P 3.45646004 5.3 1 P 3 0;0=22,1=2
P 9.46 5.3 1 P 3 0;0=22,1=2
P 6.83708996 4.5652 1 P 3 0;0=22,1=2
P 11.395 2.725 1 P 3 0;0=22,1=2
P 1.33906004 4.60351004 1 P 3 0;0=22,1=2
P 3.75998996 0.24001004 1 P 3 0;0=22,1=2
P 5.387 2.725 1 P 3 0;0=22,1=2
P 9.55795 0.26133996 1 P 3 0;0=22,1=2
P 0.80806998 5.46193996 1 P 3 0;0=22,1=2
P 1.094 5.356 1 P 3 0;0=22,1=2
P 11.865 4.455 1 P 3 0;0=22,1=2
P 1.38906004 5.15351004 1 P 3 0;0=22,1=2
P 0.58 5.591 1 P 3 0;0=22,1=2
P 7.42603996 5.15895 1 P 3 0;0=22,1=2
P 6.501 5.017 1 P 3 0;0=22,1=2
P 6.74 4.987 1 P 3 0;0=22,1=2
P 0.73 4.96 1 P 3 0;0=22,1=2
P 6.49205 5.09705 1 P 3 0;0=22,1=2
P 6.55118996 5.04705 1 P 3 0;0=22,1=2
P 6.65 5.055 1 P 3 0;0=22,1=2
P 6.495 4.9328 1 P 3 0;0=22,1=2
P 6.755 4.89705 1 P 3 0;0=22,1=2
P 6.74 4.805 1 P 3 0;0=22,1=2
P 6.78 4.94705 1 P 3 0;0=22,1=2
P 1.057 5.027 1 P 3 0;0=22,1=2
P 3.9599 5.395 1 P 3 0;0=22,1=2
P 0.95951004 5.4595 1 P 3 0;0=22,1=2
P 3.94 4.545 1 P 3 0;0=22,1=2
P 4.98268002 2.71615 0 P 1 0;0=23,1=2
P 4.68268002 2.71615 0 P 1 0;0=23,1=2
P 4.68268002 2.76615 0 P 1 0;0=23,1=2
P 4.68268002 2.81615 0 P 1 0;0=23,1=2
P 4.78268002 2.81615 0 P 1 0;0=23,1=2
P 4.73268002 2.81615 0 P 1 0;0=23,1=2
P 4.63268002 2.81615 0 P 1 0;0=23,1=2
P 4.58268002 2.81615 0 P 1 0;0=23,1=2
P 2.24606004 2.86615 0 P 1 0;0=23,1=2
P 2.29606004 2.86615 0 P 1 0;0=23,1=2
P 4.88268002 2.71615 0 P 1 0;0=23,1=2
P 5.03268002 3.81615 0 P 1 0;0=23,1=2
P 2.09606004 3.56615 0 P 1 0;0=23,1=2
P 2.14606004 2.51615 0 P 1 0;0=23,1=2
P 5.03268002 2.16615 0 P 1 0;0=23,1=2
P 4.78268002 2.71615 0 P 1 0;0=23,1=2
P 5.08268002 2.71615 0 P 1 0;0=23,1=2
P 4.58268002 2.76615 0 P 1 0;0=23,1=2
P 10.98661004 2.71615 0 P 1 0;0=23,1=2
P 10.68661004 2.71615 0 P 1 0;0=23,1=2
P 10.68661004 2.76615 0 P 1 0;0=23,1=2
P 10.68661004 2.81615 0 P 1 0;0=23,1=2
P 10.78661004 2.81615 0 P 1 0;0=23,1=2
P 10.73661004 2.81615 0 P 1 0;0=23,1=2
P 10.63661004 2.81615 0 P 1 0;0=23,1=2
P 10.58661004 2.81615 0 P 1 0;0=23,1=2
P 8.25 2.86615 0 P 1 0;0=23,1=2
P 8.3 2.86615 0 P 1 0;0=23,1=2
P 10.83661004 2.16615 0 P 1 0;0=23,1=2
P 10.88661004 2.16615 0 P 1 0;0=23,1=2
P 10.88661004 2.71615 0 P 1 0;0=23,1=2
P 11.03661004 3.81615 0 P 1 0;0=23,1=2
P 8.1 3.56615 0 P 1 0;0=23,1=2
P 8.15 2.51615 0 P 1 0;0=23,1=2
P 11.03661004 2.16615 0 P 1 0;0=23,1=2
P 10.78661004 2.71615 0 P 1 0;0=23,1=2
P 11.08661004 2.71615 0 P 1 0;0=23,1=2
P 10.58661004 2.76615 0 P 1 0;0=23,1=2
P 10.58661004 1.86615 0 P 1 0;0=23,1=2
P 10.58661004 2.01615 0 P 1 0;0=23,1=2
P 10.58661004 2.16615 0 P 1 0;0=23,1=2
P 10.58661004 2.31615 0 P 1 0;0=23,1=2
P 10.58661004 2.46615 0 P 1 0;0=23,1=2
P 10.58661004 2.51615 0 P 1 0;0=23,1=2
P 10.58661004 2.66615 0 P 1 0;0=23,1=2
P 10.58661004 2.91615 0 P 1 0;0=23,1=2
P 10.58661004 3.06615 0 P 1 0;0=23,1=2
P 10.58661004 3.21615 0 P 1 0;0=23,1=2
P 10.58661004 3.36615 0 P 1 0;0=23,1=2
P 10.58661004 3.51615 0 P 1 0;0=23,1=2
P 10.58661004 3.66615 0 P 1 0;0=23,1=2
P 10.58661004 3.81615 0 P 1 0;0=23,1=2
P 10.63661004 1.96615 0 P 1 0;0=23,1=2
P 10.63661004 2.11615 0 P 1 0;0=23,1=2
P 10.63661004 2.16615 0 P 1 0;0=23,1=2
P 10.63661004 2.21615 0 P 1 0;0=23,1=2
P 10.63661004 2.36615 0 P 1 0;0=23,1=2
P 10.63661004 2.51615 0 P 1 0;0=23,1=2
P 10.63661004 2.56615 0 P 1 0;0=23,1=2
P 10.63661004 2.71615 0 P 1 0;0=23,1=2
P 10.63661004 2.76615 0 P 1 0;0=23,1=2
P 10.63661004 2.91615 0 P 1 0;0=23,1=2
P 10.63661004 3.06615 0 P 1 0;0=23,1=2
P 10.63661004 3.21615 0 P 1 0;0=23,1=2
P 10.63661004 3.36615 0 P 1 0;0=23,1=2
P 10.63661004 3.51615 0 P 1 0;0=23,1=2
P 10.63661004 3.66615 0 P 1 0;0=23,1=2
P 10.63661004 3.81615 0 P 1 0;0=23,1=2
P 10.68661004 1.86615 0 P 1 0;0=23,1=2
P 10.68661004 2.01615 0 P 1 0;0=23,1=2
P 10.68661004 2.16615 0 P 1 0;0=23,1=2
P 10.68661004 2.31615 0 P 1 0;0=23,1=2
P 10.68661004 2.46615 0 P 1 0;0=23,1=2
P 10.68661004 2.51615 0 P 1 0;0=23,1=2
P 10.68661004 2.66615 0 P 1 0;0=23,1=2
P 10.68661004 2.91615 0 P 1 0;0=23,1=2
P 10.68661004 3.06615 0 P 1 0;0=23,1=2
P 10.68661004 3.21615 0 P 1 0;0=23,1=2
P 10.68661004 3.36615 0 P 1 0;0=23,1=2
P 10.68661004 3.51615 0 P 1 0;0=23,1=2
P 10.68661004 3.66615 0 P 1 0;0=23,1=2
P 10.68661004 3.81615 0 P 1 0;0=23,1=2
P 10.73661004 1.96615 0 P 1 0;0=23,1=2
P 10.73661004 2.11615 0 P 1 0;0=23,1=2
P 10.73661004 2.16615 0 P 1 0;0=23,1=2
P 10.73661004 2.21615 0 P 1 0;0=23,1=2
P 10.73661004 2.36615 0 P 1 0;0=23,1=2
P 10.73661004 2.51615 0 P 1 0;0=23,1=2
P 10.73661004 2.56615 0 P 1 0;0=23,1=2
P 10.73661004 2.71615 0 P 1 0;0=23,1=2
P 10.73661004 2.76615 0 P 1 0;0=23,1=2
P 10.73661004 2.91615 0 P 1 0;0=23,1=2
P 10.73661004 3.06615 0 P 1 0;0=23,1=2
P 10.73661004 3.21615 0 P 1 0;0=23,1=2
P 10.73661004 3.36615 0 P 1 0;0=23,1=2
P 10.73661004 3.51615 0 P 1 0;0=23,1=2
P 10.73661004 3.66615 0 P 1 0;0=23,1=2
P 10.73661004 3.81615 0 P 1 0;0=23,1=2
P 10.78661004 1.86615 0 P 1 0;0=23,1=2
P 10.78661004 1.91615 0 P 1 0;0=23,1=2
P 10.78661004 1.96615 0 P 1 0;0=23,1=2
P 10.78661004 2.01615 0 P 1 0;0=23,1=2
P 10.78661004 2.06615 0 P 1 0;0=23,1=2
P 10.78661004 2.11615 0 P 1 0;0=23,1=2
P 10.78661004 2.21615 0 P 1 0;0=23,1=2
P 10.78661004 2.26615 0 P 1 0;0=23,1=2
P 10.78661004 2.31615 0 P 1 0;0=23,1=2
P 10.78661004 2.36615 0 P 1 0;0=23,1=2
P 10.78661004 2.41615 0 P 1 0;0=23,1=2
P 10.78661004 2.46615 0 P 1 0;0=23,1=2
P 10.78661004 2.51615 0 P 1 0;0=23,1=2
P 10.78661004 2.56615 0 P 1 0;0=23,1=2
P 10.78661004 2.61615 0 P 1 0;0=23,1=2
P 10.78661004 2.66615 0 P 1 0;0=23,1=2
P 10.78661004 2.76615 0 P 1 0;0=23,1=2
P 10.78661004 2.91615 0 P 1 0;0=23,1=2
P 10.78661004 3.06615 0 P 1 0;0=23,1=2
P 10.78661004 3.21615 0 P 1 0;0=23,1=2
P 10.78661004 3.36615 0 P 1 0;0=23,1=2
P 10.78661004 3.51615 0 P 1 0;0=23,1=2
P 10.78661004 3.66615 0 P 1 0;0=23,1=2
P 10.78661004 3.81615 0 P 1 0;0=23,1=2
P 10.83661004 2.91615 0 P 1 0;0=23,1=2
P 10.83661004 3.06615 0 P 1 0;0=23,1=2
P 10.83661004 3.21615 0 P 1 0;0=23,1=2
P 10.83661004 3.36615 0 P 1 0;0=23,1=2
P 10.83661004 3.51615 0 P 1 0;0=23,1=2
P 10.83661004 3.66615 0 P 1 0;0=23,1=2
P 10.83661004 3.81615 0 P 1 0;0=23,1=2
P 10.88661004 1.86615 0 P 1 0;0=23,1=2
P 10.88661004 1.91615 0 P 1 0;0=23,1=2
P 10.88661004 1.96615 0 P 1 0;0=23,1=2
P 10.88661004 2.01615 0 P 1 0;0=23,1=2
P 10.88661004 2.06615 0 P 1 0;0=23,1=2
P 10.88661004 2.11615 0 P 1 0;0=23,1=2
P 10.88661004 2.21615 0 P 1 0;0=23,1=2
P 10.88661004 2.26615 0 P 1 0;0=23,1=2
P 10.88661004 2.31615 0 P 1 0;0=23,1=2
P 10.88661004 2.36615 0 P 1 0;0=23,1=2
P 10.88661004 2.41615 0 P 1 0;0=23,1=2
P 10.88661004 2.46615 0 P 1 0;0=23,1=2
P 10.88661004 2.51615 0 P 1 0;0=23,1=2
P 10.88661004 2.56615 0 P 1 0;0=23,1=2
P 10.88661004 2.61615 0 P 1 0;0=23,1=2
P 10.88661004 2.66615 0 P 1 0;0=23,1=2
P 10.88661004 2.76615 0 P 1 0;0=23,1=2
P 10.88661004 2.91615 0 P 1 0;0=23,1=2
P 10.88661004 3.06615 0 P 1 0;0=23,1=2
P 10.88661004 3.21615 0 P 1 0;0=23,1=2
P 10.88661004 3.36615 0 P 1 0;0=23,1=2
P 10.88661004 3.51615 0 P 1 0;0=23,1=2
P 10.88661004 3.66615 0 P 1 0;0=23,1=2
P 10.88661004 3.81615 0 P 1 0;0=23,1=2
P 10.93661004 1.96615 0 P 1 0;0=23,1=2
P 10.93661004 2.11615 0 P 1 0;0=23,1=2
P 10.93661004 2.16615 0 P 1 0;0=23,1=2
P 10.93661004 2.21615 0 P 1 0;0=23,1=2
P 10.93661004 2.36615 0 P 1 0;0=23,1=2
P 10.93661004 2.51615 0 P 1 0;0=23,1=2
P 10.93661004 2.56615 0 P 1 0;0=23,1=2
P 10.93661004 2.71615 0 P 1 0;0=23,1=2
P 10.93661004 2.76615 0 P 1 0;0=23,1=2
P 10.93661004 2.91615 0 P 1 0;0=23,1=2
P 10.93661004 3.06615 0 P 1 0;0=23,1=2
P 10.93661004 3.21615 0 P 1 0;0=23,1=2
P 10.93661004 3.36615 0 P 1 0;0=23,1=2
P 10.93661004 3.51615 0 P 1 0;0=23,1=2
P 10.93661004 3.66615 0 P 1 0;0=23,1=2
P 10.93661004 3.81615 0 P 1 0;0=23,1=2
P 10.98661004 1.86615 0 P 1 0;0=23,1=2
P 10.98661004 2.01615 0 P 1 0;0=23,1=2
P 10.98661004 2.16615 0 P 1 0;0=23,1=2
P 10.98661004 2.31615 0 P 1 0;0=23,1=2
P 10.98661004 2.46615 0 P 1 0;0=23,1=2
P 10.98661004 2.51615 0 P 1 0;0=23,1=2
P 10.98661004 2.66615 0 P 1 0;0=23,1=2
P 10.98661004 2.76615 0 P 1 0;0=23,1=2
P 10.98661004 2.91615 0 P 1 0;0=23,1=2
P 10.98661004 3.06615 0 P 1 0;0=23,1=2
P 10.98661004 3.21615 0 P 1 0;0=23,1=2
P 10.98661004 3.36615 0 P 1 0;0=23,1=2
P 10.98661004 3.51615 0 P 1 0;0=23,1=2
P 10.98661004 3.66615 0 P 1 0;0=23,1=2
P 10.98661004 3.81615 0 P 1 0;0=23,1=2
P 11.03661004 1.96615 0 P 1 0;0=23,1=2
P 11.03661004 2.11615 0 P 1 0;0=23,1=2
P 11.03661004 2.21615 0 P 1 0;0=23,1=2
P 11.03661004 2.36615 0 P 1 0;0=23,1=2
P 11.03661004 2.41615 0 P 1 0;0=23,1=2
P 11.03661004 2.56615 0 P 1 0;0=23,1=2
P 11.03661004 2.71615 0 P 1 0;0=23,1=2
P 11.03661004 2.76615 0 P 1 0;0=23,1=2
P 11.03661004 2.91615 0 P 1 0;0=23,1=2
P 11.03661004 3.06615 0 P 1 0;0=23,1=2
P 11.03661004 3.21615 0 P 1 0;0=23,1=2
P 11.03661004 3.36615 0 P 1 0;0=23,1=2
P 11.03661004 3.51615 0 P 1 0;0=23,1=2
P 11.03661004 3.66615 0 P 1 0;0=23,1=2
P 11.08661004 1.86615 0 P 1 0;0=23,1=2
P 11.08661004 2.01615 0 P 1 0;0=23,1=2
P 11.08661004 2.16615 0 P 1 0;0=23,1=2
P 11.08661004 2.31615 0 P 1 0;0=23,1=2
P 11.08661004 2.46615 0 P 1 0;0=23,1=2
P 11.08661004 2.51615 0 P 1 0;0=23,1=2
P 11.08661004 2.66615 0 P 1 0;0=23,1=2
P 11.08661004 2.76615 0 P 1 0;0=23,1=2
P 1.99606004 2.71615 0 P 1 0;0=23,1=2
P 1.99606004 2.76615 0 P 1 0;0=23,1=2
P 1.99606004 2.81615 0 P 1 0;0=23,1=2
P 1.99606004 2.86615 0 P 1 0;0=23,1=2
P 1.99606004 3.41615 0 P 1 0;0=23,1=2
P 1.99606004 3.56615 0 P 1 0;0=23,1=2
P 2.04606004 1.86615 0 P 1 0;0=23,1=2
P 2.04606004 1.91615 0 P 1 0;0=23,1=2
P 2.04606004 1.96615 0 P 1 0;0=23,1=2
P 2.04606004 2.01615 0 P 1 0;0=23,1=2
P 2.04606004 2.06615 0 P 1 0;0=23,1=2
P 2.04606004 2.11615 0 P 1 0;0=23,1=2
P 2.04606004 2.16615 0 P 1 0;0=23,1=2
P 2.04606004 2.21615 0 P 1 0;0=23,1=2
P 2.04606004 2.26615 0 P 1 0;0=23,1=2
P 2.04606004 2.31615 0 P 1 0;0=23,1=2
P 2.04606004 2.36615 0 P 1 0;0=23,1=2
P 2.04606004 2.41615 0 P 1 0;0=23,1=2
P 2.04606004 2.46615 0 P 1 0;0=23,1=2
P 2.04606004 2.51615 0 P 1 0;0=23,1=2
P 2.04606004 2.56615 0 P 1 0;0=23,1=2
P 2.04606004 2.61615 0 P 1 0;0=23,1=2
P 2.04606004 2.66615 0 P 1 0;0=23,1=2
P 2.04606004 2.71615 0 P 1 0;0=23,1=2
P 2.04606004 2.76615 0 P 1 0;0=23,1=2
P 2.04606004 2.81615 0 P 1 0;0=23,1=2
P 2.04606004 2.86615 0 P 1 0;0=23,1=2
P 2.04606004 2.91615 0 P 1 0;0=23,1=2
P 2.04606004 2.96615 0 P 1 0;0=23,1=2
P 2.04606004 3.01615 0 P 1 0;0=23,1=2
P 2.04606004 3.06615 0 P 1 0;0=23,1=2
P 2.04606004 3.11615 0 P 1 0;0=23,1=2
P 2.04606004 3.16615 0 P 1 0;0=23,1=2
P 2.04606004 3.21615 0 P 1 0;0=23,1=2
P 2.04606004 3.26615 0 P 1 0;0=23,1=2
P 2.04606004 3.41615 0 P 1 0;0=23,1=2
P 2.04606004 3.46615 0 P 1 0;0=23,1=2
P 2.04606004 3.51615 0 P 1 0;0=23,1=2
P 2.04606004 3.56615 0 P 1 0;0=23,1=2
P 2.04606004 3.71615 0 P 1 0;0=23,1=2
P 2.04606004 3.86615 0 P 1 0;0=23,1=2
P 2.09606004 1.86615 0 P 1 0;0=23,1=2
P 2.09606004 1.91615 0 P 1 0;0=23,1=2
P 2.09606004 1.96615 0 P 1 0;0=23,1=2
P 2.09606004 2.01615 0 P 1 0;0=23,1=2
P 2.09606004 2.06615 0 P 1 0;0=23,1=2
P 2.09606004 2.11615 0 P 1 0;0=23,1=2
P 2.09606004 2.16615 0 P 1 0;0=23,1=2
P 2.09606004 2.21615 0 P 1 0;0=23,1=2
P 2.09606004 2.26615 0 P 1 0;0=23,1=2
P 2.09606004 2.31615 0 P 1 0;0=23,1=2
P 2.09606004 2.36615 0 P 1 0;0=23,1=2
P 2.09606004 2.41615 0 P 1 0;0=23,1=2
P 2.09606004 2.46615 0 P 1 0;0=23,1=2
P 2.09606004 2.51615 0 P 1 0;0=23,1=2
P 2.09606004 2.56615 0 P 1 0;0=23,1=2
P 2.09606004 2.61615 0 P 1 0;0=23,1=2
P 2.09606004 2.66615 0 P 1 0;0=23,1=2
P 2.09606004 2.71615 0 P 1 0;0=23,1=2
P 2.09606004 2.76615 0 P 1 0;0=23,1=2
P 2.09606004 2.81615 0 P 1 0;0=23,1=2
P 2.09606004 2.86615 0 P 1 0;0=23,1=2
P 2.09606004 2.91615 0 P 1 0;0=23,1=2
P 2.09606004 2.96615 0 P 1 0;0=23,1=2
P 2.09606004 3.01615 0 P 1 0;0=23,1=2
P 2.09606004 3.06615 0 P 1 0;0=23,1=2
P 2.09606004 3.11615 0 P 1 0;0=23,1=2
P 2.09606004 3.16615 0 P 1 0;0=23,1=2
P 2.09606004 3.21615 0 P 1 0;0=23,1=2
P 2.09606004 3.36615 0 P 1 0;0=23,1=2
P 2.09606004 3.51615 0 P 1 0;0=23,1=2
P 2.09606004 3.61615 0 P 1 0;0=23,1=2
P 2.09606004 3.76615 0 P 1 0;0=23,1=2
P 2.14606004 1.86615 0 P 1 0;0=23,1=2
P 2.14606004 1.91615 0 P 1 0;0=23,1=2
P 2.14606004 1.96615 0 P 1 0;0=23,1=2
P 2.14606004 2.01615 0 P 1 0;0=23,1=2
P 2.14606004 2.06615 0 P 1 0;0=23,1=2
P 2.14606004 2.11615 0 P 1 0;0=23,1=2
P 2.14606004 2.16615 0 P 1 0;0=23,1=2
P 2.14606004 2.21615 0 P 1 0;0=23,1=2
P 2.14606004 2.26615 0 P 1 0;0=23,1=2
P 2.14606004 2.31615 0 P 1 0;0=23,1=2
P 2.14606004 2.36615 0 P 1 0;0=23,1=2
P 2.14606004 2.41615 0 P 1 0;0=23,1=2
P 2.14606004 2.46615 0 P 1 0;0=23,1=2
P 2.14606004 2.56615 0 P 1 0;0=23,1=2
P 2.14606004 2.61615 0 P 1 0;0=23,1=2
P 2.14606004 2.66615 0 P 1 0;0=23,1=2
P 2.14606004 2.71615 0 P 1 0;0=23,1=2
P 2.14606004 2.76615 0 P 1 0;0=23,1=2
P 2.14606004 2.81615 0 P 1 0;0=23,1=2
P 2.14606004 2.86615 0 P 1 0;0=23,1=2
P 2.14606004 2.91615 0 P 1 0;0=23,1=2
P 2.14606004 2.96615 0 P 1 0;0=23,1=2
P 2.14606004 3.01615 0 P 1 0;0=23,1=2
P 2.14606004 3.06615 0 P 1 0;0=23,1=2
P 2.14606004 3.11615 0 P 1 0;0=23,1=2
P 2.14606004 3.16615 0 P 1 0;0=23,1=2
P 2.14606004 3.21615 0 P 1 0;0=23,1=2
P 2.14606004 3.26615 0 P 1 0;0=23,1=2
P 2.14606004 3.41615 0 P 1 0;0=23,1=2
P 2.14606004 3.56615 0 P 1 0;0=23,1=2
P 2.14606004 3.71615 0 P 1 0;0=23,1=2
P 2.14606004 3.86615 0 P 1 0;0=23,1=2
P 2.19606004 1.86615 0 P 1 0;0=23,1=2
P 2.19606004 1.91615 0 P 1 0;0=23,1=2
P 2.19606004 1.96615 0 P 1 0;0=23,1=2
P 2.19606004 2.01615 0 P 1 0;0=23,1=2
P 2.19606004 2.06615 0 P 1 0;0=23,1=2
P 2.19606004 2.11615 0 P 1 0;0=23,1=2
P 2.19606004 2.16615 0 P 1 0;0=23,1=2
P 2.19606004 2.21615 0 P 1 0;0=23,1=2
P 2.19606004 2.26615 0 P 1 0;0=23,1=2
P 2.19606004 2.31615 0 P 1 0;0=23,1=2
P 2.19606004 2.36615 0 P 1 0;0=23,1=2
P 2.19606004 2.41615 0 P 1 0;0=23,1=2
P 2.19606004 2.46615 0 P 1 0;0=23,1=2
P 2.19606004 2.51615 0 P 1 0;0=23,1=2
P 2.19606004 2.56615 0 P 1 0;0=23,1=2
P 2.19606004 2.61615 0 P 1 0;0=23,1=2
P 2.19606004 2.66615 0 P 1 0;0=23,1=2
P 2.19606004 2.71615 0 P 1 0;0=23,1=2
P 2.19606004 2.76615 0 P 1 0;0=23,1=2
P 2.19606004 2.81615 0 P 1 0;0=23,1=2
P 2.19606004 2.86615 0 P 1 0;0=23,1=2
P 2.19606004 2.91615 0 P 1 0;0=23,1=2
P 2.19606004 2.96615 0 P 1 0;0=23,1=2
P 2.19606004 3.01615 0 P 1 0;0=23,1=2
P 2.19606004 3.06615 0 P 1 0;0=23,1=2
P 2.19606004 3.11615 0 P 1 0;0=23,1=2
P 2.19606004 3.16615 0 P 1 0;0=23,1=2
P 2.19606004 3.21615 0 P 1 0;0=23,1=2
P 2.19606004 3.36615 0 P 1 0;0=23,1=2
P 2.19606004 3.51615 0 P 1 0;0=23,1=2
P 2.19606004 3.56615 0 P 1 0;0=23,1=2
P 2.19606004 3.61615 0 P 1 0;0=23,1=2
P 2.19606004 3.76615 0 P 1 0;0=23,1=2
P 2.24606004 1.86615 0 P 1 0;0=23,1=2
P 2.24606004 1.91615 0 P 1 0;0=23,1=2
P 2.24606004 1.96615 0 P 1 0;0=23,1=2
P 2.24606004 2.01615 0 P 1 0;0=23,1=2
P 2.24606004 2.06615 0 P 1 0;0=23,1=2
P 2.24606004 2.11615 0 P 1 0;0=23,1=2
P 2.24606004 2.16615 0 P 1 0;0=23,1=2
P 2.24606004 2.21615 0 P 1 0;0=23,1=2
P 2.24606004 2.26615 0 P 1 0;0=23,1=2
P 2.24606004 2.31615 0 P 1 0;0=23,1=2
P 2.24606004 2.36615 0 P 1 0;0=23,1=2
P 2.24606004 2.41615 0 P 1 0;0=23,1=2
P 2.24606004 2.46615 0 P 1 0;0=23,1=2
P 2.24606004 2.51615 0 P 1 0;0=23,1=2
P 2.24606004 2.56615 0 P 1 0;0=23,1=2
P 2.24606004 2.61615 0 P 1 0;0=23,1=2
P 2.24606004 2.66615 0 P 1 0;0=23,1=2
P 2.24606004 2.71615 0 P 1 0;0=23,1=2
P 2.24606004 2.76615 0 P 1 0;0=23,1=2
P 2.24606004 2.81615 0 P 1 0;0=23,1=2
P 2.24606004 2.91615 0 P 1 0;0=23,1=2
P 2.24606004 2.96615 0 P 1 0;0=23,1=2
P 2.24606004 3.01615 0 P 1 0;0=23,1=2
P 2.24606004 3.06615 0 P 1 0;0=23,1=2
P 2.24606004 3.11615 0 P 1 0;0=23,1=2
P 2.24606004 3.16615 0 P 1 0;0=23,1=2
P 2.24606004 3.21615 0 P 1 0;0=23,1=2
P 2.24606004 3.26615 0 P 1 0;0=23,1=2
P 2.24606004 3.31615 0 P 1 0;0=23,1=2
P 2.24606004 3.36615 0 P 1 0;0=23,1=2
P 2.24606004 3.41615 0 P 1 0;0=23,1=2
P 2.24606004 3.46615 0 P 1 0;0=23,1=2
P 2.24606004 3.51615 0 P 1 0;0=23,1=2
P 2.24606004 3.61615 0 P 1 0;0=23,1=2
P 2.24606004 3.66615 0 P 1 0;0=23,1=2
P 2.24606004 3.71615 0 P 1 0;0=23,1=2
P 2.24606004 3.76615 0 P 1 0;0=23,1=2
P 2.24606004 3.81615 0 P 1 0;0=23,1=2
P 2.24606004 3.86615 0 P 1 0;0=23,1=2
P 2.29606004 1.86615 0 P 1 0;0=23,1=2
P 2.29606004 1.91615 0 P 1 0;0=23,1=2
P 2.29606004 1.96615 0 P 1 0;0=23,1=2
P 2.29606004 2.01615 0 P 1 0;0=23,1=2
P 2.29606004 2.06615 0 P 1 0;0=23,1=2
P 2.29606004 2.11615 0 P 1 0;0=23,1=2
P 2.29606004 2.16615 0 P 1 0;0=23,1=2
P 2.29606004 2.21615 0 P 1 0;0=23,1=2
P 2.29606004 2.26615 0 P 1 0;0=23,1=2
P 2.29606004 2.31615 0 P 1 0;0=23,1=2
P 2.29606004 2.36615 0 P 1 0;0=23,1=2
P 2.29606004 2.41615 0 P 1 0;0=23,1=2
P 2.29606004 2.46615 0 P 1 0;0=23,1=2
P 2.29606004 2.51615 0 P 1 0;0=23,1=2
P 2.29606004 2.56615 0 P 1 0;0=23,1=2
P 2.29606004 2.61615 0 P 1 0;0=23,1=2
P 2.29606004 2.66615 0 P 1 0;0=23,1=2
P 2.29606004 2.71615 0 P 1 0;0=23,1=2
P 2.29606004 2.76615 0 P 1 0;0=23,1=2
P 2.29606004 2.81615 0 P 1 0;0=23,1=2
P 2.29606004 2.91615 0 P 1 0;0=23,1=2
P 2.29606004 2.96615 0 P 1 0;0=23,1=2
P 2.29606004 3.01615 0 P 1 0;0=23,1=2
P 2.29606004 3.06615 0 P 1 0;0=23,1=2
P 2.29606004 3.11615 0 P 1 0;0=23,1=2
P 2.29606004 3.16615 0 P 1 0;0=23,1=2
P 2.29606004 3.21615 0 P 1 0;0=23,1=2
P 2.29606004 3.26615 0 P 1 0;0=23,1=2
P 2.29606004 3.31615 0 P 1 0;0=23,1=2
P 2.29606004 3.36615 0 P 1 0;0=23,1=2
P 2.29606004 3.41615 0 P 1 0;0=23,1=2
P 2.29606004 3.46615 0 P 1 0;0=23,1=2
P 2.29606004 3.51615 0 P 1 0;0=23,1=2
P 2.29606004 3.61615 0 P 1 0;0=23,1=2
P 2.29606004 3.66615 0 P 1 0;0=23,1=2
P 2.29606004 3.71615 0 P 1 0;0=23,1=2
P 2.29606004 3.76615 0 P 1 0;0=23,1=2
P 2.29606004 3.81615 0 P 1 0;0=23,1=2
P 2.29606004 3.86615 0 P 1 0;0=23,1=2
P 2.34606004 1.86615 0 P 1 0;0=23,1=2
P 2.34606004 1.91615 0 P 1 0;0=23,1=2
P 2.34606004 1.96615 0 P 1 0;0=23,1=2
P 2.34606004 2.01615 0 P 1 0;0=23,1=2
P 2.34606004 2.06615 0 P 1 0;0=23,1=2
P 2.34606004 2.11615 0 P 1 0;0=23,1=2
P 2.34606004 2.16615 0 P 1 0;0=23,1=2
P 2.34606004 2.21615 0 P 1 0;0=23,1=2
P 2.34606004 2.26615 0 P 1 0;0=23,1=2
P 2.34606004 2.31615 0 P 1 0;0=23,1=2
P 2.34606004 2.36615 0 P 1 0;0=23,1=2
P 2.34606004 2.41615 0 P 1 0;0=23,1=2
P 2.34606004 2.46615 0 P 1 0;0=23,1=2
P 2.34606004 2.51615 0 P 1 0;0=23,1=2
P 2.34606004 2.56615 0 P 1 0;0=23,1=2
P 2.34606004 2.61615 0 P 1 0;0=23,1=2
P 2.34606004 2.66615 0 P 1 0;0=23,1=2
P 2.34606004 2.71615 0 P 1 0;0=23,1=2
P 2.34606004 2.76615 0 P 1 0;0=23,1=2
P 2.34606004 2.81615 0 P 1 0;0=23,1=2
P 2.34606004 2.86615 0 P 1 0;0=23,1=2
P 2.34606004 2.91615 0 P 1 0;0=23,1=2
P 2.34606004 2.96615 0 P 1 0;0=23,1=2
P 2.34606004 3.01615 0 P 1 0;0=23,1=2
P 2.34606004 3.06615 0 P 1 0;0=23,1=2
P 2.34606004 3.11615 0 P 1 0;0=23,1=2
P 2.34606004 3.16615 0 P 1 0;0=23,1=2
P 2.34606004 3.21615 0 P 1 0;0=23,1=2
P 2.34606004 3.36615 0 P 1 0;0=23,1=2
P 2.34606004 3.51615 0 P 1 0;0=23,1=2
P 2.34606004 3.56615 0 P 1 0;0=23,1=2
P 2.34606004 3.61615 0 P 1 0;0=23,1=2
P 2.34606004 3.76615 0 P 1 0;0=23,1=2
P 2.39606004 1.86615 0 P 1 0;0=23,1=2
P 2.39606004 1.91615 0 P 1 0;0=23,1=2
P 2.39606004 1.96615 0 P 1 0;0=23,1=2
P 2.39606004 2.01615 0 P 1 0;0=23,1=2
P 2.39606004 2.06615 0 P 1 0;0=23,1=2
P 2.39606004 2.11615 0 P 1 0;0=23,1=2
P 2.39606004 2.16615 0 P 1 0;0=23,1=2
P 2.39606004 2.21615 0 P 1 0;0=23,1=2
P 2.39606004 2.26615 0 P 1 0;0=23,1=2
P 2.39606004 2.31615 0 P 1 0;0=23,1=2
P 2.39606004 2.36615 0 P 1 0;0=23,1=2
P 2.39606004 2.41615 0 P 1 0;0=23,1=2
P 2.39606004 2.46615 0 P 1 0;0=23,1=2
P 2.39606004 2.51615 0 P 1 0;0=23,1=2
P 2.39606004 2.56615 0 P 1 0;0=23,1=2
P 2.39606004 2.61615 0 P 1 0;0=23,1=2
P 2.39606004 2.66615 0 P 1 0;0=23,1=2
P 2.39606004 2.71615 0 P 1 0;0=23,1=2
P 2.39606004 2.76615 0 P 1 0;0=23,1=2
P 2.39606004 2.81615 0 P 1 0;0=23,1=2
P 2.39606004 2.86615 0 P 1 0;0=23,1=2
P 2.39606004 2.91615 0 P 1 0;0=23,1=2
P 2.39606004 2.96615 0 P 1 0;0=23,1=2
P 2.39606004 3.01615 0 P 1 0;0=23,1=2
P 2.39606004 3.06615 0 P 1 0;0=23,1=2
P 2.39606004 3.11615 0 P 1 0;0=23,1=2
P 2.39606004 3.16615 0 P 1 0;0=23,1=2
P 2.39606004 3.21615 0 P 1 0;0=23,1=2
P 2.39606004 3.26615 0 P 1 0;0=23,1=2
P 2.39606004 3.41615 0 P 1 0;0=23,1=2
P 2.39606004 3.56615 0 P 1 0;0=23,1=2
P 2.39606004 3.71615 0 P 1 0;0=23,1=2
P 2.39606004 3.86615 0 P 1 0;0=23,1=2
P 2.44606004 1.86615 0 P 1 0;0=23,1=2
P 2.44606004 1.91615 0 P 1 0;0=23,1=2
P 2.44606004 1.96615 0 P 1 0;0=23,1=2
P 2.44606004 2.01615 0 P 1 0;0=23,1=2
P 2.44606004 2.06615 0 P 1 0;0=23,1=2
P 2.44606004 2.11615 0 P 1 0;0=23,1=2
P 2.44606004 2.16615 0 P 1 0;0=23,1=2
P 2.44606004 2.21615 0 P 1 0;0=23,1=2
P 2.44606004 2.26615 0 P 1 0;0=23,1=2
P 2.44606004 2.31615 0 P 1 0;0=23,1=2
P 2.44606004 2.36615 0 P 1 0;0=23,1=2
P 2.44606004 2.41615 0 P 1 0;0=23,1=2
P 2.44606004 2.46615 0 P 1 0;0=23,1=2
P 2.44606004 2.51615 0 P 1 0;0=23,1=2
P 2.44606004 2.56615 0 P 1 0;0=23,1=2
P 2.44606004 2.61615 0 P 1 0;0=23,1=2
P 2.44606004 2.66615 0 P 1 0;0=23,1=2
P 2.44606004 2.71615 0 P 1 0;0=23,1=2
P 2.44606004 2.76615 0 P 1 0;0=23,1=2
P 2.44606004 2.81615 0 P 1 0;0=23,1=2
P 2.44606004 2.86615 0 P 1 0;0=23,1=2
P 2.44606004 2.91615 0 P 1 0;0=23,1=2
P 2.44606004 2.96615 0 P 1 0;0=23,1=2
P 2.44606004 3.01615 0 P 1 0;0=23,1=2
P 2.44606004 3.06615 0 P 1 0;0=23,1=2
P 2.44606004 3.11615 0 P 1 0;0=23,1=2
P 2.44606004 3.16615 0 P 1 0;0=23,1=2
P 2.44606004 3.21615 0 P 1 0;0=23,1=2
P 2.44606004 3.36615 0 P 1 0;0=23,1=2
P 2.44606004 3.51615 0 P 1 0;0=23,1=2
P 2.44606004 3.56615 0 P 1 0;0=23,1=2
P 2.44606004 3.61615 0 P 1 0;0=23,1=2
P 2.44606004 3.76615 0 P 1 0;0=23,1=2
P 2.49606004 1.86615 0 P 1 0;0=23,1=2
P 2.49606004 1.91615 0 P 1 0;0=23,1=2
P 2.49606004 1.96615 0 P 1 0;0=23,1=2
P 2.49606004 2.01615 0 P 1 0;0=23,1=2
P 2.49606004 2.06615 0 P 1 0;0=23,1=2
P 2.49606004 2.11615 0 P 1 0;0=23,1=2
P 2.49606004 2.16615 0 P 1 0;0=23,1=2
P 2.49606004 2.21615 0 P 1 0;0=23,1=2
P 2.49606004 2.26615 0 P 1 0;0=23,1=2
P 2.49606004 2.31615 0 P 1 0;0=23,1=2
P 2.49606004 2.36615 0 P 1 0;0=23,1=2
P 2.49606004 2.41615 0 P 1 0;0=23,1=2
P 2.49606004 2.46615 0 P 1 0;0=23,1=2
P 2.49606004 2.51615 0 P 1 0;0=23,1=2
P 2.49606004 2.56615 0 P 1 0;0=23,1=2
P 2.49606004 2.61615 0 P 1 0;0=23,1=2
P 2.49606004 2.66615 0 P 1 0;0=23,1=2
P 2.49606004 2.71615 0 P 1 0;0=23,1=2
P 2.49606004 2.76615 0 P 1 0;0=23,1=2
P 2.49606004 2.81615 0 P 1 0;0=23,1=2
P 2.49606004 2.86615 0 P 1 0;0=23,1=2
P 2.49606004 2.91615 0 P 1 0;0=23,1=2
P 2.49606004 2.96615 0 P 1 0;0=23,1=2
P 2.49606004 3.01615 0 P 1 0;0=23,1=2
P 2.49606004 3.06615 0 P 1 0;0=23,1=2
P 2.49606004 3.11615 0 P 1 0;0=23,1=2
P 2.49606004 3.16615 0 P 1 0;0=23,1=2
P 2.49606004 3.21615 0 P 1 0;0=23,1=2
P 2.49606004 3.26615 0 P 1 0;0=23,1=2
P 2.49606004 3.41615 0 P 1 0;0=23,1=2
P 2.49606004 3.56615 0 P 1 0;0=23,1=2
P 2.49606004 3.71615 0 P 1 0;0=23,1=2
P 2.49606004 3.86615 0 P 1 0;0=23,1=2
P 4.58268002 1.86615 0 P 1 0;0=23,1=2
P 4.58268002 2.01615 0 P 1 0;0=23,1=2
P 4.58268002 2.31615 0 P 1 0;0=23,1=2
P 4.58268002 2.46615 0 P 1 0;0=23,1=2
P 4.58268002 2.51615 0 P 1 0;0=23,1=2
P 4.58268002 2.66615 0 P 1 0;0=23,1=2
P 4.58268002 2.91615 0 P 1 0;0=23,1=2
P 4.58268002 3.06615 0 P 1 0;0=23,1=2
P 4.58268002 3.21615 0 P 1 0;0=23,1=2
P 4.58268002 3.36615 0 P 1 0;0=23,1=2
P 4.58268002 3.51615 0 P 1 0;0=23,1=2
P 4.58268002 3.66615 0 P 1 0;0=23,1=2
P 4.58268002 3.81615 0 P 1 0;0=23,1=2
P 4.63268002 1.96615 0 P 1 0;0=23,1=2
P 4.63268002 2.11615 0 P 1 0;0=23,1=2
P 4.63268002 2.16615 0 P 1 0;0=23,1=2
P 4.63268002 2.21615 0 P 1 0;0=23,1=2
P 4.63268002 2.36615 0 P 1 0;0=23,1=2
P 4.63268002 2.51615 0 P 1 0;0=23,1=2
P 4.63268002 2.56615 0 P 1 0;0=23,1=2
P 4.63268002 2.71615 0 P 1 0;0=23,1=2
P 4.63268002 2.76615 0 P 1 0;0=23,1=2
P 4.63268002 2.91615 0 P 1 0;0=23,1=2
P 4.63268002 3.06615 0 P 1 0;0=23,1=2
P 4.63268002 3.21615 0 P 1 0;0=23,1=2
P 4.63268002 3.36615 0 P 1 0;0=23,1=2
P 4.63268002 3.51615 0 P 1 0;0=23,1=2
P 4.63268002 3.66615 0 P 1 0;0=23,1=2
P 4.63268002 3.81615 0 P 1 0;0=23,1=2
P 4.68268002 1.86615 0 P 1 0;0=23,1=2
P 4.68268002 2.01615 0 P 1 0;0=23,1=2
P 4.68268002 2.16615 0 P 1 0;0=23,1=2
P 4.68268002 2.31615 0 P 1 0;0=23,1=2
P 4.68268002 2.46615 0 P 1 0;0=23,1=2
P 4.68268002 2.51615 0 P 1 0;0=23,1=2
P 4.68268002 2.66615 0 P 1 0;0=23,1=2
P 4.68268002 2.91615 0 P 1 0;0=23,1=2
P 4.68268002 3.06615 0 P 1 0;0=23,1=2
P 4.68268002 3.21615 0 P 1 0;0=23,1=2
P 4.68268002 3.36615 0 P 1 0;0=23,1=2
P 4.68268002 3.51615 0 P 1 0;0=23,1=2
P 4.68268002 3.66615 0 P 1 0;0=23,1=2
P 4.68268002 3.81615 0 P 1 0;0=23,1=2
P 4.73268002 1.96615 0 P 1 0;0=23,1=2
P 4.73268002 2.11615 0 P 1 0;0=23,1=2
P 4.73268002 2.16615 0 P 1 0;0=23,1=2
P 4.73268002 2.21615 0 P 1 0;0=23,1=2
P 4.73268002 2.36615 0 P 1 0;0=23,1=2
P 4.73268002 2.51615 0 P 1 0;0=23,1=2
P 4.73268002 2.56615 0 P 1 0;0=23,1=2
P 4.73268002 2.71615 0 P 1 0;0=23,1=2
P 4.73268002 2.76615 0 P 1 0;0=23,1=2
P 4.73268002 2.91615 0 P 1 0;0=23,1=2
P 4.73268002 3.06615 0 P 1 0;0=23,1=2
P 4.73268002 3.21615 0 P 1 0;0=23,1=2
P 4.73268002 3.36615 0 P 1 0;0=23,1=2
P 4.73268002 3.51615 0 P 1 0;0=23,1=2
P 4.73268002 3.66615 0 P 1 0;0=23,1=2
P 4.73268002 3.81615 0 P 1 0;0=23,1=2
P 4.78268002 1.86615 0 P 1 0;0=23,1=2
P 4.78268002 1.91615 0 P 1 0;0=23,1=2
P 4.78268002 1.96615 0 P 1 0;0=23,1=2
P 4.78268002 2.01615 0 P 1 0;0=23,1=2
P 4.78268002 2.06615 0 P 1 0;0=23,1=2
P 4.78268002 2.11615 0 P 1 0;0=23,1=2
P 4.78268002 2.16615 0 P 1 0;0=23,1=2
P 4.78268002 2.21615 0 P 1 0;0=23,1=2
P 4.78268002 2.26615 0 P 1 0;0=23,1=2
P 4.78268002 2.31615 0 P 1 0;0=23,1=2
P 4.78268002 2.36615 0 P 1 0;0=23,1=2
P 4.78268002 2.41615 0 P 1 0;0=23,1=2
P 4.78268002 2.46615 0 P 1 0;0=23,1=2
P 4.78268002 2.51615 0 P 1 0;0=23,1=2
P 4.78268002 2.56615 0 P 1 0;0=23,1=2
P 4.78268002 2.61615 0 P 1 0;0=23,1=2
P 4.78268002 2.66615 0 P 1 0;0=23,1=2
P 4.78268002 2.76615 0 P 1 0;0=23,1=2
P 4.78268002 2.91615 0 P 1 0;0=23,1=2
P 4.78268002 3.06615 0 P 1 0;0=23,1=2
P 4.78268002 3.21615 0 P 1 0;0=23,1=2
P 4.78268002 3.36615 0 P 1 0;0=23,1=2
P 4.78268002 3.51615 0 P 1 0;0=23,1=2
P 4.78268002 3.66615 0 P 1 0;0=23,1=2
P 4.78268002 3.81615 0 P 1 0;0=23,1=2
P 4.83268002 2.91615 0 P 1 0;0=23,1=2
P 4.83268002 3.06615 0 P 1 0;0=23,1=2
P 4.83268002 3.21615 0 P 1 0;0=23,1=2
P 4.83268002 3.36615 0 P 1 0;0=23,1=2
P 4.83268002 3.51615 0 P 1 0;0=23,1=2
P 4.83268002 3.66615 0 P 1 0;0=23,1=2
P 4.83268002 3.81615 0 P 1 0;0=23,1=2
P 4.88268002 1.86615 0 P 1 0;0=23,1=2
P 4.88268002 1.91615 0 P 1 0;0=23,1=2
P 4.88268002 1.96615 0 P 1 0;0=23,1=2
P 4.88268002 2.01615 0 P 1 0;0=23,1=2
P 4.88268002 2.06615 0 P 1 0;0=23,1=2
P 4.88268002 2.11615 0 P 1 0;0=23,1=2
P 4.88268002 2.21615 0 P 1 0;0=23,1=2
P 4.88268002 2.26615 0 P 1 0;0=23,1=2
P 4.88268002 2.31615 0 P 1 0;0=23,1=2
P 4.88268002 2.36615 0 P 1 0;0=23,1=2
P 4.88268002 2.41615 0 P 1 0;0=23,1=2
P 4.88268002 2.46615 0 P 1 0;0=23,1=2
P 4.88268002 2.51615 0 P 1 0;0=23,1=2
P 4.88268002 2.56615 0 P 1 0;0=23,1=2
P 4.88268002 2.61615 0 P 1 0;0=23,1=2
P 4.88268002 2.66615 0 P 1 0;0=23,1=2
P 4.88268002 2.76615 0 P 1 0;0=23,1=2
P 4.88268002 2.91615 0 P 1 0;0=23,1=2
P 4.88268002 3.06615 0 P 1 0;0=23,1=2
P 4.88268002 3.21615 0 P 1 0;0=23,1=2
P 4.88268002 3.36615 0 P 1 0;0=23,1=2
P 4.88268002 3.51615 0 P 1 0;0=23,1=2
P 4.88268002 3.66615 0 P 1 0;0=23,1=2
P 4.88268002 3.81615 0 P 1 0;0=23,1=2
P 4.93268002 1.96615 0 P 1 0;0=23,1=2
P 4.93268002 2.11615 0 P 1 0;0=23,1=2
P 4.93268002 2.16615 0 P 1 0;0=23,1=2
P 4.93268002 2.21615 0 P 1 0;0=23,1=2
P 4.93268002 2.36615 0 P 1 0;0=23,1=2
P 4.93268002 2.51615 0 P 1 0;0=23,1=2
P 4.93268002 2.56615 0 P 1 0;0=23,1=2
P 4.93268002 2.71615 0 P 1 0;0=23,1=2
P 4.93268002 2.76615 0 P 1 0;0=23,1=2
P 4.93268002 2.91615 0 P 1 0;0=23,1=2
P 4.93268002 3.06615 0 P 1 0;0=23,1=2
P 4.93268002 3.21615 0 P 1 0;0=23,1=2
P 4.93268002 3.36615 0 P 1 0;0=23,1=2
P 4.93268002 3.51615 0 P 1 0;0=23,1=2
P 4.93268002 3.66615 0 P 1 0;0=23,1=2
P 4.93268002 3.81615 0 P 1 0;0=23,1=2
P 4.98268002 1.86615 0 P 1 0;0=23,1=2
P 4.98268002 2.01615 0 P 1 0;0=23,1=2
P 4.98268002 2.16615 0 P 1 0;0=23,1=2
P 4.98268002 2.31615 0 P 1 0;0=23,1=2
P 4.98268002 2.46615 0 P 1 0;0=23,1=2
P 4.98268002 2.51615 0 P 1 0;0=23,1=2
P 4.98268002 2.66615 0 P 1 0;0=23,1=2
P 4.98268002 2.76615 0 P 1 0;0=23,1=2
P 4.98268002 2.91615 0 P 1 0;0=23,1=2
P 4.98268002 3.06615 0 P 1 0;0=23,1=2
P 4.98268002 3.21615 0 P 1 0;0=23,1=2
P 4.98268002 3.36615 0 P 1 0;0=23,1=2
P 4.98268002 3.51615 0 P 1 0;0=23,1=2
P 4.98268002 3.66615 0 P 1 0;0=23,1=2
P 4.98268002 3.81615 0 P 1 0;0=23,1=2
P 5.03268002 1.96615 0 P 1 0;0=23,1=2
P 5.03268002 2.11615 0 P 1 0;0=23,1=2
P 5.03268002 2.21615 0 P 1 0;0=23,1=2
P 5.03268002 2.36615 0 P 1 0;0=23,1=2
P 5.03268002 2.41615 0 P 1 0;0=23,1=2
P 5.03268002 2.56615 0 P 1 0;0=23,1=2
P 5.03268002 2.71615 0 P 1 0;0=23,1=2
P 5.03268002 2.76615 0 P 1 0;0=23,1=2
P 5.03268002 2.91615 0 P 1 0;0=23,1=2
P 5.03268002 3.06615 0 P 1 0;0=23,1=2
P 5.03268002 3.21615 0 P 1 0;0=23,1=2
P 5.03268002 3.36615 0 P 1 0;0=23,1=2
P 5.03268002 3.51615 0 P 1 0;0=23,1=2
P 5.03268002 3.66615 0 P 1 0;0=23,1=2
P 5.08268002 1.86615 0 P 1 0;0=23,1=2
P 5.08268002 2.01615 0 P 1 0;0=23,1=2
P 5.08268002 2.16615 0 P 1 0;0=23,1=2
P 5.08268002 2.31615 0 P 1 0;0=23,1=2
P 5.08268002 2.46615 0 P 1 0;0=23,1=2
P 5.08268002 2.51615 0 P 1 0;0=23,1=2
P 5.08268002 2.66615 0 P 1 0;0=23,1=2
P 5.08268002 2.76615 0 P 1 0;0=23,1=2
P 8 2.71615 0 P 1 0;0=23,1=2
P 8 2.76615 0 P 1 0;0=23,1=2
P 8 2.81615 0 P 1 0;0=23,1=2
P 8 2.86615 0 P 1 0;0=23,1=2
P 8 3.41615 0 P 1 0;0=23,1=2
P 8 3.56615 0 P 1 0;0=23,1=2
P 8.05 1.86615 0 P 1 0;0=23,1=2
P 8.05 1.91615 0 P 1 0;0=23,1=2
P 8.05 1.96615 0 P 1 0;0=23,1=2
P 8.05 2.01615 0 P 1 0;0=23,1=2
P 8.05 2.06615 0 P 1 0;0=23,1=2
P 8.05 2.11615 0 P 1 0;0=23,1=2
P 8.05 2.16615 0 P 1 0;0=23,1=2
P 8.05 2.21615 0 P 1 0;0=23,1=2
P 8.05 2.26615 0 P 1 0;0=23,1=2
P 8.05 2.31615 0 P 1 0;0=23,1=2
P 8.05 2.36615 0 P 1 0;0=23,1=2
P 8.05 2.41615 0 P 1 0;0=23,1=2
P 8.05 2.46615 0 P 1 0;0=23,1=2
P 8.05 2.51615 0 P 1 0;0=23,1=2
P 8.05 2.56615 0 P 1 0;0=23,1=2
P 8.05 2.61615 0 P 1 0;0=23,1=2
P 8.05 2.66615 0 P 1 0;0=23,1=2
P 8.05 2.71615 0 P 1 0;0=23,1=2
P 8.05 2.76615 0 P 1 0;0=23,1=2
P 8.05 2.81615 0 P 1 0;0=23,1=2
P 8.05 2.86615 0 P 1 0;0=23,1=2
P 8.05 2.91615 0 P 1 0;0=23,1=2
P 8.05 2.96615 0 P 1 0;0=23,1=2
P 8.05 3.01615 0 P 1 0;0=23,1=2
P 8.05 3.06615 0 P 1 0;0=23,1=2
P 8.05 3.11615 0 P 1 0;0=23,1=2
P 8.05 3.16615 0 P 1 0;0=23,1=2
P 8.05 3.21615 0 P 1 0;0=23,1=2
P 8.05 3.26615 0 P 1 0;0=23,1=2
P 8.05 3.41615 0 P 1 0;0=23,1=2
P 8.05 3.46615 0 P 1 0;0=23,1=2
P 8.05 3.51615 0 P 1 0;0=23,1=2
P 8.05 3.56615 0 P 1 0;0=23,1=2
P 8.05 3.71615 0 P 1 0;0=23,1=2
P 8.05 3.86615 0 P 1 0;0=23,1=2
P 8.1 1.86615 0 P 1 0;0=23,1=2
P 8.1 1.91615 0 P 1 0;0=23,1=2
P 8.1 1.96615 0 P 1 0;0=23,1=2
P 8.1 2.01615 0 P 1 0;0=23,1=2
P 8.1 2.06615 0 P 1 0;0=23,1=2
P 8.1 2.11615 0 P 1 0;0=23,1=2
P 8.1 2.16615 0 P 1 0;0=23,1=2
P 8.1 2.21615 0 P 1 0;0=23,1=2
P 8.1 2.26615 0 P 1 0;0=23,1=2
P 8.1 2.31615 0 P 1 0;0=23,1=2
P 8.1 2.36615 0 P 1 0;0=23,1=2
P 8.1 2.41615 0 P 1 0;0=23,1=2
P 8.1 2.46615 0 P 1 0;0=23,1=2
P 8.1 2.51615 0 P 1 0;0=23,1=2
P 8.1 2.56615 0 P 1 0;0=23,1=2
P 8.1 2.61615 0 P 1 0;0=23,1=2
P 8.1 2.66615 0 P 1 0;0=23,1=2
P 8.1 2.71615 0 P 1 0;0=23,1=2
P 8.1 2.76615 0 P 1 0;0=23,1=2
P 8.1 2.81615 0 P 1 0;0=23,1=2
P 8.1 2.86615 0 P 1 0;0=23,1=2
P 8.1 2.91615 0 P 1 0;0=23,1=2
P 8.1 2.96615 0 P 1 0;0=23,1=2
P 8.1 3.01615 0 P 1 0;0=23,1=2
P 8.1 3.06615 0 P 1 0;0=23,1=2
P 8.1 3.11615 0 P 1 0;0=23,1=2
P 8.1 3.16615 0 P 1 0;0=23,1=2
P 8.1 3.21615 0 P 1 0;0=23,1=2
P 8.1 3.36615 0 P 1 0;0=23,1=2
P 8.1 3.51615 0 P 1 0;0=23,1=2
P 8.1 3.61615 0 P 1 0;0=23,1=2
P 8.1 3.76615 0 P 1 0;0=23,1=2
P 8.15 1.86615 0 P 1 0;0=23,1=2
P 8.15 1.91615 0 P 1 0;0=23,1=2
P 8.15 1.96615 0 P 1 0;0=23,1=2
P 8.15 2.01615 0 P 1 0;0=23,1=2
P 8.15 2.06615 0 P 1 0;0=23,1=2
P 8.15 2.11615 0 P 1 0;0=23,1=2
P 8.15 2.16615 0 P 1 0;0=23,1=2
P 8.15 2.21615 0 P 1 0;0=23,1=2
P 8.15 2.26615 0 P 1 0;0=23,1=2
P 8.15 2.31615 0 P 1 0;0=23,1=2
P 8.15 2.36615 0 P 1 0;0=23,1=2
P 8.15 2.41615 0 P 1 0;0=23,1=2
P 8.15 2.46615 0 P 1 0;0=23,1=2
P 8.15 2.56615 0 P 1 0;0=23,1=2
P 8.15 2.61615 0 P 1 0;0=23,1=2
P 8.15 2.66615 0 P 1 0;0=23,1=2
P 8.15 2.71615 0 P 1 0;0=23,1=2
P 8.15 2.76615 0 P 1 0;0=23,1=2
P 8.15 2.81615 0 P 1 0;0=23,1=2
P 8.15 2.86615 0 P 1 0;0=23,1=2
P 8.15 2.91615 0 P 1 0;0=23,1=2
P 8.15 2.96615 0 P 1 0;0=23,1=2
P 8.15 3.01615 0 P 1 0;0=23,1=2
P 8.15 3.06615 0 P 1 0;0=23,1=2
P 8.15 3.11615 0 P 1 0;0=23,1=2
P 8.15 3.16615 0 P 1 0;0=23,1=2
P 8.15 3.21615 0 P 1 0;0=23,1=2
P 8.15 3.26615 0 P 1 0;0=23,1=2
P 8.15 3.41615 0 P 1 0;0=23,1=2
P 8.15 3.56615 0 P 1 0;0=23,1=2
P 8.15 3.71615 0 P 1 0;0=23,1=2
P 8.15 3.86615 0 P 1 0;0=23,1=2
P 8.2 1.86615 0 P 1 0;0=23,1=2
P 8.2 1.91615 0 P 1 0;0=23,1=2
P 8.2 1.96615 0 P 1 0;0=23,1=2
P 8.2 2.01615 0 P 1 0;0=23,1=2
P 8.2 2.06615 0 P 1 0;0=23,1=2
P 8.2 2.11615 0 P 1 0;0=23,1=2
P 8.2 2.16615 0 P 1 0;0=23,1=2
P 8.2 2.21615 0 P 1 0;0=23,1=2
P 8.2 2.26615 0 P 1 0;0=23,1=2
P 8.2 2.31615 0 P 1 0;0=23,1=2
P 8.2 2.36615 0 P 1 0;0=23,1=2
P 8.2 2.41615 0 P 1 0;0=23,1=2
P 8.2 2.46615 0 P 1 0;0=23,1=2
P 8.2 2.51615 0 P 1 0;0=23,1=2
P 8.2 2.56615 0 P 1 0;0=23,1=2
P 8.2 2.61615 0 P 1 0;0=23,1=2
P 8.2 2.66615 0 P 1 0;0=23,1=2
P 8.2 2.71615 0 P 1 0;0=23,1=2
P 8.2 2.76615 0 P 1 0;0=23,1=2
P 8.2 2.81615 0 P 1 0;0=23,1=2
P 8.2 2.86615 0 P 1 0;0=23,1=2
P 8.2 2.91615 0 P 1 0;0=23,1=2
P 8.2 2.96615 0 P 1 0;0=23,1=2
P 8.2 3.01615 0 P 1 0;0=23,1=2
P 8.2 3.06615 0 P 1 0;0=23,1=2
P 8.2 3.11615 0 P 1 0;0=23,1=2
P 8.2 3.16615 0 P 1 0;0=23,1=2
P 8.2 3.21615 0 P 1 0;0=23,1=2
P 8.2 3.36615 0 P 1 0;0=23,1=2
P 8.2 3.51615 0 P 1 0;0=23,1=2
P 8.2 3.56615 0 P 1 0;0=23,1=2
P 8.2 3.61615 0 P 1 0;0=23,1=2
P 8.2 3.76615 0 P 1 0;0=23,1=2
P 8.25 1.86615 0 P 1 0;0=23,1=2
P 8.25 1.91615 0 P 1 0;0=23,1=2
P 8.25 1.96615 0 P 1 0;0=23,1=2
P 8.25 2.01615 0 P 1 0;0=23,1=2
P 8.25 2.06615 0 P 1 0;0=23,1=2
P 8.25 2.11615 0 P 1 0;0=23,1=2
P 8.25 2.16615 0 P 1 0;0=23,1=2
P 8.25 2.21615 0 P 1 0;0=23,1=2
P 8.25 2.26615 0 P 1 0;0=23,1=2
P 8.25 2.31615 0 P 1 0;0=23,1=2
P 8.25 2.36615 0 P 1 0;0=23,1=2
P 8.25 2.41615 0 P 1 0;0=23,1=2
P 8.25 2.46615 0 P 1 0;0=23,1=2
P 8.25 2.51615 0 P 1 0;0=23,1=2
P 8.25 2.56615 0 P 1 0;0=23,1=2
P 8.25 2.61615 0 P 1 0;0=23,1=2
P 8.25 2.66615 0 P 1 0;0=23,1=2
P 8.25 2.71615 0 P 1 0;0=23,1=2
P 8.25 2.76615 0 P 1 0;0=23,1=2
P 8.25 2.81615 0 P 1 0;0=23,1=2
P 8.25 2.91615 0 P 1 0;0=23,1=2
P 8.25 2.96615 0 P 1 0;0=23,1=2
P 8.25 3.01615 0 P 1 0;0=23,1=2
P 8.25 3.06615 0 P 1 0;0=23,1=2
P 8.25 3.11615 0 P 1 0;0=23,1=2
P 8.25 3.16615 0 P 1 0;0=23,1=2
P 8.25 3.21615 0 P 1 0;0=23,1=2
P 8.25 3.26615 0 P 1 0;0=23,1=2
P 8.25 3.31615 0 P 1 0;0=23,1=2
P 8.25 3.36615 0 P 1 0;0=23,1=2
P 8.25 3.41615 0 P 1 0;0=23,1=2
P 8.25 3.46615 0 P 1 0;0=23,1=2
P 8.25 3.51615 0 P 1 0;0=23,1=2
P 8.25 3.61615 0 P 1 0;0=23,1=2
P 8.25 3.66615 0 P 1 0;0=23,1=2
P 8.25 3.71615 0 P 1 0;0=23,1=2
P 8.25 3.76615 0 P 1 0;0=23,1=2
P 8.25 3.81615 0 P 1 0;0=23,1=2
P 8.25 3.86615 0 P 1 0;0=23,1=2
P 8.3 1.86615 0 P 1 0;0=23,1=2
P 8.3 1.91615 0 P 1 0;0=23,1=2
P 8.3 1.96615 0 P 1 0;0=23,1=2
P 8.3 2.01615 0 P 1 0;0=23,1=2
P 8.3 2.06615 0 P 1 0;0=23,1=2
P 8.3 2.11615 0 P 1 0;0=23,1=2
P 8.3 2.16615 0 P 1 0;0=23,1=2
P 8.3 2.21615 0 P 1 0;0=23,1=2
P 8.3 2.26615 0 P 1 0;0=23,1=2
P 8.3 2.31615 0 P 1 0;0=23,1=2
P 8.3 2.36615 0 P 1 0;0=23,1=2
P 8.3 2.41615 0 P 1 0;0=23,1=2
P 8.3 2.46615 0 P 1 0;0=23,1=2
P 8.3 2.51615 0 P 1 0;0=23,1=2
P 8.3 2.56615 0 P 1 0;0=23,1=2
P 8.3 2.61615 0 P 1 0;0=23,1=2
P 8.3 2.66615 0 P 1 0;0=23,1=2
P 8.3 2.71615 0 P 1 0;0=23,1=2
P 8.3 2.76615 0 P 1 0;0=23,1=2
P 8.3 2.81615 0 P 1 0;0=23,1=2
P 8.3 2.91615 0 P 1 0;0=23,1=2
P 8.3 2.96615 0 P 1 0;0=23,1=2
P 8.3 3.01615 0 P 1 0;0=23,1=2
P 8.3 3.06615 0 P 1 0;0=23,1=2
P 8.3 3.11615 0 P 1 0;0=23,1=2
P 8.3 3.16615 0 P 1 0;0=23,1=2
P 8.3 3.21615 0 P 1 0;0=23,1=2
P 8.3 3.26615 0 P 1 0;0=23,1=2
P 8.3 3.31615 0 P 1 0;0=23,1=2
P 8.3 3.36615 0 P 1 0;0=23,1=2
P 8.3 3.41615 0 P 1 0;0=23,1=2
P 8.3 3.46615 0 P 1 0;0=23,1=2
P 8.3 3.51615 0 P 1 0;0=23,1=2
P 8.3 3.61615 0 P 1 0;0=23,1=2
P 8.3 3.66615 0 P 1 0;0=23,1=2
P 8.3 3.71615 0 P 1 0;0=23,1=2
P 8.3 3.76615 0 P 1 0;0=23,1=2
P 8.3 3.81615 0 P 1 0;0=23,1=2
P 8.3 3.86615 0 P 1 0;0=23,1=2
P 8.35 1.86615 0 P 1 0;0=23,1=2
P 8.35 1.91615 0 P 1 0;0=23,1=2
P 8.35 1.96615 0 P 1 0;0=23,1=2
P 8.35 2.01615 0 P 1 0;0=23,1=2
P 8.35 2.06615 0 P 1 0;0=23,1=2
P 8.35 2.11615 0 P 1 0;0=23,1=2
P 8.35 2.16615 0 P 1 0;0=23,1=2
P 8.35 2.21615 0 P 1 0;0=23,1=2
P 8.35 2.26615 0 P 1 0;0=23,1=2
P 8.35 2.31615 0 P 1 0;0=23,1=2
P 8.35 2.36615 0 P 1 0;0=23,1=2
P 8.35 2.41615 0 P 1 0;0=23,1=2
P 8.35 2.46615 0 P 1 0;0=23,1=2
P 8.35 2.51615 0 P 1 0;0=23,1=2
P 8.35 2.56615 0 P 1 0;0=23,1=2
P 8.35 2.61615 0 P 1 0;0=23,1=2
P 8.35 2.66615 0 P 1 0;0=23,1=2
P 8.35 2.71615 0 P 1 0;0=23,1=2
P 8.35 2.76615 0 P 1 0;0=23,1=2
P 8.35 2.81615 0 P 1 0;0=23,1=2
P 8.35 2.86615 0 P 1 0;0=23,1=2
P 8.35 2.91615 0 P 1 0;0=23,1=2
P 8.35 2.96615 0 P 1 0;0=23,1=2
P 8.35 3.01615 0 P 1 0;0=23,1=2
P 8.35 3.06615 0 P 1 0;0=23,1=2
P 8.35 3.11615 0 P 1 0;0=23,1=2
P 8.35 3.16615 0 P 1 0;0=23,1=2
P 8.35 3.21615 0 P 1 0;0=23,1=2
P 8.35 3.36615 0 P 1 0;0=23,1=2
P 8.35 3.51615 0 P 1 0;0=23,1=2
P 8.35 3.56615 0 P 1 0;0=23,1=2
P 8.35 3.61615 0 P 1 0;0=23,1=2
P 8.35 3.76615 0 P 1 0;0=23,1=2
P 8.4 1.86615 0 P 1 0;0=23,1=2
P 8.4 1.91615 0 P 1 0;0=23,1=2
P 8.4 1.96615 0 P 1 0;0=23,1=2
P 8.4 2.01615 0 P 1 0;0=23,1=2
P 8.4 2.06615 0 P 1 0;0=23,1=2
P 8.4 2.11615 0 P 1 0;0=23,1=2
P 8.4 2.16615 0 P 1 0;0=23,1=2
P 8.4 2.21615 0 P 1 0;0=23,1=2
P 8.4 2.26615 0 P 1 0;0=23,1=2
P 8.4 2.31615 0 P 1 0;0=23,1=2
P 8.4 2.36615 0 P 1 0;0=23,1=2
P 8.4 2.41615 0 P 1 0;0=23,1=2
P 8.4 2.46615 0 P 1 0;0=23,1=2
P 8.4 2.51615 0 P 1 0;0=23,1=2
P 8.4 2.56615 0 P 1 0;0=23,1=2
P 8.4 2.61615 0 P 1 0;0=23,1=2
P 8.4 2.66615 0 P 1 0;0=23,1=2
P 8.4 2.71615 0 P 1 0;0=23,1=2
P 8.4 2.76615 0 P 1 0;0=23,1=2
P 8.4 2.81615 0 P 1 0;0=23,1=2
P 8.4 2.86615 0 P 1 0;0=23,1=2
P 8.4 2.91615 0 P 1 0;0=23,1=2
P 8.4 2.96615 0 P 1 0;0=23,1=2
P 8.4 3.01615 0 P 1 0;0=23,1=2
P 8.4 3.06615 0 P 1 0;0=23,1=2
P 8.4 3.11615 0 P 1 0;0=23,1=2
P 8.4 3.16615 0 P 1 0;0=23,1=2
P 8.4 3.21615 0 P 1 0;0=23,1=2
P 8.4 3.26615 0 P 1 0;0=23,1=2
P 8.4 3.41615 0 P 1 0;0=23,1=2
P 8.4 3.56615 0 P 1 0;0=23,1=2
P 8.4 3.71615 0 P 1 0;0=23,1=2
P 8.4 3.86615 0 P 1 0;0=23,1=2
P 8.45 1.86615 0 P 1 0;0=23,1=2
P 8.45 1.91615 0 P 1 0;0=23,1=2
P 8.45 1.96615 0 P 1 0;0=23,1=2
P 8.45 2.01615 0 P 1 0;0=23,1=2
P 8.45 2.06615 0 P 1 0;0=23,1=2
P 8.45 2.11615 0 P 1 0;0=23,1=2
P 8.45 2.16615 0 P 1 0;0=23,1=2
P 8.45 2.21615 0 P 1 0;0=23,1=2
P 8.45 2.26615 0 P 1 0;0=23,1=2
P 8.45 2.31615 0 P 1 0;0=23,1=2
P 8.45 2.36615 0 P 1 0;0=23,1=2
P 8.45 2.41615 0 P 1 0;0=23,1=2
P 8.45 2.46615 0 P 1 0;0=23,1=2
P 8.45 2.51615 0 P 1 0;0=23,1=2
P 8.45 2.56615 0 P 1 0;0=23,1=2
P 8.45 2.61615 0 P 1 0;0=23,1=2
P 8.45 2.66615 0 P 1 0;0=23,1=2
P 8.45 2.71615 0 P 1 0;0=23,1=2
P 8.45 2.76615 0 P 1 0;0=23,1=2
P 8.45 2.81615 0 P 1 0;0=23,1=2
P 8.45 2.86615 0 P 1 0;0=23,1=2
P 8.45 2.91615 0 P 1 0;0=23,1=2
P 8.45 2.96615 0 P 1 0;0=23,1=2
P 8.45 3.01615 0 P 1 0;0=23,1=2
P 8.45 3.06615 0 P 1 0;0=23,1=2
P 8.45 3.11615 0 P 1 0;0=23,1=2
P 8.45 3.16615 0 P 1 0;0=23,1=2
P 8.45 3.21615 0 P 1 0;0=23,1=2
P 8.45 3.36615 0 P 1 0;0=23,1=2
P 8.45 3.51615 0 P 1 0;0=23,1=2
P 8.45 3.56615 0 P 1 0;0=23,1=2
P 8.45 3.61615 0 P 1 0;0=23,1=2
P 8.45 3.76615 0 P 1 0;0=23,1=2
P 8.5 1.86615 0 P 1 0;0=23,1=2
P 8.5 1.91615 0 P 1 0;0=23,1=2
P 8.5 1.96615 0 P 1 0;0=23,1=2
P 8.5 2.01615 0 P 1 0;0=23,1=2
P 8.5 2.06615 0 P 1 0;0=23,1=2
P 8.5 2.11615 0 P 1 0;0=23,1=2
P 8.5 2.16615 0 P 1 0;0=23,1=2
P 8.5 2.21615 0 P 1 0;0=23,1=2
P 8.5 2.26615 0 P 1 0;0=23,1=2
P 8.5 2.31615 0 P 1 0;0=23,1=2
P 8.5 2.36615 0 P 1 0;0=23,1=2
P 8.5 2.41615 0 P 1 0;0=23,1=2
P 8.5 2.46615 0 P 1 0;0=23,1=2
P 8.5 2.51615 0 P 1 0;0=23,1=2
P 8.5 2.56615 0 P 1 0;0=23,1=2
P 8.5 2.61615 0 P 1 0;0=23,1=2
P 8.5 2.66615 0 P 1 0;0=23,1=2
P 8.5 2.71615 0 P 1 0;0=23,1=2
P 8.5 2.76615 0 P 1 0;0=23,1=2
P 8.5 2.81615 0 P 1 0;0=23,1=2
P 8.5 2.86615 0 P 1 0;0=23,1=2
P 8.5 2.91615 0 P 1 0;0=23,1=2
P 8.5 2.96615 0 P 1 0;0=23,1=2
P 8.5 3.01615 0 P 1 0;0=23,1=2
P 8.5 3.06615 0 P 1 0;0=23,1=2
P 8.5 3.11615 0 P 1 0;0=23,1=2
P 8.5 3.16615 0 P 1 0;0=23,1=2
P 8.5 3.21615 0 P 1 0;0=23,1=2
P 8.5 3.26615 0 P 1 0;0=23,1=2
P 8.5 3.41615 0 P 1 0;0=23,1=2
P 8.5 3.56615 0 P 1 0;0=23,1=2
P 8.5 3.71615 0 P 1 0;0=23,1=2
P 8.5 3.86615 0 P 1 0;0=23,1=2
P 4.58268002 2.71615 0 P 1 0;0=23,1=2
P 10.58661004 2.71615 0 P 1 0;0=23,1=2
P 2.29606004 3.56615 0 P 1 0;0=23,1=2
P 2.24606004 3.56615 0 P 1 0;0=23,1=2
P 8.3 3.56615 0 P 1 0;0=23,1=2
P 8.25 3.56615 0 P 1 0;0=23,1=2
P 4.68268002 2.56615 0 P 1 0;0=23,1=2
P 4.68268002 2.61615 0 P 1 0;0=23,1=2
P 4.73268002 2.61615 0 P 1 0;0=23,1=2
P 4.73268002 2.66615 0 P 1 0;0=23,1=2
P 5.03268002 2.61615 0 P 1 0;0=23,1=2
P 5.03268002 2.66615 0 P 1 0;0=23,1=2
P 5.08268002 2.56615 0 P 1 0;0=23,1=2
P 5.08268002 2.61615 0 P 1 0;0=23,1=2
P 4.58268002 2.56615 0 P 1 0;0=23,1=2
P 4.58268002 2.61615 0 P 1 0;0=23,1=2
P 4.63268002 2.61615 0 P 1 0;0=23,1=2
P 4.63268002 2.66615 0 P 1 0;0=23,1=2
P 4.93268002 2.61615 0 P 1 0;0=23,1=2
P 4.93268002 2.66615 0 P 1 0;0=23,1=2
P 4.98268002 2.56615 0 P 1 0;0=23,1=2
P 4.98268002 2.61615 0 P 1 0;0=23,1=2
P 10.68661004 2.56615 0 P 1 0;0=23,1=2
P 10.68661004 2.61615 0 P 1 0;0=23,1=2
P 10.73661004 2.61615 0 P 1 0;0=23,1=2
P 10.73661004 2.66615 0 P 1 0;0=23,1=2
P 11.03661004 2.61615 0 P 1 0;0=23,1=2
P 11.03661004 2.66615 0 P 1 0;0=23,1=2
P 11.08661004 2.56615 0 P 1 0;0=23,1=2
P 11.08661004 2.61615 0 P 1 0;0=23,1=2
P 10.58661004 2.56615 0 P 1 0;0=23,1=2
P 10.58661004 2.61615 0 P 1 0;0=23,1=2
P 10.63661004 2.61615 0 P 1 0;0=23,1=2
P 10.63661004 2.66615 0 P 1 0;0=23,1=2
P 10.93661004 2.61615 0 P 1 0;0=23,1=2
P 10.93661004 2.66615 0 P 1 0;0=23,1=2
P 10.98661004 2.56615 0 P 1 0;0=23,1=2
P 10.98661004 2.61615 0 P 1 0;0=23,1=2
P 4.58268002 2.96615 0 P 1 0;0=23,1=2
P 4.58268002 3.01615 0 P 1 0;0=23,1=2
P 4.58268002 3.11615 0 P 1 0;0=23,1=2
P 4.58268002 3.16615 0 P 1 0;0=23,1=2
P 4.58268002 3.26615 0 P 1 0;0=23,1=2
P 4.58268002 3.31615 0 P 1 0;0=23,1=2
P 4.58268002 3.41615 0 P 1 0;0=23,1=2
P 4.58268002 3.46615 0 P 1 0;0=23,1=2
P 4.58268002 3.56615 0 P 1 0;0=23,1=2
P 4.58268002 3.61615 0 P 1 0;0=23,1=2
P 4.58268002 3.71615 0 P 1 0;0=23,1=2
P 4.58268002 3.76615 0 P 1 0;0=23,1=2
P 4.58268002 3.86615 0 P 1 0;0=23,1=2
P 4.63268002 2.96615 0 P 1 0;0=23,1=2
P 4.63268002 3.01615 0 P 1 0;0=23,1=2
P 4.63268002 3.11615 0 P 1 0;0=23,1=2
P 4.63268002 3.16615 0 P 1 0;0=23,1=2
P 4.63268002 3.26615 0 P 1 0;0=23,1=2
P 4.63268002 3.31615 0 P 1 0;0=23,1=2
P 4.63268002 3.41615 0 P 1 0;0=23,1=2
P 4.63268002 3.46615 0 P 1 0;0=23,1=2
P 4.63268002 3.56615 0 P 1 0;0=23,1=2
P 4.63268002 3.61615 0 P 1 0;0=23,1=2
P 4.63268002 3.71615 0 P 1 0;0=23,1=2
P 4.63268002 3.76615 0 P 1 0;0=23,1=2
P 4.63268002 3.86615 0 P 1 0;0=23,1=2
P 4.68268002 2.96615 0 P 1 0;0=23,1=2
P 4.68268002 3.01615 0 P 1 0;0=23,1=2
P 4.68268002 3.11615 0 P 1 0;0=23,1=2
P 4.68268002 3.16615 0 P 1 0;0=23,1=2
P 4.68268002 3.26615 0 P 1 0;0=23,1=2
P 4.68268002 3.31615 0 P 1 0;0=23,1=2
P 4.68268002 3.41615 0 P 1 0;0=23,1=2
P 4.68268002 3.46615 0 P 1 0;0=23,1=2
P 4.68268002 3.56615 0 P 1 0;0=23,1=2
P 4.68268002 3.61615 0 P 1 0;0=23,1=2
P 4.68268002 3.71615 0 P 1 0;0=23,1=2
P 4.68268002 3.76615 0 P 1 0;0=23,1=2
P 4.68268002 3.86615 0 P 1 0;0=23,1=2
P 4.73268002 2.96615 0 P 1 0;0=23,1=2
P 4.73268002 3.01615 0 P 1 0;0=23,1=2
P 4.73268002 3.11615 0 P 1 0;0=23,1=2
P 4.73268002 3.16615 0 P 1 0;0=23,1=2
P 4.73268002 3.26615 0 P 1 0;0=23,1=2
P 4.73268002 3.31615 0 P 1 0;0=23,1=2
P 4.73268002 3.41615 0 P 1 0;0=23,1=2
P 4.73268002 3.46615 0 P 1 0;0=23,1=2
P 4.73268002 3.56615 0 P 1 0;0=23,1=2
P 4.73268002 3.61615 0 P 1 0;0=23,1=2
P 4.73268002 3.71615 0 P 1 0;0=23,1=2
P 4.73268002 3.76615 0 P 1 0;0=23,1=2
P 4.73268002 3.86615 0 P 1 0;0=23,1=2
P 4.78268002 2.96615 0 P 1 0;0=23,1=2
P 4.78268002 3.01615 0 P 1 0;0=23,1=2
P 4.78268002 3.11615 0 P 1 0;0=23,1=2
P 4.78268002 3.16615 0 P 1 0;0=23,1=2
P 4.78268002 3.26615 0 P 1 0;0=23,1=2
P 4.78268002 3.31615 0 P 1 0;0=23,1=2
P 4.78268002 3.41615 0 P 1 0;0=23,1=2
P 4.78268002 3.46615 0 P 1 0;0=23,1=2
P 4.78268002 3.56615 0 P 1 0;0=23,1=2
P 4.78268002 3.61615 0 P 1 0;0=23,1=2
P 4.78268002 3.71615 0 P 1 0;0=23,1=2
P 4.78268002 3.76615 0 P 1 0;0=23,1=2
P 4.78268002 3.86615 0 P 1 0;0=23,1=2
P 4.83268002 2.96615 0 P 1 0;0=23,1=2
P 4.83268002 3.01615 0 P 1 0;0=23,1=2
P 4.83268002 3.11615 0 P 1 0;0=23,1=2
P 4.83268002 3.16615 0 P 1 0;0=23,1=2
P 4.83268002 3.26615 0 P 1 0;0=23,1=2
P 4.83268002 3.31615 0 P 1 0;0=23,1=2
P 4.83268002 3.41615 0 P 1 0;0=23,1=2
P 4.83268002 3.46615 0 P 1 0;0=23,1=2
P 4.83268002 3.56615 0 P 1 0;0=23,1=2
P 4.83268002 3.61615 0 P 1 0;0=23,1=2
P 4.83268002 3.71615 0 P 1 0;0=23,1=2
P 4.83268002 3.76615 0 P 1 0;0=23,1=2
P 4.83268002 3.86615 0 P 1 0;0=23,1=2
P 4.88268002 2.96615 0 P 1 0;0=23,1=2
P 4.88268002 3.01615 0 P 1 0;0=23,1=2
P 4.88268002 3.11615 0 P 1 0;0=23,1=2
P 4.88268002 3.16615 0 P 1 0;0=23,1=2
P 4.88268002 3.26615 0 P 1 0;0=23,1=2
P 4.88268002 3.31615 0 P 1 0;0=23,1=2
P 4.88268002 3.41615 0 P 1 0;0=23,1=2
P 4.88268002 3.46615 0 P 1 0;0=23,1=2
P 4.88268002 3.56615 0 P 1 0;0=23,1=2
P 4.88268002 3.61615 0 P 1 0;0=23,1=2
P 4.88268002 3.71615 0 P 1 0;0=23,1=2
P 4.88268002 3.76615 0 P 1 0;0=23,1=2
P 4.88268002 3.86615 0 P 1 0;0=23,1=2
P 4.93268002 2.96615 0 P 1 0;0=23,1=2
P 4.93268002 3.01615 0 P 1 0;0=23,1=2
P 4.93268002 3.11615 0 P 1 0;0=23,1=2
P 4.93268002 3.16615 0 P 1 0;0=23,1=2
P 4.93268002 3.26615 0 P 1 0;0=23,1=2
P 4.93268002 3.31615 0 P 1 0;0=23,1=2
P 4.93268002 3.41615 0 P 1 0;0=23,1=2
P 4.93268002 3.46615 0 P 1 0;0=23,1=2
P 4.93268002 3.56615 0 P 1 0;0=23,1=2
P 4.93268002 3.61615 0 P 1 0;0=23,1=2
P 4.93268002 3.71615 0 P 1 0;0=23,1=2
P 4.93268002 3.76615 0 P 1 0;0=23,1=2
P 4.93268002 3.86615 0 P 1 0;0=23,1=2
P 4.98268002 2.96615 0 P 1 0;0=23,1=2
P 4.98268002 3.01615 0 P 1 0;0=23,1=2
P 4.98268002 3.11615 0 P 1 0;0=23,1=2
P 4.98268002 3.16615 0 P 1 0;0=23,1=2
P 4.98268002 3.26615 0 P 1 0;0=23,1=2
P 4.98268002 3.31615 0 P 1 0;0=23,1=2
P 4.98268002 3.41615 0 P 1 0;0=23,1=2
P 4.98268002 3.46615 0 P 1 0;0=23,1=2
P 4.98268002 3.56615 0 P 1 0;0=23,1=2
P 4.98268002 3.61615 0 P 1 0;0=23,1=2
P 4.98268002 3.71615 0 P 1 0;0=23,1=2
P 4.98268002 3.76615 0 P 1 0;0=23,1=2
P 4.98268002 3.86615 0 P 1 0;0=23,1=2
P 5.03268002 2.96615 0 P 1 0;0=23,1=2
P 5.03268002 3.01615 0 P 1 0;0=23,1=2
P 5.03268002 3.11615 0 P 1 0;0=23,1=2
P 5.03268002 3.16615 0 P 1 0;0=23,1=2
P 5.03268002 3.26615 0 P 1 0;0=23,1=2
P 5.03268002 3.31615 0 P 1 0;0=23,1=2
P 5.03268002 3.41615 0 P 1 0;0=23,1=2
P 5.03268002 3.46615 0 P 1 0;0=23,1=2
P 5.03268002 3.56615 0 P 1 0;0=23,1=2
P 5.03268002 3.61615 0 P 1 0;0=23,1=2
P 5.03268002 3.71615 0 P 1 0;0=23,1=2
P 5.03268002 3.76615 0 P 1 0;0=23,1=2
P 5.03268002 3.86615 0 P 1 0;0=23,1=2
P 10.58661004 2.96615 0 P 1 0;0=23,1=2
P 10.58661004 3.01615 0 P 1 0;0=23,1=2
P 10.58661004 3.11615 0 P 1 0;0=23,1=2
P 10.58661004 3.16615 0 P 1 0;0=23,1=2
P 10.58661004 3.26615 0 P 1 0;0=23,1=2
P 10.58661004 3.31615 0 P 1 0;0=23,1=2
P 10.58661004 3.41615 0 P 1 0;0=23,1=2
P 10.58661004 3.46615 0 P 1 0;0=23,1=2
P 10.58661004 3.56615 0 P 1 0;0=23,1=2
P 10.58661004 3.61615 0 P 1 0;0=23,1=2
P 10.58661004 3.71615 0 P 1 0;0=23,1=2
P 10.58661004 3.76615 0 P 1 0;0=23,1=2
P 10.58661004 3.86615 0 P 1 0;0=23,1=2
P 10.63661004 2.96615 0 P 1 0;0=23,1=2
P 10.63661004 3.01615 0 P 1 0;0=23,1=2
P 10.63661004 3.11615 0 P 1 0;0=23,1=2
P 10.63661004 3.16615 0 P 1 0;0=23,1=2
P 10.63661004 3.26615 0 P 1 0;0=23,1=2
P 10.63661004 3.31615 0 P 1 0;0=23,1=2
P 10.63661004 3.41615 0 P 1 0;0=23,1=2
P 10.63661004 3.46615 0 P 1 0;0=23,1=2
P 10.63661004 3.56615 0 P 1 0;0=23,1=2
P 10.63661004 3.61615 0 P 1 0;0=23,1=2
P 10.63661004 3.71615 0 P 1 0;0=23,1=2
P 10.63661004 3.76615 0 P 1 0;0=23,1=2
P 10.63661004 3.86615 0 P 1 0;0=23,1=2
P 10.68661004 2.96615 0 P 1 0;0=23,1=2
P 10.68661004 3.01615 0 P 1 0;0=23,1=2
P 10.68661004 3.11615 0 P 1 0;0=23,1=2
P 10.68661004 3.16615 0 P 1 0;0=23,1=2
P 10.68661004 3.26615 0 P 1 0;0=23,1=2
P 10.68661004 3.31615 0 P 1 0;0=23,1=2
P 10.68661004 3.41615 0 P 1 0;0=23,1=2
P 10.68661004 3.46615 0 P 1 0;0=23,1=2
P 10.68661004 3.56615 0 P 1 0;0=23,1=2
P 10.68661004 3.61615 0 P 1 0;0=23,1=2
P 10.68661004 3.71615 0 P 1 0;0=23,1=2
P 10.68661004 3.76615 0 P 1 0;0=23,1=2
P 10.68661004 3.86615 0 P 1 0;0=23,1=2
P 10.73661004 2.96615 0 P 1 0;0=23,1=2
P 10.73661004 3.01615 0 P 1 0;0=23,1=2
P 10.73661004 3.11615 0 P 1 0;0=23,1=2
P 10.73661004 3.16615 0 P 1 0;0=23,1=2
P 10.73661004 3.26615 0 P 1 0;0=23,1=2
P 10.73661004 3.31615 0 P 1 0;0=23,1=2
P 10.73661004 3.41615 0 P 1 0;0=23,1=2
P 10.73661004 3.46615 0 P 1 0;0=23,1=2
P 10.73661004 3.56615 0 P 1 0;0=23,1=2
P 10.73661004 3.61615 0 P 1 0;0=23,1=2
P 10.73661004 3.71615 0 P 1 0;0=23,1=2
P 10.73661004 3.76615 0 P 1 0;0=23,1=2
P 10.73661004 3.86615 0 P 1 0;0=23,1=2
P 10.78661004 2.96615 0 P 1 0;0=23,1=2
P 10.78661004 3.01615 0 P 1 0;0=23,1=2
P 10.78661004 3.11615 0 P 1 0;0=23,1=2
P 10.78661004 3.16615 0 P 1 0;0=23,1=2
P 10.78661004 3.26615 0 P 1 0;0=23,1=2
P 10.78661004 3.31615 0 P 1 0;0=23,1=2
P 10.78661004 3.41615 0 P 1 0;0=23,1=2
P 10.78661004 3.46615 0 P 1 0;0=23,1=2
P 10.78661004 3.56615 0 P 1 0;0=23,1=2
P 10.78661004 3.61615 0 P 1 0;0=23,1=2
P 10.78661004 3.71615 0 P 1 0;0=23,1=2
P 10.78661004 3.76615 0 P 1 0;0=23,1=2
P 10.78661004 3.86615 0 P 1 0;0=23,1=2
P 10.83661004 2.96615 0 P 1 0;0=23,1=2
P 10.83661004 3.01615 0 P 1 0;0=23,1=2
P 10.83661004 3.11615 0 P 1 0;0=23,1=2
P 10.83661004 3.16615 0 P 1 0;0=23,1=2
P 10.83661004 3.26615 0 P 1 0;0=23,1=2
P 10.83661004 3.31615 0 P 1 0;0=23,1=2
P 10.83661004 3.41615 0 P 1 0;0=23,1=2
P 10.83661004 3.46615 0 P 1 0;0=23,1=2
P 10.83661004 3.56615 0 P 1 0;0=23,1=2
P 10.83661004 3.61615 0 P 1 0;0=23,1=2
P 10.83661004 3.71615 0 P 1 0;0=23,1=2
P 10.83661004 3.76615 0 P 1 0;0=23,1=2
P 10.83661004 3.86615 0 P 1 0;0=23,1=2
P 10.88661004 2.96615 0 P 1 0;0=23,1=2
P 10.88661004 3.01615 0 P 1 0;0=23,1=2
P 10.88661004 3.11615 0 P 1 0;0=23,1=2
P 10.88661004 3.16615 0 P 1 0;0=23,1=2
P 10.88661004 3.26615 0 P 1 0;0=23,1=2
P 10.88661004 3.31615 0 P 1 0;0=23,1=2
P 10.88661004 3.41615 0 P 1 0;0=23,1=2
P 10.88661004 3.46615 0 P 1 0;0=23,1=2
P 10.88661004 3.56615 0 P 1 0;0=23,1=2
P 10.88661004 3.61615 0 P 1 0;0=23,1=2
P 10.88661004 3.71615 0 P 1 0;0=23,1=2
P 10.88661004 3.76615 0 P 1 0;0=23,1=2
P 10.88661004 3.86615 0 P 1 0;0=23,1=2
P 10.93661004 2.96615 0 P 1 0;0=23,1=2
P 10.93661004 3.01615 0 P 1 0;0=23,1=2
P 10.93661004 3.11615 0 P 1 0;0=23,1=2
P 10.93661004 3.16615 0 P 1 0;0=23,1=2
P 10.93661004 3.26615 0 P 1 0;0=23,1=2
P 10.93661004 3.31615 0 P 1 0;0=23,1=2
P 10.93661004 3.41615 0 P 1 0;0=23,1=2
P 10.93661004 3.46615 0 P 1 0;0=23,1=2
P 10.93661004 3.56615 0 P 1 0;0=23,1=2
P 10.93661004 3.61615 0 P 1 0;0=23,1=2
P 10.93661004 3.71615 0 P 1 0;0=23,1=2
P 10.93661004 3.76615 0 P 1 0;0=23,1=2
P 10.93661004 3.86615 0 P 1 0;0=23,1=2
P 10.98661004 2.96615 0 P 1 0;0=23,1=2
P 10.98661004 3.01615 0 P 1 0;0=23,1=2
P 10.98661004 3.11615 0 P 1 0;0=23,1=2
P 10.98661004 3.16615 0 P 1 0;0=23,1=2
P 10.98661004 3.26615 0 P 1 0;0=23,1=2
P 10.98661004 3.31615 0 P 1 0;0=23,1=2
P 10.98661004 3.41615 0 P 1 0;0=23,1=2
P 10.98661004 3.46615 0 P 1 0;0=23,1=2
P 10.98661004 3.56615 0 P 1 0;0=23,1=2
P 10.98661004 3.61615 0 P 1 0;0=23,1=2
P 10.98661004 3.71615 0 P 1 0;0=23,1=2
P 10.98661004 3.76615 0 P 1 0;0=23,1=2
P 10.98661004 3.86615 0 P 1 0;0=23,1=2
P 11.03661004 2.96615 0 P 1 0;0=23,1=2
P 11.03661004 3.01615 0 P 1 0;0=23,1=2
P 11.03661004 3.11615 0 P 1 0;0=23,1=2
P 11.03661004 3.16615 0 P 1 0;0=23,1=2
P 11.03661004 3.26615 0 P 1 0;0=23,1=2
P 11.03661004 3.31615 0 P 1 0;0=23,1=2
P 11.03661004 3.41615 0 P 1 0;0=23,1=2
P 11.03661004 3.46615 0 P 1 0;0=23,1=2
P 11.03661004 3.56615 0 P 1 0;0=23,1=2
P 11.03661004 3.61615 0 P 1 0;0=23,1=2
P 11.03661004 3.71615 0 P 1 0;0=23,1=2
P 11.03661004 3.76615 0 P 1 0;0=23,1=2
P 11.03661004 3.86615 0 P 1 0;0=23,1=2
P 10.88661004 2.81615 0 P 1 0;0=23,1=2
P 10.93661004 2.81615 0 P 1 0;0=23,1=2
P 10.98661004 2.81615 0 P 1 0;0=23,1=2
P 11.03661004 2.81615 0 P 1 0;0=23,1=2
P 11.08661004 2.81615 0 P 1 0;0=23,1=2
P 4.88268002 2.81615 0 P 1 0;0=23,1=2
P 4.93268002 2.81615 0 P 1 0;0=23,1=2
P 4.98268002 2.81615 0 P 1 0;0=23,1=2
P 5.03268002 2.81615 0 P 1 0;0=23,1=2
P 5.08268002 2.81615 0 P 1 0;0=23,1=2
P 10.73661004 1.86615 0 P 1 0;0=23,1=2
P 10.73661004 1.91615 0 P 1 0;0=23,1=2
P 10.68661004 1.91615 0 P 1 0;0=23,1=2
P 10.68661004 1.96615 0 P 1 0;0=23,1=2
P 10.63661004 1.86615 0 P 1 0;0=23,1=2
P 10.63661004 1.91615 0 P 1 0;0=23,1=2
P 10.58661004 1.91615 0 P 1 0;0=23,1=2
P 10.58661004 1.96615 0 P 1 0;0=23,1=2
P 10.73661004 2.01615 0 P 1 0;0=23,1=2
P 10.73661004 2.06615 0 P 1 0;0=23,1=2
P 10.63661004 2.01615 0 P 1 0;0=23,1=2
P 10.63661004 2.06615 0 P 1 0;0=23,1=2
P 10.58661004 2.06615 0 P 1 0;0=23,1=2
P 10.58661004 2.11615 0 P 1 0;0=23,1=2
P 10.68661004 2.06615 0 P 1 0;0=23,1=2
P 10.68661004 2.11615 0 P 1 0;0=23,1=2
P 10.73661004 2.26615 0 P 1 0;0=23,1=2
P 10.73661004 2.31615 0 P 1 0;0=23,1=2
P 10.68661004 2.21615 0 P 1 0;0=23,1=2
P 10.68661004 2.26615 0 P 1 0;0=23,1=2
P 10.58661004 2.21615 0 P 1 0;0=23,1=2
P 10.58661004 2.26615 0 P 1 0;0=23,1=2
P 10.63661004 2.26615 0 P 1 0;0=23,1=2
P 10.63661004 2.31615 0 P 1 0;0=23,1=2
P 10.68661004 2.36615 0 P 1 0;0=23,1=2
P 10.68661004 2.41615 0 P 1 0;0=23,1=2
P 10.58661004 2.36615 0 P 1 0;0=23,1=2
P 10.58661004 2.41615 0 P 1 0;0=23,1=2
P 10.63661004 2.41615 0 P 1 0;0=23,1=2
P 10.63661004 2.46615 0 P 1 0;0=23,1=2
P 10.73661004 2.41615 0 P 1 0;0=23,1=2
P 10.73661004 2.46615 0 P 1 0;0=23,1=2
P 5.08268002 1.91615 0 P 1 0;0=23,1=2
P 5.08268002 1.96615 0 P 1 0;0=23,1=2
P 5.03268002 1.86615 0 P 1 0;0=23,1=2
P 5.03268002 1.91615 0 P 1 0;0=23,1=2
P 4.93268002 1.86615 0 P 1 0;0=23,1=2
P 4.93268002 1.91615 0 P 1 0;0=23,1=2
P 4.98268002 1.91615 0 P 1 0;0=23,1=2
P 4.98268002 1.96615 0 P 1 0;0=23,1=2
P 5.03268002 2.01615 0 P 1 0;0=23,1=2
P 5.03268002 2.06615 0 P 1 0;0=23,1=2
P 4.93268002 2.01615 0 P 1 0;0=23,1=2
P 4.93268002 2.06615 0 P 1 0;0=23,1=2
P 4.98268002 2.06615 0 P 1 0;0=23,1=2
P 4.98268002 2.11615 0 P 1 0;0=23,1=2
P 5.08268002 2.06615 0 P 1 0;0=23,1=2
P 5.08268002 2.11615 0 P 1 0;0=23,1=2
P 5.08268002 2.21615 0 P 1 0;0=23,1=2
P 5.08268002 2.26615 0 P 1 0;0=23,1=2
P 5.03268002 2.26615 0 P 1 0;0=23,1=2
P 5.03268002 2.31615 0 P 1 0;0=23,1=2
P 4.98268002 2.21615 0 P 1 0;0=23,1=2
P 4.98268002 2.26615 0 P 1 0;0=23,1=2
P 4.93268002 2.26615 0 P 1 0;0=23,1=2
P 4.93268002 2.31615 0 P 1 0;0=23,1=2
P 5.08268002 2.36615 0 P 1 0;0=23,1=2
P 5.08268002 2.41615 0 P 1 0;0=23,1=2
P 4.98268002 2.36615 0 P 1 0;0=23,1=2
P 4.98268002 2.41615 0 P 1 0;0=23,1=2
P 4.93268002 2.41615 0 P 1 0;0=23,1=2
P 4.93268002 2.46615 0 P 1 0;0=23,1=2
P 5.03268002 2.46615 0 P 1 0;0=23,1=2
P 5.03268002 2.51615 0 P 1 0;0=23,1=2
P 11.08661004 1.91615 0 P 1 0;0=23,1=2
P 11.08661004 1.96615 0 P 1 0;0=23,1=2
P 11.03661004 1.86615 0 P 1 0;0=23,1=2
P 11.03661004 1.91615 0 P 1 0;0=23,1=2
P 10.93661004 1.86615 0 P 1 0;0=23,1=2
P 10.93661004 1.91615 0 P 1 0;0=23,1=2
P 10.98661004 1.91615 0 P 1 0;0=23,1=2
P 10.98661004 1.96615 0 P 1 0;0=23,1=2
P 11.03661004 2.01615 0 P 1 0;0=23,1=2
P 11.03661004 2.06615 0 P 1 0;0=23,1=2
P 10.93661004 2.01615 0 P 1 0;0=23,1=2
P 10.93661004 2.06615 0 P 1 0;0=23,1=2
P 10.98661004 2.06615 0 P 1 0;0=23,1=2
P 10.98661004 2.11615 0 P 1 0;0=23,1=2
P 11.08661004 2.06615 0 P 1 0;0=23,1=2
P 11.08661004 2.11615 0 P 1 0;0=23,1=2
P 11.08661004 2.21615 0 P 1 0;0=23,1=2
P 11.08661004 2.26615 0 P 1 0;0=23,1=2
P 11.03661004 2.26615 0 P 1 0;0=23,1=2
P 11.03661004 2.31615 0 P 1 0;0=23,1=2
P 10.98661004 2.21615 0 P 1 0;0=23,1=2
P 10.98661004 2.26615 0 P 1 0;0=23,1=2
P 10.93661004 2.26615 0 P 1 0;0=23,1=2
P 10.93661004 2.31615 0 P 1 0;0=23,1=2
P 11.08661004 2.36615 0 P 1 0;0=23,1=2
P 11.08661004 2.41615 0 P 1 0;0=23,1=2
P 10.98661004 2.36615 0 P 1 0;0=23,1=2
P 10.98661004 2.41615 0 P 1 0;0=23,1=2
P 10.93661004 2.41615 0 P 1 0;0=23,1=2
P 10.93661004 2.46615 0 P 1 0;0=23,1=2
P 11.03661004 2.46615 0 P 1 0;0=23,1=2
P 11.03661004 2.51615 0 P 1 0;0=23,1=2
P 6.6015 4.89736004 1 P 3 0;0=24,1=2
P 6.6015 4.93673996 1 P 3 0;0=24,1=2
P 6.62118996 4.87768002 1 P 3 0;0=24,1=2
P 6.62118996 4.91705 1 P 3 0;0=24,1=2
P 6.62118996 4.95641998 1 P 3 0;0=24,1=2
P 6.64088002 4.89736004 1 P 3 0;0=24,1=2
P 6.64088002 4.93673996 1 P 3 0;0=24,1=2
P 3.07 4.42 1 P 3 0;0=1,1=2
P 3.105 4.47 1 P 3 0;0=1,1=2
P 9.07353996 4.42 1 P 3 0;0=1,1=2
P 9.10853996 4.47 1 P 3 0;0=1,1=2
P 11.135 2.845 1 P 3 0;0=1,1=2
P 7.445 1.705 1 P 3 0;0=1,1=2
P 10.00731004 0.036 1 P 3 0;0=1,1=2
P 10.01 2.191 1 P 3 0;0=1,1=2
P 10.01 2.2481 1 P 3 0;0=1,1=2
P 10.01 2.32725 1 P 3 0;0=1,1=2
P 10.01 2.38435 1 P 3 0;0=1,1=2
P 10.01 2.46235 1 P 3 0;0=1,1=2
P 10.01 2.51945 1 P 3 0;0=1,1=2
P 10.01 2.6159 1 P 3 0;0=1,1=2
P 10.01 2.673 1 P 3 0;0=1,1=2
P 10.02901004 5.98761998 1 P 3 0;0=1,1=2
P 10.03 4.51 1 P 3 0;0=1,1=2
P 10.05731004 0.036 1 P 3 0;0=1,1=2
P 10.07901004 5.98761998 1 P 3 0;0=1,1=2
P 10.10731004 0.036 1 P 3 0;0=1,1=2
P 10.11778996 2.78 1 P 3 0;0=1,1=2
P 10.125 2.008 1 P 3 0;0=1,1=2
P 10.125 2.0651 1 P 3 0;0=1,1=2
P 10.125 2.1224 1 P 3 0;0=1,1=2
P 10.125 2.1795 1 P 3 0;0=1,1=2
P 10.125 2.2597 1 P 3 0;0=1,1=2
P 10.125 2.3168 1 P 3 0;0=1,1=2
P 10.125 2.3948 1 P 3 0;0=1,1=2
P 10.125 2.4519 1 P 3 0;0=1,1=2
P 10.125 2.5299 1 P 3 0;0=1,1=2
P 10.125 2.587 1 P 3 0;0=1,1=2
P 10.125 2.688 1 P 3 0;0=1,1=2
P 10.125 2.7451 1 P 3 0;0=1,1=2
P 10.12901004 5.98761998 1 P 3 0;0=1,1=2
P 10.15731004 0.036 1 P 3 0;0=1,1=2
P 10.16606998 2.81 1 P 3 0;0=1,1=2
P 10.17901004 5.98761998 1 P 3 0;0=1,1=2
P 10.20731004 0.036 1 P 3 0;0=1,1=2
P 10.22901004 5.98761998 1 P 3 0;0=1,1=2
P 10.25731004 0.036 1 P 3 0;0=1,1=2
P 10.26 1.9179 1 P 3 0;0=1,1=2
P 10.26 1.975 1 P 3 0;0=1,1=2
P 10.26498996 4.9431 1 P 3 0;0=1,1=2
P 10.26498996 4.9831 1 P 3 0;0=1,1=2
P 10.26498996 5.0281 1 P 3 0;0=1,1=2
P 10.26498996 5.0731 1 P 3 0;0=1,1=2
P 10.26498996 5.1181 1 P 3 0;0=1,1=2
P 10.27901004 5.98761998 1 P 3 0;0=1,1=2
P 1.02873996 0.036 1 P 3 0;0=1,1=2
P 1.02901004 5.98761998 1 P 3 0;0=1,1=2
P 10.295 1.6559 1 P 3 0;0=1,1=2
P 10.295 1.713 1 P 3 0;0=1,1=2
P 10.29525 1.8199 1 P 3 0;0=1,1=2
P 10.29525 1.877 1 P 3 0;0=1,1=2
P 1.03 5.065 1 P 3 0;0=1,1=2
P 10.30498996 4.9431 1 P 3 0;0=1,1=2
P 10.30498996 4.9831 1 P 3 0;0=1,1=2
P 10.30498996 5.0281 1 P 3 0;0=1,1=2
P 10.30498996 5.0731 1 P 3 0;0=1,1=2
P 10.30498996 5.1181 1 P 3 0;0=1,1=2
P 10.30731004 0.036 1 P 3 0;0=1,1=2
P 10.32901004 5.98761998 1 P 3 0;0=1,1=2
P 10.33998996 4.9231 1 P 3 0;0=1,1=2
P 10.34498996 5.1181 1 P 3 0;0=1,1=2
P 10.35731004 0.036 1 P 3 0;0=1,1=2
P 10.37313996 1.55336004 1 P 3 0;0=1,1=2
P 10.37901004 5.98761998 1 P 3 0;0=1,1=2
P 10.38498996 5.1181 1 P 3 0;0=1,1=2
P 10.40731004 0.036 1 P 3 0;0=1,1=2
P 10.41451004 1.51198002 1 P 3 0;0=1,1=2
P 10.4159 1.43 1 P 3 0;0=1,1=2
P 10.42498996 4.9431 1 P 3 0;0=1,1=2
P 10.42498996 4.9831 1 P 3 0;0=1,1=2
P 10.42498996 5.0281 1 P 3 0;0=1,1=2
P 10.42498996 5.0731 1 P 3 0;0=1,1=2
P 10.42498996 5.1181 1 P 3 0;0=1,1=2
P 10.42901004 5.98761998 1 P 3 0;0=1,1=2
P 10.43 1.277 1 P 3 0;0=1,1=2
P 10.43 1.3341 1 P 3 0;0=1,1=2
P 10.45731004 0.036 1 P 3 0;0=1,1=2
P 10.46498996 4.9431 1 P 3 0;0=1,1=2
P 10.46498996 4.9831 1 P 3 0;0=1,1=2
P 10.46498996 5.0281 1 P 3 0;0=1,1=2
P 10.46498996 5.0731 1 P 3 0;0=1,1=2
P 10.46498996 5.1181 1 P 3 0;0=1,1=2
P 10.465 5.165 1 P 3 0;0=1,1=2
P 10.465 5.195 1 P 3 0;0=1,1=2
P 10.465 5.245 1 P 3 0;0=1,1=2
P 10.465 5.275 1 P 3 0;0=1,1=2
P 10.473 1.43 1 P 3 0;0=1,1=2
P 10.47901004 5.98761998 1 P 3 0;0=1,1=2
P 10.50731004 0.036 1 P 3 0;0=1,1=2
P 10.515 5.32 1 P 3 0;0=1,1=2
P 10.52901004 5.98761998 1 P 3 0;0=1,1=2
P 10.55731004 0.036 1 P 3 0;0=1,1=2
P 10.57901004 5.98761998 1 P 3 0;0=1,1=2
P 10.60731004 0.036 1 P 3 0;0=1,1=2
P 10.62901004 5.98761998 1 P 3 0;0=1,1=2
P 10.65498996 4.9431 1 P 3 0;0=1,1=2
P 10.65498996 4.9831 1 P 3 0;0=1,1=2
P 10.65498996 5.0281 1 P 3 0;0=1,1=2
P 10.65498996 5.0731 1 P 3 0;0=1,1=2
P 10.65498996 5.1181 1 P 3 0;0=1,1=2
P 10.65731004 0.036 1 P 3 0;0=1,1=2
P 10.67901004 5.98761998 1 P 3 0;0=1,1=2
P 10.69498996 4.9431 1 P 3 0;0=1,1=2
P 10.69498996 4.9831 1 P 3 0;0=1,1=2
P 10.69498996 5.0281 1 P 3 0;0=1,1=2
P 10.69498996 5.0731 1 P 3 0;0=1,1=2
P 10.69498996 5.1181 1 P 3 0;0=1,1=2
P 10.70731004 0.036 1 P 3 0;0=1,1=2
P 10.72901004 5.98761998 1 P 3 0;0=1,1=2
P 10.72998996 4.9231 1 P 3 0;0=1,1=2
P 10.73498996 5.1181 1 P 3 0;0=1,1=2
P 10.75731004 0.036 1 P 3 0;0=1,1=2
P 10.77498996 4.9231 1 P 3 0;0=1,1=2
P 10.77498996 5.1181 1 P 3 0;0=1,1=2
P 10.77901004 5.98761998 1 P 3 0;0=1,1=2
P 1.07873996 0.036 1 P 3 0;0=1,1=2
P 1.07901004 5.98761998 1 P 3 0;0=1,1=2
P 10.80498996 5.42656004 1 P 3 0;0=1,1=2
P 10.80498996 5.56656004 1 P 3 0;0=1,1=2
P 10.80731004 0.036 1 P 3 0;0=1,1=2
P 10.81498996 4.9431 1 P 3 0;0=1,1=2
P 10.81498996 4.9831 1 P 3 0;0=1,1=2
P 10.81498996 5.0281 1 P 3 0;0=1,1=2
P 10.81498996 5.0731 1 P 3 0;0=1,1=2
P 10.81498996 5.1181 1 P 3 0;0=1,1=2
P 10.82901004 5.98761998 1 P 3 0;0=1,1=2
P 10.84498996 5.42656004 1 P 3 0;0=1,1=2
P 10.84498996 5.56656004 1 P 3 0;0=1,1=2
P 10.85498996 4.9431 1 P 3 0;0=1,1=2
P 10.85498996 4.9831 1 P 3 0;0=1,1=2
P 10.85498996 5.0281 1 P 3 0;0=1,1=2
P 10.85498996 5.0731 1 P 3 0;0=1,1=2
P 10.85498996 5.1181 1 P 3 0;0=1,1=2
P 10.85731004 0.036 1 P 3 0;0=1,1=2
P 10.87901004 5.98761998 1 P 3 0;0=1,1=2
P 10.90731004 0.036 1 P 3 0;0=1,1=2
P 10.92901004 5.98761998 1 P 3 0;0=1,1=2
P 10.95731004 0.036 1 P 3 0;0=1,1=2
P 10.97035 5.42656004 1 P 3 0;0=1,1=2
P 10.97035 5.56656004 1 P 3 0;0=1,1=2
P 10.97901004 5.98761998 1 P 3 0;0=1,1=2
P 11.00731004 0.036 1 P 3 0;0=1,1=2
P 11.01035 5.42656004 1 P 3 0;0=1,1=2
P 11.01035 5.56656004 1 P 3 0;0=1,1=2
P 11.02901004 5.98761998 1 P 3 0;0=1,1=2
P 11.05731004 0.036 1 P 3 0;0=1,1=2
P 11.07901004 5.98761998 1 P 3 0;0=1,1=2
P 11.10731004 0.036 1 P 3 0;0=1,1=2
P 11.12901004 5.98761998 1 P 3 0;0=1,1=2
P 11.13571004 5.42656004 1 P 3 0;0=1,1=2
P 11.13571004 5.56656004 1 P 3 0;0=1,1=2
P 11.15731004 0.036 1 P 3 0;0=1,1=2
P 11.17571004 5.42656004 1 P 3 0;0=1,1=2
P 11.17571004 5.56656004 1 P 3 0;0=1,1=2
P 11.17901004 5.98761998 1 P 3 0;0=1,1=2
P 11.20731004 0.036 1 P 3 0;0=1,1=2
P 11.22901004 5.98761998 1 P 3 0;0=1,1=2
P 1.12303002 5.46016004 1 P 3 0;0=1,1=2
P 11.25731004 0.036 1 P 3 0;0=1,1=2
P 11.27901004 5.98761998 1 P 3 0;0=1,1=2
P 1.12873996 0.036 1 P 3 0;0=1,1=2
P 1.12901004 5.98761998 1 P 3 0;0=1,1=2
P 11.30106998 5.42656004 1 P 3 0;0=1,1=2
P 11.30106998 5.56656004 1 P 3 0;0=1,1=2
P 11.30731004 0.036 1 P 3 0;0=1,1=2
P 11.32901004 5.98761998 1 P 3 0;0=1,1=2
P 11.34106998 5.42656004 1 P 3 0;0=1,1=2
P 11.34106998 5.56656004 1 P 3 0;0=1,1=2
P 11.35731004 0.036 1 P 3 0;0=1,1=2
P 11.37901004 5.98761998 1 P 3 0;0=1,1=2
P 11.40731004 0.036 1 P 3 0;0=1,1=2
P 11.42901004 5.98761998 1 P 3 0;0=1,1=2
P 11.45278996 2.9414 1 P 3 0;0=1,1=2
P 11.45278996 2.9764 1 P 3 0;0=1,1=2
P 11.45278996 3.0214 1 P 3 0;0=1,1=2
P 11.45278996 3.0564 1 P 3 0;0=1,1=2
P 11.45278996 3.1014 1 P 3 0;0=1,1=2
P 11.45278996 3.1364 1 P 3 0;0=1,1=2
P 11.45278996 3.1814 1 P 3 0;0=1,1=2
P 11.45278996 3.2164 1 P 3 0;0=1,1=2
P 11.45278996 3.2614 1 P 3 0;0=1,1=2
P 11.45278996 3.2964 1 P 3 0;0=1,1=2
P 11.45731004 0.036 1 P 3 0;0=1,1=2
P 11.46643002 5.42656004 1 P 3 0;0=1,1=2
P 11.46643002 5.56656004 1 P 3 0;0=1,1=2
P 11.47901004 5.98761998 1 P 3 0;0=1,1=2
P 11.49316004 1.4635 1 P 3 0;0=1,1=2
P 11.49316004 1.5605 1 P 3 0;0=1,1=2
P 11.49316004 1.6235 1 P 3 0;0=1,1=2
P 11.49316004 1.7835 1 P 3 0;0=1,1=2
P 11.49316004 1.8805 1 P 3 0;0=1,1=2
P 11.49316004 1.9435 1 P 3 0;0=1,1=2
P 11.49316004 2.0405 1 P 3 0;0=1,1=2
P 11.49316004 2.1035 1 P 3 0;0=1,1=2
P 11.49316004 2.3605 1 P 3 0;0=1,1=2
P 11.49316004 2.4235 1 P 3 0;0=1,1=2
P 11.49316004 2.5205 1 P 3 0;0=1,1=2
P 11.49316004 2.5835 1 P 3 0;0=1,1=2
P 11.49366004 1.401 1 P 3 0;0=1,1=2
P 11.49366004 1.721 1 P 3 0;0=1,1=2
P 11.50361998 2.73 1 P 3 0;0=1,1=2
P 11.50361998 2.8 1 P 3 0;0=1,1=2
P 11.50643002 5.42656004 1 P 3 0;0=1,1=2
P 11.50643002 5.56656004 1 P 3 0;0=1,1=2
P 11.50731004 0.036 1 P 3 0;0=1,1=2
P 11.52901004 5.98761998 1 P 3 0;0=1,1=2
P 11.55731004 0.036 1 P 3 0;0=1,1=2
P 11.57901004 5.98761998 1 P 3 0;0=1,1=2
P 11.58613002 2.855 1 P 3 0;0=1,1=2
P 11.60731004 0.036 1 P 3 0;0=1,1=2
P 11.62901004 5.98761998 1 P 3 0;0=1,1=2
P 11.63178996 5.42656004 1 P 3 0;0=1,1=2
P 11.63178996 5.56656004 1 P 3 0;0=1,1=2
P 11.65731004 0.036 1 P 3 0;0=1,1=2
P 11.67178996 5.42656004 1 P 3 0;0=1,1=2
P 11.67178996 5.56656004 1 P 3 0;0=1,1=2
P 11.67901004 5.98761998 1 P 3 0;0=1,1=2
P 11.69316004 1.4805 1 P 3 0;0=1,1=2
P 11.69316004 1.5435 1 P 3 0;0=1,1=2
P 11.69316004 1.8005 1 P 3 0;0=1,1=2
P 11.69316004 1.8635 1 P 3 0;0=1,1=2
P 11.69316004 1.9605 1 P 3 0;0=1,1=2
P 11.69316004 2.0235 1 P 3 0;0=1,1=2
P 11.69316004 2.1205 1 P 3 0;0=1,1=2
P 11.69316004 2.1835 1 P 3 0;0=1,1=2
P 11.69316004 2.2805 1 P 3 0;0=1,1=2
P 11.69316004 2.3435 1 P 3 0;0=1,1=2
P 11.69316004 2.4405 1 P 3 0;0=1,1=2
P 11.69316004 2.5035 1 P 3 0;0=1,1=2
P 11.69316004 2.6005 1 P 3 0;0=1,1=2
P 11.69316004 2.6635 1 P 3 0;0=1,1=2
P 11.70731004 0.036 1 P 3 0;0=1,1=2
P 11.72901004 5.98761998 1 P 3 0;0=1,1=2
P 11.74316004 1.6405 1 P 3 0;0=1,1=2
P 11.74316004 1.7035 1 P 3 0;0=1,1=2
P 11.75731004 0.036 1 P 3 0;0=1,1=2
P 11.7719 4.80998996 1 P 3 0;0=1,1=2
P 11.7719 4.85498996 1 P 3 0;0=1,1=2
P 11.7719 4.90498996 1 P 3 0;0=1,1=2
P 11.7719 4.94998996 1 P 3 0;0=1,1=2
P 11.77901004 5.98761998 1 P 3 0;0=1,1=2
P 1.17873996 0.036 1 P 3 0;0=1,1=2
P 1.17901004 5.98761998 1 P 3 0;0=1,1=2
P 11.79316004 2.2005 1 P 3 0;0=1,1=2
P 11.79316004 2.2635 1 P 3 0;0=1,1=2
P 11.79715 5.42656004 1 P 3 0;0=1,1=2
P 11.79715 5.56656004 1 P 3 0;0=1,1=2
P 11.80731004 0.036 1 P 3 0;0=1,1=2
P 11.8219 4.80998996 1 P 3 0;0=1,1=2
P 11.8219 4.94998996 1 P 3 0;0=1,1=2
P 11.82901004 5.98761998 1 P 3 0;0=1,1=2
P 11.83715 5.42656004 1 P 3 0;0=1,1=2
P 11.83715 5.56656004 1 P 3 0;0=1,1=2
P 11.845 2.85 1 P 3 0;0=1,1=2
P 11.85731004 0.036 1 P 3 0;0=1,1=2
P 11.8719 4.80998996 1 P 3 0;0=1,1=2
P 11.8719 4.94998996 1 P 3 0;0=1,1=2
P 11.87901004 5.98761998 1 P 3 0;0=1,1=2
P 1.18906004 5.04351004 1 P 3 0;0=1,1=2
P 11.90731004 0.036 1 P 3 0;0=1,1=2
P 11.9219 4.80998996 1 P 3 0;0=1,1=2
P 11.9219 4.94998996 1 P 3 0;0=1,1=2
P 11.92901004 5.98761998 1 P 3 0;0=1,1=2
P 11.95731004 0.036 1 P 3 0;0=1,1=2
P 11.96251004 5.42656004 1 P 3 0;0=1,1=2
P 11.96251004 5.56656004 1 P 3 0;0=1,1=2
P 11.9719 4.80998996 1 P 3 0;0=1,1=2
P 11.9719 4.85498996 1 P 3 0;0=1,1=2
P 11.9719 4.90498996 1 P 3 0;0=1,1=2
P 11.9719 4.94998996 1 P 3 0;0=1,1=2
P 11.97901004 5.98761998 1 P 3 0;0=1,1=2
P 12.00251004 5.42656004 1 P 3 0;0=1,1=2
P 12.00251004 5.56656004 1 P 3 0;0=1,1=2
P 12.00731004 0.036 1 P 3 0;0=1,1=2
P 1.20176998 5.46016004 1 P 3 0;0=1,1=2
P 1.20176998 5.78 1 P 3 0;0=1,1=2
P 12.025 4.915 1 P 3 0;0=1,1=2
P 12.02901004 5.98761998 1 P 3 0;0=1,1=2
P 12.055 4.915 1 P 3 0;0=1,1=2
P 12.05731004 0.036 1 P 3 0;0=1,1=2
P 12.07901004 5.98761998 1 P 3 0;0=1,1=2
P 12.10731004 0.036 1 P 3 0;0=1,1=2
P 12.12 4.965 1 P 3 0;0=1,1=2
P 12.12786998 5.42656004 1 P 3 0;0=1,1=2
P 12.12786998 5.56656004 1 P 3 0;0=1,1=2
P 12.12901004 5.98761998 1 P 3 0;0=1,1=2
P 12.15731004 0.036 1 P 3 0;0=1,1=2
P 12.16786998 5.42656004 1 P 3 0;0=1,1=2
P 12.16786998 5.56656004 1 P 3 0;0=1,1=2
P 12.17901004 5.98761998 1 P 3 0;0=1,1=2
P 12.185 4.915 1 P 3 0;0=1,1=2
P 12.20731004 0.036 1 P 3 0;0=1,1=2
P 12.215 4.915 1 P 3 0;0=1,1=2
P 12.22901004 5.98761998 1 P 3 0;0=1,1=2
P 12.25731004 0.036 1 P 3 0;0=1,1=2
P 12.27901004 5.98761998 1 P 3 0;0=1,1=2
P 1.22873996 0.036 1 P 3 0;0=1,1=2
P 1.22901004 5.98761998 1 P 3 0;0=1,1=2
P 12.30731004 0.036 1 P 3 0;0=1,1=2
P 12.32901004 5.98761998 1 P 3 0;0=1,1=2
P 12.34 2.19 1 P 3 0;0=1,1=2
P 12.35731004 0.036 1 P 3 0;0=1,1=2
P 12.37901004 5.98761998 1 P 3 0;0=1,1=2
P 1.23906004 4.60351004 1 P 3 0;0=1,1=2
P 12.40731004 0.036 1 P 3 0;0=1,1=2
P 12.42901004 5.98761998 1 P 3 0;0=1,1=2
P 12.45731004 0.036 1 P 3 0;0=1,1=2
P 12.47901004 5.98761998 1 P 3 0;0=1,1=2
P 12.50731004 0.036 1 P 3 0;0=1,1=2
P 12.52901004 5.98761998 1 P 3 0;0=1,1=2
P 12.55731004 0.036 1 P 3 0;0=1,1=2
P 12.57901004 5.98761998 1 P 3 0;0=1,1=2
P 12.60731004 0.036 1 P 3 0;0=1,1=2
P 12.62901004 5.98761998 1 P 3 0;0=1,1=2
P 12.65731004 0.036 1 P 3 0;0=1,1=2
P 12.67901004 5.98761998 1 P 3 0;0=1,1=2
P 12.70731004 0.036 1 P 3 0;0=1,1=2
P 12.72901004 5.98761998 1 P 3 0;0=1,1=2
P 12.75731004 0.036 1 P 3 0;0=1,1=2
P 12.77901004 5.98761998 1 P 3 0;0=1,1=2
P 1.27873996 0.036 1 P 3 0;0=1,1=2
P 1.27901004 5.98761998 1 P 3 0;0=1,1=2
P 0.12873996 0.036 1 P 3 0;0=1,1=2
P 1.28051004 5.46016004 1 P 3 0;0=1,1=2
P 1.28051004 5.78 1 P 3 0;0=1,1=2
P 12.80731004 0.036 1 P 3 0;0=1,1=2
P 12.82901004 5.98761998 1 P 3 0;0=1,1=2
P 12.85728996 0.03738996 1 P 3 0;0=1,1=2
P 12.87726004 5.97451004 1 P 3 0;0=1,1=2
P 12.88911004 0.07596004 1 P 3 0;0=1,1=2
P 12.8892 1.02596004 1 P 3 0;0=1,1=2
P 12.8892 1.07596004 1 P 3 0;0=1,1=2
P 12.8892 1.12596004 1 P 3 0;0=1,1=2
P 12.8892 1.17596004 1 P 3 0;0=1,1=2
P 12.8892 1.22596004 1 P 3 0;0=1,1=2
P 12.8892 0.12596004 1 P 3 0;0=1,1=2
P 12.8892 1.27596004 1 P 3 0;0=1,1=2
P 12.8892 1.32596004 1 P 3 0;0=1,1=2
P 12.8892 1.37596004 1 P 3 0;0=1,1=2
P 12.8892 1.42596004 1 P 3 0;0=1,1=2
P 12.8892 1.47596004 1 P 3 0;0=1,1=2
P 12.8892 1.52596004 1 P 3 0;0=1,1=2
P 12.8892 1.57596004 1 P 3 0;0=1,1=2
P 12.8892 1.62596004 1 P 3 0;0=1,1=2
P 12.8892 1.67596004 1 P 3 0;0=1,1=2
P 12.8892 1.72596004 1 P 3 0;0=1,1=2
P 12.8892 0.17596004 1 P 3 0;0=1,1=2
P 12.8892 1.77596004 1 P 3 0;0=1,1=2
P 12.8892 1.82596004 1 P 3 0;0=1,1=2
P 12.8892 1.87596004 1 P 3 0;0=1,1=2
P 12.8892 1.92596004 1 P 3 0;0=1,1=2
P 12.8892 1.97596004 1 P 3 0;0=1,1=2
P 12.8892 2.02596004 1 P 3 0;0=1,1=2
P 12.8892 2.07596004 1 P 3 0;0=1,1=2
P 12.8892 2.17596004 1 P 3 0;0=1,1=2
P 12.8892 2.22596004 1 P 3 0;0=1,1=2
P 12.8892 0.22596004 1 P 3 0;0=1,1=2
P 12.8892 2.27596004 1 P 3 0;0=1,1=2
P 12.8892 2.32596004 1 P 3 0;0=1,1=2
P 12.8892 2.37596004 1 P 3 0;0=1,1=2
P 12.8892 2.42596004 1 P 3 0;0=1,1=2
P 12.8892 2.47596004 1 P 3 0;0=1,1=2
P 12.8892 2.52596004 1 P 3 0;0=1,1=2
P 12.8892 2.57596004 1 P 3 0;0=1,1=2
P 12.8892 2.62596004 1 P 3 0;0=1,1=2
P 12.8892 2.67596004 1 P 3 0;0=1,1=2
P 12.8892 2.72596004 1 P 3 0;0=1,1=2
P 12.8892 0.27596004 1 P 3 0;0=1,1=2
P 12.8892 2.77596004 1 P 3 0;0=1,1=2
P 12.8892 2.82596004 1 P 3 0;0=1,1=2
P 12.8892 2.87596004 1 P 3 0;0=1,1=2
P 12.8892 2.92596004 1 P 3 0;0=1,1=2
P 12.8892 2.97596004 1 P 3 0;0=1,1=2
P 12.8892 3.02596004 1 P 3 0;0=1,1=2
P 12.8892 3.07596004 1 P 3 0;0=1,1=2
P 12.8892 3.12596004 1 P 3 0;0=1,1=2
P 12.8892 3.17596004 1 P 3 0;0=1,1=2
P 12.8892 3.22596004 1 P 3 0;0=1,1=2
P 12.8892 0.32596004 1 P 3 0;0=1,1=2
P 12.8892 3.27596004 1 P 3 0;0=1,1=2
P 12.8892 3.32596004 1 P 3 0;0=1,1=2
P 12.8892 3.37596004 1 P 3 0;0=1,1=2
P 12.8892 3.42596004 1 P 3 0;0=1,1=2
P 12.8892 3.47596004 1 P 3 0;0=1,1=2
P 12.8892 3.52596004 1 P 3 0;0=1,1=2
P 12.8892 3.57596004 1 P 3 0;0=1,1=2
P 12.8892 3.62596004 1 P 3 0;0=1,1=2
P 12.8892 3.67596004 1 P 3 0;0=1,1=2
P 12.8892 3.72596004 1 P 3 0;0=1,1=2
P 12.8892 0.37596004 1 P 3 0;0=1,1=2
P 12.8892 3.77596004 1 P 3 0;0=1,1=2
P 12.8892 3.82596004 1 P 3 0;0=1,1=2
P 12.8892 3.87596004 1 P 3 0;0=1,1=2
P 12.8892 3.92596004 1 P 3 0;0=1,1=2
P 12.8892 3.97596004 1 P 3 0;0=1,1=2
P 12.8892 4.02596004 1 P 3 0;0=1,1=2
P 12.8892 4.07596004 1 P 3 0;0=1,1=2
P 12.8892 4.12596004 1 P 3 0;0=1,1=2
P 12.8892 4.17596004 1 P 3 0;0=1,1=2
P 12.8892 4.22596004 1 P 3 0;0=1,1=2
P 12.8892 0.42596004 1 P 3 0;0=1,1=2
P 12.8892 4.27596004 1 P 3 0;0=1,1=2
P 12.8892 4.32596004 1 P 3 0;0=1,1=2
P 12.8892 4.37596004 1 P 3 0;0=1,1=2
P 12.8892 4.42596004 1 P 3 0;0=1,1=2
P 12.8892 4.47596004 1 P 3 0;0=1,1=2
P 12.8892 4.52596004 1 P 3 0;0=1,1=2
P 12.8892 4.57596004 1 P 3 0;0=1,1=2
P 12.8892 4.62596004 1 P 3 0;0=1,1=2
P 12.8892 4.67596004 1 P 3 0;0=1,1=2
P 12.8892 4.72596004 1 P 3 0;0=1,1=2
P 12.8892 0.47596004 1 P 3 0;0=1,1=2
P 12.8892 4.77596004 1 P 3 0;0=1,1=2
P 12.8892 4.82596004 1 P 3 0;0=1,1=2
P 12.8892 0.52596004 1 P 3 0;0=1,1=2
P 12.8892 5.27596004 1 P 3 0;0=1,1=2
P 12.8892 5.32596004 1 P 3 0;0=1,1=2
P 12.8892 5.37596004 1 P 3 0;0=1,1=2
P 12.8892 5.42596004 1 P 3 0;0=1,1=2
P 12.8892 5.47596004 1 P 3 0;0=1,1=2
P 12.8892 5.52596004 1 P 3 0;0=1,1=2
P 12.8892 5.57596004 1 P 3 0;0=1,1=2
P 12.8892 5.62596004 1 P 3 0;0=1,1=2
P 12.8892 5.67596004 1 P 3 0;0=1,1=2
P 12.8892 5.72596004 1 P 3 0;0=1,1=2
P 12.8892 0.57596004 1 P 3 0;0=1,1=2
P 12.8892 5.77596004 1 P 3 0;0=1,1=2
P 12.8892 5.82596004 1 P 3 0;0=1,1=2
P 12.8892 5.87596004 1 P 3 0;0=1,1=2
P 12.8892 5.92596004 1 P 3 0;0=1,1=2
P 12.8892 0.62596004 1 P 3 0;0=1,1=2
P 0.12901004 5.98761998 1 P 3 0;0=1,1=2
P 1.305 5.885 1 P 3 0;0=1,1=2
P 1.31 5.355 1 P 3 0;0=1,1=2
P 1.32873996 0.036 1 P 3 0;0=1,1=2
P 1.32901004 5.98761998 1 P 3 0;0=1,1=2
P 1.33656004 4.85601004 1 P 3 0;0=1,1=2
P 1.355 5.885 1 P 3 0;0=1,1=2
P 1.36 5.355 1 P 3 0;0=1,1=2
P 1.37873996 0.036 1 P 3 0;0=1,1=2
P 1.37901004 5.98761998 1 P 3 0;0=1,1=2
P 1.405 5.885 1 P 3 0;0=1,1=2
P 1.41 5.355 1 P 3 0;0=1,1=2
P 1.42873996 0.036 1 P 3 0;0=1,1=2
P 1.42901004 5.98761998 1 P 3 0;0=1,1=2
P 1.455 5.885 1 P 3 0;0=1,1=2
P 1.46 5.355 1 P 3 0;0=1,1=2
P 1.47873996 0.036 1 P 3 0;0=1,1=2
P 1.47901004 5.98761998 1 P 3 0;0=1,1=2
P 1.51673002 5.46016004 1 P 3 0;0=1,1=2
P 1.51673002 5.78 1 P 3 0;0=1,1=2
P 1.52873996 0.036 1 P 3 0;0=1,1=2
P 1.52901004 5.98761998 1 P 3 0;0=1,1=2
P 1.56221004 4.81401998 1 P 3 0;0=1,1=2
P 1.56221004 5.023 1 P 3 0;0=1,1=2
P 1.56765 4.66826004 1 P 3 0;0=1,1=2
P 1.56765 5.13026004 1 P 3 0;0=1,1=2
P 1.57873996 0.036 1 P 3 0;0=1,1=2
P 1.57901004 5.98761998 1 P 3 0;0=1,1=2
P 1.62765 4.66826004 1 P 3 0;0=1,1=2
P 1.62765 5.13026004 1 P 3 0;0=1,1=2
P 1.62873996 0.036 1 P 3 0;0=1,1=2
P 1.62901004 5.98761998 1 P 3 0;0=1,1=2
P 1.63173002 4.81526998 1 P 3 0;0=1,1=2
P 1.63308002 4.92 1 P 3 0;0=1,1=2
P 1.63308002 5.023 1 P 3 0;0=1,1=2
P 1.6385 5.09223996 1 P 3 0;0=1,1=2
P 1.63851004 4.74418002 1 P 3 0;0=1,1=2
P 1.67873996 0.036 1 P 3 0;0=1,1=2
P 1.67901004 5.98761998 1 P 3 0;0=1,1=2
P 1.6985 5.09223996 1 P 3 0;0=1,1=2
P 1.69851004 4.74418002 1 P 3 0;0=1,1=2
P 1.7 4.812 1 P 3 0;0=1,1=2
P 1.70395 4.92 1 P 3 0;0=1,1=2
P 1.70395 5.023 1 P 3 0;0=1,1=2
P 1.72873996 0.036 1 P 3 0;0=1,1=2
P 1.72901004 5.98761998 1 P 3 0;0=1,1=2
P 1.77481004 4.92 1 P 3 0;0=1,1=2
P 1.77481004 5.023 1 P 3 0;0=1,1=2
P 1.776 4.812 1 P 3 0;0=1,1=2
P 1.77873996 0.036 1 P 3 0;0=1,1=2
P 1.77901004 5.98761998 1 P 3 0;0=1,1=2
P 0.17873996 0.036 1 P 3 0;0=1,1=2
P 1.78025 4.74418002 1 P 3 0;0=1,1=2
P 0.17901004 5.98761998 1 P 3 0;0=1,1=2
P 1.792 2.4781 1 P 3 0;0=1,1=2
P 1.82873996 0.036 1 P 3 0;0=1,1=2
P 1.82901004 5.98761998 1 P 3 0;0=1,1=2
P 1.84025 4.74418002 1 P 3 0;0=1,1=2
P 1.84568002 4.81 1 P 3 0;0=1,1=2
P 1.84568002 4.92 1 P 3 0;0=1,1=2
P 1.84568002 5.023 1 P 3 0;0=1,1=2
P 1.85111004 4.61826004 1 P 3 0;0=1,1=2
P 1.85111004 5.13026004 1 P 3 0;0=1,1=2
P 1.87873996 0.036 1 P 3 0;0=1,1=2
P 1.87901004 5.98761998 1 P 3 0;0=1,1=2
P 1.91111004 4.61826004 1 P 3 0;0=1,1=2
P 1.91111004 5.13026004 1 P 3 0;0=1,1=2
P 1.91653996 4.92 1 P 3 0;0=1,1=2
P 1.91653996 5.023 1 P 3 0;0=1,1=2
P 1.92 4.81 1 P 3 0;0=1,1=2
P 1.92196998 5.09223996 1 P 3 0;0=1,1=2
P 1.92346004 5.377 1 P 3 0;0=1,1=2
P 1.92873996 0.036 1 P 3 0;0=1,1=2
P 1.92901004 5.98761998 1 P 3 0;0=1,1=2
P 1.97873996 0.036 1 P 3 0;0=1,1=2
P 1.97901004 5.98761998 1 P 3 0;0=1,1=2
P 1.98196998 5.09223996 1 P 3 0;0=1,1=2
P 1.98741004 4.92 1 P 3 0;0=1,1=2
P 1.98741004 5.023 1 P 3 0;0=1,1=2
P 1.99 4.81 1 P 3 0;0=1,1=2
P 2.01853002 4.62815 1 P 3 0;0=1,1=2
P 2.02873996 0.036 1 P 3 0;0=1,1=2
P 2.02901004 5.98761998 1 P 3 0;0=1,1=2
P 2.05828002 4.92 1 P 3 0;0=1,1=2
P 2.05828002 5.023 1 P 3 0;0=1,1=2
P 2.06086998 4.81 1 P 3 0;0=1,1=2
P 2.06371004 4.74418002 1 P 3 0;0=1,1=2
P 2.06371004 5.13026004 1 P 3 0;0=1,1=2
P 2.07853002 4.62815 1 P 3 0;0=1,1=2
P 2.07873996 0.036 1 P 3 0;0=1,1=2
P 2.07901004 5.98761998 1 P 3 0;0=1,1=2
P 2.12371004 4.74418002 1 P 3 0;0=1,1=2
P 2.12371004 5.13026004 1 P 3 0;0=1,1=2
P 2.12873996 0.036 1 P 3 0;0=1,1=2
P 2.12901004 5.98761998 1 P 3 0;0=1,1=2
P 2.12913996 4.81 1 P 3 0;0=1,1=2
P 2.12913996 4.92 1 P 3 0;0=1,1=2
P 2.12913996 5.023 1 P 3 0;0=1,1=2
P 2.13456998 5.09223996 1 P 3 0;0=1,1=2
P 2.14346004 5.377 1 P 3 0;0=1,1=2
P 2.17873996 0.036 1 P 3 0;0=1,1=2
P 2.17901004 5.98761998 1 P 3 0;0=1,1=2
P 2.19456998 5.09223996 1 P 3 0;0=1,1=2
P 2.20001004 4.81 1 P 3 0;0=1,1=2
P 2.20001004 4.926 1 P 3 0;0=1,1=2
P 2.20001004 5.023 1 P 3 0;0=1,1=2
P 2.20543996 4.74418002 1 P 3 0;0=1,1=2
P 2.20855 4.62826004 1 P 3 0;0=1,1=2
P 2.22873996 0.036 1 P 3 0;0=1,1=2
P 2.22901004 5.98761998 1 P 3 0;0=1,1=2
P 2.26543996 4.74418002 1 P 3 0;0=1,1=2
P 2.26855 4.62826004 1 P 3 0;0=1,1=2
P 2.27086998 4.81 1 P 3 0;0=1,1=2
P 2.27086998 4.92 1 P 3 0;0=1,1=2
P 2.27086998 5.023 1 P 3 0;0=1,1=2
P 2.27873996 0.036 1 P 3 0;0=1,1=2
P 2.27901004 5.98761998 1 P 3 0;0=1,1=2
P 0.22873996 0.036 1 P 3 0;0=1,1=2
P 0.22901004 5.98761998 1 P 3 0;0=1,1=2
P 2.32873996 0.036 1 P 3 0;0=1,1=2
P 2.32901004 5.98761998 1 P 3 0;0=1,1=2
P 2.34173996 4.81 1 P 3 0;0=1,1=2
P 2.34173996 4.92 1 P 3 0;0=1,1=2
P 2.34173996 5.023 1 P 3 0;0=1,1=2
P 2.34716998 4.70326004 1 P 3 0;0=1,1=2
P 2.34716998 5.15373996 1 P 3 0;0=1,1=2
P 2.37873996 0.036 1 P 3 0;0=1,1=2
P 2.37901004 5.98761998 1 P 3 0;0=1,1=2
P 2.40716998 4.70326004 1 P 3 0;0=1,1=2
P 2.40716998 5.15373996 1 P 3 0;0=1,1=2
P 2.41261004 4.81401998 1 P 3 0;0=1,1=2
P 2.41261004 5.023 1 P 3 0;0=1,1=2
P 2.42873996 0.036 1 P 3 0;0=1,1=2
P 2.42901004 5.98761998 1 P 3 0;0=1,1=2
P 2.47873996 0.036 1 P 3 0;0=1,1=2
P 2.47901004 5.98761998 1 P 3 0;0=1,1=2
P 2.52873996 0.036 1 P 3 0;0=1,1=2
P 2.52901004 5.98761998 1 P 3 0;0=1,1=2
P 2.57873996 0.036 1 P 3 0;0=1,1=2
P 2.57901004 5.98761998 1 P 3 0;0=1,1=2
P 2.62873996 0.036 1 P 3 0;0=1,1=2
P 2.62901004 5.98761998 1 P 3 0;0=1,1=2
P 2.67873996 0.036 1 P 3 0;0=1,1=2
P 2.67901004 5.98761998 1 P 3 0;0=1,1=2
P 2.72681004 4.81401998 1 P 3 0;0=1,1=2
P 2.72681004 5.023 1 P 3 0;0=1,1=2
P 2.72873996 0.036 1 P 3 0;0=1,1=2
P 2.72901004 5.98761998 1 P 3 0;0=1,1=2
P 2.73225 4.70573996 1 P 3 0;0=1,1=2
P 2.73225 5.17873996 1 P 3 0;0=1,1=2
P 2.77873996 0.036 1 P 3 0;0=1,1=2
P 2.77901004 5.98761998 1 P 3 0;0=1,1=2
P 0.27873996 0.036 1 P 3 0;0=1,1=2
P 0.27901004 5.98761998 1 P 3 0;0=1,1=2
P 2.79225 4.70573996 1 P 3 0;0=1,1=2
P 2.79225 5.17873996 1 P 3 0;0=1,1=2
P 2.79768002 4.81401998 1 P 3 0;0=1,1=2
P 2.79768002 4.92 1 P 3 0;0=1,1=2
P 2.79768002 5.023 1 P 3 0;0=1,1=2
P 2.80311004 4.74418002 1 P 3 0;0=1,1=2
P 2.82873996 0.036 1 P 3 0;0=1,1=2
P 2.82901004 5.98761998 1 P 3 0;0=1,1=2
P 2.86311004 4.74418002 1 P 3 0;0=1,1=2
P 2.86555 4.81401998 1 P 3 0;0=1,1=2
P 2.86855 4.92 1 P 3 0;0=1,1=2
P 2.86855 5.023 1 P 3 0;0=1,1=2
P 2.87086998 5.20876004 1 P 3 0;0=1,1=2
P 2.87708002 4.70573996 1 P 3 0;0=1,1=2
P 2.87873996 0.036 1 P 3 0;0=1,1=2
P 2.87901004 5.98761998 1 P 3 0;0=1,1=2
P 2.92873996 0.036 1 P 3 0;0=1,1=2
P 2.92901004 5.98761998 1 P 3 0;0=1,1=2
P 2.93086998 5.20876004 1 P 3 0;0=1,1=2
P 2.93708002 4.70573996 1 P 3 0;0=1,1=2
P 2.93941004 5.023 1 P 3 0;0=1,1=2
P 2.94141004 4.81401998 1 P 3 0;0=1,1=2
P 2.9422 2.925 1 P 3 0;0=1,1=2
P 2.945 4.92 1 P 3 0;0=1,1=2
P 2.97721004 2.7861 1 P 3 0;0=1,1=2
P 2.97721004 2.8989 1 P 3 0;0=1,1=2
P 2.97873996 0.036 1 P 3 0;0=1,1=2
P 2.97901004 5.98761998 1 P 3 0;0=1,1=2
P 3.01028002 4.81401998 1 P 3 0;0=1,1=2
P 3.01028002 4.92 1 P 3 0;0=1,1=2
P 3.01028002 5.023 1 P 3 0;0=1,1=2
P 3.01571004 4.70573996 1 P 3 0;0=1,1=2
P 3.01571004 5.20373996 1 P 3 0;0=1,1=2
P 3.02873996 0.036 1 P 3 0;0=1,1=2
P 3.02901004 5.98761998 1 P 3 0;0=1,1=2
P 3.06791998 5.332 1 P 3 0;0=1,1=2
P 3.07571004 4.70573996 1 P 3 0;0=1,1=2
P 3.07571004 5.20373996 1 P 3 0;0=1,1=2
P 3.07691004 4.81401998 1 P 3 0;0=1,1=2
P 3.07873996 0.036 1 P 3 0;0=1,1=2
P 3.07901004 5.98761998 1 P 3 0;0=1,1=2
P 3.08113996 4.92 1 P 3 0;0=1,1=2
P 3.08113996 5.023 1 P 3 0;0=1,1=2
P 3.08656998 5.09223996 1 P 3 0;0=1,1=2
P 3.12873996 0.036 1 P 3 0;0=1,1=2
P 3.12901004 5.98761998 1 P 3 0;0=1,1=2
P 3.14 4.92 1 P 3 0;0=1,1=2
P 3.14656998 5.09223996 1 P 3 0;0=1,1=2
P 3.15201004 5.023 1 P 3 0;0=1,1=2
P 3.15398002 4.81401998 1 P 3 0;0=1,1=2
P 3.15743996 4.74418002 1 P 3 0;0=1,1=2
P 3.17873996 0.036 1 P 3 0;0=1,1=2
P 3.17901004 5.98761998 1 P 3 0;0=1,1=2
P 3.21743996 4.74418002 1 P 3 0;0=1,1=2
P 3.22288002 4.81401998 1 P 3 0;0=1,1=2
P 3.22288002 4.92 1 P 3 0;0=1,1=2
P 3.22288002 5.023 1 P 3 0;0=1,1=2
P 3.22831004 4.68073996 1 P 3 0;0=1,1=2
P 3.22831004 5.18128002 1 P 3 0;0=1,1=2
P 3.22873996 0.036 1 P 3 0;0=1,1=2
P 3.22901004 5.98761998 1 P 3 0;0=1,1=2
P 3.26 5.332 1 P 3 0;0=1,1=2
P 3.275 4.92 1 P 3 0;0=1,1=2
P 3.27873996 0.036 1 P 3 0;0=1,1=2
P 3.27901004 5.98761998 1 P 3 0;0=1,1=2
P 0.32873996 0.036 1 P 3 0;0=1,1=2
P 3.28831004 4.68073996 1 P 3 0;0=1,1=2
P 3.28831004 5.18128002 1 P 3 0;0=1,1=2
P 0.32901004 5.98761998 1 P 3 0;0=1,1=2
P 3.29373996 4.81401998 1 P 3 0;0=1,1=2
P 3.29373996 5.023 1 P 3 0;0=1,1=2
P 3.29916998 5.14223996 1 P 3 0;0=1,1=2
P 3.32873996 0.036 1 P 3 0;0=1,1=2
P 3.32901004 5.98761998 1 P 3 0;0=1,1=2
P 3.35916998 5.14223996 1 P 3 0;0=1,1=2
P 3.36461004 4.81401998 1 P 3 0;0=1,1=2
P 3.36461004 4.926 1 P 3 0;0=1,1=2
P 3.36461004 5.023 1 P 3 0;0=1,1=2
P 3.37003996 4.74418002 1 P 3 0;0=1,1=2
P 3.37003996 5.18128002 1 P 3 0;0=1,1=2
P 3.37873996 0.036 1 P 3 0;0=1,1=2
P 3.37901004 5.98761998 1 P 3 0;0=1,1=2
P 3.41 5.332 1 P 3 0;0=1,1=2
P 3.42873996 0.036 1 P 3 0;0=1,1=2
P 3.42901004 5.98761998 1 P 3 0;0=1,1=2
P 3.43003996 4.74418002 1 P 3 0;0=1,1=2
P 3.43003996 5.18128002 1 P 3 0;0=1,1=2
P 3.43546998 4.81401998 1 P 3 0;0=1,1=2
P 3.43546998 4.928 1 P 3 0;0=1,1=2
P 3.43546998 5.023 1 P 3 0;0=1,1=2
P 3.44091004 4.62573996 1 P 3 0;0=1,1=2
P 3.47873996 0.036 1 P 3 0;0=1,1=2
P 3.47901004 5.98761998 1 P 3 0;0=1,1=2
P 3.50091004 4.62573996 1 P 3 0;0=1,1=2
P 3.50633996 4.81401998 1 P 3 0;0=1,1=2
P 3.50633996 4.92 1 P 3 0;0=1,1=2
P 3.50633996 5.023 1 P 3 0;0=1,1=2
P 3.51176998 4.68098996 1 P 3 0;0=1,1=2
P 3.51176998 5.17873996 1 P 3 0;0=1,1=2
P 3.52873996 0.036 1 P 3 0;0=1,1=2
P 3.52901004 5.98761998 1 P 3 0;0=1,1=2
P 3.57 4.45 1 P 3 0;0=1,1=2
P 3.57176998 4.68098996 1 P 3 0;0=1,1=2
P 3.57176998 5.17873996 1 P 3 0;0=1,1=2
P 3.57721004 4.81401998 1 P 3 0;0=1,1=2
P 3.57721004 5.023 1 P 3 0;0=1,1=2
P 3.57873996 0.036 1 P 3 0;0=1,1=2
P 3.57901004 5.98761998 1 P 3 0;0=1,1=2
P 0.036 1.00868002 1 P 3 0;0=1,1=2
P 0.036 1.05868002 1 P 3 0;0=1,1=2
P 0.036 0.10868002 1 P 3 0;0=1,1=2
P 0.036 1.10868002 1 P 3 0;0=1,1=2
P 0.036 1.15868002 1 P 3 0;0=1,1=2
P 0.036 1.20868002 1 P 3 0;0=1,1=2
P 0.036 1.25868002 1 P 3 0;0=1,1=2
P 0.036 1.30868002 1 P 3 0;0=1,1=2
P 0.036 1.35868002 1 P 3 0;0=1,1=2
P 0.036 1.40868002 1 P 3 0;0=1,1=2
P 0.036 1.45868002 1 P 3 0;0=1,1=2
P 0.036 1.50868002 1 P 3 0;0=1,1=2
P 0.036 1.55868002 1 P 3 0;0=1,1=2
P 0.036 0.15868002 1 P 3 0;0=1,1=2
P 0.036 1.60868002 1 P 3 0;0=1,1=2
P 0.036 1.65868002 1 P 3 0;0=1,1=2
P 0.036 1.70868002 1 P 3 0;0=1,1=2
P 0.036 1.75868002 1 P 3 0;0=1,1=2
P 0.036 1.80868002 1 P 3 0;0=1,1=2
P 0.036 1.85868002 1 P 3 0;0=1,1=2
P 0.036 1.90868002 1 P 3 0;0=1,1=2
P 0.036 1.95868002 1 P 3 0;0=1,1=2
P 0.036 2.00868002 1 P 3 0;0=1,1=2
P 0.036 2.05868002 1 P 3 0;0=1,1=2
P 0.036 0.20868002 1 P 3 0;0=1,1=2
P 0.036 2.10868002 1 P 3 0;0=1,1=2
P 0.036 2.15868002 1 P 3 0;0=1,1=2
P 0.036 2.20868002 1 P 3 0;0=1,1=2
P 0.036 2.25868002 1 P 3 0;0=1,1=2
P 0.036 2.30868002 1 P 3 0;0=1,1=2
P 0.036 2.35868002 1 P 3 0;0=1,1=2
P 0.036 2.40868002 1 P 3 0;0=1,1=2
P 0.036 2.45868002 1 P 3 0;0=1,1=2
P 0.036 2.50868002 1 P 3 0;0=1,1=2
P 0.036 2.55868002 1 P 3 0;0=1,1=2
P 0.036 0.25868002 1 P 3 0;0=1,1=2
P 0.036 2.60868002 1 P 3 0;0=1,1=2
P 0.036 2.65868002 1 P 3 0;0=1,1=2
P 0.036 2.70868002 1 P 3 0;0=1,1=2
P 0.036 2.75868002 1 P 3 0;0=1,1=2
P 0.036 2.80868002 1 P 3 0;0=1,1=2
P 0.036 2.85868002 1 P 3 0;0=1,1=2
P 0.036 2.90868002 1 P 3 0;0=1,1=2
P 0.036 2.95868002 1 P 3 0;0=1,1=2
P 0.036 3.00868002 1 P 3 0;0=1,1=2
P 0.036 3.05868002 1 P 3 0;0=1,1=2
P 0.036 0.30868002 1 P 3 0;0=1,1=2
P 0.036 3.10868002 1 P 3 0;0=1,1=2
P 0.036 3.15868002 1 P 3 0;0=1,1=2
P 0.036 3.20868002 1 P 3 0;0=1,1=2
P 0.036 3.25868002 1 P 3 0;0=1,1=2
P 0.036 3.30868002 1 P 3 0;0=1,1=2
P 0.036 3.35868002 1 P 3 0;0=1,1=2
P 0.036 3.40868002 1 P 3 0;0=1,1=2
P 0.036 3.45868002 1 P 3 0;0=1,1=2
P 0.036 3.50868002 1 P 3 0;0=1,1=2
P 0.036 3.55868002 1 P 3 0;0=1,1=2
P 0.036 0.35868002 1 P 3 0;0=1,1=2
P 0.036 3.60868002 1 P 3 0;0=1,1=2
P 0.036 3.65868002 1 P 3 0;0=1,1=2
P 0.036 3.70868002 1 P 3 0;0=1,1=2
P 0.036 3.75868002 1 P 3 0;0=1,1=2
P 0.036 3.80868002 1 P 3 0;0=1,1=2
P 0.036 3.85868002 1 P 3 0;0=1,1=2
P 0.036 3.90868002 1 P 3 0;0=1,1=2
P 0.036 3.95868002 1 P 3 0;0=1,1=2
P 0.036 4.00868002 1 P 3 0;0=1,1=2
P 0.036 4.05868002 1 P 3 0;0=1,1=2
P 0.036 0.40868002 1 P 3 0;0=1,1=2
P 0.036 4.10868002 1 P 3 0;0=1,1=2
P 0.036 4.15868002 1 P 3 0;0=1,1=2
P 0.036 4.20868002 1 P 3 0;0=1,1=2
P 0.036 4.25868002 1 P 3 0;0=1,1=2
P 0.036 4.30868002 1 P 3 0;0=1,1=2
P 0.036 4.35868002 1 P 3 0;0=1,1=2
P 0.036 4.40868002 1 P 3 0;0=1,1=2
P 0.036 4.45868002 1 P 3 0;0=1,1=2
P 0.036 4.50868002 1 P 3 0;0=1,1=2
P 0.036 4.55868002 1 P 3 0;0=1,1=2
P 0.036 0.45868002 1 P 3 0;0=1,1=2
P 0.036 4.60868002 1 P 3 0;0=1,1=2
P 0.036 4.65868002 1 P 3 0;0=1,1=2
P 0.036 4.70868002 1 P 3 0;0=1,1=2
P 0.036 4.75868002 1 P 3 0;0=1,1=2
P 0.036 0.50868002 1 P 3 0;0=1,1=2
P 0.036 5.25868002 1 P 3 0;0=1,1=2
P 0.036 5.30868002 1 P 3 0;0=1,1=2
P 0.036 5.35868002 1 P 3 0;0=1,1=2
P 0.036 5.40868002 1 P 3 0;0=1,1=2
P 0.036 5.45868002 1 P 3 0;0=1,1=2
P 0.036 5.50868002 1 P 3 0;0=1,1=2
P 0.036 5.55868002 1 P 3 0;0=1,1=2
P 0.036 0.55868002 1 P 3 0;0=1,1=2
P 0.036 5.60868002 1 P 3 0;0=1,1=2
P 0.036 5.65868002 1 P 3 0;0=1,1=2
P 0.036 5.70868002 1 P 3 0;0=1,1=2
P 0.036 5.75868002 1 P 3 0;0=1,1=2
P 0.036 5.80868002 1 P 3 0;0=1,1=2
P 0.036 5.85868002 1 P 3 0;0=1,1=2
P 0.036 5.90868002 1 P 3 0;0=1,1=2
P 3.60998996 0.24 1 P 3 0;0=1,1=2
P 3.62873996 0.036 1 P 3 0;0=1,1=2
P 3.62901004 5.98761998 1 P 3 0;0=1,1=2
P 3.65998996 0.345 1 P 3 0;0=1,1=2
P 3.66 4.63 1 P 3 0;0=1,1=2
P 3.67873996 0.036 1 P 3 0;0=1,1=2
P 3.67901004 5.98761998 1 P 3 0;0=1,1=2
P 3.72 4.45 1 P 3 0;0=1,1=2
P 3.72873996 0.036 1 P 3 0;0=1,1=2
P 3.72901004 5.98761998 1 P 3 0;0=1,1=2
P 3.77 4.86 1 P 3 0;0=1,1=2
P 3.77873996 0.036 1 P 3 0;0=1,1=2
P 3.77901004 5.98761998 1 P 3 0;0=1,1=2
P 0.37873996 0.036 1 P 3 0;0=1,1=2
P 0.37901004 5.98761998 1 P 3 0;0=1,1=2
P 0.03826998 5.95863002 1 P 3 0;0=1,1=2
P 3.82873996 0.036 1 P 3 0;0=1,1=2
P 3.82901004 5.98761998 1 P 3 0;0=1,1=2
P 3.835 4.6 1 P 3 0;0=1,1=2
P 3.86826998 2.64558996 1 P 3 0;0=1,1=2
P 3.87 5.125 1 P 3 0;0=1,1=2
P 3.87873996 0.036 1 P 3 0;0=1,1=2
P 3.87901004 5.98761998 1 P 3 0;0=1,1=2
P 3.92873996 0.036 1 P 3 0;0=1,1=2
P 3.92901004 5.98761998 1 P 3 0;0=1,1=2
P 3.97873996 0.036 1 P 3 0;0=1,1=2
P 3.97901004 5.98761998 1 P 3 0;0=1,1=2
P 3.9865 4.635 1 P 3 0;0=1,1=2
P 4.02873996 0.036 1 P 3 0;0=1,1=2
P 4.02901004 5.98761998 1 P 3 0;0=1,1=2
P 4.07386004 2.55 1 P 3 0;0=1,1=2
P 4.07873996 0.036 1 P 3 0;0=1,1=2
P 4.07901004 5.98761998 1 P 3 0;0=1,1=2
P 4.1049 4.7649 1 P 3 0;0=1,1=2
P 4.12873996 0.036 1 P 3 0;0=1,1=2
P 4.12901004 5.98761998 1 P 3 0;0=1,1=2
P 4.14 4.655 1 P 3 0;0=1,1=2
P 4.15221004 2.9281 1 P 3 0;0=1,1=2
P 4.17873996 0.036 1 P 3 0;0=1,1=2
P 4.17901004 5.98761998 1 P 3 0;0=1,1=2
P 4.22873996 0.036 1 P 3 0;0=1,1=2
P 4.22901004 5.98761998 1 P 3 0;0=1,1=2
P 4.26105 4.9431 1 P 3 0;0=1,1=2
P 4.26105 4.9831 1 P 3 0;0=1,1=2
P 4.26105 5.0281 1 P 3 0;0=1,1=2
P 4.26105 5.0731 1 P 3 0;0=1,1=2
P 4.26105 5.1181 1 P 3 0;0=1,1=2
P 4.27873996 0.036 1 P 3 0;0=1,1=2
P 4.27901004 5.98761998 1 P 3 0;0=1,1=2
P 0.42873996 0.036 1 P 3 0;0=1,1=2
P 0.42901004 5.98761998 1 P 3 0;0=1,1=2
P 4.30105 4.9431 1 P 3 0;0=1,1=2
P 4.30105 4.9831 1 P 3 0;0=1,1=2
P 4.30105 5.0281 1 P 3 0;0=1,1=2
P 4.30105 5.0731 1 P 3 0;0=1,1=2
P 4.30105 5.1181 1 P 3 0;0=1,1=2
P 4.32873996 0.036 1 P 3 0;0=1,1=2
P 4.32901004 5.98761998 1 P 3 0;0=1,1=2
P 4.33605 4.9231 1 P 3 0;0=1,1=2
P 4.34105 5.1181 1 P 3 0;0=1,1=2
P 4.37873996 0.036 1 P 3 0;0=1,1=2
P 4.37901004 5.98761998 1 P 3 0;0=1,1=2
P 4.38105 4.9231 1 P 3 0;0=1,1=2
P 4.38105 5.1181 1 P 3 0;0=1,1=2
P 4.42105 4.9431 1 P 3 0;0=1,1=2
P 4.42105 4.9831 1 P 3 0;0=1,1=2
P 4.42105 5.0281 1 P 3 0;0=1,1=2
P 4.42105 5.0731 1 P 3 0;0=1,1=2
P 4.42105 5.1181 1 P 3 0;0=1,1=2
P 4.42873996 0.036 1 P 3 0;0=1,1=2
P 4.42901004 5.98761998 1 P 3 0;0=1,1=2
P 4.46105 4.9431 1 P 3 0;0=1,1=2
P 4.46105 4.9831 1 P 3 0;0=1,1=2
P 4.46105 5.0281 1 P 3 0;0=1,1=2
P 4.46105 5.0731 1 P 3 0;0=1,1=2
P 4.46105 5.1181 1 P 3 0;0=1,1=2
P 4.47873996 0.036 1 P 3 0;0=1,1=2
P 4.47901004 5.98761998 1 P 3 0;0=1,1=2
P 4.52873996 0.036 1 P 3 0;0=1,1=2
P 4.52901004 5.98761998 1 P 3 0;0=1,1=2
P 4.57873996 0.036 1 P 3 0;0=1,1=2
P 4.57901004 5.98761998 1 P 3 0;0=1,1=2
P 4.62873996 0.036 1 P 3 0;0=1,1=2
P 4.62901004 5.98761998 1 P 3 0;0=1,1=2
P 4.65105 4.9431 1 P 3 0;0=1,1=2
P 4.65105 4.9831 1 P 3 0;0=1,1=2
P 4.65105 5.0281 1 P 3 0;0=1,1=2
P 4.65105 5.0731 1 P 3 0;0=1,1=2
P 4.65105 5.1181 1 P 3 0;0=1,1=2
P 4.67873996 0.036 1 P 3 0;0=1,1=2
P 4.67901004 5.98761998 1 P 3 0;0=1,1=2
P 4.69105 4.9431 1 P 3 0;0=1,1=2
P 4.69105 4.9831 1 P 3 0;0=1,1=2
P 4.69105 5.0281 1 P 3 0;0=1,1=2
P 4.69105 5.0731 1 P 3 0;0=1,1=2
P 4.69105 5.1181 1 P 3 0;0=1,1=2
P 4.7 5.54928996 1 P 3 0;0=1,1=2
P 4.72605 4.9231 1 P 3 0;0=1,1=2
P 4.72873996 0.036 1 P 3 0;0=1,1=2
P 4.72901004 5.98761998 1 P 3 0;0=1,1=2
P 4.73105 5.1181 1 P 3 0;0=1,1=2
P 4.77105 4.9231 1 P 3 0;0=1,1=2
P 4.77105 5.1181 1 P 3 0;0=1,1=2
P 4.77873996 0.03611998 1 P 3 0;0=1,1=2
P 4.77901004 5.98761998 1 P 3 0;0=1,1=2
P 0.47873996 0.036 1 P 3 0;0=1,1=2
P 0.47901004 5.98761998 1 P 3 0;0=1,1=2
P 4.81 5.375 1 P 3 0;0=1,1=2
P 4.81105 4.9431 1 P 3 0;0=1,1=2
P 4.81105 4.9831 1 P 3 0;0=1,1=2
P 4.81105 5.0281 1 P 3 0;0=1,1=2
P 4.81105 5.0731 1 P 3 0;0=1,1=2
P 4.81105 5.1181 1 P 3 0;0=1,1=2
P 4.81703996 0.06826004 1 P 3 0;0=1,1=2
P 4.81833996 0.11825 1 P 3 0;0=1,1=2
P 4.81833996 0.16825 1 P 3 0;0=1,1=2
P 4.81833996 0.21825 1 P 3 0;0=1,1=2
P 4.81833996 0.26825 1 P 3 0;0=1,1=2
P 4.81833996 0.31825 1 P 3 0;0=1,1=2
P 4.81918996 0.36823996 1 P 3 0;0=1,1=2
P 0.4826 5.8976 1 P 3 0;0=1,1=2
P 4.82901004 5.98761998 1 P 3 0;0=1,1=2
P 4.83591004 0.41536004 1 P 3 0;0=1,1=2
P 4.85105 4.9431 1 P 3 0;0=1,1=2
P 4.85105 4.9831 1 P 3 0;0=1,1=2
P 4.85105 5.0281 1 P 3 0;0=1,1=2
P 4.85105 5.0731 1 P 3 0;0=1,1=2
P 4.85105 5.1181 1 P 3 0;0=1,1=2
P 4.87108996 0.45088996 1 P 3 0;0=1,1=2
P 4.87901004 5.98761998 1 P 3 0;0=1,1=2
P 4.91805 0.46808002 1 P 3 0;0=1,1=2
P 4.92 5.7 1 P 3 0;0=1,1=2
P 4.92901004 5.98761998 1 P 3 0;0=1,1=2
P 4.96 5.375 1 P 3 0;0=1,1=2
P 4.96803996 0.46906998 1 P 3 0;0=1,1=2
P 4.97901004 5.98761998 1 P 3 0;0=1,1=2
P 5.01803996 0.46906998 1 P 3 0;0=1,1=2
P 5.02901004 5.98761998 1 P 3 0;0=1,1=2
P 5.04441004 5.605 1 P 3 0;0=1,1=2
P 5.06803996 0.46906998 1 P 3 0;0=1,1=2
P 5.07901004 5.98761998 1 P 3 0;0=1,1=2
P 5.11803996 0.46906998 1 P 3 0;0=1,1=2
P 5.12901004 5.98761998 1 P 3 0;0=1,1=2
P 5.16 5.645 1 P 3 0;0=1,1=2
P 5.16803996 0.46906998 1 P 3 0;0=1,1=2
P 5.17901004 5.98761998 1 P 3 0;0=1,1=2
P 5.21803996 0.46906998 1 P 3 0;0=1,1=2
P 5.22901004 5.98761998 1 P 3 0;0=1,1=2
P 5.26803996 0.46906998 1 P 3 0;0=1,1=2
P 5.27901004 5.98761998 1 P 3 0;0=1,1=2
P 0.52873996 0.036 1 P 3 0;0=1,1=2
P 0.52901004 5.98761998 1 P 3 0;0=1,1=2
P 5.31803996 0.46906998 1 P 3 0;0=1,1=2
P 5.32901004 5.98761998 1 P 3 0;0=1,1=2
P 5.36803996 0.46906998 1 P 3 0;0=1,1=2
P 5.37901004 5.98761998 1 P 3 0;0=1,1=2
P 5.38048002 1.5957 1 P 3 0;0=1,1=2
P 5.38048002 1.6528 1 P 3 0;0=1,1=2
P 5.38048002 1.732 1 P 3 0;0=1,1=2
P 5.38048002 1.7891 1 P 3 0;0=1,1=2
P 5.38048002 1.8717 1 P 3 0;0=1,1=2
P 5.38048002 1.9288 1 P 3 0;0=1,1=2
P 5.38048002 2.0071 1 P 3 0;0=1,1=2
P 5.38048002 2.0642 1 P 3 0;0=1,1=2
P 5.38048002 2.1478 1 P 3 0;0=1,1=2
P 5.38048002 2.2049 1 P 3 0;0=1,1=2
P 5.38048002 2.2832 1 P 3 0;0=1,1=2
P 5.38048002 2.3403 1 P 3 0;0=1,1=2
P 5.38048002 2.4186 1 P 3 0;0=1,1=2
P 5.38048002 2.4757 1 P 3 0;0=1,1=2
P 5.38048002 2.5578 1 P 3 0;0=1,1=2
P 5.38048002 2.6149 1 P 3 0;0=1,1=2
P 5.41803996 0.46906998 1 P 3 0;0=1,1=2
P 5.42901004 5.98761998 1 P 3 0;0=1,1=2
P 5.44886004 2.9414 1 P 3 0;0=1,1=2
P 5.44886004 2.9764 1 P 3 0;0=1,1=2
P 5.44886004 3.0214 1 P 3 0;0=1,1=2
P 5.44886004 3.0564 1 P 3 0;0=1,1=2
P 5.44886004 3.1014 1 P 3 0;0=1,1=2
P 5.44886004 3.1364 1 P 3 0;0=1,1=2
P 5.44886004 3.1814 1 P 3 0;0=1,1=2
P 5.44886004 3.2164 1 P 3 0;0=1,1=2
P 5.44886004 3.2614 1 P 3 0;0=1,1=2
P 5.44886004 3.2964 1 P 3 0;0=1,1=2
P 5.46803996 0.46906998 1 P 3 0;0=1,1=2
P 5.47901004 5.98761998 1 P 3 0;0=1,1=2
P 5.49221004 2.73 1 P 3 0;0=1,1=2
P 5.51803996 0.46906998 1 P 3 0;0=1,1=2
P 5.52901004 5.98761998 1 P 3 0;0=1,1=2
P 5.53531004 1.6642 1 P 3 0;0=1,1=2
P 5.53531004 1.7213 1 P 3 0;0=1,1=2
P 5.53531004 1.8032 1 P 3 0;0=1,1=2
P 5.53531004 1.8603 1 P 3 0;0=1,1=2
P 5.53531004 1.9393 1 P 3 0;0=1,1=2
P 5.53531004 1.9964 1 P 3 0;0=1,1=2
P 5.53531004 2.0802 1 P 3 0;0=1,1=2
P 5.53531004 2.1373 1 P 3 0;0=1,1=2
P 5.53531004 2.2156 1 P 3 0;0=1,1=2
P 5.53531004 2.2727 1 P 3 0;0=1,1=2
P 5.53531004 2.351 1 P 3 0;0=1,1=2
P 5.53531004 2.4081 1 P 3 0;0=1,1=2
P 5.53531004 2.4902 1 P 3 0;0=1,1=2
P 5.53531004 2.5473 1 P 3 0;0=1,1=2
P 5.53531004 2.6254 1 P 3 0;0=1,1=2
P 5.53531004 2.6825 1 P 3 0;0=1,1=2
P 5.53593996 4.55505 1 P 3 0;0=1,1=2
P 5.56803996 0.46906998 1 P 3 0;0=1,1=2
P 5.5722 3 1 P 3 0;0=1,1=2
P 5.57708996 4.5102 1 P 3 0;0=1,1=2
P 5.57901004 5.98761998 1 P 3 0;0=1,1=2
P 5.5822 2.855 1 P 3 0;0=1,1=2
P 5.61708996 4.5102 1 P 3 0;0=1,1=2
P 5.61803996 0.46906998 1 P 3 0;0=1,1=2
P 5.62901004 5.98761998 1 P 3 0;0=1,1=2
P 5.65708996 4.5102 1 P 3 0;0=1,1=2
P 5.66803996 0.46906998 1 P 3 0;0=1,1=2
P 5.67901004 5.98761998 1 P 3 0;0=1,1=2
P 5.69708996 4.5102 1 P 3 0;0=1,1=2
P 5.71803996 0.46906998 1 P 3 0;0=1,1=2
P 5.72901004 5.98761998 1 P 3 0;0=1,1=2
P 5.73708996 4.5102 1 P 3 0;0=1,1=2
P 5.75778996 3.02558996 1 P 3 0;0=1,1=2
P 5.76803996 0.46906998 1 P 3 0;0=1,1=2
P 5.77708996 4.5102 1 P 3 0;0=1,1=2
P 5.77901004 5.98761998 1 P 3 0;0=1,1=2
P 0.57873996 0.036 1 P 3 0;0=1,1=2
P 0.57901004 5.98761998 1 P 3 0;0=1,1=2
P 5.81708996 4.5102 1 P 3 0;0=1,1=2
P 5.81803996 0.46906998 1 P 3 0;0=1,1=2
P 5.82901004 5.98761998 1 P 3 0;0=1,1=2
P 5.84968996 2.85 1 P 3 0;0=1,1=2
P 5.85708996 4.5102 1 P 3 0;0=1,1=2
P 5.86803996 0.46906998 1 P 3 0;0=1,1=2
P 5.87901004 5.98761998 1 P 3 0;0=1,1=2
P 5.89708996 4.5102 1 P 3 0;0=1,1=2
P 5.91803996 0.46906998 1 P 3 0;0=1,1=2
P 5.9192 2.943 1 P 3 0;0=1,1=2
P 5.92901004 5.98761998 1 P 3 0;0=1,1=2
P 5.93708996 4.5102 1 P 3 0;0=1,1=2
P 5.96803996 0.46906998 1 P 3 0;0=1,1=2
P 5.97708996 4.5102 1 P 3 0;0=1,1=2
P 5.97901004 5.98761998 1 P 3 0;0=1,1=2
P 6.01708996 4.5102 1 P 3 0;0=1,1=2
P 6.01803996 0.46906998 1 P 3 0;0=1,1=2
P 6.02901004 5.98761998 1 P 3 0;0=1,1=2
P 6.05708996 4.5102 1 P 3 0;0=1,1=2
P 6.06803996 0.46906998 1 P 3 0;0=1,1=2
P 6.07901004 5.98761998 1 P 3 0;0=1,1=2
P 6.09708996 4.5102 1 P 3 0;0=1,1=2
P 6.11803996 0.46906998 1 P 3 0;0=1,1=2
P 6.12901004 5.98761998 1 P 3 0;0=1,1=2
P 6.16803996 0.46906998 1 P 3 0;0=1,1=2
P 6.17901004 5.98761998 1 P 3 0;0=1,1=2
P 6.21803996 0.46906998 1 P 3 0;0=1,1=2
P 6.22901004 5.98761998 1 P 3 0;0=1,1=2
P 6.26803996 0.46906998 1 P 3 0;0=1,1=2
P 6.27901004 5.98761998 1 P 3 0;0=1,1=2
P 0.62873996 0.036 1 P 3 0;0=1,1=2
P 0.62901004 5.98761998 1 P 3 0;0=1,1=2
P 6.31295 4.99705 1 P 3 0;0=1,1=2
P 6.315 4.625 1 P 3 0;0=1,1=2
P 6.315 4.66 1 P 3 0;0=1,1=2
P 6.315 4.705 1 P 3 0;0=1,1=2
P 6.315 4.74 1 P 3 0;0=1,1=2
P 6.315 4.785 1 P 3 0;0=1,1=2
P 6.315 4.82 1 P 3 0;0=1,1=2
P 6.315 4.865 1 P 3 0;0=1,1=2
P 6.315 4.9 1 P 3 0;0=1,1=2
P 6.31803996 0.46906998 1 P 3 0;0=1,1=2
P 6.32901004 5.98761998 1 P 3 0;0=1,1=2
P 6.36803996 0.46906998 1 P 3 0;0=1,1=2
P 6.37901004 5.98761998 1 P 3 0;0=1,1=2
P 6.385 5.07 1 P 3 0;0=1,1=2
P 6.41803996 0.46906998 1 P 3 0;0=1,1=2
P 6.42901004 5.98761998 1 P 3 0;0=1,1=2
P 6.46803996 0.46906998 1 P 3 0;0=1,1=2
P 6.47901004 5.98761998 1 P 3 0;0=1,1=2
P 6.51803002 0.46861998 1 P 3 0;0=1,1=2
P 6.52901004 5.98761998 1 P 3 0;0=1,1=2
P 0.65348996 1.85608996 1 P 3 0;0=1,1=2
P 0.65348996 1.91628996 1 P 3 0;0=1,1=2
P 6.56568002 0.45345 1 P 3 0;0=1,1=2
P 6.57901004 5.98761998 1 P 3 0;0=1,1=2
P 6.59708996 5.0502 1 P 3 0;0=1,1=2
P 6.60233996 0.41946004 1 P 3 0;0=1,1=2
P 6.605 4.77 1 P 3 0;0=1,1=2
P 6.62 4.61 1 P 3 0;0=1,1=2
P 6.62 4.645 1 P 3 0;0=1,1=2
P 6.62 4.69 1 P 3 0;0=1,1=2
P 6.62 4.725 1 P 3 0;0=1,1=2
P 6.62106998 0.3731 1 P 3 0;0=1,1=2
P 6.62261998 0.12311998 1 P 3 0;0=1,1=2
P 6.62261998 0.17311998 1 P 3 0;0=1,1=2
P 6.62261998 0.22311998 1 P 3 0;0=1,1=2
P 6.62261998 0.27311998 1 P 3 0;0=1,1=2
P 6.62261998 0.32311998 1 P 3 0;0=1,1=2
P 6.62298996 0.07311998 1 P 3 0;0=1,1=2
P 6.62901004 5.98761998 1 P 3 0;0=1,1=2
P 6.65218996 4.77 1 P 3 0;0=1,1=2
P 6.65731004 0.03676004 1 P 3 0;0=1,1=2
P 6.67901004 5.98761998 1 P 3 0;0=1,1=2
P 6.70731004 0.036 1 P 3 0;0=1,1=2
P 6.72901004 5.98761998 1 P 3 0;0=1,1=2
P 6.75731004 0.036 1 P 3 0;0=1,1=2
P 6.77901004 5.98761998 1 P 3 0;0=1,1=2
P 0.67873996 0.036 1 P 3 0;0=1,1=2
P 0.67901004 5.98761998 1 P 3 0;0=1,1=2
P 6.80731004 0.036 1 P 3 0;0=1,1=2
P 6.82901004 5.98761998 1 P 3 0;0=1,1=2
P 6.85731004 0.036 1 P 3 0;0=1,1=2
P 6.87 5 1 P 3 0;0=1,1=2
P 6.87901004 5.98761998 1 P 3 0;0=1,1=2
P 6.905 4.88705 1 P 3 0;0=1,1=2
P 6.905 4.94705 1 P 3 0;0=1,1=2
P 6.90731004 0.036 1 P 3 0;0=1,1=2
P 6.92901004 5.98761998 1 P 3 0;0=1,1=2
P 6.955 4.72 1 P 3 0;0=1,1=2
P 6.955 4.76 1 P 3 0;0=1,1=2
P 6.955 4.8 1 P 3 0;0=1,1=2
P 6.955 4.84 1 P 3 0;0=1,1=2
P 6.95731004 0.036 1 P 3 0;0=1,1=2
P 6.97901004 5.98761998 1 P 3 0;0=1,1=2
P 7.00731004 0.036 1 P 3 0;0=1,1=2
P 0.705 5.355 1 P 3 0;0=1,1=2
P 7.1926 5.04351004 1 P 3 0;0=1,1=2
P 7.2426 4.60351004 1 P 3 0;0=1,1=2
P 0.72873996 0.036 1 P 3 0;0=1,1=2
P 0.72901004 5.98761998 1 P 3 0;0=1,1=2
P 0.73 5.175 1 P 3 0;0=1,1=2
P 7.3401 4.85601004 1 P 3 0;0=1,1=2
P 7.35731004 0.036 1 P 3 0;0=1,1=2
P 7.37901004 5.98761998 1 P 3 0;0=1,1=2
P 7.40731004 0.036 1 P 3 0;0=1,1=2
P 7.42901004 5.98761998 1 P 3 0;0=1,1=2
P 7.45731004 0.036 1 P 3 0;0=1,1=2
P 7.47901004 5.98761998 1 P 3 0;0=1,1=2
P 7.50731004 0.036 1 P 3 0;0=1,1=2
P 7.52901004 5.98761998 1 P 3 0;0=1,1=2
P 7.55731004 0.036 1 P 3 0;0=1,1=2
P 7.56575 4.81401998 1 P 3 0;0=1,1=2
P 7.56575 5.023 1 P 3 0;0=1,1=2
P 7.57118996 4.66826004 1 P 3 0;0=1,1=2
P 7.57118996 5.13026004 1 P 3 0;0=1,1=2
P 7.57901004 5.98761998 1 P 3 0;0=1,1=2
P 7.60731004 0.036 1 P 3 0;0=1,1=2
P 7.62901004 5.98761998 1 P 3 0;0=1,1=2
P 7.63118996 4.66826004 1 P 3 0;0=1,1=2
P 7.63118996 5.13026004 1 P 3 0;0=1,1=2
P 7.63526998 4.81526998 1 P 3 0;0=1,1=2
P 7.63661998 4.92 1 P 3 0;0=1,1=2
P 7.63661998 5.023 1 P 3 0;0=1,1=2
P 7.64203996 5.09223996 1 P 3 0;0=1,1=2
P 7.64205 4.74418002 1 P 3 0;0=1,1=2
P 7.65731004 0.036 1 P 3 0;0=1,1=2
P 7.67901004 5.98761998 1 P 3 0;0=1,1=2
P 7.70203996 5.09223996 1 P 3 0;0=1,1=2
P 7.70205 4.74418002 1 P 3 0;0=1,1=2
P 7.70353996 4.812 1 P 3 0;0=1,1=2
P 7.70731004 0.036 1 P 3 0;0=1,1=2
P 7.70748996 4.9207 1 P 3 0;0=1,1=2
P 7.70748996 5.023 1 P 3 0;0=1,1=2
P 7.72901004 5.98761998 1 P 3 0;0=1,1=2
P 7.75731004 0.036 1 P 3 0;0=1,1=2
P 7.77835 4.9207 1 P 3 0;0=1,1=2
P 7.77835 5.023 1 P 3 0;0=1,1=2
P 7.77901004 5.98761998 1 P 3 0;0=1,1=2
P 7.77953996 4.812 1 P 3 0;0=1,1=2
P 0.77873996 0.036 1 P 3 0;0=1,1=2
P 7.78378996 4.74418002 1 P 3 0;0=1,1=2
P 0.77901004 5.98761998 1 P 3 0;0=1,1=2
P 0.07873996 0.036 1 P 3 0;0=1,1=2
P 7.80731004 0.036 1 P 3 0;0=1,1=2
P 7.82901004 5.98761998 1 P 3 0;0=1,1=2
P 7.84378996 4.74418002 1 P 3 0;0=1,1=2
P 7.84921998 4.81 1 P 3 0;0=1,1=2
P 7.84921998 4.9207 1 P 3 0;0=1,1=2
P 7.84921998 5.023 1 P 3 0;0=1,1=2
P 7.85465 4.61826004 1 P 3 0;0=1,1=2
P 7.85465 5.13026004 1 P 3 0;0=1,1=2
P 7.85731004 0.036 1 P 3 0;0=1,1=2
P 7.87901004 5.98761998 1 P 3 0;0=1,1=2
P 0.07901004 5.98761998 1 P 3 0;0=1,1=2
P 7.90731004 0.036 1 P 3 0;0=1,1=2
P 7.91465 4.61826004 1 P 3 0;0=1,1=2
P 7.91465 5.13026004 1 P 3 0;0=1,1=2
P 7.92008002 4.9207 1 P 3 0;0=1,1=2
P 7.92008002 5.023 1 P 3 0;0=1,1=2
P 7.92353996 4.81 1 P 3 0;0=1,1=2
P 7.92551004 5.09223996 1 P 3 0;0=1,1=2
P 7.927 5.377 1 P 3 0;0=1,1=2
P 7.92901004 5.98761998 1 P 3 0;0=1,1=2
P 7.95731004 0.036 1 P 3 0;0=1,1=2
P 7.97901004 5.98761998 1 P 3 0;0=1,1=2
P 7.98551004 5.09223996 1 P 3 0;0=1,1=2
P 7.99095 4.9207 1 P 3 0;0=1,1=2
P 7.99095 5.023 1 P 3 0;0=1,1=2
P 7.99353996 4.81 1 P 3 0;0=1,1=2
P 8.00731004 0.036 1 P 3 0;0=1,1=2
P 8.02206998 4.62815 1 P 3 0;0=1,1=2
P 8.02901004 5.98761998 1 P 3 0;0=1,1=2
P 8.05731004 0.036 1 P 3 0;0=1,1=2
P 8.06181998 4.9207 1 P 3 0;0=1,1=2
P 8.06181998 5.023 1 P 3 0;0=1,1=2
P 8.06441004 4.81 1 P 3 0;0=1,1=2
P 8.06725 4.74418002 1 P 3 0;0=1,1=2
P 8.06725 5.13026004 1 P 3 0;0=1,1=2
P 8.07901004 5.98761998 1 P 3 0;0=1,1=2
P 8.08206998 4.62815 1 P 3 0;0=1,1=2
P 8.10731004 0.036 1 P 3 0;0=1,1=2
P 8.12725 4.74418002 1 P 3 0;0=1,1=2
P 8.12725 5.13026004 1 P 3 0;0=1,1=2
P 8.12901004 5.98761998 1 P 3 0;0=1,1=2
P 8.13268002 4.81 1 P 3 0;0=1,1=2
P 8.13268002 4.9207 1 P 3 0;0=1,1=2
P 8.13268002 5.023 1 P 3 0;0=1,1=2
P 8.13811004 5.09223996 1 P 3 0;0=1,1=2
P 8.147 5.377 1 P 3 0;0=1,1=2
P 8.15731004 0.036 1 P 3 0;0=1,1=2
P 8.17901004 5.98761998 1 P 3 0;0=1,1=2
P 8.19811004 5.09223996 1 P 3 0;0=1,1=2
P 8.20355 4.81 1 P 3 0;0=1,1=2
P 8.20355 4.9267 1 P 3 0;0=1,1=2
P 8.20355 5.023 1 P 3 0;0=1,1=2
P 8.20731004 0.036 1 P 3 0;0=1,1=2
P 8.20898002 4.74418002 1 P 3 0;0=1,1=2
P 8.21208996 4.62826004 1 P 3 0;0=1,1=2
P 8.22901004 5.98761998 1 P 3 0;0=1,1=2
P 8.25731004 0.036 1 P 3 0;0=1,1=2
P 8.26898002 4.74418002 1 P 3 0;0=1,1=2
P 8.27208996 4.62826004 1 P 3 0;0=1,1=2
P 8.27441004 4.81 1 P 3 0;0=1,1=2
P 8.27441004 4.9207 1 P 3 0;0=1,1=2
P 8.27441004 5.023 1 P 3 0;0=1,1=2
P 8.27901004 5.98761998 1 P 3 0;0=1,1=2
P 0.82873996 0.036 1 P 3 0;0=1,1=2
P 0.82901004 5.98761998 1 P 3 0;0=1,1=2
P 8.30731004 0.036 1 P 3 0;0=1,1=2
P 8.32901004 5.98761998 1 P 3 0;0=1,1=2
P 8.34528002 4.81 1 P 3 0;0=1,1=2
P 8.34528002 4.9207 1 P 3 0;0=1,1=2
P 8.34528002 5.023 1 P 3 0;0=1,1=2
P 8.35071004 4.70326004 1 P 3 0;0=1,1=2
P 8.35071004 5.15373996 1 P 3 0;0=1,1=2
P 8.35731004 0.036 1 P 3 0;0=1,1=2
P 8.37901004 5.98761998 1 P 3 0;0=1,1=2
P 8.40731004 0.036 1 P 3 0;0=1,1=2
P 8.41071004 4.70326004 1 P 3 0;0=1,1=2
P 8.41071004 5.15373996 1 P 3 0;0=1,1=2
P 8.41615 4.81401998 1 P 3 0;0=1,1=2
P 8.41615 5.023 1 P 3 0;0=1,1=2
P 8.42901004 5.98761998 1 P 3 0;0=1,1=2
P 8.45731004 0.036 1 P 3 0;0=1,1=2
P 8.47901004 5.98761998 1 P 3 0;0=1,1=2
P 0.84953002 5.17 1 P 3 0;0=1,1=2
P 8.50731004 0.036 1 P 3 0;0=1,1=2
P 8.52901004 5.98761998 1 P 3 0;0=1,1=2
P 8.55731004 0.036 1 P 3 0;0=1,1=2
P 8.57901004 5.98761998 1 P 3 0;0=1,1=2
P 8.60731004 0.036 1 P 3 0;0=1,1=2
P 8.62901004 5.98761998 1 P 3 0;0=1,1=2
P 8.65731004 0.036 1 P 3 0;0=1,1=2
P 8.67901004 5.98761998 1 P 3 0;0=1,1=2
P 8.70731004 0.036 1 P 3 0;0=1,1=2
P 8.72901004 5.98761998 1 P 3 0;0=1,1=2
P 8.73035 4.81401998 1 P 3 0;0=1,1=2
P 8.73035 5.023 1 P 3 0;0=1,1=2
P 8.73578996 4.70573996 1 P 3 0;0=1,1=2
P 8.73578996 5.17873996 1 P 3 0;0=1,1=2
P 8.75731004 0.036 1 P 3 0;0=1,1=2
P 8.77901004 5.98761998 1 P 3 0;0=1,1=2
P 0.87873996 0.036 1 P 3 0;0=1,1=2
P 0.87901004 5.98761998 1 P 3 0;0=1,1=2
P 8.79578996 4.70573996 1 P 3 0;0=1,1=2
P 8.79578996 5.17873996 1 P 3 0;0=1,1=2
P 8.80121998 4.81401998 1 P 3 0;0=1,1=2
P 8.80121998 4.92 1 P 3 0;0=1,1=2
P 8.80121998 5.023 1 P 3 0;0=1,1=2
P 8.80665 4.74418002 1 P 3 0;0=1,1=2
P 8.80731004 0.036 1 P 3 0;0=1,1=2
P 8.82901004 5.98761998 1 P 3 0;0=1,1=2
P 8.85731004 0.036 1 P 3 0;0=1,1=2
P 8.86665 4.74418002 1 P 3 0;0=1,1=2
P 8.86908996 4.81401998 1 P 3 0;0=1,1=2
P 8.87208996 4.92 1 P 3 0;0=1,1=2
P 8.87208996 5.023 1 P 3 0;0=1,1=2
P 8.87441004 5.20876004 1 P 3 0;0=1,1=2
P 8.87901004 5.98761998 1 P 3 0;0=1,1=2
P 8.88061998 4.70573996 1 P 3 0;0=1,1=2
P 8.90731004 0.036 1 P 3 0;0=1,1=2
P 8.92901004 5.98761998 1 P 3 0;0=1,1=2
P 8.93441004 5.20876004 1 P 3 0;0=1,1=2
P 8.94061998 4.70573996 1 P 3 0;0=1,1=2
P 8.94278996 2.925 1 P 3 0;0=1,1=2
P 8.94295 5.023 1 P 3 0;0=1,1=2
P 8.94495 4.81401998 1 P 3 0;0=1,1=2
P 8.94853996 4.92 1 P 3 0;0=1,1=2
P 8.95731004 0.036 1 P 3 0;0=1,1=2
P 8.97901004 5.98761998 1 P 3 0;0=1,1=2
P 8.98115 2.7861 1 P 3 0;0=1,1=2
P 8.98115 2.8989 1 P 3 0;0=1,1=2
P 9.00731004 0.036 1 P 3 0;0=1,1=2
P 9.01381998 4.81401998 1 P 3 0;0=1,1=2
P 9.01381998 4.92 1 P 3 0;0=1,1=2
P 9.01381998 5.023 1 P 3 0;0=1,1=2
P 9.01925 4.70573996 1 P 3 0;0=1,1=2
P 9.01925 5.20373996 1 P 3 0;0=1,1=2
P 9.02901004 5.98761998 1 P 3 0;0=1,1=2
P 9.05731004 0.036 1 P 3 0;0=1,1=2
P 9.07 5.332 1 P 3 0;0=1,1=2
P 9.07901004 5.98761998 1 P 3 0;0=1,1=2
P 9.07925 4.70573996 1 P 3 0;0=1,1=2
P 9.07925 5.20373996 1 P 3 0;0=1,1=2
P 9.08045 4.81401998 1 P 3 0;0=1,1=2
P 9.08468002 4.92 1 P 3 0;0=1,1=2
P 9.08468002 5.023 1 P 3 0;0=1,1=2
P 9.09011004 5.09223996 1 P 3 0;0=1,1=2
P 9.10731004 0.036 1 P 3 0;0=1,1=2
P 9.12901004 5.98761998 1 P 3 0;0=1,1=2
P 9.14353996 4.92 1 P 3 0;0=1,1=2
P 9.15011004 5.09223996 1 P 3 0;0=1,1=2
P 9.15555 5.023 1 P 3 0;0=1,1=2
P 9.15731004 0.036 1 P 3 0;0=1,1=2
P 9.15751998 4.81401998 1 P 3 0;0=1,1=2
P 9.16098002 4.74418002 1 P 3 0;0=1,1=2
P 9.17901004 5.98761998 1 P 3 0;0=1,1=2
P 9.20731004 0.036 1 P 3 0;0=1,1=2
P 9.22098002 4.74418002 1 P 3 0;0=1,1=2
P 9.22641998 4.81401998 1 P 3 0;0=1,1=2
P 9.22641998 4.92 1 P 3 0;0=1,1=2
P 9.22641998 5.023 1 P 3 0;0=1,1=2
P 9.22901004 5.98761998 1 P 3 0;0=1,1=2
P 9.23185 4.68073996 1 P 3 0;0=1,1=2
P 9.23185 5.18128002 1 P 3 0;0=1,1=2
P 9.25731004 0.036 1 P 3 0;0=1,1=2
P 9.265 5.332 1 P 3 0;0=1,1=2
P 9.27853996 4.92 1 P 3 0;0=1,1=2
P 9.27901004 5.98761998 1 P 3 0;0=1,1=2
P 0.92873996 0.036 1 P 3 0;0=1,1=2
P 0.92901004 5.98761998 1 P 3 0;0=1,1=2
P 9.29185 4.68073996 1 P 3 0;0=1,1=2
P 9.29185 5.18128002 1 P 3 0;0=1,1=2
P 9.29728002 4.81401998 1 P 3 0;0=1,1=2
P 9.29728002 5.023 1 P 3 0;0=1,1=2
P 9.30271004 5.14223996 1 P 3 0;0=1,1=2
P 9.30731004 0.036 1 P 3 0;0=1,1=2
P 9.32901004 5.98761998 1 P 3 0;0=1,1=2
P 9.35731004 0.036 1 P 3 0;0=1,1=2
P 9.36271004 5.14223996 1 P 3 0;0=1,1=2
P 9.36815 4.81401998 1 P 3 0;0=1,1=2
P 9.36815 4.926 1 P 3 0;0=1,1=2
P 9.36815 5.023 1 P 3 0;0=1,1=2
P 9.37358002 4.74418002 1 P 3 0;0=1,1=2
P 9.37358002 5.18128002 1 P 3 0;0=1,1=2
P 9.37901004 5.98761998 1 P 3 0;0=1,1=2
P 9.40731004 0.036 1 P 3 0;0=1,1=2
P 9.40795 0.26133002 1 P 3 0;0=1,1=2
P 9.415 5.332 1 P 3 0;0=1,1=2
P 9.42901004 5.98761998 1 P 3 0;0=1,1=2
P 9.43358002 4.74418002 1 P 3 0;0=1,1=2
P 9.43358002 5.18128002 1 P 3 0;0=1,1=2
P 9.43901004 4.81401998 1 P 3 0;0=1,1=2
P 9.43901004 4.928 1 P 3 0;0=1,1=2
P 9.43901004 5.023 1 P 3 0;0=1,1=2
P 9.44445 4.62573996 1 P 3 0;0=1,1=2
P 9.45731004 0.036 1 P 3 0;0=1,1=2
P 9.45795 0.36633002 1 P 3 0;0=1,1=2
P 9.47901004 5.98761998 1 P 3 0;0=1,1=2
P 9.50445 4.62573996 1 P 3 0;0=1,1=2
P 9.50731004 0.036 1 P 3 0;0=1,1=2
P 9.50988002 4.81401998 1 P 3 0;0=1,1=2
P 9.50988002 4.92 1 P 3 0;0=1,1=2
P 9.50988002 5.023 1 P 3 0;0=1,1=2
P 9.51531004 4.68098996 1 P 3 0;0=1,1=2
P 9.51531004 5.17873996 1 P 3 0;0=1,1=2
P 9.52901004 5.98761998 1 P 3 0;0=1,1=2
P 0.955 5.325 1 P 3 0;0=1,1=2
P 9.55731004 0.036 1 P 3 0;0=1,1=2
P 9.57531004 4.68098996 1 P 3 0;0=1,1=2
P 9.57531004 5.17873996 1 P 3 0;0=1,1=2
P 9.57901004 5.98761998 1 P 3 0;0=1,1=2
P 9.58075 4.81401998 1 P 3 0;0=1,1=2
P 9.58075 5.023 1 P 3 0;0=1,1=2
P 9.60731004 0.036 1 P 3 0;0=1,1=2
P 9.62901004 5.98761998 1 P 3 0;0=1,1=2
P 9.64796004 0.79643002 1 P 3 0;0=1,1=2
P 9.65731004 0.036 1 P 3 0;0=1,1=2
P 9.67901004 5.98761998 1 P 3 0;0=1,1=2
P 9.70731004 0.036 1 P 3 0;0=1,1=2
P 9.72901004 5.98761998 1 P 3 0;0=1,1=2
P 9.75731004 0.036 1 P 3 0;0=1,1=2
P 9.77901004 5.98761998 1 P 3 0;0=1,1=2
P 0.97873996 0.036 1 P 3 0;0=1,1=2
P 0.97901004 5.98761998 1 P 3 0;0=1,1=2
P 9.80731004 0.036 1 P 3 0;0=1,1=2
P 9.82901004 5.98761998 1 P 3 0;0=1,1=2
P 9.85731004 0.036 1 P 3 0;0=1,1=2
P 9.87901004 5.98761998 1 P 3 0;0=1,1=2
P 9.90731004 0.036 1 P 3 0;0=1,1=2
P 9.91 4.7 1 P 3 0;0=1,1=2
P 9.92901004 5.98761998 1 P 3 0;0=1,1=2
P 9.95731004 0.036 1 P 3 0;0=1,1=2
P 9.96 4.69 1 P 3 0;0=1,1=2
P 9.97901004 5.98761998 1 P 3 0;0=1,1=2
P 9.995 2.87558996 1 P 3 0;0=1,1=2
P 0.64808996 1.655 1 P 3 0;0=1,1=2
P 0.73 5.78 1 P 3 0;0=1,1=2
P 3.6817 5.74 1 P 3 0;0=1,1=2
P 4.125 2.725 1 P 3 0;0=1,1=2
P 4.125 2.682 1 P 3 0;0=1,1=2
P 5.03 5.4 1 P 3 0;0=1,1=2
P 0.81 5.78 1 P 3 0;0=1,1=2
P 3.815 5.815 1 P 3 0;0=1,1=2
P 10.07 2.928 1 P 3 0;0=1,1=2
P 9.995 2.936 1 P 3 0;0=1,1=2
P 1.122 5.417 1 P 3 0;0=1,1=2
P 5.855 0.925 1 P 3 0;0=1,1=2
P 11.235 3.3 1 P 3 0;0=1,1=2
P 4.07 4.625 1 P 3 0;0=1,1=2
P 10.80498996 5.6431 1 P 3 0;0=1,1=2
P 10.80498996 5.7831 1 P 3 0;0=1,1=2
P 10.84498996 5.6431 1 P 3 0;0=1,1=2
P 10.84498996 5.7831 1 P 3 0;0=1,1=2
P 10.97035 5.6431 1 P 3 0;0=1,1=2
P 10.97035 5.7831 1 P 3 0;0=1,1=2
P 10.99998996 4.9131 1 P 3 0;0=1,1=2
P 10.99998996 4.9531 1 P 3 0;0=1,1=2
P 10.99998996 4.9931 1 P 3 0;0=1,1=2
P 10.99998996 5.0381 1 P 3 0;0=1,1=2
P 10.99998996 5.0831 1 P 3 0;0=1,1=2
P 10.99998996 5.1231 1 P 3 0;0=1,1=2
P 10.99998996 5.1631 1 P 3 0;0=1,1=2
P 11.01035 5.6431 1 P 3 0;0=1,1=2
P 11.01035 5.7831 1 P 3 0;0=1,1=2
P 11.03998996 4.9131 1 P 3 0;0=1,1=2
P 11.03998996 4.9531 1 P 3 0;0=1,1=2
P 11.03998996 4.9931 1 P 3 0;0=1,1=2
P 11.03998996 5.0381 1 P 3 0;0=1,1=2
P 11.03998996 5.0831 1 P 3 0;0=1,1=2
P 11.03998996 5.1231 1 P 3 0;0=1,1=2
P 11.03998996 5.1631 1 P 3 0;0=1,1=2
P 11.08498996 4.9131 1 P 3 0;0=1,1=2
P 11.08498996 4.9531 1 P 3 0;0=1,1=2
P 11.08498996 5.1231 1 P 3 0;0=1,1=2
P 11.08498996 5.1631 1 P 3 0;0=1,1=2
P 11.13498996 4.9131 1 P 3 0;0=1,1=2
P 11.13498996 4.9531 1 P 3 0;0=1,1=2
P 11.13498996 5.1231 1 P 3 0;0=1,1=2
P 11.13498996 5.1631 1 P 3 0;0=1,1=2
P 11.13571004 5.6431 1 P 3 0;0=1,1=2
P 11.13571004 5.7831 1 P 3 0;0=1,1=2
P 11.17571004 5.6431 1 P 3 0;0=1,1=2
P 11.17571004 5.7831 1 P 3 0;0=1,1=2
P 11.17998996 4.9131 1 P 3 0;0=1,1=2
P 11.17998996 4.9531 1 P 3 0;0=1,1=2
P 11.17998996 4.9931 1 P 3 0;0=1,1=2
P 11.17998996 5.0381 1 P 3 0;0=1,1=2
P 11.17998996 5.0831 1 P 3 0;0=1,1=2
P 11.17998996 5.1231 1 P 3 0;0=1,1=2
P 11.17998996 5.1631 1 P 3 0;0=1,1=2
P 11.21998996 4.9131 1 P 3 0;0=1,1=2
P 11.21998996 4.9531 1 P 3 0;0=1,1=2
P 11.21998996 4.9931 1 P 3 0;0=1,1=2
P 11.21998996 5.0381 1 P 3 0;0=1,1=2
P 11.21998996 5.0831 1 P 3 0;0=1,1=2
P 11.21998996 5.1231 1 P 3 0;0=1,1=2
P 11.21998996 5.1631 1 P 3 0;0=1,1=2
P 11.30106998 5.6431 1 P 3 0;0=1,1=2
P 11.30106998 5.7831 1 P 3 0;0=1,1=2
P 11.34106998 5.6431 1 P 3 0;0=1,1=2
P 11.34106998 5.7831 1 P 3 0;0=1,1=2
P 11.4269 4.80998996 1 P 3 0;0=1,1=2
P 11.4269 4.85498996 1 P 3 0;0=1,1=2
P 11.4269 4.90498996 1 P 3 0;0=1,1=2
P 11.4269 4.94998996 1 P 3 0;0=1,1=2
P 11.46643002 5.6431 1 P 3 0;0=1,1=2
P 11.46643002 5.7831 1 P 3 0;0=1,1=2
P 11.4769 4.80998996 1 P 3 0;0=1,1=2
P 11.4769 4.94998996 1 P 3 0;0=1,1=2
P 11.50643002 5.6431 1 P 3 0;0=1,1=2
P 11.50643002 5.7831 1 P 3 0;0=1,1=2
P 11.5269 4.80998996 1 P 3 0;0=1,1=2
P 11.5269 4.94998996 1 P 3 0;0=1,1=2
P 11.5769 4.80998996 1 P 3 0;0=1,1=2
P 11.5769 4.94998996 1 P 3 0;0=1,1=2
P 11.6269 4.80998996 1 P 3 0;0=1,1=2
P 11.6269 4.85498996 1 P 3 0;0=1,1=2
P 11.6269 4.90498996 1 P 3 0;0=1,1=2
P 11.6269 4.94998996 1 P 3 0;0=1,1=2
P 11.63178996 5.6431 1 P 3 0;0=1,1=2
P 11.63178996 5.7831 1 P 3 0;0=1,1=2
P 11.67178996 5.6431 1 P 3 0;0=1,1=2
P 11.67178996 5.7831 1 P 3 0;0=1,1=2
P 11.79715 5.6431 1 P 3 0;0=1,1=2
P 11.79715 5.7831 1 P 3 0;0=1,1=2
P 11.83715 5.6431 1 P 3 0;0=1,1=2
P 11.83715 5.7831 1 P 3 0;0=1,1=2
P 11.96251004 5.6431 1 P 3 0;0=1,1=2
P 11.96251004 5.7831 1 P 3 0;0=1,1=2
P 12.00251004 5.6431 1 P 3 0;0=1,1=2
P 12.00251004 5.7831 1 P 3 0;0=1,1=2
P 12.12786998 5.6431 1 P 3 0;0=1,1=2
P 12.12786998 5.7831 1 P 3 0;0=1,1=2
P 12.16786998 5.6431 1 P 3 0;0=1,1=2
P 12.16786998 5.7831 1 P 3 0;0=1,1=2
P 4.99605 4.9131 1 P 3 0;0=1,1=2
P 4.99605 4.9531 1 P 3 0;0=1,1=2
P 4.99605 4.9931 1 P 3 0;0=1,1=2
P 4.99605 5.0381 1 P 3 0;0=1,1=2
P 4.99605 5.0831 1 P 3 0;0=1,1=2
P 4.99605 5.1231 1 P 3 0;0=1,1=2
P 4.99605 5.1631 1 P 3 0;0=1,1=2
P 5.03605 4.9131 1 P 3 0;0=1,1=2
P 5.03605 4.9531 1 P 3 0;0=1,1=2
P 5.03605 4.9931 1 P 3 0;0=1,1=2
P 5.03605 5.0381 1 P 3 0;0=1,1=2
P 5.03605 5.0831 1 P 3 0;0=1,1=2
P 5.03605 5.1231 1 P 3 0;0=1,1=2
P 5.03605 5.1631 1 P 3 0;0=1,1=2
P 5.08105 4.9131 1 P 3 0;0=1,1=2
P 5.08105 4.9531 1 P 3 0;0=1,1=2
P 5.08105 5.1231 1 P 3 0;0=1,1=2
P 5.08105 5.1631 1 P 3 0;0=1,1=2
P 5.13105 4.9131 1 P 3 0;0=1,1=2
P 5.13105 4.9531 1 P 3 0;0=1,1=2
P 5.13105 5.1231 1 P 3 0;0=1,1=2
P 5.13105 5.1631 1 P 3 0;0=1,1=2
P 5.17605 4.9131 1 P 3 0;0=1,1=2
P 5.17605 4.9531 1 P 3 0;0=1,1=2
P 5.17605 4.9931 1 P 3 0;0=1,1=2
P 5.17605 5.0381 1 P 3 0;0=1,1=2
P 5.17605 5.0831 1 P 3 0;0=1,1=2
P 5.17605 5.1231 1 P 3 0;0=1,1=2
P 5.17605 5.1631 1 P 3 0;0=1,1=2
P 5.21605 4.9131 1 P 3 0;0=1,1=2
P 5.21605 4.9531 1 P 3 0;0=1,1=2
P 5.21605 4.9931 1 P 3 0;0=1,1=2
P 5.21605 5.0381 1 P 3 0;0=1,1=2
P 5.21605 5.0831 1 P 3 0;0=1,1=2
P 5.21605 5.1231 1 P 3 0;0=1,1=2
P 5.21605 5.1631 1 P 3 0;0=1,1=2
P 6.34948996 5.03 1 P 3 0;0=1,1=2
P 6.72708996 4.5652 1 P 3 0;0=1,1=2
P 6.76208996 4.5652 1 P 3 0;0=1,1=2
P 6.79708996 4.5652 1 P 3 0;0=1,1=2
P 6.87208996 4.5652 1 P 3 0;0=1,1=2
P 6.90208996 4.5652 1 P 3 0;0=1,1=2
P 4.26605 4.6631 1 P 3 0;0=1,1=2
P 4.26605 4.7031 1 P 3 0;0=1,1=2
P 4.26605 4.7481 1 P 3 0;0=1,1=2
P 4.26605 4.7931 1 P 3 0;0=1,1=2
P 4.26605 4.8381 1 P 3 0;0=1,1=2
P 4.30605 4.6631 1 P 3 0;0=1,1=2
P 4.30605 4.7031 1 P 3 0;0=1,1=2
P 4.30605 4.7481 1 P 3 0;0=1,1=2
P 4.30605 4.7931 1 P 3 0;0=1,1=2
P 4.30605 4.8381 1 P 3 0;0=1,1=2
P 4.34105 4.6431 1 P 3 0;0=1,1=2
P 4.34605 4.8381 1 P 3 0;0=1,1=2
P 4.38605 4.6431 1 P 3 0;0=1,1=2
P 4.38605 4.8381 1 P 3 0;0=1,1=2
P 4.42605 4.6631 1 P 3 0;0=1,1=2
P 4.42605 4.7031 1 P 3 0;0=1,1=2
P 4.42605 4.7481 1 P 3 0;0=1,1=2
P 4.42605 4.7931 1 P 3 0;0=1,1=2
P 4.42605 4.8381 1 P 3 0;0=1,1=2
P 4.46605 4.6631 1 P 3 0;0=1,1=2
P 4.46605 4.7031 1 P 3 0;0=1,1=2
P 4.46605 4.7481 1 P 3 0;0=1,1=2
P 4.46605 4.7931 1 P 3 0;0=1,1=2
P 4.46605 4.8381 1 P 3 0;0=1,1=2
P 4.65605 4.6631 1 P 3 0;0=1,1=2
P 4.65605 4.7031 1 P 3 0;0=1,1=2
P 4.65605 4.7481 1 P 3 0;0=1,1=2
P 4.65605 4.7931 1 P 3 0;0=1,1=2
P 4.65605 4.8381 1 P 3 0;0=1,1=2
P 4.69605 4.6631 1 P 3 0;0=1,1=2
P 4.69605 4.7031 1 P 3 0;0=1,1=2
P 4.69605 4.7481 1 P 3 0;0=1,1=2
P 4.69605 4.7931 1 P 3 0;0=1,1=2
P 4.69605 4.8381 1 P 3 0;0=1,1=2
P 4.73105 4.6431 1 P 3 0;0=1,1=2
P 4.73605 4.8381 1 P 3 0;0=1,1=2
P 4.77605 4.6431 1 P 3 0;0=1,1=2
P 4.77605 4.8381 1 P 3 0;0=1,1=2
P 4.81605 4.6631 1 P 3 0;0=1,1=2
P 4.81605 4.7031 1 P 3 0;0=1,1=2
P 4.81605 4.7481 1 P 3 0;0=1,1=2
P 4.81605 4.7931 1 P 3 0;0=1,1=2
P 4.81605 4.8381 1 P 3 0;0=1,1=2
P 4.85605 4.6631 1 P 3 0;0=1,1=2
P 4.85605 4.7031 1 P 3 0;0=1,1=2
P 4.85605 4.7481 1 P 3 0;0=1,1=2
P 4.85605 4.7931 1 P 3 0;0=1,1=2
P 4.85605 4.8381 1 P 3 0;0=1,1=2
P 5.03605 4.6731 1 P 3 0;0=1,1=2
P 5.03605 4.7131 1 P 3 0;0=1,1=2
P 5.03605 4.7581 1 P 3 0;0=1,1=2
P 5.03605 4.8031 1 P 3 0;0=1,1=2
P 5.03605 4.8431 1 P 3 0;0=1,1=2
P 5.08105 4.6731 1 P 3 0;0=1,1=2
P 5.08105 4.8431 1 P 3 0;0=1,1=2
P 5.13105 4.6731 1 P 3 0;0=1,1=2
P 5.13105 4.8431 1 P 3 0;0=1,1=2
P 5.17605 4.6731 1 P 3 0;0=1,1=2
P 5.17605 4.7131 1 P 3 0;0=1,1=2
P 5.17605 4.7581 1 P 3 0;0=1,1=2
P 5.17605 4.8031 1 P 3 0;0=1,1=2
P 5.17605 4.8431 1 P 3 0;0=1,1=2
P 10.26998996 4.6631 1 P 3 0;0=1,1=2
P 10.26998996 4.7031 1 P 3 0;0=1,1=2
P 10.26998996 4.7481 1 P 3 0;0=1,1=2
P 10.26998996 4.7931 1 P 3 0;0=1,1=2
P 10.26998996 4.8381 1 P 3 0;0=1,1=2
P 10.30998996 4.6631 1 P 3 0;0=1,1=2
P 10.30998996 4.7031 1 P 3 0;0=1,1=2
P 10.30998996 4.7481 1 P 3 0;0=1,1=2
P 10.30998996 4.7931 1 P 3 0;0=1,1=2
P 10.30998996 4.8381 1 P 3 0;0=1,1=2
P 10.34498996 4.6431 1 P 3 0;0=1,1=2
P 10.34998996 4.8381 1 P 3 0;0=1,1=2
P 10.38998996 4.6431 1 P 3 0;0=1,1=2
P 10.38998996 4.8381 1 P 3 0;0=1,1=2
P 10.42998996 4.6631 1 P 3 0;0=1,1=2
P 10.42998996 4.7031 1 P 3 0;0=1,1=2
P 10.42998996 4.7481 1 P 3 0;0=1,1=2
P 10.42998996 4.7931 1 P 3 0;0=1,1=2
P 10.42998996 4.8381 1 P 3 0;0=1,1=2
P 10.46998996 4.6631 1 P 3 0;0=1,1=2
P 10.46998996 4.7031 1 P 3 0;0=1,1=2
P 10.46998996 4.7481 1 P 3 0;0=1,1=2
P 10.46998996 4.7931 1 P 3 0;0=1,1=2
P 10.46998996 4.8381 1 P 3 0;0=1,1=2
P 10.65998996 4.6631 1 P 3 0;0=1,1=2
P 10.65998996 4.7031 1 P 3 0;0=1,1=2
P 10.65998996 4.7481 1 P 3 0;0=1,1=2
P 10.65998996 4.7931 1 P 3 0;0=1,1=2
P 10.65998996 4.8381 1 P 3 0;0=1,1=2
P 10.69998996 4.6631 1 P 3 0;0=1,1=2
P 10.69998996 4.7031 1 P 3 0;0=1,1=2
P 10.69998996 4.7481 1 P 3 0;0=1,1=2
P 10.69998996 4.7931 1 P 3 0;0=1,1=2
P 10.69998996 4.8381 1 P 3 0;0=1,1=2
P 10.73498996 4.6431 1 P 3 0;0=1,1=2
P 10.73998996 4.8381 1 P 3 0;0=1,1=2
P 10.77998996 4.6431 1 P 3 0;0=1,1=2
P 10.77998996 4.8381 1 P 3 0;0=1,1=2
P 10.81998996 4.6631 1 P 3 0;0=1,1=2
P 10.81998996 4.7031 1 P 3 0;0=1,1=2
P 10.81998996 4.7481 1 P 3 0;0=1,1=2
P 10.81998996 4.7931 1 P 3 0;0=1,1=2
P 10.81998996 4.8381 1 P 3 0;0=1,1=2
P 10.85998996 4.6631 1 P 3 0;0=1,1=2
P 10.85998996 4.7031 1 P 3 0;0=1,1=2
P 10.85998996 4.7481 1 P 3 0;0=1,1=2
P 10.85998996 4.7931 1 P 3 0;0=1,1=2
P 10.85998996 4.8381 1 P 3 0;0=1,1=2
P 11.03998996 4.6731 1 P 3 0;0=1,1=2
P 11.03998996 4.7131 1 P 3 0;0=1,1=2
P 11.03998996 4.7581 1 P 3 0;0=1,1=2
P 11.03998996 4.8031 1 P 3 0;0=1,1=2
P 11.03998996 4.8431 1 P 3 0;0=1,1=2
P 11.08498996 4.6731 1 P 3 0;0=1,1=2
P 11.08498996 4.8431 1 P 3 0;0=1,1=2
P 11.13498996 4.6731 1 P 3 0;0=1,1=2
P 11.13498996 4.8431 1 P 3 0;0=1,1=2
P 11.17998996 4.6731 1 P 3 0;0=1,1=2
P 11.17998996 4.7131 1 P 3 0;0=1,1=2
P 11.17998996 4.7581 1 P 3 0;0=1,1=2
P 11.17998996 4.8031 1 P 3 0;0=1,1=2
P 11.17998996 4.8431 1 P 3 0;0=1,1=2
P 10.03 4.61 1 P 3 0;0=1,1=2
P 10.07286004 2.82336998 1 P 3 0;0=1,1=2
P 11.395 2.8 1 P 3 0;0=1,1=2
P 11.58613002 2.785 1 P 3 0;0=1,1=2
P 11.58613002 2.905 1 P 3 0;0=1,1=2
P 1.23906004 4.69351004 1 P 3 0;0=1,1=2
P 1.335 5.78 1 P 3 0;0=1,1=2
P 1.37925 5.78 1 P 3 0;0=1,1=2
P 1.42 5.78 1 P 3 0;0=1,1=2
P 1.45798996 5.78 1 P 3 0;0=1,1=2
P 3.67 4.45 1 P 3 0;0=1,1=2
P 3.70998996 0.7 1 P 3 0;0=1,1=2
P 3.71203002 0.77535 1 P 3 0;0=1,1=2
P 3.72 4.545 1 P 3 0;0=1,1=2
P 3.89 4.655 1 P 3 0;0=1,1=2
P 3.91 5.51 1 P 3 0;0=1,1=2
P 3.9899 4.765 1 P 3 0;0=1,1=2
P 4.02893002 2.59336998 1 P 3 0;0=1,1=2
P 4.0599 5.395 1 P 3 0;0=1,1=2
P 4.1049 4.86 1 P 3 0;0=1,1=2
P 5.125 5.4 1 P 3 0;0=1,1=2
P 5.37968996 2.8 1 P 3 0;0=1,1=2
P 5.5822 2.785 1 P 3 0;0=1,1=2
P 5.5822 2.905 1 P 3 0;0=1,1=2
P 7.2426 4.69351004 1 P 3 0;0=1,1=2
P 7.2926 4.60351004 1 P 3 0;0=1,1=2
P 9.46795 0.82631998 1 P 3 0;0=1,1=2
P 9.50795 0.72133002 1 P 3 0;0=1,1=2
P 9.98 4.51 1 P 3 0;0=1,1=2
P 3.733 5.075 1 P 3 0;0=1,1=2
P 1.03 4.96 1 P 3 0;0=1,1=2
P 1.03 5.155 1 P 3 0;0=1,1=2
P 1.04 5.885 1 P 3 0;0=1,1=2
P 1.044 5.448 1 P 3 0;0=1,1=2
P 1.12 5.885 1 P 3 0;0=1,1=2
P 11.67761998 2.85 1 P 3 0;0=1,1=2
P 1.18906004 4.95351004 1 P 3 0;0=1,1=2
P 1.23906004 5.15351004 1 P 3 0;0=1,1=2
P 1.28906004 5.15351004 1 P 3 0;0=1,1=2
P 1.32 5.46 1 P 3 0;0=1,1=2
P 1.35925 5.46016004 1 P 3 0;0=1,1=2
P 1.4 5.46 1 P 3 0;0=1,1=2
P 1.43798996 5.46016004 1 P 3 0;0=1,1=2
P 3.77 4.765 1 P 3 0;0=1,1=2
P 3.94 4.655 1 P 3 0;0=1,1=2
P 4.14 4.745 1 P 3 0;0=1,1=2
P 4.76 5.375 1 P 3 0;0=1,1=2
P 4.892 5.767 1 P 3 0;0=1,1=2
P 4.96 5.5 1 P 3 0;0=1,1=2
P 5.088 5.767 1 P 3 0;0=1,1=2
P 5.16 5.555 1 P 3 0;0=1,1=2
P 5.67368996 2.85 1 P 3 0;0=1,1=2
P 5.8522 2.97 1 P 3 0;0=1,1=2
P 5.855 3.07 1 P 3 0;0=1,1=2
P 7.1926 4.95351004 1 P 3 0;0=1,1=2
P 7.2426 5.15351004 1 P 3 0;0=1,1=2
P 7.2926 5.15351004 1 P 3 0;0=1,1=2
P 0.73 5.205 1 P 3 0;0=1,1=2
P 0.73 5.885 1 P 3 0;0=1,1=2
P 0.755 5.355 1 P 3 0;0=1,1=2
P 0.81 5.885 1 P 3 0;0=1,1=2
P 0.81016004 5.17 1 P 3 0;0=1,1=2
P 0.83 5.355 1 P 3 0;0=1,1=2
P 0.89 5.885 1 P 3 0;0=1,1=2
P 0.9 5.355 1 P 3 0;0=1,1=2
P 0.91 5.075 1 P 3 0;0=1,1=2
P 0.97 5.885 1 P 3 0;0=1,1=2
P 11.28278996 2.9414 1 P 3 0;0=1,1=2
P 11.28278996 2.9764 1 P 3 0;0=1,1=2
P 11.28278996 3.0214 1 P 3 0;0=1,1=2
P 11.28278996 3.0564 1 P 3 0;0=1,1=2
P 11.28278996 3.1014 1 P 3 0;0=1,1=2
P 11.28278996 3.1364 1 P 3 0;0=1,1=2
P 11.28278996 3.1814 1 P 3 0;0=1,1=2
P 11.28278996 3.2164 1 P 3 0;0=1,1=2
P 11.28278996 3.2614 1 P 3 0;0=1,1=2
P 11.28278996 3.2964 1 P 3 0;0=1,1=2
P 5.27886004 2.9414 1 P 3 0;0=1,1=2
P 5.27886004 2.9764 1 P 3 0;0=1,1=2
P 5.27886004 3.0214 1 P 3 0;0=1,1=2
P 5.27886004 3.0564 1 P 3 0;0=1,1=2
P 5.27886004 3.1014 1 P 3 0;0=1,1=2
P 5.27886004 3.1364 1 P 3 0;0=1,1=2
P 5.27886004 3.1814 1 P 3 0;0=1,1=2
P 5.27886004 3.2164 1 P 3 0;0=1,1=2
P 5.27886004 3.2614 1 P 3 0;0=1,1=2
P 5.27886004 3.2964 1 P 3 0;0=1,1=2
P 5.57708996 4.6802 1 P 3 0;0=1,1=2
P 5.59708996 4.7302 1 P 3 0;0=1,1=2
P 5.59708996 4.7702 1 P 3 0;0=1,1=2
P 5.59708996 4.8102 1 P 3 0;0=1,1=2
P 5.61708996 4.6802 1 P 3 0;0=1,1=2
P 5.65708996 4.6802 1 P 3 0;0=1,1=2
P 5.67708996 4.7302 1 P 3 0;0=1,1=2
P 5.67708996 4.7702 1 P 3 0;0=1,1=2
P 5.67708996 4.8102 1 P 3 0;0=1,1=2
P 5.69708996 4.6802 1 P 3 0;0=1,1=2
P 5.73708996 4.6802 1 P 3 0;0=1,1=2
P 5.75708996 4.7302 1 P 3 0;0=1,1=2
P 5.75708996 4.7702 1 P 3 0;0=1,1=2
P 5.75708996 4.8102 1 P 3 0;0=1,1=2
P 5.77708996 4.6802 1 P 3 0;0=1,1=2
P 5.81708996 4.6802 1 P 3 0;0=1,1=2
P 5.83708996 4.7302 1 P 3 0;0=1,1=2
P 5.83708996 4.7702 1 P 3 0;0=1,1=2
P 5.83708996 4.8102 1 P 3 0;0=1,1=2
P 5.85708996 4.6802 1 P 3 0;0=1,1=2
P 5.89708996 4.6802 1 P 3 0;0=1,1=2
P 5.91708996 4.7302 1 P 3 0;0=1,1=2
P 5.91708996 4.7702 1 P 3 0;0=1,1=2
P 5.91708996 4.8102 1 P 3 0;0=1,1=2
P 5.93708996 4.6802 1 P 3 0;0=1,1=2
P 5.97708996 4.6802 1 P 3 0;0=1,1=2
P 5.99708996 4.7302 1 P 3 0;0=1,1=2
P 5.99708996 4.7702 1 P 3 0;0=1,1=2
P 5.99708996 4.8102 1 P 3 0;0=1,1=2
P 6.01708996 4.6802 1 P 3 0;0=1,1=2
P 6.05708996 4.6802 1 P 3 0;0=1,1=2
P 6.07708996 4.7302 1 P 3 0;0=1,1=2
P 6.07708996 4.7702 1 P 3 0;0=1,1=2
P 6.07708996 4.8102 1 P 3 0;0=1,1=2
P 6.09708996 4.6802 1 P 3 0;0=1,1=2
P 6.13708996 4.6402 1 P 3 0;0=1,1=2
P 6.13708996 4.6802 1 P 3 0;0=1,1=2
P 6.13708996 4.7202 1 P 3 0;0=1,1=2
P 6.13708996 4.7602 1 P 3 0;0=1,1=2
P 6.13708996 4.8002 1 P 3 0;0=1,1=2
P 6.13708996 4.8402 1 P 3 0;0=1,1=2
P 6.13708996 4.8852 1 P 3 0;0=1,1=2
P 6.13708996 4.9252 1 P 3 0;0=1,1=2
P 6.385 5.03 1 P 3 0;0=1,1=2
P 3.795 4.6 1 P 3 0;0=1,1=2
P 4.86 5.375 1 P 3 0;0=1,1=2
P 6.74 4.845 1 P 3 0;0=1,1=2
P 6.74018996 4.765 1 P 3 0;0=1,1=2
P 6.785 4.685 1 P 3 0;0=1,1=2
P 6.785 4.725 1 P 3 0;0=1,1=2
P 6.785 4.765 1 P 3 0;0=1,1=2
P 6.785 4.805 1 P 3 0;0=1,1=2
P 6.785 4.845 1 P 3 0;0=1,1=2
P 0.88681004 5.78181004 1 P 3 0;0=1,1=2
P 4.91 5.375 1 P 3 0;0=1,1=2
P 2.09606004 3.81615 0 P 1 0;0=23,1=2
P 3.09656998 5.0535 0 P 1 0;0=23,1=2
P 2.09606004 3.86615 0 P 1 0;0=23,1=2
P 3.13656998 5.0535 0 P 1 0;0=23,1=2
P 2.19606004 3.81615 0 P 1 0;0=23,1=2
P 3.02571004 4.667 0 P 1 0;0=23,1=2
P 2.19606004 3.86615 0 P 1 0;0=23,1=2
P 3.06571004 4.667 0 P 1 0;0=23,1=2
P 2.14606004 3.76615 0 P 1 0;0=23,1=2
P 3.02571004 5.165 0 P 1 0;0=23,1=2
P 2.14606004 3.81615 0 P 1 0;0=23,1=2
P 3.06571004 5.165 0 P 1 0;0=23,1=2
P 2.04606004 3.76615 0 P 1 0;0=23,1=2
P 2.88708002 4.667 0 P 1 0;0=23,1=2
P 2.04606004 3.81615 0 P 1 0;0=23,1=2
P 2.92708002 4.667 0 P 1 0;0=23,1=2
P 2.19606004 3.66615 0 P 1 0;0=23,1=2
P 2.81311004 4.78291998 0 P 1 0;0=23,1=2
P 2.19606004 3.71615 0 P 1 0;0=23,1=2
P 2.85311004 4.78291998 0 P 1 0;0=23,1=2
P 2.14606004 3.61615 0 P 1 0;0=23,1=2
P 2.88086998 5.17001998 0 P 1 0;0=23,1=2
P 2.14606004 3.66615 0 P 1 0;0=23,1=2
P 2.92086998 5.17001998 0 P 1 0;0=23,1=2
P 2.09606004 3.66615 0 P 1 0;0=23,1=2
P 2.74225 4.667 0 P 1 0;0=23,1=2
P 2.09606004 3.71615 0 P 1 0;0=23,1=2
P 2.78225 4.667 0 P 1 0;0=23,1=2
P 2.04606004 3.61615 0 P 1 0;0=23,1=2
P 2.74225 5.14 0 P 1 0;0=23,1=2
P 2.04606004 3.66615 0 P 1 0;0=23,1=2
P 2.78225 5.14 0 P 1 0;0=23,1=2
P 8.1 3.81615 0 P 1 0;0=23,1=2
P 9.10011004 5.0535 0 P 1 0;0=23,1=2
P 8.1 3.86615 0 P 1 0;0=23,1=2
P 9.14011004 5.0535 0 P 1 0;0=23,1=2
P 8.2 3.81615 0 P 1 0;0=23,1=2
P 9.02925 4.667 0 P 1 0;0=23,1=2
P 8.2 3.86615 0 P 1 0;0=23,1=2
P 9.06925 4.667 0 P 1 0;0=23,1=2
P 8.15 3.76615 0 P 1 0;0=23,1=2
P 9.02925 5.165 0 P 1 0;0=23,1=2
P 8.15 3.81615 0 P 1 0;0=23,1=2
P 9.06925 5.165 0 P 1 0;0=23,1=2
P 8.05 3.76615 0 P 1 0;0=23,1=2
P 8.89061998 4.667 0 P 1 0;0=23,1=2
P 8.05 3.81615 0 P 1 0;0=23,1=2
P 8.93061998 4.667 0 P 1 0;0=23,1=2
P 8.2 3.66615 0 P 1 0;0=23,1=2
P 8.81665 4.78291998 0 P 1 0;0=23,1=2
P 8.2 3.71615 0 P 1 0;0=23,1=2
P 8.85665 4.78291998 0 P 1 0;0=23,1=2
P 8.15 3.61615 0 P 1 0;0=23,1=2
P 8.88441004 5.17001998 0 P 1 0;0=23,1=2
P 8.15 3.66615 0 P 1 0;0=23,1=2
P 8.92441004 5.17001998 0 P 1 0;0=23,1=2
P 8.1 3.66615 0 P 1 0;0=23,1=2
P 8.74578996 4.667 0 P 1 0;0=23,1=2
P 8.1 3.71615 0 P 1 0;0=23,1=2
P 8.78578996 4.667 0 P 1 0;0=23,1=2
P 8.05 3.61615 0 P 1 0;0=23,1=2
P 8.74578996 5.14 0 P 1 0;0=23,1=2
P 8.05 3.66615 0 P 1 0;0=23,1=2
P 8.78578996 5.14 0 P 1 0;0=23,1=2
P 2.34606004 3.81615 0 P 1 0;0=23,1=2
P 3.27831004 5.22001998 0 P 1 0;0=23,1=2
P 2.34606004 3.86615 0 P 1 0;0=23,1=2
P 3.23831004 5.22001998 0 P 1 0;0=23,1=2
P 2.44606004 3.81615 0 P 1 0;0=23,1=2
P 3.20743996 4.78291998 0 P 1 0;0=23,1=2
P 2.44606004 3.86615 0 P 1 0;0=23,1=2
P 3.16743996 4.78291998 0 P 1 0;0=23,1=2
P 2.49606004 3.76615 0 P 1 0;0=23,1=2
P 3.34916998 5.1035 0 P 1 0;0=23,1=2
P 2.49606004 3.81615 0 P 1 0;0=23,1=2
P 3.30916998 5.1035 0 P 1 0;0=23,1=2
P 2.39606004 3.76615 0 P 1 0;0=23,1=2
P 3.27831004 4.642 0 P 1 0;0=23,1=2
P 2.39606004 3.81615 0 P 1 0;0=23,1=2
P 3.23831004 4.642 0 P 1 0;0=23,1=2
P 2.44606004 3.66615 0 P 1 0;0=23,1=2
P 3.42003996 4.78291998 0 P 1 0;0=23,1=2
P 2.44606004 3.71615 0 P 1 0;0=23,1=2
P 3.38003996 4.78291998 0 P 1 0;0=23,1=2
P 2.49606004 3.61615 0 P 1 0;0=23,1=2
P 3.56176998 5.14 0 P 1 0;0=23,1=2
P 2.49606004 3.66615 0 P 1 0;0=23,1=2
P 3.52176998 5.14 0 P 1 0;0=23,1=2
P 2.39606004 3.61615 0 P 1 0;0=23,1=2
P 3.49091004 4.587 0 P 1 0;0=23,1=2
P 2.39606004 3.66615 0 P 1 0;0=23,1=2
P 3.45091004 4.587 0 P 1 0;0=23,1=2
P 2.34606004 3.66615 0 P 1 0;0=23,1=2
P 3.56176998 4.71973002 0 P 1 0;0=23,1=2
P 2.34606004 3.71615 0 P 1 0;0=23,1=2
P 3.52176998 4.71973002 0 P 1 0;0=23,1=2
P 8.35 3.81615 0 P 1 0;0=23,1=2
P 9.28185 5.22001998 0 P 1 0;0=23,1=2
P 8.35 3.86615 0 P 1 0;0=23,1=2
P 9.24185 5.22001998 0 P 1 0;0=23,1=2
P 8.45 3.81615 0 P 1 0;0=23,1=2
P 9.21098002 4.78291998 0 P 1 0;0=23,1=2
P 8.45 3.86615 0 P 1 0;0=23,1=2
P 9.17098002 4.78291998 0 P 1 0;0=23,1=2
P 8.5 3.76615 0 P 1 0;0=23,1=2
P 9.35271004 5.1035 0 P 1 0;0=23,1=2
P 8.5 3.81615 0 P 1 0;0=23,1=2
P 9.31271004 5.1035 0 P 1 0;0=23,1=2
P 8.4 3.76615 0 P 1 0;0=23,1=2
P 9.28185 4.642 0 P 1 0;0=23,1=2
P 8.4 3.81615 0 P 1 0;0=23,1=2
P 9.24185 4.642 0 P 1 0;0=23,1=2
P 8.45 3.66615 0 P 1 0;0=23,1=2
P 9.42358002 4.78291998 0 P 1 0;0=23,1=2
P 8.45 3.71615 0 P 1 0;0=23,1=2
P 9.38358002 4.78291998 0 P 1 0;0=23,1=2
P 8.5 3.61615 0 P 1 0;0=23,1=2
P 9.56531004 5.14 0 P 1 0;0=23,1=2
P 8.5 3.66615 0 P 1 0;0=23,1=2
P 9.52531004 5.14 0 P 1 0;0=23,1=2
P 8.4 3.61615 0 P 1 0;0=23,1=2
P 9.49445 4.587 0 P 1 0;0=23,1=2
P 8.4 3.66615 0 P 1 0;0=23,1=2
P 9.45445 4.587 0 P 1 0;0=23,1=2
P 8.35 3.66615 0 P 1 0;0=23,1=2
P 9.56531004 4.71973002 0 P 1 0;0=23,1=2
P 8.35 3.71615 0 P 1 0;0=23,1=2
P 9.52531004 4.71973002 0 P 1 0;0=23,1=2
P 4.83268002 2.16615 0 P 1 0;0=23,1=2
P 4.88268002 2.16615 0 P 1 0;0=23,1=2
P 1.93196998 5.0535 0 P 1 0;0=23,1=2
P 1.99606004 3.46615 0 P 1 0;0=23,1=2
P 1.97196998 5.0535 0 P 1 0;0=23,1=2
P 1.99606004 3.51615 0 P 1 0;0=23,1=2
P 1.86111004 4.657 0 P 1 0;0=23,1=2
P 2.14606004 3.46615 0 P 1 0;0=23,1=2
P 1.90111004 4.657 0 P 1 0;0=23,1=2
P 2.14606004 3.51615 0 P 1 0;0=23,1=2
P 1.86111004 5.169 0 P 1 0;0=23,1=2
P 2.19606004 3.41615 0 P 1 0;0=23,1=2
P 1.90111004 5.169 0 P 1 0;0=23,1=2
P 2.19606004 3.46615 0 P 1 0;0=23,1=2
P 1.79025 4.78291998 0 P 1 0;0=23,1=2
P 2.09606004 3.41615 0 P 1 0;0=23,1=2
P 1.83025 4.78291998 0 P 1 0;0=23,1=2
P 2.09606004 3.46615 0 P 1 0;0=23,1=2
P 1.64851004 4.78291998 0 P 1 0;0=23,1=2
P 2.14606004 3.31615 0 P 1 0;0=23,1=2
P 1.68851004 4.78291998 0 P 1 0;0=23,1=2
P 2.14606004 3.36615 0 P 1 0;0=23,1=2
P 1.6485 5.0535 0 P 1 0;0=23,1=2
P 2.19606004 3.26615 0 P 1 0;0=23,1=2
P 1.6885 5.0535 0 P 1 0;0=23,1=2
P 2.19606004 3.31615 0 P 1 0;0=23,1=2
P 1.57765 4.707 0 P 1 0;0=23,1=2
P 2.09606004 3.26615 0 P 1 0;0=23,1=2
P 1.61765 4.707 0 P 1 0;0=23,1=2
P 2.09606004 3.31615 0 P 1 0;0=23,1=2
P 1.57765 5.169 0 P 1 0;0=23,1=2
P 2.04606004 3.31615 0 P 1 0;0=23,1=2
P 1.61765 5.169 0 P 1 0;0=23,1=2
P 2.04606004 3.36615 0 P 1 0;0=23,1=2
P 7.93551004 5.0535 0 P 1 0;0=23,1=2
P 8 3.46615 0 P 1 0;0=23,1=2
P 7.97551004 5.0535 0 P 1 0;0=23,1=2
P 8 3.51615 0 P 1 0;0=23,1=2
P 7.86465 4.657 0 P 1 0;0=23,1=2
P 8.15 3.46615 0 P 1 0;0=23,1=2
P 7.90465 4.657 0 P 1 0;0=23,1=2
P 8.15 3.51615 0 P 1 0;0=23,1=2
P 7.86465 5.169 0 P 1 0;0=23,1=2
P 8.2 3.41615 0 P 1 0;0=23,1=2
P 7.90465 5.169 0 P 1 0;0=23,1=2
P 8.2 3.46615 0 P 1 0;0=23,1=2
P 7.79378996 4.78291998 0 P 1 0;0=23,1=2
P 8.1 3.41615 0 P 1 0;0=23,1=2
P 7.83378996 4.78291998 0 P 1 0;0=23,1=2
P 8.1 3.46615 0 P 1 0;0=23,1=2
P 7.65205 4.78291998 0 P 1 0;0=23,1=2
P 8.15 3.31615 0 P 1 0;0=23,1=2
P 7.69205 4.78291998 0 P 1 0;0=23,1=2
P 8.15 3.36615 0 P 1 0;0=23,1=2
P 7.65203996 5.0535 0 P 1 0;0=23,1=2
P 8.2 3.26615 0 P 1 0;0=23,1=2
P 7.69203996 5.0535 0 P 1 0;0=23,1=2
P 8.2 3.31615 0 P 1 0;0=23,1=2
P 7.58118996 4.707 0 P 1 0;0=23,1=2
P 8.1 3.26615 0 P 1 0;0=23,1=2
P 7.62118996 4.707 0 P 1 0;0=23,1=2
P 8.1 3.31615 0 P 1 0;0=23,1=2
P 7.58118996 5.169 0 P 1 0;0=23,1=2
P 8.05 3.31615 0 P 1 0;0=23,1=2
P 7.62118996 5.169 0 P 1 0;0=23,1=2
P 8.05 3.36615 0 P 1 0;0=23,1=2
P 2.11371004 5.169 0 P 1 0;0=23,1=2
P 2.39606004 3.46615 0 P 1 0;0=23,1=2
P 2.07371004 5.169 0 P 1 0;0=23,1=2
P 2.39606004 3.51615 0 P 1 0;0=23,1=2
P 2.06853002 4.66688996 0 P 1 0;0=23,1=2
P 2.49606004 3.46615 0 P 1 0;0=23,1=2
P 2.02853002 4.66688996 0 P 1 0;0=23,1=2
P 2.49606004 3.51615 0 P 1 0;0=23,1=2
P 2.18456998 5.0535 0 P 1 0;0=23,1=2
P 2.44606004 3.41615 0 P 1 0;0=23,1=2
P 2.14456998 5.0535 0 P 1 0;0=23,1=2
P 2.44606004 3.46615 0 P 1 0;0=23,1=2
P 2.11371004 4.78291998 0 P 1 0;0=23,1=2
P 2.34606004 3.41615 0 P 1 0;0=23,1=2
P 2.07371004 4.78291998 0 P 1 0;0=23,1=2
P 2.34606004 3.46615 0 P 1 0;0=23,1=2
P 2.25543996 4.78291998 0 P 1 0;0=23,1=2
P 2.49606004 3.31615 0 P 1 0;0=23,1=2
P 2.21543996 4.78291998 0 P 1 0;0=23,1=2
P 2.49606004 3.36615 0 P 1 0;0=23,1=2
P 2.39716998 5.115 0 P 1 0;0=23,1=2
P 2.44606004 3.26615 0 P 1 0;0=23,1=2
P 2.35716998 5.115 0 P 1 0;0=23,1=2
P 2.44606004 3.31615 0 P 1 0;0=23,1=2
P 2.25855 4.667 0 P 1 0;0=23,1=2
P 2.39606004 3.31615 0 P 1 0;0=23,1=2
P 2.21855 4.667 0 P 1 0;0=23,1=2
P 2.39606004 3.36615 0 P 1 0;0=23,1=2
P 2.34606004 3.26615 0 P 1 0;0=23,1=2
P 2.39716998 4.742 0 P 1 0;0=23,1=2
P 2.34606004 3.31615 0 P 1 0;0=23,1=2
P 2.35716998 4.742 0 P 1 0;0=23,1=2
P 8.11725 5.169 0 P 1 0;0=23,1=2
P 8.4 3.46615 0 P 1 0;0=23,1=2
P 8.07725 5.169 0 P 1 0;0=23,1=2
P 8.4 3.51615 0 P 1 0;0=23,1=2
P 8.07206998 4.66688996 0 P 1 0;0=23,1=2
P 8.5 3.46615 0 P 1 0;0=23,1=2
P 8.03206998 4.66688996 0 P 1 0;0=23,1=2
P 8.5 3.51615 0 P 1 0;0=23,1=2
P 8.18811004 5.0535 0 P 1 0;0=23,1=2
P 8.45 3.41615 0 P 1 0;0=23,1=2
P 8.14811004 5.0535 0 P 1 0;0=23,1=2
P 8.45 3.46615 0 P 1 0;0=23,1=2
P 8.11725 4.78291998 0 P 1 0;0=23,1=2
P 8.35 3.41615 0 P 1 0;0=23,1=2
P 8.07725 4.78291998 0 P 1 0;0=23,1=2
P 8.35 3.46615 0 P 1 0;0=23,1=2
P 8.25898002 4.78291998 0 P 1 0;0=23,1=2
P 8.5 3.31615 0 P 1 0;0=23,1=2
P 8.21898002 4.78291998 0 P 1 0;0=23,1=2
P 8.5 3.36615 0 P 1 0;0=23,1=2
P 8.40071004 5.115 0 P 1 0;0=23,1=2
P 8.45 3.26615 0 P 1 0;0=23,1=2
P 8.36071004 5.115 0 P 1 0;0=23,1=2
P 8.45 3.31615 0 P 1 0;0=23,1=2
P 8.26208996 4.667 0 P 1 0;0=23,1=2
P 8.4 3.31615 0 P 1 0;0=23,1=2
P 8.22208996 4.667 0 P 1 0;0=23,1=2
P 8.4 3.36615 0 P 1 0;0=23,1=2
P 8.35 3.26615 0 P 1 0;0=23,1=2
P 8.40071004 4.742 0 P 1 0;0=23,1=2
P 8.35 3.31615 0 P 1 0;0=23,1=2
P 8.36071004 4.742 0 P 1 0;0=23,1=2
P 4.73268002 1.86615 0 P 1 0;0=23,1=2
P 4.73268002 1.91615 0 P 1 0;0=23,1=2
P 4.68268002 1.91615 0 P 1 0;0=23,1=2
P 4.68268002 1.96615 0 P 1 0;0=23,1=2
P 4.63268002 1.86615 0 P 1 0;0=23,1=2
P 4.63268002 1.91615 0 P 1 0;0=23,1=2
P 4.58268002 1.91615 0 P 1 0;0=23,1=2
P 4.58268002 1.96615 0 P 1 0;0=23,1=2
P 4.73268002 2.01615 0 P 1 0;0=23,1=2
P 4.73268002 2.06615 0 P 1 0;0=23,1=2
P 4.63268002 2.01615 0 P 1 0;0=23,1=2
P 4.63268002 2.06615 0 P 1 0;0=23,1=2
P 4.58268002 2.06615 0 P 1 0;0=23,1=2
P 4.58268002 2.11615 0 P 1 0;0=23,1=2
P 4.68268002 2.06615 0 P 1 0;0=23,1=2
P 4.68268002 2.11615 0 P 1 0;0=23,1=2
P 4.73268002 2.26615 0 P 1 0;0=23,1=2
P 4.73268002 2.31615 0 P 1 0;0=23,1=2
P 4.68268002 2.21615 0 P 1 0;0=23,1=2
P 4.68268002 2.26615 0 P 1 0;0=23,1=2
P 4.58268002 2.21615 0 P 1 0;0=23,1=2
P 4.58268002 2.26615 0 P 1 0;0=23,1=2
P 4.63268002 2.26615 0 P 1 0;0=23,1=2
P 4.63268002 2.31615 0 P 1 0;0=23,1=2
P 4.68268002 2.36615 0 P 1 0;0=23,1=2
P 4.68268002 2.41615 0 P 1 0;0=23,1=2
P 4.58268002 2.36615 0 P 1 0;0=23,1=2
P 4.58268002 2.41615 0 P 1 0;0=23,1=2
P 4.63268002 2.41615 0 P 1 0;0=23,1=2
P 4.63268002 2.46615 0 P 1 0;0=23,1=2
P 4.73268002 2.41615 0 P 1 0;0=23,1=2
P 4.73268002 2.46615 0 P 1 0;0=23,1=2
P 3.42003996 5.22001998 0 P 1 0;0=23,1=2
P 3.38003996 5.22001998 0 P 1 0;0=23,1=2
P 9.42358002 5.22001998 0 P 1 0;0=23,1=2
P 9.38358002 5.22001998 0 P 1 0;0=23,1=2
P 0.69348996 1.90611998 0 P 1 0;0=23,1=2
P 0.69348996 1.86611998 0 P 1 0;0=23,1=2
P 10.395 1.32555 0 P 1 0;0=23,1=2
P 10.395 1.28555 0 P 1 0;0=23,1=2
P 10.42445 1.395 0 P 1 0;0=23,1=2
P 10.46445 1.395 0 P 1 0;0=23,1=2
P 10.35543002 1.52156998 0 P 1 0;0=23,1=2
P 10.38371998 1.49328002 0 P 1 0;0=23,1=2
P 10.26 1.66445 0 P 1 0;0=23,1=2
P 10.26 1.70445 0 P 1 0;0=23,1=2
P 10.26025 1.82845 0 P 1 0;0=23,1=2
P 10.26025 1.86845 0 P 1 0;0=23,1=2
P 10.225 1.92645 0 P 1 0;0=23,1=2
P 10.225 1.96645 0 P 1 0;0=23,1=2
P 10.09 2.01655 0 P 1 0;0=23,1=2
P 10.09 2.05655 0 P 1 0;0=23,1=2
P 10.09 2.13095 0 P 1 0;0=23,1=2
P 10.09 2.17095 0 P 1 0;0=23,1=2
P 9.975 2.19955 0 P 1 0;0=23,1=2
P 9.975 2.23955 0 P 1 0;0=23,1=2
P 9.975 2.3358 0 P 1 0;0=23,1=2
P 9.975 2.3758 0 P 1 0;0=23,1=2
P 10.09 2.26825 0 P 1 0;0=23,1=2
P 10.09 2.30825 0 P 1 0;0=23,1=2
P 10.09 2.44335 0 P 1 0;0=23,1=2
P 10.09 2.40335 0 P 1 0;0=23,1=2
P 10.09 2.53845 0 P 1 0;0=23,1=2
P 10.09 2.57845 0 P 1 0;0=23,1=2
P 9.975 2.4709 0 P 1 0;0=23,1=2
P 9.975 2.5109 0 P 1 0;0=23,1=2
P 9.975 2.66445 0 P 1 0;0=23,1=2
P 9.975 2.62445 0 P 1 0;0=23,1=2
P 10.09 2.69655 0 P 1 0;0=23,1=2
P 10.09 2.73655 0 P 1 0;0=23,1=2
P 2.97721004 2.825 0 P 1 0;0=23,1=2
P 2.97721004 2.865 0 P 1 0;0=23,1=2
P 8.98115 2.825 0 P 1 0;0=23,1=2
P 8.98115 2.865 0 P 1 0;0=23,1=2
P 5.57531004 1.8108 0 P 1 0;0=23,1=2
P 5.57531004 1.8508 0 P 1 0;0=23,1=2
P 5.57531004 1.7118 0 P 1 0;0=23,1=2
P 5.57531004 1.6718 0 P 1 0;0=23,1=2
P 5.42048002 1.6433 0 P 1 0;0=23,1=2
P 5.42048002 1.6033 0 P 1 0;0=23,1=2
P 5.42048002 1.7396 0 P 1 0;0=23,1=2
P 5.42048002 1.7796 0 P 1 0;0=23,1=2
P 5.57531004 1.9469 0 P 1 0;0=23,1=2
P 5.57531004 1.9869 0 P 1 0;0=23,1=2
P 5.42048002 1.87835 0 P 1 0;0=23,1=2
P 5.42048002 1.91835 0 P 1 0;0=23,1=2
P 5.57531004 2.0878 0 P 1 0;0=23,1=2
P 5.57531004 2.1278 0 P 1 0;0=23,1=2
P 5.42048002 2.0147 0 P 1 0;0=23,1=2
P 5.42048002 2.0547 0 P 1 0;0=23,1=2
P 5.57531004 2.2232 0 P 1 0;0=23,1=2
P 5.57531004 2.2632 0 P 1 0;0=23,1=2
P 5.42048002 2.2908 0 P 1 0;0=23,1=2
P 5.42048002 2.3308 0 P 1 0;0=23,1=2
P 5.42048002 2.1554 0 P 1 0;0=23,1=2
P 5.42048002 2.1954 0 P 1 0;0=23,1=2
P 5.57531004 2.3586 0 P 1 0;0=23,1=2
P 5.57531004 2.3986 0 P 1 0;0=23,1=2
P 5.42048002 2.4262 0 P 1 0;0=23,1=2
P 5.42048002 2.4662 0 P 1 0;0=23,1=2
P 5.57531004 2.4978 0 P 1 0;0=23,1=2
P 5.57531004 2.5378 0 P 1 0;0=23,1=2
P 5.57531004 2.633 0 P 1 0;0=23,1=2
P 5.57531004 2.673 0 P 1 0;0=23,1=2
P 5.42048002 2.5654 0 P 1 0;0=23,1=2
P 5.42048002 2.6054 0 P 1 0;0=23,1=2
P 11.78316004 1.652 0 P 1 0;0=23,1=2
P 11.78316004 1.692 0 P 1 0;0=23,1=2
P 11.73316004 1.532 0 P 1 0;0=23,1=2
P 11.73316004 1.492 0 P 1 0;0=23,1=2
P 11.53316004 1.452 0 P 1 0;0=23,1=2
P 11.53316004 1.412 0 P 1 0;0=23,1=2
P 11.53316004 1.572 0 P 1 0;0=23,1=2
P 11.53316004 1.612 0 P 1 0;0=23,1=2
P 11.73316004 1.812 0 P 1 0;0=23,1=2
P 11.73316004 1.852 0 P 1 0;0=23,1=2
P 11.53316004 1.732 0 P 1 0;0=23,1=2
P 11.53316004 1.772 0 P 1 0;0=23,1=2
P 11.73316004 1.972 0 P 1 0;0=23,1=2
P 11.73316004 2.012 0 P 1 0;0=23,1=2
P 11.53316004 1.892 0 P 1 0;0=23,1=2
P 11.53316004 1.932 0 P 1 0;0=23,1=2
P 11.73316004 2.132 0 P 1 0;0=23,1=2
P 11.73316004 2.172 0 P 1 0;0=23,1=2
P 11.83316004 2.212 0 P 1 0;0=23,1=2
P 11.83316004 2.252 0 P 1 0;0=23,1=2
P 11.53316004 2.052 0 P 1 0;0=23,1=2
P 11.53316004 2.092 0 P 1 0;0=23,1=2
P 11.73316004 2.292 0 P 1 0;0=23,1=2
P 11.73316004 2.332 0 P 1 0;0=23,1=2
P 11.53316004 2.372 0 P 1 0;0=23,1=2
P 11.53316004 2.412 0 P 1 0;0=23,1=2
P 11.73316004 2.452 0 P 1 0;0=23,1=2
P 11.73316004 2.492 0 P 1 0;0=23,1=2
P 11.73316004 2.612 0 P 1 0;0=23,1=2
P 11.73316004 2.652 0 P 1 0;0=23,1=2
P 11.53316004 2.532 0 P 1 0;0=23,1=2
P 11.53316004 2.572 0 P 1 0;0=23,1=2

### steps/drc/layers/l10/features
#
#Feature symbol names
#
$0 r2
$1 r3.7
$2 r4.5
$3 r6
$4 r15
$5 r17
$6 r20
$7 r43.7
$8 r74.8
$9 s15

#
#Feature attribute names
#
@0 .nomenclature
@1 .pattern_fill
@2 .string_mirrored
@3 .geometry
@4 .string
@5 .pad_usage
@6 .string_angle

#
#Feature attribute text strings
#
&0 C1_11P0_7TP
&1 V17D8AT30SM11
&2 C1_11P0_7
&3 V20D10AT28SM14
&4 TPB30V20D10AT28BPM
&5 C1_9P1_4
&6 S1_9P1_4
&7 SHEET
&8 TITLE
&9 SCALE 1:1
&10 LAYER
&11 OF
&12 ART
&13 12
&14 Barreleye G2 SXM2-Riser
&15 A1
&16 DATE OCT/27/2017
&17 INTERNAL LAYER 10
&18 10

#
#Layer features
#
L 0.875 -0.25 0.925 -0.3 2 P 0 
L 0.925 -0.3 1.435 -0.3 2 P 0 
L 1.435 -0.3 1.445 -0.31 2 P 0 
L 1.445 -0.31 1.445 -0.405 2 P 0 
L 1.445 -0.405 1.46 -0.42 2 P 0 
L 1.46 -0.42 1.5016 -0.42 2 P 0 
L 1.5016 -0.42 1.5061 -0.4155 2 P 0 
L 1.5061 -0.4155 1.5061 -0.1945 2 P 0 
L 1.5061 -0.1945 1.5106 -0.19 2 P 0 
L 1.5106 -0.19 1.5611 -0.19 2 P 0 
L 1.5611 -0.19 1.5656 -0.1945 2 P 0 
L 1.5656 -0.1945 1.5656 -0.4155 2 P 0 
L 1.5656 -0.4155 1.5701 -0.42 2 P 0 
L 1.5701 -0.42 1.6206 -0.42 2 P 0 
L 1.6206 -0.42 1.6251 -0.4155 2 P 0 
L 1.6251 -0.4155 1.6251 -0.1945 2 P 0 
L 1.6251 -0.1945 1.6296 -0.19 2 P 0 
L 1.6296 -0.19 1.6801 -0.19 2 P 0 
L 1.6801 -0.19 1.6846 -0.1945 2 P 0 
L 1.6846 -0.1945 1.6846 -0.4155 2 P 0 
L 1.6846 -0.4155 1.6891 -0.42 2 P 0 
L 1.6891 -0.42 1.7396 -0.42 2 P 0 
L 1.7396 -0.42 1.7441 -0.4155 2 P 0 
L 1.7441 -0.4155 1.7441 -0.1945 2 P 0 
L 1.7441 -0.1945 1.7486 -0.19 2 P 0 
L 1.7486 -0.19 1.7991 -0.19 2 P 0 
L 1.7991 -0.19 1.8036 -0.1945 2 P 0 
L 1.8036 -0.1945 1.8036 -0.4155 2 P 0 
L 1.8036 -0.4155 1.8081 -0.42 2 P 0 
L 1.8081 -0.42 1.8586 -0.42 2 P 0 
L 1.8586 -0.42 1.8631 -0.4155 2 P 0 
L 1.8631 -0.4155 1.8631 -0.1945 2 P 0 
L 1.8631 -0.1945 1.8676 -0.19 2 P 0 
L 1.8676 -0.19 1.9181 -0.19 2 P 0 
L 1.9181 -0.19 1.9226 -0.1945 2 P 0 
L 1.9226 -0.1945 1.9226 -0.4155 2 P 0 
L 1.9226 -0.4155 1.9271 -0.42 2 P 0 
L 1.9271 -0.42 1.9776 -0.42 2 P 0 
L 1.9776 -0.42 1.9821 -0.4155 2 P 0 
L 1.9821 -0.4155 1.9821 -0.1945 2 P 0 
L 1.9821 -0.1945 1.9866 -0.19 2 P 0 
L 1.9866 -0.19 2.0371 -0.19 2 P 0 
L 2.0371 -0.19 2.0416 -0.1945 2 P 0 
L 2.0416 -0.1945 2.0416 -0.4155 2 P 0 
L 2.0416 -0.4155 2.0461 -0.42 2 P 0 
L 2.0461 -0.42 2.0966 -0.42 2 P 0 
L 2.0966 -0.42 2.1011 -0.4155 2 P 0 
L 2.1011 -0.4155 2.1011 -0.1945 2 P 0 
L 2.1011 -0.1945 2.1056 -0.19 2 P 0 
L 2.1056 -0.19 2.1561 -0.19 2 P 0 
L 2.1561 -0.19 2.1606 -0.1945 2 P 0 
L 2.1606 -0.1945 2.1606 -0.4155 2 P 0 
L 2.1606 -0.4155 2.1651 -0.42 2 P 0 
L 2.1651 -0.42 2.2156 -0.42 2 P 0 
L 2.2156 -0.42 2.2201 -0.4155 2 P 0 
L 2.2201 -0.4155 2.2201 -0.1945 2 P 0 
L 2.2201 -0.1945 2.2246 -0.19 2 P 0 
L 2.2246 -0.19 2.2751 -0.19 2 P 0 
L 2.2751 -0.19 2.2796 -0.1945 2 P 0 
L 2.2796 -0.1945 2.2796 -0.4155 2 P 0 
L 2.2796 -0.4155 2.2841 -0.42 2 P 0 
L 2.2841 -0.42 2.3346 -0.42 2 P 0 
L 2.3346 -0.42 2.3391 -0.4155 2 P 0 
L 2.3391 -0.4155 2.3391 -0.1945 2 P 0 
L 2.3391 -0.1945 2.3436 -0.19 2 P 0 
L 2.3436 -0.19 2.3941 -0.19 2 P 0 
L 2.3941 -0.19 2.3986 -0.1945 2 P 0 
L 2.3986 -0.1945 2.3986 -0.4155 2 P 0 
L 2.3986 -0.4155 2.4031 -0.42 2 P 0 
L 2.4031 -0.42 2.4536 -0.42 2 P 0 
L 2.4536 -0.42 2.4581 -0.4155 2 P 0 
L 2.4581 -0.4155 2.4581 -0.1945 2 P 0 
L 2.4581 -0.1945 2.4626 -0.19 2 P 0 
L 2.4626 -0.19 2.5131 -0.19 2 P 0 
L 2.5131 -0.19 2.5176 -0.1945 2 P 0 
L 2.5176 -0.1945 2.5176 -0.4155 2 P 0 
L 2.5176 -0.4155 2.5221 -0.42 2 P 0 
L 2.5221 -0.42 2.5726 -0.42 2 P 0 
L 2.5726 -0.42 2.5771 -0.4155 2 P 0 
L 2.5771 -0.4155 2.5771 -0.1945 2 P 0 
L 2.5771 -0.1945 2.5816 -0.19 2 P 0 
L 2.5816 -0.19 2.6321 -0.19 2 P 0 
L 2.6321 -0.19 2.6366 -0.1945 2 P 0 
L 2.6366 -0.1945 2.6366 -0.4155 2 P 0 
L 2.6366 -0.4155 2.6411 -0.42 2 P 0 
L 2.6411 -0.42 2.6916 -0.42 2 P 0 
L 2.6916 -0.42 2.6961 -0.4155 2 P 0 
L 2.6961 -0.4155 2.6961 -0.1945 2 P 0 
L 2.6961 -0.1945 2.7006 -0.19 2 P 0 
L 2.7006 -0.19 2.7511 -0.19 2 P 0 
L 2.7511 -0.19 2.7556 -0.1945 2 P 0 
L 2.7556 -0.1945 2.7556 -0.4155 2 P 0 
L 2.7556 -0.4155 2.7601 -0.42 2 P 0 
L 2.7601 -0.42 2.8106 -0.42 2 P 0 
L 2.8106 -0.42 2.8151 -0.4155 2 P 0 
L 2.8151 -0.4155 2.8151 -0.1945 2 P 0 
L 2.8151 -0.1945 2.8196 -0.19 2 P 0 
L 2.8196 -0.19 2.8701 -0.19 2 P 0 
L 2.8701 -0.19 2.8746 -0.1945 2 P 0 
L 2.8746 -0.1945 2.8746 -0.4155 2 P 0 
L 2.8746 -0.4155 2.8791 -0.42 2 P 0 
L 2.8791 -0.42 2.9296 -0.42 2 P 0 
L 2.9296 -0.42 2.9341 -0.4155 2 P 0 
L 2.9341 -0.4155 2.9341 -0.1945 2 P 0 
L 2.9341 -0.1945 2.9386 -0.19 2 P 0 
L 2.9386 -0.19 2.9891 -0.19 2 P 0 
L 2.9891 -0.19 2.9936 -0.1945 2 P 0 
L 2.9936 -0.1945 2.9936 -0.4155 2 P 0 
P 0.875 -0.25 7 P 0 0;3=0,5=0
P 1.065 6.26 7 P 0 0;3=0,5=0
L 9.021 6.30625 1.0687 6.30625 1 P 0 
L 1.0687 6.30625 1.065 6.30255 1 P 0 
L 1.065 6.30255 1.065 6.26 1 P 0 
P 1.065 6.36 7 P 0 0;3=0,5=0
L 9.021 6.31375 1.0687 6.31375 1 P 0 
L 1.0687 6.31375 1.065 6.31745 1 P 0 
L 1.065 6.31745 1.065 6.36 1 P 0 
P 5.42048002 1.7396 5 P 0 0;3=1,5=1
P 0.09448996 2.55511998 7 P 0 0;3=2,5=0
L 0.09448996 2.55511998 0.12571004 2.5239 1 P 0 
L 0.12571004 2.5239 0.12571004 2.50101998 1 P 0 
L 0.12571004 2.50101998 0.15388996 2.47283996 1 P 0 
L 0.15388996 2.47283996 0.26681998 2.47283996 1 P 0 
L 0.26681998 2.47283996 0.28783996 2.47653996 1 P 0 
L 0.28783996 2.47653996 0.33328002 2.50835 1 P 0 
L 0.33328002 2.50835 0.34733996 2.51083996 1 P 0 
L 0.34733996 2.51083996 0.36988002 2.51083996 1 P 0 
L 0.36988002 2.51083996 0.38226004 2.51301998 1 P 0 
L 0.38226004 2.51301998 0.44446998 2.55658996 1 P 0 
L 0.44446998 2.55658996 0.5 2.56638002 1 P 0 
L 0.5 2.56638002 0.57281004 2.55353996 1 P 0 
L 0.57281004 2.55353996 0.62523002 2.51683002 1 P 0 
L 0.62523002 2.51683002 1.12968996 1.79641998 1 P 0 
L 1.12968996 1.79641998 2.07831004 1.13218996 1 P 0 
L 2.07831004 1.13218996 2.74515 1.01461004 1 P 0 
L 2.74515 1.01461004 4.00523002 1.23681004 1 P 0 
L 4.00523002 1.23681004 4.63978996 1.12491998 1 P 0 
L 4.63978996 1.12491998 4.96895 1.18296004 1 P 0 
L 4.96895 1.18296004 5.07701998 1.25863996 1 P 0 
L 5.07701998 1.25863996 5.26511004 1.52725 1 P 0 
L 5.26511004 1.52725 5.28768002 1.65526998 1 P 0 
L 5.28768002 1.65526998 5.35031998 1.74473996 1 P 0 
L 5.35031998 1.74473996 5.36625 1.7559 1 P 0 
L 5.36625 1.7559 5.40418002 1.7559 1 P 0 
L 5.40418002 1.7559 5.42048002 1.7396 1 P 0 
P 5.42048002 1.7796 5 P 0 0;3=1,5=1
P 0.17323002 2.51575 7 P 0 0;3=2,5=0
L 0.17323002 2.51575 0.17323002 2.51611004 1 P 0 
L 0.17323002 2.51611004 0.155 2.53433996 1 P 0 
L 0.155 2.53433996 0.137 2.53433996 1 P 0 
L 0.137 2.53433996 0.13321004 2.53055 1 P 0 
L 0.13321004 2.53055 0.13321004 2.50413002 1 P 0 
L 0.13321004 2.50413002 0.157 2.48033996 1 P 0 
L 0.157 2.48033996 0.26616004 2.48033996 1 P 0 
L 0.26616004 2.48033996 0.2849 2.48363996 1 P 0 
L 0.2849 2.48363996 0.33033996 2.51545 1 P 0 
L 0.33033996 2.51545 0.34668002 2.51833996 1 P 0 
L 0.34668002 2.51833996 0.36921998 2.51833996 1 P 0 
L 0.36921998 2.51833996 0.37931998 2.52011998 1 P 0 
L 0.37931998 2.52011998 0.44153002 2.56368996 1 P 0 
L 0.44153002 2.56368996 0.5 2.574 1 P 0 
L 0.5 2.574 0.57575 2.56063996 1 P 0 
L 0.57575 2.56063996 0.63061998 2.52221998 1 P 0 
L 0.63061998 2.52221998 1.13508002 1.80181004 1 P 0 
L 1.13508002 1.80181004 2.08125 1.13928996 1 P 0 
L 2.08125 1.13928996 2.74515 1.02223002 1 P 0 
L 2.74515 1.02223002 4.00523002 1.24443002 1 P 0 
L 4.00523002 1.24443002 4.63978996 1.13253996 1 P 0 
L 4.63978996 1.13253996 4.96601004 1.19006004 1 P 0 
L 4.96601004 1.19006004 5.07163002 1.26403002 1 P 0 
L 5.07163002 1.26403002 5.25801004 1.53018996 1 P 0 
L 5.25801004 1.53018996 5.28058002 1.65821004 1 P 0 
L 5.28058002 1.65821004 5.34493002 1.75013002 1 P 0 
L 5.34493002 1.75013002 5.36193996 1.76203996 1 P 0 
L 5.36193996 1.76203996 5.3633 1.7634 1 P 0 
L 5.3633 1.7634 5.40428002 1.7634 1 P 0 
L 5.40428002 1.7634 5.42048002 1.7796 1 P 0 
P 5.57531004 2.0878 5 P 0 0;3=1,5=1
P 0.09448996 3.1063 7 P 0 0;3=2,5=0
L 5.57531004 2.0878 5.55901004 2.1041 1 P 0 
L 5.55901004 2.1041 5.533 2.1041 1 P 0 
L 5.533 2.1041 5.52346004 2.10241998 1 P 0 
L 5.52346004 2.10241998 5.51118002 2.09381998 1 P 0 
L 5.51118002 2.09381998 5.49908996 2.07655 1 P 0 
L 5.49908996 2.07655 5.48746998 2.01065 1 P 0 
L 5.48746998 2.01065 5.47108996 1.9873 1 P 0 
L 5.47108996 1.9873 5.44288996 1.96756004 1 P 0 
L 5.44288996 1.96756004 5.35798996 1.9526 1 P 0 
L 5.35798996 1.9526 5.34 1.94 1 P 0 
L 5.34 1.94 5.31205 1.90008996 1 P 0 
L 5.31205 1.90008996 5.29856004 1.82365 1 P 0 
L 5.29856004 1.82365 5.21403996 1.70293002 1 P 0 
L 5.21403996 1.70293002 5.18438002 1.53478996 1 P 0 
L 5.18438002 1.53478996 5.10696998 1.42423002 1 P 0 
L 5.10696998 1.42423002 5.10696998 1.42421998 1 P 0 
L 5.10696998 1.42421998 5.02976004 1.31396004 1 P 0 
L 5.02976004 1.31396004 4.94236998 1.25276998 1 P 0 
L 4.94236998 1.25276998 4.75591998 1.21988996 1 P 0 
L 4.75591998 1.21988996 4.01803002 1.35001004 1 P 0 
L 4.01803002 1.35001004 2.72691004 1.12236004 1 P 0 
L 2.72691004 1.12236004 2.12318002 1.22878996 1 P 0 
L 2.12318002 1.22878996 1.25088002 1.83956998 1 P 0 
L 1.25088002 1.83956998 0.41346004 3.03553996 1 P 0 
L 0.41346004 3.03553996 0.37911998 3.05958996 1 P 0 
L 0.37911998 3.05958996 0.36533996 3.06201998 1 P 0 
L 0.36533996 3.06201998 0.34735 3.06201998 1 P 0 
L 0.34735 3.06201998 0.33328002 3.05953002 1 P 0 
L 0.33328002 3.05953002 0.28783996 3.02771998 1 P 0 
L 0.28783996 3.02771998 0.26681998 3.02401998 1 P 0 
L 0.26681998 3.02401998 0.15388996 3.02401998 1 P 0 
L 0.15388996 3.02401998 0.12571004 3.0522 1 P 0 
L 0.12571004 3.0522 0.12571004 3.07508002 1 P 0 
L 0.12571004 3.07508002 0.09448996 3.1063 1 P 0 
P 5.57531004 2.1278 5 P 0 0;3=1,5=1
P 0.17323002 3.06693002 7 P 0 0;3=2,5=0
L 5.57531004 2.1278 5.55911004 2.1116 1 P 0 
L 5.55911004 2.1116 5.53233996 2.1116 1 P 0 
L 5.53233996 2.1116 5.52051998 2.10951998 1 P 0 
L 5.52051998 2.10951998 5.50578996 2.09921004 1 P 0 
L 5.50578996 2.09921004 5.49198996 2.07948996 1 P 0 
L 5.49198996 2.07948996 5.48036998 2.01358996 1 P 0 
L 5.48036998 2.01358996 5.4657 1.99268996 1 P 0 
L 5.4657 1.99268996 5.43995 1.97466004 1 P 0 
L 5.43995 1.97466004 5.35505 1.9597 1 P 0 
L 5.35505 1.9597 5.33461004 1.94538996 1 P 0 
L 5.33461004 1.94538996 5.30495 1.90303002 1 P 0 
L 5.30495 1.90303002 5.29146004 1.82658996 1 P 0 
L 5.29146004 1.82658996 5.20693996 1.70586998 1 P 0 
L 5.20693996 1.70586998 5.17728002 1.53773002 1 P 0 
L 5.17728002 1.53773002 5.02436998 1.31935 1 P 0 
L 5.02436998 1.31935 4.93943002 1.25986998 1 P 0 
L 4.93943002 1.25986998 4.75591998 1.22751004 1 P 0 
L 4.75591998 1.22751004 4.01803002 1.35763002 1 P 0 
L 4.01803002 1.35763002 2.72691004 1.12998002 1 P 0 
L 2.72691004 1.12998002 2.12611998 1.23588996 1 P 0 
L 2.12611998 1.23588996 1.25626998 1.84496004 1 P 0 
L 1.25626998 1.84496004 0.41885 3.04093002 1 P 0 
L 0.41885 3.04093002 0.38206004 3.06668996 1 P 0 
L 0.38206004 3.06668996 0.366 3.06951998 1 P 0 
L 0.366 3.06951998 0.34668996 3.06951998 1 P 0 
L 0.34668996 3.06951998 0.33033996 3.06663002 1 P 0 
L 0.33033996 3.06663002 0.2849 3.03481998 1 P 0 
L 0.2849 3.03481998 0.26616004 3.03151998 1 P 0 
L 0.26616004 3.03151998 0.157 3.03151998 1 P 0 
L 0.157 3.03151998 0.13321004 3.05531004 1 P 0 
L 0.13321004 3.05531004 0.13321004 3.08173002 1 P 0 
L 0.13321004 3.08173002 0.137 3.08551998 1 P 0 
L 0.137 3.08551998 0.155 3.08551998 1 P 0 
L 0.155 3.08551998 0.17323002 3.06728996 1 P 0 
L 0.17323002 3.06728996 0.17323002 3.06693002 1 P 0 
P 5.57531004 2.2232 5 P 0 0;3=1,5=1
P 0.17323002 3.46063002 7 P 0 0;3=2,5=0
L 0.17323002 3.46063002 0.1562 3.4436 1 P 0 
L 0.1562 3.4436 0.13651998 3.4436 1 P 0 
L 0.13651998 3.4436 0.13 3.45011998 1 P 0 
L 0.13 3.45011998 0.13 3.47011998 1 P 0 
L 0.13 3.47011998 0.155 3.49511998 1 P 0 
L 0.155 3.49511998 0.27 3.49511998 1 P 0 
L 0.27 3.49511998 0.2851 3.49246004 1 P 0 
L 0.2851 3.49246004 0.32998002 3.46103002 1 P 0 
L 0.32998002 3.46103002 0.34651004 3.45811998 1 P 0 
L 0.34651004 3.45811998 0.36633996 3.45811998 1 P 0 
L 0.36633996 3.45811998 0.40923002 3.45055 1 P 0 
L 0.40923002 3.45055 0.44911998 3.42261004 1 P 0 
L 0.44911998 3.42261004 0.51261004 3.33193996 1 P 0 
L 0.51261004 3.33193996 0.58201998 2.93833002 1 P 0 
L 0.58201998 2.93833002 1.3402 1.85555 1 P 0 
L 1.3402 1.85555 2.1471 1.29055 1 P 0 
L 2.1471 1.29055 2.72305 1.18898002 1 P 0 
L 2.72305 1.18898002 4.01573002 1.41691998 1 P 0 
L 4.01573002 1.41691998 4.8103 1.2768 1 P 0 
L 4.8103 1.2768 4.92256998 1.2966 1 P 0 
L 4.92256998 1.2966 4.98831004 1.34263002 1 P 0 
L 4.98831004 1.34263002 5.12878996 1.54326998 1 P 0 
L 5.12878996 1.54326998 5.15978002 1.71898002 1 P 0 
L 5.15978002 1.71898002 5.24438996 1.83983002 1 P 0 
L 5.24438996 1.83983002 5.26493002 1.95635 1 P 0 
L 5.26493002 1.95635 5.34813002 2.07518002 1 P 0 
L 5.34813002 2.07518002 5.35998996 2.08348996 1 P 0 
L 5.35998996 2.08348996 5.44113002 2.09781998 1 P 0 
L 5.44113002 2.09781998 5.47241998 2.11973996 1 P 0 
L 5.47241998 2.11973996 5.49273002 2.14873996 1 P 0 
L 5.49273002 2.14873996 5.50443996 2.21515 1 P 0 
L 5.50443996 2.21515 5.51663002 2.23258002 1 P 0 
L 5.51663002 2.23258002 5.52318996 2.23716998 1 P 0 
L 5.52318996 2.23716998 5.5364 2.2395 1 P 0 
L 5.5364 2.2395 5.55901004 2.2395 1 P 0 
L 5.55901004 2.2395 5.57531004 2.2232 1 P 0 
P 5.57531004 2.2632 5 P 0 0;3=1,5=1
P 0.09448996 3.42126004 7 P 0 0;3=2,5=0
L 0.09448996 3.42126004 0.1225 3.44926998 1 P 0 
L 0.1225 3.44926998 0.1225 3.47323002 1 P 0 
L 0.1225 3.47323002 0.15188996 3.50261998 1 P 0 
L 0.15188996 3.50261998 0.27066004 3.50261998 1 P 0 
L 0.27066004 3.50261998 0.28803996 3.49956004 1 P 0 
L 0.28803996 3.49956004 0.33291998 3.46813002 1 P 0 
L 0.33291998 3.46813002 0.34716998 3.46561998 1 P 0 
L 0.34716998 3.46561998 0.367 3.46561998 1 P 0 
L 0.367 3.46561998 0.41216998 3.45765 1 P 0 
L 0.41216998 3.45765 0.45451004 3.428 1 P 0 
L 0.45451004 3.428 0.51971004 3.33488002 1 P 0 
L 0.51971004 3.33488002 0.58911998 2.94126998 1 P 0 
L 0.58911998 2.94126998 1.34558996 1.86093996 1 P 0 
L 1.34558996 1.86093996 2.15003996 1.29765 1 P 0 
L 2.15003996 1.29765 2.72305 1.1966 1 P 0 
L 2.72305 1.1966 4.01573002 1.42453996 1 P 0 
L 4.01573002 1.42453996 4.01703002 1.42431998 1 P 0 
L 4.01703002 1.42431998 4.01703002 1.42431004 1 P 0 
L 4.01703002 1.42431004 4.8103 1.28441998 1 P 0 
L 4.8103 1.28441998 4.91963002 1.3037 1 P 0 
L 4.91963002 1.3037 4.98291998 1.34801998 1 P 0 
L 4.98291998 1.34801998 5.12168996 1.54621004 1 P 0 
L 5.12168996 1.54621004 5.15268002 1.72191998 1 P 0 
L 5.15268002 1.72191998 5.23728996 1.84276998 1 P 0 
L 5.23728996 1.84276998 5.25783002 1.95928996 1 P 0 
L 5.25783002 1.95928996 5.34273996 2.08056998 1 P 0 
L 5.34273996 2.08056998 5.35705 2.09058996 1 P 0 
L 5.35705 2.09058996 5.43818996 2.10491998 1 P 0 
L 5.43818996 2.10491998 5.46703002 2.12513002 1 P 0 
L 5.46703002 2.12513002 5.48563002 2.15168002 1 P 0 
L 5.48563002 2.15168002 5.49733996 2.21808996 1 P 0 
L 5.49733996 2.21808996 5.51123996 2.23798002 1 P 0 
L 5.51123996 2.23798002 5.52025 2.24426998 1 P 0 
L 5.52025 2.24426998 5.53573996 2.247 1 P 0 
L 5.53573996 2.247 5.55911004 2.247 1 P 0 
L 5.55911004 2.247 5.57531004 2.2632 1 P 0 
P 5.42048002 2.4662 5 P 0 0;3=1,5=1
P 0.09448996 4.05118002 7 P 0 0;3=2,5=0
L 0.09448996 4.05118002 0.1225 4.07918996 1 P 0 
L 0.1225 4.07918996 0.1225 4.10315 1 P 0 
L 0.1225 4.10315 0.15188996 4.13253996 1 P 0 
L 0.15188996 4.13253996 0.27066004 4.13253996 1 P 0 
L 0.27066004 4.13253996 0.28803996 4.12948002 1 P 0 
L 0.28803996 4.12948002 0.33291998 4.09805 1 P 0 
L 0.33291998 4.09805 0.34716998 4.09553996 1 P 0 
L 0.34716998 4.09553996 0.367 4.09553996 1 P 0 
L 0.367 4.09553996 0.38651998 4.0921 1 P 0 
L 0.38651998 4.0921 0.45908002 4.04128996 1 P 0 
L 0.45908002 4.04128996 0.51111998 3.96698002 1 P 0 
L 0.51111998 3.96698002 0.52728996 3.87523002 1 P 0 
L 0.52728996 3.87523002 1.94301004 1.85341004 1 P 0 
L 1.94301004 1.85341004 2.01793002 1.80093996 1 P 0 
L 2.01793002 1.80093996 2.08996998 1.78823996 1 P 0 
L 2.08996998 1.78823996 2.2491 1.8163 1 P 0 
L 2.2491 1.8163 3.19826004 1.64896004 1 P 0 
L 3.19826004 1.64896004 4.34221998 1.85066998 1 P 0 
L 4.34221998 1.85066998 4.6687 1.79311004 1 P 0 
L 4.6687 1.79311004 4.80451004 1.81705 1 P 0 
L 4.80451004 1.81705 4.91825 1.79698996 1 P 0 
L 4.91825 1.79698996 5.07403996 1.82446998 1 P 0 
L 5.07403996 1.82446998 5.10336004 1.84501004 1 P 0 
L 5.10336004 1.84501004 5.15081998 1.91283996 1 P 0 
L 5.15081998 1.91283996 5.20638002 2.22776998 1 P 0 
L 5.20638002 2.22776998 5.35181998 2.43543996 1 P 0 
L 5.35181998 2.43543996 5.36755 2.44646004 1 P 0 
L 5.36755 2.44646004 5.38651998 2.4498 1 P 0 
L 5.38651998 2.4498 5.40408002 2.4498 1 P 0 
L 5.40408002 2.4498 5.42048002 2.4662 1 P 0 
P 5.57531004 2.3986 5 P 0 0;3=1,5=1
P 0.09448996 3.8937 7 P 0 0;3=2,5=0
L 5.57531004 2.3986 5.55911004 2.3824 1 P 0 
L 5.55911004 2.3824 5.53455 2.3824 1 P 0 
L 5.53455 2.3824 5.47496998 2.39291004 1 P 0 
L 5.47496998 2.39291004 5.37523996 2.37531998 1 P 0 
L 5.37523996 2.37531998 5.33571004 2.34766998 1 P 0 
L 5.33571004 2.34766998 5.22128996 2.18426004 1 P 0 
L 5.22128996 2.18426004 5.17173996 1.90318002 1 P 0 
L 5.17173996 1.90318002 5.11856998 1.82726004 1 P 0 
L 5.11856998 1.82726004 5.08403996 1.80308002 1 P 0 
L 5.08403996 1.80308002 4.91671998 1.77358002 1 P 0 
L 4.91671998 1.77358002 4.80558002 1.79316998 1 P 0 
L 4.80558002 1.79316998 4.67066998 1.76938996 1 P 0 
L 4.67066998 1.76938996 4.34618002 1.82665 1 P 0 
L 4.34618002 1.82665 3.19826004 1.62423996 1 P 0 
L 3.19826004 1.62423996 2.25258996 1.79101004 1 P 0 
L 2.25258996 1.79101004 2.09245 1.76278002 1 P 0 
L 2.09245 1.76278002 2.00171998 1.77876998 1 P 0 
L 2.00171998 1.77876998 1.9206 1.8356 1 P 0 
L 1.9206 1.8356 0.48633996 3.88393002 1 P 0 
L 0.48633996 3.88393002 0.4232 3.92815 1 P 0 
L 0.4232 3.92815 0.367 3.93806004 1 P 0 
L 0.367 3.93806004 0.34716998 3.93806004 1 P 0 
L 0.34716998 3.93806004 0.33291998 3.94056998 1 P 0 
L 0.33291998 3.94056998 0.28803996 3.972 1 P 0 
L 0.28803996 3.972 0.27066004 3.97506004 1 P 0 
L 0.27066004 3.97506004 0.15188996 3.97506004 1 P 0 
L 0.15188996 3.97506004 0.1225 3.94566998 1 P 0 
L 0.1225 3.94566998 0.1225 3.92171004 1 P 0 
L 0.1225 3.92171004 0.09448996 3.8937 1 P 0 
P 5.57531004 2.673 5 P 0 0;3=1,5=1
P 0.09448996 4.36613996 7 P 0 0;3=2,5=0
L 5.57531004 2.673 5.55871004 2.6564 1 P 0 
L 5.55871004 2.6564 5.53436998 2.6564 1 P 0 
L 5.53436998 2.6564 5.53426004 2.65628996 1 P 0 
L 5.53426004 2.65628996 5.52053002 2.65386998 1 P 0 
L 5.52053002 2.65386998 5.50808002 2.64516004 1 P 0 
L 5.50808002 2.64516004 5.49536998 2.62701998 1 P 0 
L 5.49536998 2.62701998 5.48471004 2.56653002 1 P 0 
L 5.48471004 2.56653002 5.47451004 2.55196998 1 P 0 
L 5.47451004 2.55196998 5.4497 2.53458996 1 P 0 
L 5.4497 2.53458996 5.42233002 2.52976004 1 P 0 
L 5.42233002 2.52976004 5.39846998 2.53396998 1 P 0 
L 5.39846998 2.53396998 5.38415 2.53143996 1 P 0 
L 5.38415 2.53143996 5.38415 2.53145 1 P 0 
L 5.38415 2.53145 5.37145 2.53368002 1 P 0 
L 5.37145 2.53368002 5.34315 2.55351004 1 P 0 
L 5.34315 2.55351004 5.19808002 2.76071998 1 P 0 
L 5.19808002 2.76071998 5.16541998 2.94576998 1 P 0 
L 5.16541998 2.94576998 5.17708996 3.01188996 1 P 0 
L 5.17708996 3.01188996 5.15866004 3.11641998 1 P 0 
L 5.15866004 3.11641998 5.17623002 3.21613002 1 P 0 
L 5.17623002 3.21613002 5.1609 3.30311998 1 P 0 
L 5.1609 3.30311998 5.23626004 3.73073996 1 P 0 
L 5.23626004 3.73073996 5.21526998 3.8497 1 P 0 
L 5.21526998 3.8497 5.195 3.87865 1 P 0 
L 5.195 3.87865 5.195 3.87866004 1 P 0 
L 5.195 3.87866004 5.17493002 3.90731004 1 P 0 
L 5.17493002 3.90731004 5.09531004 3.96306998 1 P 0 
L 5.09531004 3.96306998 4.92341998 3.99338002 1 P 0 
L 4.92341998 3.99338002 4.82676998 3.97635 1 P 0 
L 4.82676998 3.97635 3.53771998 4.20365 1 P 0 
L 3.53771998 4.20365 2.25195 3.97688996 1 P 0 
L 2.25195 3.97688996 2.07573996 4.00796998 1 P 0 
L 2.07573996 4.00796998 1.56658002 4.36446998 1 P 0 
L 1.56658002 4.36446998 0.83625 4.49323996 1 P 0 
L 0.83625 4.49323996 0.367 4.4105 1 P 0 
L 0.367 4.4105 0.34716998 4.4105 1 P 0 
L 0.34716998 4.4105 0.33291998 4.41301004 1 P 0 
L 0.33291998 4.41301004 0.28803996 4.44443996 1 P 0 
L 0.28803996 4.44443996 0.27066004 4.4475 1 P 0 
L 0.27066004 4.4475 0.15188996 4.4475 1 P 0 
L 0.15188996 4.4475 0.1225 4.41811004 1 P 0 
L 0.1225 4.41811004 0.1225 4.39415 1 P 0 
L 0.1225 4.39415 0.09448996 4.36613996 1 P 0 
P 5.57531004 1.9869 5 P 0 0;3=1,5=1
P 0.17323002 2.75196998 7 P 0 0;3=2,5=0
L 5.57531004 1.9869 5.55911004 1.9707 1 P 0 
L 5.55911004 1.9707 5.52263002 1.9707 1 P 0 
L 5.52263002 1.9707 5.50241004 1.95653996 1 P 0 
L 5.50241004 1.95653996 5.48661004 1.93396004 1 P 0 
L 5.48661004 1.93396004 5.47446998 1.86516998 1 P 0 
L 5.47446998 1.86516998 5.46636004 1.8536 1 P 0 
L 5.46636004 1.8536 5.44476004 1.83848002 1 P 0 
L 5.44476004 1.83848002 5.36548996 1.8245 1 P 0 
L 5.36548996 1.8245 5.34848996 1.81258996 1 P 0 
L 5.34848996 1.81258996 5.25991998 1.68611004 1 P 0 
L 5.25991998 1.68611004 5.23391998 1.53861998 1 P 0 
L 5.23391998 1.53861998 5.05065 1.27688996 1 P 0 
L 5.05065 1.27688996 4.95981998 1.21328996 1 P 0 
L 4.95981998 1.21328996 4.68061998 1.16406998 1 P 0 
L 4.68061998 1.16406998 4.01561004 1.28133002 1 P 0 
L 4.01561004 1.28133002 2.7422 1.05678002 1 P 0 
L 2.7422 1.05678002 2.10401998 1.1693 1 P 0 
L 2.10401998 1.1693 1.16501998 1.82678002 1 P 0 
L 1.16501998 1.82678002 0.90048996 2.20456998 1 P 0 
L 0.90048996 2.20456998 0.9005 2.20456998 1 P 0 
L 0.9005 2.20456998 0.63446998 2.58451004 1 P 0 
L 0.63446998 2.58451004 0.40026998 2.74851998 1 P 0 
L 0.40026998 2.74851998 0.366 2.75456004 1 P 0 
L 0.366 2.75456004 0.34668996 2.75456004 1 P 0 
L 0.34668996 2.75456004 0.33033996 2.75166998 1 P 0 
L 0.33033996 2.75166998 0.2849 2.71986004 1 P 0 
L 0.2849 2.71986004 0.26616004 2.71656004 1 P 0 
L 0.26616004 2.71656004 0.157 2.71656004 1 P 0 
L 0.157 2.71656004 0.13321004 2.74035 1 P 0 
L 0.13321004 2.74035 0.13321004 2.76676998 1 P 0 
L 0.13321004 2.76676998 0.137 2.77056004 1 P 0 
L 0.137 2.77056004 0.155 2.77056004 1 P 0 
L 0.155 2.77056004 0.17323002 2.75233002 1 P 0 
L 0.17323002 2.75233002 0.17323002 2.75196998 1 P 0 
P 5.57531004 2.4978 5 P 0 0;3=1,5=1
P 0.17323002 4.24803002 7 P 0 0;3=2,5=0
L 5.57531004 2.4978 5.55941004 2.5137 1 P 0 
L 5.55941004 2.5137 5.50468996 2.5137 1 P 0 
L 5.50468996 2.5137 5.42333002 2.49935 1 P 0 
L 5.42333002 2.49935 5.42201998 2.49958002 1 P 0 
L 5.42201998 2.49958002 5.42203002 2.49958002 1 P 0 
L 5.42203002 2.49958002 5.40175 2.50316004 1 P 0 
L 5.40175 2.50316004 5.38698002 2.50055 1 P 0 
L 5.38698002 2.50055 5.35891998 2.50551004 1 P 0 
L 5.35891998 2.50551004 5.32056004 2.53233996 1 P 0 
L 5.32056004 2.53233996 5.16906004 2.74871998 1 P 0 
L 5.16906004 2.74871998 5.13416004 2.94671004 1 P 0 
L 5.13416004 2.94671004 5.14548996 3.01116004 1 P 0 
L 5.14548996 3.01116004 5.12693002 3.1164 1 P 0 
L 5.12693002 3.1164 5.14451004 3.21618996 1 P 0 
L 5.14451004 3.21618996 5.14451004 3.2162 1 P 0 
L 5.14451004 3.2162 5.12873002 3.3057 1 P 0 
L 5.12873002 3.3057 5.20341998 3.72951004 1 P 0 
L 5.20341998 3.72951004 5.18396004 3.83991998 1 P 0 
L 5.18396004 3.83991998 5.15248996 3.88486998 1 P 0 
L 5.15248996 3.88486998 5.08305 3.9335 1 P 0 
L 5.08305 3.9335 4.92806998 3.96083996 1 P 0 
L 4.92806998 3.96083996 4.83128002 3.94378002 1 P 0 
L 4.83128002 3.94378002 3.547 4.17021998 1 P 0 
L 3.547 4.17021998 2.25188002 3.94176998 1 P 0 
L 2.25188002 3.94176998 2.05831998 3.97591004 1 P 0 
L 2.05831998 3.97591004 1.55381998 4.32916004 1 P 0 
L 1.55381998 4.32916004 0.94753996 4.43603002 1 P 0 
L 0.94753996 4.43603002 0.59783002 4.37435 1 P 0 
L 0.59783002 4.37435 0.42963002 4.25656004 1 P 0 
L 0.42963002 4.25656004 0.367 4.24551998 1 P 0 
L 0.367 4.24551998 0.34651004 4.24551998 1 P 0 
L 0.34651004 4.24551998 0.33163002 4.24813996 1 P 0 
L 0.33163002 4.24813996 0.33161998 4.24813996 1 P 0 
L 0.33161998 4.24813996 0.32998002 4.24843002 1 P 0 
L 0.32998002 4.24843002 0.2851 4.27986004 1 P 0 
L 0.2851 4.27986004 0.27 4.28251998 1 P 0 
L 0.27 4.28251998 0.155 4.28251998 1 P 0 
L 0.155 4.28251998 0.13 4.25751998 1 P 0 
L 0.13 4.25751998 0.13 4.23751998 1 P 0 
L 0.13 4.23751998 0.13651998 4.231 1 P 0 
L 0.13651998 4.231 0.1562 4.231 1 P 0 
L 0.1562 4.231 0.17323002 4.24803002 1 P 0 
L 5.57531004 1.6718 5.55961004 1.6875 1 P 0 
L 5.55961004 1.6875 5.52571004 1.6875 1 P 0 
L 5.52571004 1.6875 5.50501998 1.67301004 1 P 0 
L 5.50501998 1.67301004 5.49961998 1.66531004 1 P 0 
L 5.49961998 1.66531004 5.49961998 1.6653 1 P 0 
L 5.49961998 1.6653 5.49423996 1.65763996 1 P 0 
L 5.49423996 1.65763996 5.47531004 1.5502 1 P 0 
L 5.47531004 1.5502 5.37418002 1.40578996 1 P 0 
L 5.37418002 1.40578996 4.97846004 1.12861004 1 P 0 
L 4.97846004 1.12861004 4.59491998 1.06098996 1 P 0 
L 4.59491998 1.06098996 3.98698996 1.16818002 1 P 0 
L 3.98698996 1.16818002 2.7476 0.94961998 1 P 0 
L 2.7476 0.94961998 2.04093996 1.07423002 1 P 0 
L 2.04093996 1.07423002 1.06016004 1.76098996 1 P 0 
L 1.06016004 1.76098996 0.80718996 2.12208996 1 P 0 
L 0.80718996 2.12208996 0.66403996 2.22231004 1 P 0 
L 0.66403996 2.22231004 0.35703002 2.27646004 1 P 0 
L 0.35703002 2.27646004 0.34006004 2.27348002 1 P 0 
L 0.34006004 2.27348002 0.28656004 2.23601998 1 P 0 
L 0.28656004 2.23601998 0.15211004 2.23601998 1 P 0 
L 0.15211004 2.23601998 0.141 2.22491004 1 P 0 
L 0.141 2.22491004 0.141 2.20651998 1 P 0 
L 0.141 2.20651998 0.14673002 2.20078996 1 P 0 
L 0.14673002 2.20078996 0.17323002 2.20078996 1 P 0 
P 5.57531004 1.6718 5 P 0 0;3=1,5=1
P 0.17323002 2.20078996 7 P 0 0;3=2,5=0
P 5.57531004 2.633 5 P 0 0;3=1,5=1
P 0.17323002 4.40551004 7 P 0 0;3=2,5=0
L 5.57531004 2.633 5.55941004 2.6489 1 P 0 
L 5.55941004 2.6489 5.53556004 2.6489 1 P 0 
L 5.53556004 2.6489 5.52346998 2.64676998 1 P 0 
L 5.52346998 2.64676998 5.51346998 2.63976998 1 P 0 
L 5.51346998 2.63976998 5.50246998 2.62408002 1 P 0 
L 5.50246998 2.62408002 5.49181004 2.56358996 1 P 0 
L 5.49181004 2.56358996 5.4799 2.54658002 1 P 0 
L 5.4799 2.54658002 5.45263996 2.52748996 1 P 0 
L 5.45263996 2.52748996 5.42233002 2.52213996 1 P 0 
L 5.42233002 2.52213996 5.39846998 2.52635 1 P 0 
L 5.39846998 2.52635 5.38415 2.52381998 1 P 0 
L 5.38415 2.52381998 5.36851004 2.52658002 1 P 0 
L 5.36851004 2.52658002 5.33776004 2.54811998 1 P 0 
L 5.33776004 2.54811998 5.19098002 2.75778002 1 P 0 
L 5.19098002 2.75778002 5.1578 2.94576998 1 P 0 
L 5.1578 2.94576998 5.16946998 3.01188996 1 P 0 
L 5.16946998 3.01188996 5.15103996 3.11641998 1 P 0 
L 5.15103996 3.11641998 5.16861004 3.21613002 1 P 0 
L 5.16861004 3.21613002 5.15328002 3.30311998 1 P 0 
L 5.15328002 3.30311998 5.22863996 3.73073996 1 P 0 
L 5.22863996 3.73073996 5.20816998 3.84676004 1 P 0 
L 5.20816998 3.84676004 5.16953996 3.90191998 1 P 0 
L 5.16953996 3.90191998 5.09251998 3.95586004 1 P 0 
L 5.09251998 3.95586004 5.09236998 3.95596998 1 P 0 
L 5.09236998 3.95596998 4.92341998 3.98576004 1 P 0 
L 4.92341998 3.98576004 4.82676998 3.96873002 1 P 0 
L 4.82676998 3.96873002 3.53771998 4.19603002 1 P 0 
L 3.53771998 4.19603002 2.25195 3.96926998 1 P 0 
L 2.25195 3.96926998 2.0728 4.00086998 1 P 0 
L 2.0728 4.00086998 1.56363996 4.35736998 1 P 0 
L 1.56363996 4.35736998 0.83625 4.48561998 1 P 0 
L 0.83625 4.48561998 0.36766004 4.403 1 P 0 
L 0.36766004 4.403 0.34651004 4.403 1 P 0 
L 0.34651004 4.403 0.32998002 4.40591004 1 P 0 
L 0.32998002 4.40591004 0.2851 4.43733996 1 P 0 
L 0.2851 4.43733996 0.27 4.44 1 P 0 
L 0.27 4.44 0.155 4.44 1 P 0 
L 0.155 4.44 0.13 4.415 1 P 0 
L 0.13 4.415 0.13 4.395 1 P 0 
L 0.13 4.395 0.137 4.388 1 P 0 
L 0.137 4.388 0.15571998 4.388 1 P 0 
L 0.15571998 4.388 0.17323002 4.40551004 1 P 0 
L 5.57531004 1.7118 5.55851004 1.695 1 P 0 
L 5.55851004 1.695 5.52333996 1.695 1 P 0 
L 5.52333996 1.695 5.49963002 1.6784 1 P 0 
L 5.49963002 1.6784 5.48713996 1.66058002 1 P 0 
L 5.48713996 1.66058002 5.46821004 1.55313996 1 P 0 
L 5.46821004 1.55313996 5.36878996 1.41118002 1 P 0 
L 5.36878996 1.41118002 4.97551998 1.13571004 1 P 0 
L 4.97551998 1.13571004 4.59491998 1.06861004 1 P 0 
L 4.59491998 1.06861004 3.98698996 1.1758 1 P 0 
L 3.98698996 1.1758 2.7476 0.95723996 1 P 0 
L 2.7476 0.95723996 2.04388002 1.08133002 1 P 0 
L 2.04388002 1.08133002 1.06555 1.76638002 1 P 0 
L 1.06555 1.76638002 0.81258002 2.12748002 1 P 0 
L 0.81258002 2.12748002 0.66698002 2.22941004 1 P 0 
L 0.66698002 2.22941004 0.35703002 2.28408002 1 P 0 
L 0.35703002 2.28408002 0.33711998 2.28058002 1 P 0 
L 0.33711998 2.28058002 0.28418996 2.24351998 1 P 0 
L 0.28418996 2.24351998 0.149 2.24351998 1 P 0 
L 0.149 2.24351998 0.13123996 2.22576004 1 P 0 
L 0.13123996 2.22576004 0.12323996 2.22576004 1 P 0 
L 0.12323996 2.22576004 0.09448996 2.24016004 1 P 0 
P 5.57531004 1.7118 5 P 0 0;3=1,5=1
P 0.09448996 2.24016004 7 P 0 0;3=2,5=0
P 5.57531004 2.5378 5 P 0 0;3=1,5=1
P 0.09448996 4.20866004 7 P 0 0;3=2,5=0
L 5.57531004 2.5378 5.55871004 2.5212 1 P 0 
L 5.55871004 2.5212 5.50403002 2.5212 1 P 0 
L 5.50403002 2.5212 5.42333002 2.50696998 1 P 0 
L 5.42333002 2.50696998 5.40175 2.51078002 1 P 0 
L 5.40175 2.51078002 5.38698002 2.50816998 1 P 0 
L 5.38698002 2.50816998 5.36186004 2.51261004 1 P 0 
L 5.36186004 2.51261004 5.32595 2.53773002 1 P 0 
L 5.32595 2.53773002 5.17616004 2.75166004 1 P 0 
L 5.17616004 2.75166004 5.14178002 2.94671004 1 P 0 
L 5.14178002 2.94671004 5.15311004 3.01116004 1 P 0 
L 5.15311004 3.01116004 5.13455 3.1164 1 P 0 
L 5.13455 3.1164 5.15213002 3.2162 1 P 0 
L 5.15213002 3.2162 5.13635 3.3057 1 P 0 
L 5.13635 3.3057 5.21103996 3.72951004 1 P 0 
L 5.21103996 3.72951004 5.19106004 3.84286004 1 P 0 
L 5.19106004 3.84286004 5.15788002 3.89026004 1 P 0 
L 5.15788002 3.89026004 5.08598996 3.9406 1 P 0 
L 5.08598996 3.9406 4.92806998 3.96846004 1 P 0 
L 4.92806998 3.96846004 4.83128002 3.9514 1 P 0 
L 4.83128002 3.9514 3.547 4.17783996 1 P 0 
L 3.547 4.17783996 2.25188002 3.94938996 1 P 0 
L 2.25188002 3.94938996 2.06126004 3.98301004 1 P 0 
L 2.06126004 3.98301004 1.55676004 4.33626004 1 P 0 
L 1.55676004 4.33626004 0.94753996 4.44365 1 P 0 
L 0.94753996 4.44365 0.59488996 4.38145 1 P 0 
L 0.59488996 4.38145 0.42668996 4.26366004 1 P 0 
L 0.42668996 4.26366004 0.36633996 4.25303002 1 P 0 
L 0.36633996 4.25303002 0.36633002 4.25301998 1 P 0 
L 0.36633002 4.25301998 0.34716998 4.25301998 1 P 0 
L 0.34716998 4.25301998 0.33291998 4.25553002 1 P 0 
L 0.33291998 4.25553002 0.28803996 4.28696004 1 P 0 
L 0.28803996 4.28696004 0.27066004 4.29001998 1 P 0 
L 0.27066004 4.29001998 0.15188996 4.29001998 1 P 0 
L 0.15188996 4.29001998 0.1225 4.26063002 1 P 0 
L 0.1225 4.26063002 0.1225 4.23666998 1 P 0 
L 0.1225 4.23666998 0.09448996 4.20866004 1 P 0 
P 5.42048002 1.6433 5 P 0 0;3=1,5=1
P 0.09448996 2.39763996 7 P 0 0;3=2,5=0
L 5.42048002 1.6433 5.40428002 1.6271 1 P 0 
L 5.40428002 1.6271 5.36911998 1.6271 1 P 0 
L 5.36911998 1.6271 5.35206004 1.6241 1 P 0 
L 5.35206004 1.6241 5.33011004 1.60873002 1 P 0 
L 5.33011004 1.60873002 5.28801004 1.54858996 1 P 0 
L 5.28801004 1.54858996 5.2826 1.51796998 1 P 0 
L 5.2826 1.51796998 5.09501004 1.25008996 1 P 0 
L 5.09501004 1.25008996 4.97398996 1.16533996 1 P 0 
L 4.97398996 1.16533996 4.60618002 1.10045 1 P 0 
L 4.60618002 1.10045 3.99358002 1.20846998 1 P 0 
L 3.99358002 1.20846998 2.74646004 0.98855 1 P 0 
L 2.74646004 0.98855 2.0655 1.10863002 1 P 0 
L 2.0655 1.10863002 1.0945 1.78853996 1 P 0 
L 1.0945 1.78853996 0.59516004 2.50165 1 P 0 
L 0.59516004 2.50165 0.56673002 2.52155 1 P 0 
L 0.56673002 2.52155 0.52781998 2.52841004 1 P 0 
L 0.52781998 2.52841004 0.48861998 2.5215 1 P 0 
L 0.48861998 2.5215 0.37558002 2.44236998 1 P 0 
L 0.37558002 2.44236998 0.36786004 2.441 1 P 0 
L 0.36786004 2.441 0.35385 2.441 1 P 0 
L 0.35385 2.441 0.33711998 2.43806004 1 P 0 
L 0.33711998 2.43806004 0.31063996 2.41951998 1 P 0 
L 0.31063996 2.41951998 0.31063002 2.41951998 1 P 0 
L 0.31063002 2.41951998 0.28418996 2.401 1 P 0 
L 0.28418996 2.401 0.149 2.401 1 P 0 
L 0.149 2.401 0.13123996 2.38323996 1 P 0 
L 0.13123996 2.38323996 0.12323996 2.38323996 1 P 0 
L 0.12323996 2.38323996 0.09448996 2.39763996 1 P 0 
P 5.42048002 2.6054 5 P 0 0;3=1,5=1
P 0.09448996 4.52361998 7 P 0 0;3=2,5=0
L 5.42048002 2.6054 5.40388002 2.5888 1 P 0 
L 5.40388002 2.5888 5.38 2.5888 1 P 0 
L 5.38 2.5888 5.35861998 2.59256998 1 P 0 
L 5.35861998 2.59256998 5.33686998 2.60778996 1 P 0 
L 5.33686998 2.60778996 5.22316004 2.77016004 1 P 0 
L 5.22316004 2.77016004 5.19178002 2.94826998 1 P 0 
L 5.19178002 2.94826998 5.20205 3.00663996 1 P 0 
L 5.20205 3.00663996 5.18296998 3.11485 1 P 0 
L 5.18296998 3.11485 5.20176998 3.22148996 1 P 0 
L 5.20176998 3.22148996 5.18745 3.30268996 1 P 0 
L 5.18745 3.30268996 5.26186998 3.72498002 1 P 0 
L 5.26186998 3.72498002 5.2382 3.8592 1 P 0 
L 5.2382 3.8592 5.19233002 3.92471004 1 P 0 
L 5.19233002 3.92471004 5.10481004 3.986 1 P 0 
L 5.10481004 3.986 4.92303002 4.01805 1 P 0 
L 4.92303002 4.01805 4.83151998 4.00191998 1 P 0 
L 4.83151998 4.00191998 3.53265 4.23095 1 P 0 
L 3.53265 4.23095 3.53133996 4.23071998 1 P 0 
L 3.53133996 4.23071998 3.53135 4.23071998 1 P 0 
L 3.53135 4.23071998 2.25393996 4.00548996 1 P 0 
L 2.25393996 4.00548996 2.07811004 4.03648996 1 P 0 
L 2.07811004 4.03648996 1.56143002 4.39828002 1 P 0 
L 1.56143002 4.39828002 0.4905 4.58711998 1 P 0 
L 0.4905 4.58711998 0.37933996 4.5675 1 P 0 
L 0.37933996 4.5675 0.33311004 4.5675 1 P 0 
L 0.33311004 4.5675 0.29811004 4.6025 1 P 0 
L 0.29811004 4.6025 0.15188996 4.6025 1 P 0 
L 0.15188996 4.6025 0.12571004 4.57631998 1 P 0 
L 0.12571004 4.57631998 0.12571004 4.55483996 1 P 0 
L 0.12571004 4.55483996 0.09448996 4.52361998 1 P 0 
P 5.42048002 1.87835 5 P 0 0;3=1,5=1
P 0.09448996 2.94881998 7 P 0 0;3=2,5=0
L 5.42048002 1.87835 5.40323002 1.8956 1 P 0 
L 5.40323002 1.8956 5.365 1.8956 1 P 0 
L 5.365 1.8956 5.34996004 1.88506004 1 P 0 
L 5.34996004 1.88506004 5.33678996 1.86626004 1 P 0 
L 5.33678996 1.86626004 5.3283 1.81803996 1 P 0 
L 5.3283 1.81803996 5.24123002 1.69371998 1 P 0 
L 5.24123002 1.69371998 5.21361004 1.53703996 1 P 0 
L 5.21361004 1.53703996 5.04226004 1.29231998 1 P 0 
L 5.04226004 1.29231998 4.95013002 1.22781004 1 P 0 
L 4.95013002 1.22781004 4.72338996 1.18783002 1 P 0 
L 4.72338996 1.18783002 4.0158 1.3126 1 P 0 
L 4.0158 1.3126 2.73706998 1.08713002 1 P 0 
L 2.73706998 1.08713002 2.10581004 1.19843002 1 P 0 
L 2.10581004 1.19843002 1.20475 1.82935 1 P 0 
L 1.20475 1.82935 0.51688002 2.8118 1 P 0 
L 0.51688002 2.8118 0.39131998 2.89971004 1 P 0 
L 0.39131998 2.89971004 0.36393996 2.90453996 1 P 0 
L 0.36393996 2.90453996 0.34735 2.90453996 1 P 0 
L 0.34735 2.90453996 0.33328002 2.90205 1 P 0 
L 0.33328002 2.90205 0.28783996 2.87023996 1 P 0 
L 0.28783996 2.87023996 0.26681998 2.86653996 1 P 0 
L 0.26681998 2.86653996 0.15388996 2.86653996 1 P 0 
L 0.15388996 2.86653996 0.12571004 2.89471998 1 P 0 
L 0.12571004 2.89471998 0.12571004 2.9176 1 P 0 
L 0.12571004 2.9176 0.09448996 2.94881998 1 P 0 
P 5.57531004 2.3586 5 P 0 0;3=1,5=1
P 0.17323002 3.93306998 7 P 0 0;3=2,5=0
L 5.57531004 2.3586 5.55901004 2.3749 1 P 0 
L 5.55901004 2.3749 5.53388996 2.3749 1 P 0 
L 5.53388996 2.3749 5.47496998 2.38528996 1 P 0 
L 5.47496998 2.38528996 5.37818002 2.36821998 1 P 0 
L 5.37818002 2.36821998 5.3411 2.34228002 1 P 0 
L 5.3411 2.34228002 5.22838996 2.18131998 1 P 0 
L 5.22838996 2.18131998 5.17883996 1.90023996 1 P 0 
L 5.17883996 1.90023996 5.12396004 1.82186998 1 P 0 
L 5.12396004 1.82186998 5.08698002 1.79598002 1 P 0 
L 5.08698002 1.79598002 4.91671998 1.76596004 1 P 0 
L 4.91671998 1.76596004 4.80558002 1.78555 1 P 0 
L 4.80558002 1.78555 4.67066998 1.76176998 1 P 0 
L 4.67066998 1.76176998 4.34618002 1.81903002 1 P 0 
L 4.34618002 1.81903002 3.19826004 1.61661998 1 P 0 
L 3.19826004 1.61661998 2.25258996 1.78338996 1 P 0 
L 2.25258996 1.78338996 2.09245 1.75516004 1 P 0 
L 2.09245 1.75516004 1.99878002 1.77166998 1 P 0 
L 1.99878002 1.77166998 1.91521004 1.83021004 1 P 0 
L 1.91521004 1.83021004 0.48095 3.87853996 1 P 0 
L 0.48095 3.87853996 0.42026004 3.92105 1 P 0 
L 0.42026004 3.92105 0.36633996 3.93056004 1 P 0 
L 0.36633996 3.93056004 0.34651004 3.93056004 1 P 0 
L 0.34651004 3.93056004 0.32998002 3.93346998 1 P 0 
L 0.32998002 3.93346998 0.2851 3.9649 1 P 0 
L 0.2851 3.9649 0.27 3.96756004 1 P 0 
L 0.27 3.96756004 0.155 3.96756004 1 P 0 
L 0.155 3.96756004 0.13 3.94256004 1 P 0 
L 0.13 3.94256004 0.13 3.92256004 1 P 0 
L 0.13 3.92256004 0.13651998 3.91603996 1 P 0 
L 0.13651998 3.91603996 0.1562 3.91603996 1 P 0 
L 0.1562 3.91603996 0.17323002 3.93306998 1 P 0 
P 5.42048002 1.6033 5 P 0 0;3=1,5=1
P 0.17323002 2.35826998 7 P 0 0;3=2,5=0
L 5.42048002 1.6033 5.40418002 1.6196 1 P 0 
L 5.40418002 1.6196 5.36978002 1.6196 1 P 0 
L 5.36978002 1.6196 5.355 1.617 1 P 0 
L 5.355 1.617 5.3355 1.60333996 1 P 0 
L 5.3355 1.60333996 5.29511004 1.54565 1 P 0 
L 5.29511004 1.54565 5.2897 1.51503002 1 P 0 
L 5.2897 1.51503002 5.1004 1.2447 1 P 0 
L 5.1004 1.2447 4.97693002 1.15823996 1 P 0 
L 4.97693002 1.15823996 4.60618002 1.09283002 1 P 0 
L 4.60618002 1.09283002 3.99358002 1.20085 1 P 0 
L 3.99358002 1.20085 2.74646004 0.98093002 1 P 0 
L 2.74646004 0.98093002 2.06256004 1.10153002 1 P 0 
L 2.06256004 1.10153002 1.08911004 1.78315 1 P 0 
L 1.08911004 1.78315 0.58976998 2.49626004 1 P 0 
L 0.58976998 2.49626004 0.56378996 2.51445 1 P 0 
L 0.56378996 2.51445 0.52781998 2.52078996 1 P 0 
L 0.52781998 2.52078996 0.49156004 2.5144 1 P 0 
L 0.49156004 2.5144 0.37853002 2.43526998 1 P 0 
L 0.37853002 2.43526998 0.36851998 2.4335 1 P 0 
L 0.36851998 2.4335 0.35451004 2.4335 1 P 0 
L 0.35451004 2.4335 0.34006004 2.43096004 1 P 0 
L 0.34006004 2.43096004 0.28656004 2.3935 1 P 0 
L 0.28656004 2.3935 0.15211004 2.3935 1 P 0 
L 0.15211004 2.3935 0.141 2.38238996 1 P 0 
L 0.141 2.38238996 0.141 2.364 1 P 0 
L 0.141 2.364 0.14673002 2.35826998 1 P 0 
L 0.14673002 2.35826998 0.17323002 2.35826998 1 P 0 
P 5.42048002 2.4262 5 P 0 0;3=1,5=1
P 0.17323002 4.09055 7 P 0 0;3=2,5=0
L 0.17323002 4.09055 0.1562 4.07351998 1 P 0 
L 0.1562 4.07351998 0.13651998 4.07351998 1 P 0 
L 0.13651998 4.07351998 0.13 4.08003996 1 P 0 
L 0.13 4.08003996 0.13 4.10003996 1 P 0 
L 0.13 4.10003996 0.155 4.12503996 1 P 0 
L 0.155 4.12503996 0.27 4.12503996 1 P 0 
L 0.27 4.12503996 0.2851 4.12238002 1 P 0 
L 0.2851 4.12238002 0.32998002 4.09095 1 P 0 
L 0.32998002 4.09095 0.34651004 4.08803996 1 P 0 
L 0.34651004 4.08803996 0.36633996 4.08803996 1 P 0 
L 0.36633996 4.08803996 0.38358002 4.085 1 P 0 
L 0.38358002 4.085 0.45368996 4.0359 1 P 0 
L 0.45368996 4.0359 0.50401998 3.96403996 1 P 0 
L 0.50401998 3.96403996 0.52018996 3.87228996 1 P 0 
L 0.52018996 3.87228996 1.93761998 1.84801998 1 P 0 
L 1.93761998 1.84801998 2.01498996 1.79383996 1 P 0 
L 2.01498996 1.79383996 2.08996998 1.78061998 1 P 0 
L 2.08996998 1.78061998 2.09126998 1.78083996 1 P 0 
L 2.09126998 1.78083996 2.09126998 1.78085 1 P 0 
L 2.09126998 1.78085 2.2491 1.80868002 1 P 0 
L 2.2491 1.80868002 3.19826004 1.64133996 1 P 0 
L 3.19826004 1.64133996 4.34221998 1.84305 1 P 0 
L 4.34221998 1.84305 4.6687 1.78548996 1 P 0 
L 4.6687 1.78548996 4.80451004 1.80943002 1 P 0 
L 4.80451004 1.80943002 4.91825 1.78936998 1 P 0 
L 4.91825 1.78936998 5.07698002 1.81736998 1 P 0 
L 5.07698002 1.81736998 5.10875 1.83961998 1 P 0 
L 5.10875 1.83961998 5.15791998 1.9099 1 P 0 
L 5.15791998 1.9099 5.21348002 2.22483002 1 P 0 
L 5.21348002 2.22483002 5.35721004 2.43005 1 P 0 
L 5.35721004 2.43005 5.37048996 2.43936004 1 P 0 
L 5.37048996 2.43936004 5.38718002 2.4423 1 P 0 
L 5.38718002 2.4423 5.40438002 2.4423 1 P 0 
L 5.40438002 2.4423 5.42048002 2.4262 1 P 0 
P 5.42048002 1.91835 5 P 0 0;3=1,5=1
P 0.17323002 2.90945 7 P 0 0;3=2,5=0
L 5.42048002 1.91835 5.40523002 1.9031 1 P 0 
L 5.40523002 1.9031 5.36205 1.9031 1 P 0 
L 5.36205 1.9031 5.36068996 1.90173996 1 P 0 
L 5.36068996 1.90173996 5.34456998 1.89045 1 P 0 
L 5.34456998 1.89045 5.32968996 1.8692 1 P 0 
L 5.32968996 1.8692 5.3212 1.82098002 1 P 0 
L 5.3212 1.82098002 5.23413002 1.69666004 1 P 0 
L 5.23413002 1.69666004 5.20651004 1.53998002 1 P 0 
L 5.20651004 1.53998002 5.03686998 1.29771004 1 P 0 
L 5.03686998 1.29771004 4.94718996 1.23491004 1 P 0 
L 4.94718996 1.23491004 4.72338996 1.19545 1 P 0 
L 4.72338996 1.19545 4.0158 1.32021998 1 P 0 
L 4.0158 1.32021998 2.73706998 1.09475 1 P 0 
L 2.73706998 1.09475 2.10875 1.20553002 1 P 0 
L 2.10875 1.20553002 1.21013996 1.83473996 1 P 0 
L 1.21013996 1.83473996 0.52226998 2.81718996 1 P 0 
L 0.52226998 2.81718996 0.39426004 2.90681004 1 P 0 
L 0.39426004 2.90681004 0.3646 2.91203996 1 P 0 
L 0.3646 2.91203996 0.34668996 2.91203996 1 P 0 
L 0.34668996 2.91203996 0.33033996 2.90915 1 P 0 
L 0.33033996 2.90915 0.2849 2.87733996 1 P 0 
L 0.2849 2.87733996 0.26616004 2.87403996 1 P 0 
L 0.26616004 2.87403996 0.157 2.87403996 1 P 0 
L 0.157 2.87403996 0.13321004 2.89783002 1 P 0 
L 0.13321004 2.89783002 0.13321004 2.92425 1 P 0 
L 0.13321004 2.92425 0.137 2.92803996 1 P 0 
L 0.137 2.92803996 0.155 2.92803996 1 P 0 
L 0.155 2.92803996 0.17323002 2.90981004 1 P 0 
L 0.17323002 2.90981004 0.17323002 2.90945 1 P 0 
P 5.42048002 2.0547 5 P 0 0;3=1,5=1
P 0.17323002 3.22441004 7 P 0 0;3=2,5=0
L 5.42048002 2.0547 5.40428002 2.0385 1 P 0 
L 5.40428002 2.0385 5.36881998 2.0385 1 P 0 
L 5.36881998 2.0385 5.36871004 2.03838996 1 P 0 
L 5.36871004 2.03838996 5.35148996 2.03536004 1 P 0 
L 5.35148996 2.03536004 5.33983996 2.02721004 1 P 0 
L 5.33983996 2.02721004 5.282 1.9446 1 P 0 
L 5.282 1.9446 5.26161998 1.82893996 1 P 0 
L 5.26161998 1.82893996 5.18058002 1.71321004 1 P 0 
L 5.18058002 1.71321004 5.15008002 1.54028002 1 P 0 
L 5.15008002 1.54028002 5.00568996 1.3341 1 P 0 
L 5.00568996 1.3341 4.9305 1.28141998 1 P 0 
L 4.9305 1.28141998 4.77988002 1.25486998 1 P 0 
L 4.77988002 1.25486998 4.0151 1.38973002 1 P 0 
L 4.0151 1.38973002 2.73196998 1.16348002 1 P 0 
L 2.73196998 1.16348002 2.13103996 1.26946004 1 P 0 
L 2.13103996 1.26946004 1.30201998 1.84993996 1 P 0 
L 1.30201998 1.84993996 0.53473996 2.94571004 1 P 0 
L 0.53473996 2.94571004 0.51125 3.07893996 1 P 0 
L 0.51125 3.07893996 0.42933996 3.19591998 1 P 0 
L 0.42933996 3.19591998 0.39133996 3.22253002 1 P 0 
L 0.39133996 3.22253002 0.366 3.227 1 P 0 
L 0.366 3.227 0.34668002 3.227 1 P 0 
L 0.34668002 3.227 0.33033996 3.22411004 1 P 0 
L 0.33033996 3.22411004 0.2849 3.1923 1 P 0 
L 0.2849 3.1923 0.26616004 3.189 1 P 0 
L 0.26616004 3.189 0.157 3.189 1 P 0 
L 0.157 3.189 0.13321004 3.21278996 1 P 0 
L 0.13321004 3.21278996 0.13321004 3.23921004 1 P 0 
L 0.13321004 3.23921004 0.137 3.243 1 P 0 
L 0.137 3.243 0.155 3.243 1 P 0 
L 0.155 3.243 0.17323002 3.22476998 1 P 0 
L 0.17323002 3.22476998 0.17323002 3.22441004 1 P 0 
P 5.57531004 1.9469 5 P 0 0;3=1,5=1
P 0.09448996 2.79133996 7 P 0 0;3=2,5=0
L 5.57531004 1.9469 5.55901004 1.9632 1 P 0 
L 5.55901004 1.9632 5.525 1.9632 1 P 0 
L 5.525 1.9632 5.5078 1.95115 1 P 0 
L 5.5078 1.95115 5.49371004 1.93101998 1 P 0 
L 5.49371004 1.93101998 5.48156998 1.86223002 1 P 0 
L 5.48156998 1.86223002 5.47175 1.84821004 1 P 0 
L 5.47175 1.84821004 5.4477 1.83138002 1 P 0 
L 5.4477 1.83138002 5.36843002 1.8174 1 P 0 
L 5.36843002 1.8174 5.35388002 1.8072 1 P 0 
L 5.35388002 1.8072 5.26701998 1.68316998 1 P 0 
L 5.26701998 1.68316998 5.24101998 1.53568002 1 P 0 
L 5.24101998 1.53568002 5.05603996 1.2715 1 P 0 
L 5.05603996 1.2715 4.96276004 1.20618996 1 P 0 
L 4.96276004 1.20618996 4.68061998 1.15645 1 P 0 
L 4.68061998 1.15645 4.01561004 1.27371004 1 P 0 
L 4.01561004 1.27371004 2.7422 1.04916004 1 P 0 
L 2.7422 1.04916004 2.10108002 1.1622 1 P 0 
L 2.10108002 1.1622 1.15963002 1.82138996 1 P 0 
L 1.15963002 1.82138996 0.62908002 2.57911998 1 P 0 
L 0.62908002 2.57911998 0.39733002 2.74141998 1 P 0 
L 0.39733002 2.74141998 0.38136004 2.74423002 1 P 0 
L 0.38136004 2.74423002 0.38133996 2.74423996 1 P 0 
L 0.38133996 2.74423996 0.36533996 2.74706004 1 P 0 
L 0.36533996 2.74706004 0.34735 2.74706004 1 P 0 
L 0.34735 2.74706004 0.33328002 2.74456998 1 P 0 
L 0.33328002 2.74456998 0.28783996 2.71276004 1 P 0 
L 0.28783996 2.71276004 0.26681998 2.70906004 1 P 0 
L 0.26681998 2.70906004 0.15388996 2.70906004 1 P 0 
L 0.15388996 2.70906004 0.12571004 2.73723996 1 P 0 
L 0.12571004 2.73723996 0.12571004 2.76011998 1 P 0 
L 0.12571004 2.76011998 0.09448996 2.79133996 1 P 0 
P 5.42048002 2.0147 5 P 0 0;3=1,5=1
P 0.09448996 3.26378002 7 P 0 0;3=2,5=0
L 5.42048002 2.0147 5.40418002 2.031 1 P 0 
L 5.40418002 2.031 5.37 2.031 1 P 0 
L 5.37 2.031 5.35443002 2.02826004 1 P 0 
L 5.35443002 2.02826004 5.34523002 2.02181998 1 P 0 
L 5.34523002 2.02181998 5.2891 1.94166004 1 P 0 
L 5.2891 1.94166004 5.26871998 1.826 1 P 0 
L 5.26871998 1.826 5.18768002 1.71026998 1 P 0 
L 5.18768002 1.71026998 5.15718002 1.53733996 1 P 0 
L 5.15718002 1.53733996 5.01108002 1.32871004 1 P 0 
L 5.01108002 1.32871004 4.93343996 1.27431998 1 P 0 
L 4.93343996 1.27431998 4.77988002 1.24725 1 P 0 
L 4.77988002 1.24725 4.0151 1.38211004 1 P 0 
L 4.0151 1.38211004 2.73196998 1.15586004 1 P 0 
L 2.73196998 1.15586004 2.1281 1.26236004 1 P 0 
L 2.1281 1.26236004 1.29663002 1.84455 1 P 0 
L 1.29663002 1.84455 0.52763996 2.94276998 1 P 0 
L 0.52763996 2.94276998 0.50415 3.076 1 P 0 
L 0.50415 3.076 0.42395 3.19053002 1 P 0 
L 0.42395 3.19053002 0.38838996 3.21543002 1 P 0 
L 0.38838996 3.21543002 0.3884 3.21543002 1 P 0 
L 0.3884 3.21543002 0.36533996 3.2195 1 P 0 
L 0.36533996 3.2195 0.34735 3.2195 1 P 0 
L 0.34735 3.2195 0.33328002 3.21701004 1 P 0 
L 0.33328002 3.21701004 0.28783996 3.1852 1 P 0 
L 0.28783996 3.1852 0.26681998 3.1815 1 P 0 
L 0.26681998 3.1815 0.15388996 3.1815 1 P 0 
L 0.15388996 3.1815 0.12571004 3.20968002 1 P 0 
L 0.12571004 3.20968002 0.12571004 3.23256004 1 P 0 
L 0.12571004 3.23256004 0.09448996 3.26378002 1 P 0 
P 5.57531004 1.8508 5 P 0 0;3=1,5=1
P 0.09448996 2.00393996 7 P 0 0;3=2,5=0
L 0.09448996 2.00393996 0.11688996 2.01515 1 P 0 
L 0.11688996 2.01515 0.13323996 2.01515 1 P 0 
L 0.13323996 2.01515 0.14788996 2.0005 1 P 0 
L 0.14788996 2.0005 0.29111004 2.0005 1 P 0 
L 0.29111004 2.0005 0.33011004 2.0395 1 P 0 
L 0.33011004 2.0395 0.361 2.0395 1 P 0 
L 0.361 2.0395 0.36183002 2.03935 1 P 0 
L 0.36183002 2.03935 0.37791004 2.04218002 1 P 0 
L 0.37791004 2.04218002 0.40205 2.05906998 1 P 0 
L 0.40205 2.05906998 0.44458002 2.11981004 1 P 0 
L 0.44458002 2.11981004 0.50418002 2.16155 1 P 0 
L 0.50418002 2.16155 0.59148996 2.17693996 1 P 0 
L 0.59148996 2.17693996 0.68613002 2.16025 1 P 0 
L 0.68613002 2.16025 0.77058996 2.10111004 1 P 0 
L 0.77058996 2.10111004 1.0213 1.74308002 1 P 0 
L 1.0213 1.74308002 2.01833996 1.04495 1 P 0 
L 2.01833996 1.04495 2.74511004 0.91681004 1 P 0 
L 2.74511004 0.91681004 3.9877 1.13591004 1 P 0 
L 3.9877 1.13591004 4.57493996 1.03235 1 P 0 
L 4.57493996 1.03235 4.99815 1.10696004 1 P 0 
L 4.99815 1.10696004 5.48098996 1.44503002 1 P 0 
L 5.48098996 1.44503002 5.624 1.64926998 1 P 0 
L 5.624 1.64926998 5.64363002 1.76066998 1 P 0 
L 5.64363002 1.76066998 5.63353996 1.81778996 1 P 0 
L 5.63353996 1.81778996 5.62668002 1.8276 1 P 0 
L 5.62668002 1.8276 5.61668002 1.8346 1 P 0 
L 5.61668002 1.8346 5.59151004 1.8346 1 P 0 
L 5.59151004 1.8346 5.57531004 1.8508 1 P 0 
P 5.57531004 1.8108 5 P 0 0;3=1,5=1
P 0.17323002 2.04331004 7 P 0 0;3=2,5=0
L 0.17323002 2.04331004 0.15131004 2.04331004 1 P 0 
L 0.15131004 2.04331004 0.141 2.033 1 P 0 
L 0.141 2.033 0.141 2.018 1 P 0 
L 0.141 2.018 0.151 2.008 1 P 0 
L 0.151 2.008 0.288 2.008 1 P 0 
L 0.288 2.008 0.327 2.047 1 P 0 
L 0.327 2.047 0.362 2.047 1 P 0 
L 0.362 2.047 0.37496998 2.04928002 1 P 0 
L 0.37496998 2.04928002 0.39666004 2.06446004 1 P 0 
L 0.39666004 2.06446004 0.40281998 2.07328002 1 P 0 
L 0.40281998 2.07328002 0.40175 2.07923002 1 P 0 
L 0.40175 2.07923002 0.40813996 2.08833002 1 P 0 
L 0.40813996 2.08833002 0.4141 2.08938002 1 P 0 
L 0.4141 2.08938002 0.42048002 2.09848002 1 P 0 
L 0.42048002 2.09848002 0.41941004 2.10443002 1 P 0 
L 0.41941004 2.10443002 0.4258 2.11353002 1 P 0 
L 0.4258 2.11353002 0.43175 2.11458002 1 P 0 
L 0.43175 2.11458002 0.43918996 2.1252 1 P 0 
L 0.43918996 2.1252 0.50123996 2.16865 1 P 0 
L 0.50123996 2.16865 0.52216004 2.17235 1 P 0 
L 0.52216004 2.17235 0.52543996 2.17701998 1 P 0 
L 0.52543996 2.17701998 0.5364 2.17896004 1 P 0 
L 0.5364 2.17896004 0.54105 2.17568002 1 P 0 
L 0.54105 2.17568002 0.552 2.17761004 1 P 0 
L 0.552 2.17761004 0.55528002 2.18228002 1 P 0 
L 0.55528002 2.18228002 0.56623996 2.18421998 1 P 0 
L 0.56623996 2.18421998 0.57088996 2.18093002 1 P 0 
L 0.57088996 2.18093002 0.59148996 2.18456004 1 P 0 
L 0.59148996 2.18456004 0.68906998 2.16735 1 P 0 
L 0.68906998 2.16735 0.74368002 2.12911004 1 P 0 
L 0.74368002 2.12911004 0.75051998 2.13033002 1 P 0 
L 0.75051998 2.13033002 0.75963002 2.12396004 1 P 0 
L 0.75963002 2.12396004 0.76083002 2.11711004 1 P 0 
L 0.76083002 2.11711004 0.77598002 2.1065 1 P 0 
L 0.77598002 2.1065 1.02668996 1.74846998 1 P 0 
L 1.02668996 1.74846998 2.02128002 1.05205 1 P 0 
L 2.02128002 1.05205 2.74511004 0.92443002 1 P 0 
L 2.74511004 0.92443002 3.9877 1.14353002 1 P 0 
L 3.9877 1.14353002 3.989 1.14331004 1 P 0 
L 3.989 1.14331004 3.989 1.1433 1 P 0 
L 3.989 1.1433 4.57493996 1.03996998 1 P 0 
L 4.57493996 1.03996998 4.99521004 1.11406004 1 P 0 
L 4.99521004 1.11406004 5.4756 1.45041998 1 P 0 
L 5.4756 1.45041998 5.6169 1.65221004 1 P 0 
L 5.6169 1.65221004 5.63601004 1.76066998 1 P 0 
L 5.63601004 1.76066998 5.63121998 1.78776998 1 P 0 
L 5.63121998 1.78776998 5.63121004 1.78776998 1 P 0 
L 5.63121004 1.78776998 5.62643996 1.81485 1 P 0 
L 5.62643996 1.81485 5.6213 1.8222 1 P 0 
L 5.6213 1.8222 5.62128996 1.82221004 1 P 0 
L 5.62128996 1.82221004 5.61431004 1.8271 1 P 0 
L 5.61431004 1.8271 5.59161004 1.8271 1 P 0 
L 5.59161004 1.8271 5.57531004 1.8108 1 P 0 
P 5.42048002 2.1554 5 P 0 0;3=1,5=1
P 0.17323002 3.77558996 7 P 0 0;3=2,5=0
L 0.17323002 3.77558996 0.1562 3.75856004 1 P 0 
L 0.1562 3.75856004 0.13651998 3.75856004 1 P 0 
L 0.13651998 3.75856004 0.13 3.76508002 1 P 0 
L 0.13 3.76508002 0.13 3.78508002 1 P 0 
L 0.13 3.78508002 0.155 3.81008002 1 P 0 
L 0.155 3.81008002 0.27 3.81008002 1 P 0 
L 0.27 3.81008002 0.2851 3.80741998 1 P 0 
L 0.2851 3.80741998 0.32998002 3.77598996 1 P 0 
L 0.32998002 3.77598996 0.34651004 3.77308002 1 P 0 
L 0.34651004 3.77308002 0.36633996 3.77308002 1 P 0 
L 0.36633996 3.77308002 0.43951004 3.76018002 1 P 0 
L 0.43951004 3.76018002 0.6177 3.63541004 1 P 0 
L 0.6177 3.63541004 1.89528002 1.81081004 1 P 0 
L 1.89528002 1.81081004 1.98793996 1.74593996 1 P 0 
L 1.98793996 1.74593996 2.09656004 1.72678996 1 P 0 
L 2.09656004 1.72678996 2.24743996 1.75338996 1 P 0 
L 2.24743996 1.75338996 3.1876 1.58763002 1 P 0 
L 3.1876 1.58763002 4.35343996 1.79321004 1 P 0 
L 4.35343996 1.79321004 4.67243002 1.73696004 1 P 0 
L 4.67243002 1.73696004 4.80805 1.76086998 1 P 0 
L 4.80805 1.76086998 4.91358996 1.74226004 1 P 0 
L 4.91358996 1.74226004 5.09553002 1.77435 1 P 0 
L 5.09553002 1.77435 5.14066998 1.80596004 1 P 0 
L 5.14066998 1.80596004 5.20095 1.89205 1 P 0 
L 5.20095 1.89205 5.21711004 1.98375 1 P 0 
L 5.21711004 1.98375 5.33401004 2.15068996 1 P 0 
L 5.33401004 2.15068996 5.364 2.1717 1 P 0 
L 5.364 2.1717 5.40418002 2.1717 1 P 0 
L 5.40418002 2.1717 5.42048002 2.1554 1 P 0 
P 5.42048002 2.5654 5 P 0 0;3=1,5=1
P 0.17323002 4.563 7 P 0 0;3=2,5=0
L 5.42048002 2.5654 5.40458002 2.5813 1 P 0 
L 5.40458002 2.5813 5.37933996 2.5813 1 P 0 
L 5.37933996 2.5813 5.35568002 2.58546998 1 P 0 
L 5.35568002 2.58546998 5.33148002 2.6024 1 P 0 
L 5.33148002 2.6024 5.21606004 2.76721998 1 P 0 
L 5.21606004 2.76721998 5.18416004 2.94826998 1 P 0 
L 5.18416004 2.94826998 5.19443002 3.00663996 1 P 0 
L 5.19443002 3.00663996 5.17535 3.11485 1 P 0 
L 5.17535 3.11485 5.19415 3.22148996 1 P 0 
L 5.19415 3.22148996 5.17983002 3.30268996 1 P 0 
L 5.17983002 3.30268996 5.25425 3.72498002 1 P 0 
L 5.25425 3.72498002 5.2311 3.85626004 1 P 0 
L 5.2311 3.85626004 5.18693996 3.91931998 1 P 0 
L 5.18693996 3.91931998 5.10186998 3.9789 1 P 0 
L 5.10186998 3.9789 4.92303002 4.01043002 1 P 0 
L 4.92303002 4.01043002 4.83151998 3.9943 1 P 0 
L 4.83151998 3.9943 3.53265 4.22333002 1 P 0 
L 3.53265 4.22333002 2.25393996 3.99786998 1 P 0 
L 2.25393996 3.99786998 2.07516998 4.02938996 1 P 0 
L 2.07516998 4.02938996 1.55848996 4.39118002 1 P 0 
L 1.55848996 4.39118002 0.4905 4.5795 1 P 0 
L 0.4905 4.5795 0.38 4.56 1 P 0 
L 0.38 4.56 0.33 4.56 1 P 0 
L 0.33 4.56 0.295 4.595 1 P 0 
L 0.295 4.595 0.155 4.595 1 P 0 
L 0.155 4.595 0.13321004 4.57321004 1 P 0 
L 0.13321004 4.57321004 0.13321004 4.54978996 1 P 0 
L 0.13321004 4.54978996 0.141 4.542 1 P 0 
L 0.141 4.542 0.15223002 4.542 1 P 0 
L 0.15223002 4.542 0.17323002 4.563 1 P 0 
P 5.42048002 2.1954 5 P 0 0;3=1,5=1
P 0.09448996 3.73621998 7 P 0 0;3=2,5=0
L 0.09448996 3.73621998 0.1225 3.76423002 1 P 0 
L 0.1225 3.76423002 0.1225 3.78818996 1 P 0 
L 0.1225 3.78818996 0.15188996 3.81758002 1 P 0 
L 0.15188996 3.81758002 0.27066004 3.81758002 1 P 0 
L 0.27066004 3.81758002 0.28803996 3.81451998 1 P 0 
L 0.28803996 3.81451998 0.33291998 3.78308996 1 P 0 
L 0.33291998 3.78308996 0.34716998 3.78058002 1 P 0 
L 0.34716998 3.78058002 0.367 3.78058002 1 P 0 
L 0.367 3.78058002 0.44245 3.76728002 1 P 0 
L 0.44245 3.76728002 0.62308996 3.6408 1 P 0 
L 0.62308996 3.6408 1.90066998 1.8162 1 P 0 
L 1.90066998 1.8162 1.99088002 1.75303996 1 P 0 
L 1.99088002 1.75303996 2.09656004 1.73441004 1 P 0 
L 2.09656004 1.73441004 2.24743996 1.76101004 1 P 0 
L 2.24743996 1.76101004 3.1876 1.59525 1 P 0 
L 3.1876 1.59525 4.35343996 1.80083002 1 P 0 
L 4.35343996 1.80083002 4.67243002 1.74458002 1 P 0 
L 4.67243002 1.74458002 4.80805 1.76848996 1 P 0 
L 4.80805 1.76848996 4.80935 1.76826998 1 P 0 
L 4.80935 1.76826998 4.80935 1.76826004 1 P 0 
L 4.80935 1.76826004 4.91358996 1.74988002 1 P 0 
L 4.91358996 1.74988002 5.09258996 1.78145 1 P 0 
L 5.09258996 1.78145 5.13528002 1.81135 1 P 0 
L 5.13528002 1.81135 5.19385 1.89498996 1 P 0 
L 5.19385 1.89498996 5.21001004 1.98668996 1 P 0 
L 5.21001004 1.98668996 5.32861998 2.15608002 1 P 0 
L 5.32861998 2.15608002 5.36163002 2.1792 1 P 0 
L 5.36163002 2.1792 5.40428002 2.1792 1 P 0 
L 5.40428002 2.1792 5.42048002 2.1954 1 P 0 
P 0.09448996 3.57873996 7 P 0 0;3=2,5=0
P 5.42048002 2.3308 5 P 0 0;3=1,5=1
L 0.09448996 3.57873996 0.09885 3.5831 1 P 0 
L 0.09885 3.5831 0.13628996 3.5831 1 P 0 
L 0.13628996 3.5831 0.14488996 3.5745 1 P 0 
L 0.14488996 3.5745 0.27195 3.5745 1 P 0 
L 0.27195 3.5745 0.28946998 3.57138996 1 P 0 
L 0.28946998 3.57138996 0.33673002 3.5383 1 P 0 
L 0.33673002 3.5383 0.34976004 3.536 1 P 0 
L 0.34976004 3.536 0.37735 3.536 1 P 0 
L 0.37735 3.536 0.39955 3.53208996 1 P 0 
L 0.39955 3.53208996 0.39956004 3.53208996 1 P 0 
L 0.39956004 3.53208996 0.89176004 3.18771004 1 P 0 
L 0.89176004 3.18771004 1.86698996 1.79496004 1 P 0 
L 1.86698996 1.79496004 1.97288002 1.72081004 1 P 0 
L 1.97288002 1.72081004 2.09961998 1.69846998 1 P 0 
L 2.09961998 1.69846998 2.25253996 1.72543996 1 P 0 
L 2.25253996 1.72543996 3.18816998 1.56043002 1 P 0 
L 3.18816998 1.56043002 4.35748996 1.76661004 1 P 0 
L 4.35748996 1.76661004 4.67378996 1.71085 1 P 0 
L 4.67378996 1.71085 4.80783002 1.73448002 1 P 0 
L 4.80783002 1.73448002 4.90581998 1.71718996 1 P 0 
L 4.90581998 1.71718996 5.1047 1.75228002 1 P 0 
L 5.1047 1.75228002 5.15841004 1.78988996 1 P 0 
L 5.15841004 1.78988996 5.22501004 1.885 1 P 0 
L 5.22501004 1.885 5.23898996 1.9644 1 P 0 
L 5.23898996 1.9644 5.32823996 2.09175 1 P 0 
L 5.32823996 2.09175 5.34916998 2.10641998 1 P 0 
L 5.34916998 2.10641998 5.43338996 2.12126998 1 P 0 
L 5.43338996 2.12126998 5.45595 2.13706004 1 P 0 
L 5.45595 2.13706004 5.47018002 2.15738996 1 P 0 
L 5.47018002 2.15738996 5.48436998 2.23771998 1 P 0 
L 5.48436998 2.23771998 5.47541998 2.28851004 1 P 0 
L 5.47541998 2.28851004 5.46423996 2.30448996 1 P 0 
L 5.46423996 2.30448996 5.44993002 2.3145 1 P 0 
L 5.44993002 2.3145 5.43678002 2.3145 1 P 0 
L 5.43678002 2.3145 5.42048002 2.3308 1 P 0 
P 0.17323002 3.61811004 7 P 0 0;3=2,5=0
P 5.42048002 2.2908 5 P 0 0;3=1,5=1
L 0.17323002 3.61811004 0.16011004 3.61811004 1 P 0 
L 0.16011004 3.61811004 0.1422 3.6002 1 P 0 
L 0.1422 3.6002 0.1422 3.5878 1 P 0 
L 0.1422 3.5878 0.148 3.582 1 P 0 
L 0.148 3.582 0.27261004 3.582 1 P 0 
L 0.27261004 3.582 0.29241004 3.57848996 1 P 0 
L 0.29241004 3.57848996 0.33966998 3.5454 1 P 0 
L 0.33966998 3.5454 0.35041998 3.5435 1 P 0 
L 0.35041998 3.5435 0.37801004 3.5435 1 P 0 
L 0.37801004 3.5435 0.4025 3.53918996 1 P 0 
L 0.4025 3.53918996 0.89715 3.1931 1 P 0 
L 0.89715 3.1931 0.90571004 3.18088002 1 P 0 
L 0.90571004 3.18088002 0.91191004 3.1798 1 P 0 
L 0.91191004 3.1798 0.9183 3.17068996 1 P 0 
L 0.9183 3.17068996 0.91718002 3.16448996 1 P 0 
L 0.91718002 3.16448996 0.92356004 3.15538002 1 P 0 
L 0.92356004 3.15538002 0.92976998 3.1543 1 P 0 
L 0.92976998 3.1543 0.93616004 3.14518996 1 P 0 
L 0.93616004 3.14518996 0.93503996 3.13898996 1 P 0 
L 0.93503996 3.13898996 0.94141998 3.12988002 1 P 0 
L 0.94141998 3.12988002 0.94763002 3.1288 1 P 0 
L 0.94763002 3.1288 0.95401998 3.11968996 1 P 0 
L 0.95401998 3.11968996 0.9529 3.11348996 1 P 0 
L 0.9529 3.11348996 1.87238002 1.80035 1 P 0 
L 1.87238002 1.80035 1.97581998 1.72791004 1 P 0 
L 1.97581998 1.72791004 2.09961998 1.70608996 1 P 0 
L 2.09961998 1.70608996 2.25253996 1.73306004 1 P 0 
L 2.25253996 1.73306004 3.18816998 1.56805 1 P 0 
L 3.18816998 1.56805 4.35748996 1.77423002 1 P 0 
L 4.35748996 1.77423002 4.67378996 1.71846998 1 P 0 
L 4.67378996 1.71846998 4.80783002 1.7421 1 P 0 
L 4.80783002 1.7421 4.90581998 1.72481004 1 P 0 
L 4.90581998 1.72481004 5.10176004 1.75938002 1 P 0 
L 5.10176004 1.75938002 5.15301998 1.79528002 1 P 0 
L 5.15301998 1.79528002 5.21791004 1.88793996 1 P 0 
L 5.21791004 1.88793996 5.23188996 1.96733996 1 P 0 
L 5.23188996 1.96733996 5.32285 2.09713996 1 P 0 
L 5.32285 2.09713996 5.34623002 2.11351998 1 P 0 
L 5.34623002 2.11351998 5.43045 2.12836998 1 P 0 
L 5.43045 2.12836998 5.45056004 2.14245 1 P 0 
L 5.45056004 2.14245 5.46308002 2.16033002 1 P 0 
L 5.46308002 2.16033002 5.47061998 2.20301004 1 P 0 
L 5.47061998 2.20301004 5.46626998 2.20918002 1 P 0 
L 5.46626998 2.20918002 5.46821004 2.22013002 1 P 0 
L 5.46821004 2.22013002 5.4744 2.22446004 1 P 0 
L 5.4744 2.22446004 5.47675 2.23771998 1 P 0 
L 5.47675 2.23771998 5.47466998 2.24946004 1 P 0 
L 5.47466998 2.24946004 5.46916998 2.2533 1 P 0 
L 5.46916998 2.2533 5.46723996 2.26423996 1 P 0 
L 5.46723996 2.26423996 5.4711 2.26971998 1 P 0 
L 5.4711 2.26971998 5.46831998 2.28556998 1 P 0 
L 5.46831998 2.28556998 5.45885 2.2991 1 P 0 
L 5.45885 2.2991 5.44756004 2.307 1 P 0 
L 5.44756004 2.307 5.43668002 2.307 1 P 0 
L 5.43668002 2.307 5.42048002 2.2908 1 P 0 
P 12.63778996 4.12991998 7 P 0 0;3=2,5=0
P 11.53316004 2.372 5 P 0 0;3=1,5=1
L 12.63778996 4.12991998 12.60796998 4.1001 1 P 0 
L 12.60796998 4.1001 12.60796998 4.06818996 1 P 0 
L 12.60796998 4.06818996 12.5882 4.04841998 1 P 0 
L 12.5882 4.04841998 12.5516 4.04841998 1 P 0 
L 12.5516 4.04841998 12.50898996 4.04091004 1 P 0 
L 12.50898996 4.04091004 12.45143996 4.00061004 1 P 0 
L 12.45143996 4.00061004 12.40003996 3.92721004 1 P 0 
L 12.40003996 3.92721004 12.2822 3.25903002 1 P 0 
L 12.2822 3.25903002 11.93766998 2.767 1 P 0 
L 11.93766998 2.767 11.89498996 2.52495 1 P 0 
L 11.89498996 2.52495 11.84078002 2.44751004 1 P 0 
L 11.84078002 2.44751004 11.78118996 2.40578996 1 P 0 
L 11.78118996 2.40578996 11.70206004 2.39183996 1 P 0 
L 11.70206004 2.39183996 11.65698996 2.39978002 1 P 0 
L 11.65698996 2.39978002 11.59158002 2.38825 1 P 0 
L 11.59158002 2.38825 11.54941004 2.38825 1 P 0 
L 11.54941004 2.38825 11.53316004 2.372 1 P 0 
P 11.53316004 1.892 5 P 0 0;3=1,5=1
P 12.55905 3.30315 7 P 0 0;3=2,5=0
L 12.55905 3.30315 12.57933996 3.28286004 1 P 0 
L 12.57933996 3.28286004 12.59301004 3.28286004 1 P 0 
L 12.59301004 3.28286004 12.59826998 3.28811998 1 P 0 
L 12.59826998 3.28811998 12.59826998 3.31948002 1 P 0 
L 12.59826998 3.31948002 12.57868996 3.33906004 1 P 0 
L 12.57868996 3.33906004 12.53985 3.33906004 1 P 0 
L 12.53985 3.33906004 12.5257 3.33656004 1 P 0 
L 12.5257 3.33656004 12.51343002 3.32796998 1 P 0 
L 12.51343002 3.32796998 12.36258002 3.11253002 1 P 0 
L 12.36258002 3.11253002 12.36258996 3.11253002 1 P 0 
L 12.36258996 3.11253002 12.36256004 3.11248996 1 P 0 
L 12.36256004 3.11248996 12.35103002 3.09605 1 P 0 
L 12.35103002 3.09605 12.23706004 2.44966004 1 P 0 
L 12.23706004 2.44966004 12.11426004 2.27428996 1 P 0 
L 12.11426004 2.27428996 11.84858002 2.08826004 1 P 0 
L 11.84858002 2.08826004 11.71268996 2.06428996 1 P 0 
L 11.71268996 2.06428996 11.68013996 2.07001998 1 P 0 
L 11.68013996 2.07001998 11.61525 2.05858996 1 P 0 
L 11.61525 2.05858996 11.59018996 2.04103996 1 P 0 
L 11.59018996 2.04103996 11.58066004 2.02743996 1 P 0 
L 11.58066004 2.02743996 11.57375 1.98825 1 P 0 
L 11.57375 1.98825 11.58101004 1.94708996 1 P 0 
L 11.58101004 1.94708996 11.57658996 1.922 1 P 0 
L 11.57658996 1.922 11.57098002 1.91398002 1 P 0 
L 11.57098002 1.91398002 11.5659 1.91041998 1 P 0 
L 11.5659 1.91041998 11.55371004 1.90825 1 P 0 
L 11.55371004 1.90825 11.54941004 1.90825 1 P 0 
L 11.54941004 1.90825 11.53316004 1.892 1 P 0 
P 11.03998996 4.8431 6 P 0 0;3=3,5=1
P 11.08498996 4.8431 6 P 0 0;3=3,5=1
P 11.13498996 4.8431 6 P 0 0;3=3,5=1
P 11.17998996 4.8431 6 P 0 0;3=3,5=1
P 11.17998996 4.8031 6 P 0 0;3=3,5=1
P 11.17998996 4.7581 6 P 0 0;3=3,5=1
P 11.17998996 4.7131 6 P 0 0;3=3,5=1
P 11.17998996 4.6731 6 P 0 0;3=3,5=1
P 11.03998996 4.6731 6 P 0 0;3=3,5=1
P 11.08498996 4.6731 6 P 0 0;3=3,5=1
P 11.13498996 4.6731 6 P 0 0;3=3,5=1
P 11.03998996 4.7131 6 P 0 0;3=3,5=1
P 11.03998996 4.8031 6 P 0 0;3=3,5=1
P 11.03998996 4.7581 6 P 0 0;3=3,5=1
P 10.81998996 4.6631 6 P 0 0;3=3,5=1
P 10.85998996 4.6631 6 P 0 0;3=3,5=1
P 10.65998996 4.6631 6 P 0 0;3=3,5=1
P 10.69998996 4.6631 6 P 0 0;3=3,5=1
P 10.81998996 4.7031 6 P 0 0;3=3,5=1
P 10.81998996 4.8381 6 P 0 0;3=3,5=1
P 10.81998996 4.7931 6 P 0 0;3=3,5=1
P 10.81998996 4.7481 6 P 0 0;3=3,5=1
P 10.85998996 4.7031 6 P 0 0;3=3,5=1
P 10.85998996 4.8381 6 P 0 0;3=3,5=1
P 10.85998996 4.7931 6 P 0 0;3=3,5=1
P 10.85998996 4.7481 6 P 0 0;3=3,5=1
P 10.65998996 4.7031 6 P 0 0;3=3,5=1
P 10.65998996 4.8381 6 P 0 0;3=3,5=1
P 10.65998996 4.7931 6 P 0 0;3=3,5=1
P 10.65998996 4.7481 6 P 0 0;3=3,5=1
P 10.69998996 4.7031 6 P 0 0;3=3,5=1
P 10.69998996 4.8381 6 P 0 0;3=3,5=1
P 10.69998996 4.7931 6 P 0 0;3=3,5=1
P 10.69998996 4.7481 6 P 0 0;3=3,5=1
P 10.77998996 4.6431 6 P 0 0;3=3,5=1
P 10.73498996 4.6431 6 P 0 0;3=3,5=1
P 10.73998996 4.8381 6 P 0 0;3=3,5=1
P 10.77998996 4.8381 6 P 0 0;3=3,5=1
P 10.30998996 4.6631 6 P 0 0;3=3,5=1
P 10.26998996 4.6631 6 P 0 0;3=3,5=1
P 10.34498996 4.6431 6 P 0 0;3=3,5=1
P 10.38998996 4.6431 6 P 0 0;3=3,5=1
P 10.42998996 4.6631 6 P 0 0;3=3,5=1
P 10.46998996 4.6631 6 P 0 0;3=3,5=1
P 10.30998996 4.7481 6 P 0 0;3=3,5=1
P 10.30998996 4.7931 6 P 0 0;3=3,5=1
P 10.30998996 4.7031 6 P 0 0;3=3,5=1
P 10.26998996 4.7481 6 P 0 0;3=3,5=1
P 10.26998996 4.7931 6 P 0 0;3=3,5=1
P 10.26998996 4.7031 6 P 0 0;3=3,5=1
P 10.26998996 4.8381 6 P 0 0;3=3,5=1
P 10.30998996 4.8381 6 P 0 0;3=3,5=1
P 10.38998996 4.8381 6 P 0 0;3=3,5=1
P 10.34998996 4.8381 6 P 0 0;3=3,5=1
P 10.46998996 4.8381 6 P 0 0;3=3,5=1
P 10.42998996 4.8381 6 P 0 0;3=3,5=1
P 10.42998996 4.7031 6 P 0 0;3=3,5=1
P 10.42998996 4.7931 6 P 0 0;3=3,5=1
P 10.42998996 4.7481 6 P 0 0;3=3,5=1
P 10.46998996 4.7031 6 P 0 0;3=3,5=1
P 10.46998996 4.7931 6 P 0 0;3=3,5=1
P 10.46998996 4.7481 6 P 0 0;3=3,5=1
P 10.58661004 3.16615 5 P 0 0;3=1,5=1
P 10.63661004 3.01615 5 P 0 0;3=1,5=1
P 10.58661004 3.11615 5 P 0 0;3=1,5=1
P 10.58661004 3.01615 5 P 0 0;3=1,5=1
P 10.63661004 3.11615 5 P 0 0;3=1,5=1
P 10.63661004 2.96615 5 P 0 0;3=1,5=1
P 10.58661004 2.96615 5 P 0 0;3=1,5=1
P 10.58661004 3.41615 5 P 0 0;3=1,5=1
P 10.63661004 3.16615 5 P 0 0;3=1,5=1
P 10.63661004 3.26615 5 P 0 0;3=1,5=1
P 10.58661004 3.31615 5 P 0 0;3=1,5=1
P 10.58661004 3.26615 5 P 0 0;3=1,5=1
P 10.63661004 3.31615 5 P 0 0;3=1,5=1
P 10.63661004 3.56615 5 P 0 0;3=1,5=1
P 10.63661004 3.61615 5 P 0 0;3=1,5=1
P 10.58661004 3.56615 5 P 0 0;3=1,5=1
P 10.58661004 3.61615 5 P 0 0;3=1,5=1
P 10.63661004 3.46615 5 P 0 0;3=1,5=1
P 10.63661004 3.41615 5 P 0 0;3=1,5=1
P 10.58661004 3.46615 5 P 0 0;3=1,5=1
P 10.63661004 3.86615 5 P 0 0;3=1,5=1
P 10.63661004 3.76615 5 P 0 0;3=1,5=1
P 10.58661004 3.86615 5 P 0 0;3=1,5=1
P 10.58661004 3.76615 5 P 0 0;3=1,5=1
P 10.63661004 3.71615 5 P 0 0;3=1,5=1
P 10.58661004 3.71615 5 P 0 0;3=1,5=1
P 10.88661004 2.96615 5 P 0 0;3=1,5=1
P 10.83661004 2.96615 5 P 0 0;3=1,5=1
P 10.88661004 3.01615 5 P 0 0;3=1,5=1
P 10.83661004 3.01615 5 P 0 0;3=1,5=1
P 10.88661004 3.11615 5 P 0 0;3=1,5=1
P 10.83661004 3.11615 5 P 0 0;3=1,5=1
P 10.83661004 3.16615 5 P 0 0;3=1,5=1
P 10.78661004 3.16615 5 P 0 0;3=1,5=1
P 10.68661004 3.16615 5 P 0 0;3=1,5=1
P 10.73661004 3.16615 5 P 0 0;3=1,5=1
P 10.78661004 3.01615 5 P 0 0;3=1,5=1
P 10.78661004 3.11615 5 P 0 0;3=1,5=1
P 10.73661004 3.01615 5 P 0 0;3=1,5=1
P 10.73661004 3.11615 5 P 0 0;3=1,5=1
P 10.68661004 3.01615 5 P 0 0;3=1,5=1
P 10.68661004 3.11615 5 P 0 0;3=1,5=1
P 10.78661004 2.96615 5 P 0 0;3=1,5=1
P 10.73661004 2.96615 5 P 0 0;3=1,5=1
P 10.68661004 2.96615 5 P 0 0;3=1,5=1
P 10.88661004 3.16615 5 P 0 0;3=1,5=1
P 10.88661004 3.26615 5 P 0 0;3=1,5=1
P 10.83661004 3.26615 5 P 0 0;3=1,5=1
P 10.83661004 3.31615 5 P 0 0;3=1,5=1
P 10.88661004 3.31615 5 P 0 0;3=1,5=1
P 10.83661004 3.41615 5 P 0 0;3=1,5=1
P 10.78661004 3.41615 5 P 0 0;3=1,5=1
P 10.68661004 3.41615 5 P 0 0;3=1,5=1
P 10.73661004 3.41615 5 P 0 0;3=1,5=1
P 10.78661004 3.31615 5 P 0 0;3=1,5=1
P 10.78661004 3.26615 5 P 0 0;3=1,5=1
P 10.68661004 3.31615 5 P 0 0;3=1,5=1
P 10.68661004 3.26615 5 P 0 0;3=1,5=1
P 10.73661004 3.26615 5 P 0 0;3=1,5=1
P 10.73661004 3.31615 5 P 0 0;3=1,5=1
P 10.88661004 3.41615 5 P 0 0;3=1,5=1
P 10.83661004 3.46615 5 P 0 0;3=1,5=1
P 10.88661004 3.46615 5 P 0 0;3=1,5=1
P 10.83661004 3.56615 5 P 0 0;3=1,5=1
P 10.88661004 3.56615 5 P 0 0;3=1,5=1
P 10.83661004 3.61615 5 P 0 0;3=1,5=1
P 10.88661004 3.61615 5 P 0 0;3=1,5=1
P 10.78661004 3.56615 5 P 0 0;3=1,5=1
P 10.78661004 3.61615 5 P 0 0;3=1,5=1
P 10.68661004 3.61615 5 P 0 0;3=1,5=1
P 10.68661004 3.56615 5 P 0 0;3=1,5=1
P 10.73661004 3.61615 5 P 0 0;3=1,5=1
P 10.73661004 3.56615 5 P 0 0;3=1,5=1
P 10.78661004 3.46615 5 P 0 0;3=1,5=1
P 10.73661004 3.46615 5 P 0 0;3=1,5=1
P 10.68661004 3.46615 5 P 0 0;3=1,5=1
P 10.83661004 3.71615 5 P 0 0;3=1,5=1
P 10.88661004 3.71615 5 P 0 0;3=1,5=1
P 10.83661004 3.76615 5 P 0 0;3=1,5=1
P 10.88661004 3.76615 5 P 0 0;3=1,5=1
P 10.83661004 3.86615 5 P 0 0;3=1,5=1
P 10.88661004 3.86615 5 P 0 0;3=1,5=1
P 10.78661004 3.86615 5 P 0 0;3=1,5=1
P 10.78661004 3.76615 5 P 0 0;3=1,5=1
P 10.68661004 3.86615 5 P 0 0;3=1,5=1
P 10.68661004 3.76615 5 P 0 0;3=1,5=1
P 10.73661004 3.86615 5 P 0 0;3=1,5=1
P 10.73661004 3.76615 5 P 0 0;3=1,5=1
P 10.78661004 3.71615 5 P 0 0;3=1,5=1
P 10.68661004 3.71615 5 P 0 0;3=1,5=1
P 10.73661004 3.71615 5 P 0 0;3=1,5=1
P 11.03661004 2.96615 5 P 0 0;3=1,5=1
P 10.93661004 2.96615 5 P 0 0;3=1,5=1
P 10.98661004 2.96615 5 P 0 0;3=1,5=1
P 11.03661004 3.01615 5 P 0 0;3=1,5=1
P 10.93661004 3.01615 5 P 0 0;3=1,5=1
P 10.98661004 3.01615 5 P 0 0;3=1,5=1
P 11.03661004 3.11615 5 P 0 0;3=1,5=1
P 10.93661004 3.11615 5 P 0 0;3=1,5=1
P 10.98661004 3.11615 5 P 0 0;3=1,5=1
P 11.03661004 3.16615 5 P 0 0;3=1,5=1
P 10.93661004 3.16615 5 P 0 0;3=1,5=1
P 10.98661004 3.16615 5 P 0 0;3=1,5=1
P 11.03661004 3.26615 5 P 0 0;3=1,5=1
P 10.93661004 3.26615 5 P 0 0;3=1,5=1
P 10.98661004 3.26615 5 P 0 0;3=1,5=1
P 10.98661004 3.31615 5 P 0 0;3=1,5=1
P 10.93661004 3.31615 5 P 0 0;3=1,5=1
P 11.03661004 3.31615 5 P 0 0;3=1,5=1
P 10.98661004 3.41615 5 P 0 0;3=1,5=1
P 10.93661004 3.41615 5 P 0 0;3=1,5=1
P 11.03661004 3.41615 5 P 0 0;3=1,5=1
P 10.98661004 3.46615 5 P 0 0;3=1,5=1
P 10.93661004 3.46615 5 P 0 0;3=1,5=1
P 11.03661004 3.46615 5 P 0 0;3=1,5=1
P 10.98661004 3.56615 5 P 0 0;3=1,5=1
P 10.93661004 3.56615 5 P 0 0;3=1,5=1
P 11.03661004 3.56615 5 P 0 0;3=1,5=1
P 10.98661004 3.61615 5 P 0 0;3=1,5=1
P 10.93661004 3.61615 5 P 0 0;3=1,5=1
P 11.03661004 3.61615 5 P 0 0;3=1,5=1
P 10.98661004 3.71615 5 P 0 0;3=1,5=1
P 10.93661004 3.71615 5 P 0 0;3=1,5=1
P 11.03661004 3.71615 5 P 0 0;3=1,5=1
P 10.98661004 3.76615 5 P 0 0;3=1,5=1
P 10.93661004 3.76615 5 P 0 0;3=1,5=1
P 11.03661004 3.76615 5 P 0 0;3=1,5=1
P 10.98661004 3.86615 5 P 0 0;3=1,5=1
P 10.93661004 3.86615 5 P 0 0;3=1,5=1
P 11.03661004 3.86615 5 P 0 0;3=1,5=1
S P 0
OB 11.173 2.943 I
OS 10.587 2.943
OS 10.25998996063 3.27001003937
OS 10.25998996063 4.84498996063
OS 10.27 4.855
OS 11.17808996063 4.855
OS 11.2 4.83308996063
OS 11.2 2.97
OS 11.173 2.943
OE
OB 11.044130019685 4.22441003937 H
OC 11.044130019685 4.22441003937 10.836619980315 4.22441003937 N
OE
OB 10.602630019685 3.06615 H
OC 10.602630019685 3.06615 10.58661003937 3.06615 N
OE
OB 10.602630019685 3.21615 H
OC 10.602630019685 3.21615 10.58661003937 3.21615 N
OE
OB 10.602630019685 3.36615 H
OC 10.602630019685 3.36615 10.58661003937 3.36615 N
OE
OB 10.602630019685 3.51615 H
OC 10.602630019685 3.51615 10.58661003937 3.51615 N
OE
OB 10.602630019685 3.81615 H
OC 10.602630019685 3.81615 10.58661003937 3.81615 N
OE
OB 10.602630019685 3.66615 H
OC 10.602630019685 3.66615 10.58661003937 3.66615 N
OE
OB 10.702630019685 3.06615 H
OC 10.702630019685 3.06615 10.68661003937 3.06615 N
OE
OB 10.752630019685 3.06615 H
OC 10.752630019685 3.06615 10.73661003937 3.06615 N
OE
OB 10.802630019685 3.06615 H
OC 10.802630019685 3.06615 10.78661003937 3.06615 N
OE
OB 10.852630019685 3.06615 H
OC 10.852630019685 3.06615 10.83661003937 3.06615 N
OE
OB 10.652630019685 3.06615 H
OC 10.652630019685 3.06615 10.63661003937 3.06615 N
OE
OB 10.702630019685 3.21615 H
OC 10.702630019685 3.21615 10.68661003937 3.21615 N
OE
OB 10.702630019685 3.36615 H
OC 10.702630019685 3.36615 10.68661003937 3.36615 N
OE
OB 10.752630019685 3.21615 H
OC 10.752630019685 3.21615 10.73661003937 3.21615 N
OE
OB 10.802630019685 3.21615 H
OC 10.802630019685 3.21615 10.78661003937 3.21615 N
OE
OB 10.752630019685 3.36615 H
OC 10.752630019685 3.36615 10.73661003937 3.36615 N
OE
OB 10.802630019685 3.36615 H
OC 10.802630019685 3.36615 10.78661003937 3.36615 N
OE
OB 10.852630019685 3.36615 H
OC 10.852630019685 3.36615 10.83661003937 3.36615 N
OE
OB 10.852630019685 3.21615 H
OC 10.852630019685 3.21615 10.83661003937 3.21615 N
OE
OB 10.652630019685 3.21615 H
OC 10.652630019685 3.21615 10.63661003937 3.21615 N
OE
OB 10.652630019685 3.36615 H
OC 10.652630019685 3.36615 10.63661003937 3.36615 N
OE
OB 10.702630019685 3.51615 H
OC 10.702630019685 3.51615 10.68661003937 3.51615 N
OE
OB 10.752630019685 3.51615 H
OC 10.752630019685 3.51615 10.73661003937 3.51615 N
OE
OB 10.802630019685 3.51615 H
OC 10.802630019685 3.51615 10.78661003937 3.51615 N
OE
OB 10.852630019685 3.51615 H
OC 10.852630019685 3.51615 10.83661003937 3.51615 N
OE
OB 10.652630019685 3.51615 H
OC 10.652630019685 3.51615 10.63661003937 3.51615 N
OE
OB 10.702630019685 3.81615 H
OC 10.702630019685 3.81615 10.68661003937 3.81615 N
OE
OB 10.752630019685 3.81615 H
OC 10.752630019685 3.81615 10.73661003937 3.81615 N
OE
OB 10.802630019685 3.81615 H
OC 10.802630019685 3.81615 10.78661003937 3.81615 N
OE
OB 10.852630019685 3.81615 H
OC 10.852630019685 3.81615 10.83661003937 3.81615 N
OE
OB 10.702630019685 3.66615 H
OC 10.702630019685 3.66615 10.68661003937 3.66615 N
OE
OB 10.752630019685 3.66615 H
OC 10.752630019685 3.66615 10.73661003937 3.66615 N
OE
OB 10.802630019685 3.66615 H
OC 10.802630019685 3.66615 10.78661003937 3.66615 N
OE
OB 10.852630019685 3.66615 H
OC 10.852630019685 3.66615 10.83661003937 3.66615 N
OE
OB 10.652630019685 3.66615 H
OC 10.652630019685 3.66615 10.63661003937 3.66615 N
OE
OB 10.652630019685 3.81615 H
OC 10.652630019685 3.81615 10.63661003937 3.81615 N
OE
OB 11.002630019685 3.06615 H
OC 11.002630019685 3.06615 10.98661003937 3.06615 N
OE
OB 10.952630019685 3.06615 H
OC 10.952630019685 3.06615 10.93661003937 3.06615 N
OE
OB 11.052630019685 3.06615 H
OC 11.052630019685 3.06615 11.03661003937 3.06615 N
OE
OB 10.902630019685 3.06615 H
OC 10.902630019685 3.06615 10.88661003937 3.06615 N
OE
OB 11.052630019685 3.36615 H
OC 11.052630019685 3.36615 11.03661003937 3.36615 N
OE
OB 10.952630019685 3.36615 H
OC 10.952630019685 3.36615 10.93661003937 3.36615 N
OE
OB 11.002630019685 3.36615 H
OC 11.002630019685 3.36615 10.98661003937 3.36615 N
OE
OB 11.002630019685 3.21615 H
OC 11.002630019685 3.21615 10.98661003937 3.21615 N
OE
OB 10.952630019685 3.21615 H
OC 10.952630019685 3.21615 10.93661003937 3.21615 N
OE
OB 11.052630019685 3.21615 H
OC 11.052630019685 3.21615 11.03661003937 3.21615 N
OE
OB 10.902630019685 3.36615 H
OC 10.902630019685 3.36615 10.88661003937 3.36615 N
OE
OB 10.902630019685 3.21615 H
OC 10.902630019685 3.21615 10.88661003937 3.21615 N
OE
OB 11.052630019685 3.51615 H
OC 11.052630019685 3.51615 11.03661003937 3.51615 N
OE
OB 10.952630019685 3.51615 H
OC 10.952630019685 3.51615 10.93661003937 3.51615 N
OE
OB 11.002630019685 3.51615 H
OC 11.002630019685 3.51615 10.98661003937 3.51615 N
OE
OB 10.902630019685 3.51615 H
OC 10.902630019685 3.51615 10.88661003937 3.51615 N
OE
OB 10.952630019685 3.81615 H
OC 10.952630019685 3.81615 10.93661003937 3.81615 N
OE
OB 11.002630019685 3.81615 H
OC 11.002630019685 3.81615 10.98661003937 3.81615 N
OE
OB 11.052630019685 3.66615 H
OC 11.052630019685 3.66615 11.03661003937 3.66615 N
OE
OB 10.952630019685 3.66615 H
OC 10.952630019685 3.66615 10.93661003937 3.66615 N
OE
OB 11.002630019685 3.66615 H
OC 11.002630019685 3.66615 10.98661003937 3.66615 N
OE
OB 10.902630019685 3.66615 H
OC 10.902630019685 3.66615 10.88661003937 3.66615 N
OE
OB 10.902630019685 3.81615 H
OC 10.902630019685 3.81615 10.88661003937 3.81615 N
OE
OB 11.052630019685 3.81615 H
OC 11.052630019685 3.81615 11.03661003937 3.81615 N
OE
SE
P 12.55905 2.59448996 7 P 0 0;3=2,5=0
P 11.53316004 1.572 5 P 0 0;3=1,5=1
L 12.55905 2.59448996 12.57933996 2.5742 1 P 0 
L 12.57933996 2.5742 12.59301004 2.5742 1 P 0 
L 12.59301004 2.5742 12.59826998 2.57946004 1 P 0 
L 12.59826998 2.57946004 12.59826998 2.61081998 1 P 0 
L 12.59826998 2.61081998 12.57868996 2.6304 1 P 0 
L 12.57868996 2.6304 12.54073002 2.6304 1 P 0 
L 12.54073002 2.6304 12.50283996 2.62373002 1 P 0 
L 12.50283996 2.62373002 12.47131998 2.60166004 1 P 0 
L 12.47131998 2.60166004 12.36776004 2.45376004 1 P 0 
L 12.36776004 2.45376004 12.35191004 2.36383002 1 P 0 
L 12.35191004 2.36383002 12.10118996 2.00581998 1 P 0 
L 12.10118996 2.00581998 11.77756998 1.77921998 1 P 0 
L 11.77756998 1.77921998 11.62438002 1.75218002 1 P 0 
L 11.62438002 1.75218002 11.5968 1.73286004 1 P 0 
L 11.5968 1.73286004 11.5835 1.71386004 1 P 0 
L 11.5835 1.71386004 11.57483002 1.66466004 1 P 0 
L 11.57483002 1.66466004 11.58003002 1.63515 1 P 0 
L 11.58003002 1.63515 11.5745 1.60376998 1 P 0 
L 11.5745 1.60376998 11.56773996 1.59411004 1 P 0 
L 11.56773996 1.59411004 11.56131004 1.58961004 1 P 0 
L 11.56131004 1.58961004 11.55995 1.58825 1 P 0 
L 11.55995 1.58825 11.54941004 1.58825 1 P 0 
L 11.54941004 1.58825 11.53316004 1.572 1 P 0 
P 11.53316004 1.412 5 P 0 0;3=1,5=1
P 12.63778996 2.39763996 7 P 0 0;3=2,5=0
L 12.63778996 2.39763996 12.63275 2.40268002 1 P 0 
L 12.63275 2.40268002 12.59278996 2.40268002 1 P 0 
L 12.59278996 2.40268002 12.58438996 2.39428002 1 P 0 
L 12.58438996 2.39428002 12.5253 2.39428002 1 P 0 
L 12.5253 2.39428002 12.4995 2.38973002 1 P 0 
L 12.4995 2.38973002 12.32718996 2.26908002 1 P 0 
L 12.32718996 2.26908002 12.12548002 1.98101998 1 P 0 
L 12.12548002 1.98101998 11.8126 1.76193002 1 P 0 
L 11.8126 1.76193002 11.72305 1.74613002 1 P 0 
L 11.72305 1.74613002 11.71058002 1.7374 1 P 0 
L 11.71058002 1.7374 11.69966998 1.72178996 1 P 0 
L 11.69966998 1.72178996 11.69073996 1.67118996 1 P 0 
L 11.69073996 1.67118996 11.69456004 1.64948002 1 P 0 
L 11.69456004 1.64948002 11.6907 1.62763002 1 P 0 
L 11.6907 1.62763002 11.68151998 1.61451004 1 P 0 
L 11.68151998 1.61451004 11.65901004 1.59876004 1 P 0 
L 11.65901004 1.59876004 11.61653002 1.59128996 1 P 0 
L 11.61653002 1.59128996 11.60198996 1.58526004 1 P 0 
L 11.60198996 1.58526004 11.58461004 1.56043996 1 P 0 
L 11.58461004 1.56043996 11.57873002 1.52715 1 P 0 
L 11.57873002 1.52715 11.58471004 1.49333996 1 P 0 
L 11.58471004 1.49333996 11.5757 1.44228996 1 P 0 
L 11.5757 1.44228996 11.57036004 1.43465 1 P 0 
L 11.57036004 1.43465 11.56123996 1.42825 1 P 0 
L 11.56123996 1.42825 11.54941004 1.42825 1 P 0 
L 11.54941004 1.42825 11.53316004 1.412 1 P 0 
P 11.53316004 1.452 5 P 0 0;3=1,5=1
P 12.55905 2.43701004 7 P 0 0;3=2,5=0
L 12.55905 2.43701004 12.57826998 2.43701004 1 P 0 
L 12.57826998 2.43701004 12.5892 2.42608002 1 P 0 
L 12.5892 2.42608002 12.5892 2.4097 1 P 0 
L 12.5892 2.4097 12.58128002 2.40178002 1 P 0 
L 12.58128002 2.40178002 12.52463996 2.40178002 1 P 0 
L 12.52463996 2.40178002 12.49656004 2.39683002 1 P 0 
L 12.49656004 2.39683002 12.3218 2.27446998 1 P 0 
L 12.3218 2.27446998 12.12008996 1.98641004 1 P 0 
L 12.12008996 1.98641004 11.80966004 1.76903002 1 P 0 
L 11.80966004 1.76903002 11.80965 1.76903002 1 P 0 
L 11.80965 1.76903002 11.72011004 1.75323002 1 P 0 
L 11.72011004 1.75323002 11.70518996 1.74278996 1 P 0 
L 11.70518996 1.74278996 11.70441998 1.7417 1 P 0 
L 11.70441998 1.7417 11.70443002 1.7417 1 P 0 
L 11.70443002 1.7417 11.69256998 1.72473002 1 P 0 
L 11.69256998 1.72473002 11.68311998 1.67118996 1 P 0 
L 11.68311998 1.67118996 11.68693996 1.64948002 1 P 0 
L 11.68693996 1.64948002 11.6836 1.63056998 1 P 0 
L 11.6836 1.63056998 11.68358996 1.63056998 1 P 0 
L 11.68358996 1.63056998 11.67613002 1.6199 1 P 0 
L 11.67613002 1.6199 11.65606998 1.60586004 1 P 0 
L 11.65606998 1.60586004 11.61441998 1.59853996 1 P 0 
L 11.61441998 1.59853996 11.61366004 1.59823002 1 P 0 
L 11.61366004 1.59823002 11.61366004 1.59821998 1 P 0 
L 11.61366004 1.59821998 11.59708996 1.59136004 1 P 0 
L 11.59708996 1.59136004 11.57751004 1.56338002 1 P 0 
L 11.57751004 1.56338002 11.57428002 1.54508996 1 P 0 
L 11.57428002 1.54508996 11.57111004 1.52715 1 P 0 
L 11.57111004 1.52715 11.57708996 1.49333996 1 P 0 
L 11.57708996 1.49333996 11.5686 1.44523002 1 P 0 
L 11.5686 1.44523002 11.56496004 1.44003996 1 P 0 
L 11.56496004 1.44003996 11.55886998 1.43575 1 P 0 
L 11.55886998 1.43575 11.54941004 1.43575 1 P 0 
L 11.54941004 1.43575 11.53316004 1.452 1 P 0 
P 11.83316004 2.212 5 P 0 0;3=1,5=1
P 12.63778996 3.65748002 7 P 0 0;3=2,5=0
L 11.83316004 2.212 11.84941004 2.22825 1 P 0 
L 11.84941004 2.22825 11.88371998 2.22825 1 P 0 
L 11.88371998 2.22825 11.91701004 2.23411998 1 P 0 
L 11.91701004 2.23411998 12.06903996 2.34058996 1 P 0 
L 12.06903996 2.34058996 12.1817 2.50146998 1 P 0 
L 12.1817 2.50146998 12.29 3.11568996 1 P 0 
L 12.29 3.11568996 12.37656004 3.2393 1 P 0 
L 12.37656004 3.2393 12.41913002 3.48066004 1 P 0 
L 12.41913002 3.48066004 12.45713996 3.53495 1 P 0 
L 12.45713996 3.53495 12.50421998 3.56791998 1 P 0 
L 12.50421998 3.56791998 12.5516 3.57628002 1 P 0 
L 12.5516 3.57628002 12.5885 3.57628002 1 P 0 
L 12.5885 3.57628002 12.60796998 3.59575 1 P 0 
L 12.60796998 3.59575 12.60796998 3.62766004 1 P 0 
L 12.60796998 3.62766004 12.63778996 3.65748002 1 P 0 
P 11.53316004 1.932 5 P 0 0;3=1,5=1
P 12.63778996 3.26378002 7 P 0 0;3=2,5=0
L 12.63778996 3.26378002 12.60576998 3.2958 1 P 0 
L 12.60576998 3.2958 12.60576998 3.32258996 1 P 0 
L 12.60576998 3.32258996 12.5818 3.34656004 1 P 0 
L 12.5818 3.34656004 12.53283002 3.34656004 1 P 0 
L 12.53283002 3.34656004 12.53146998 3.3452 1 P 0 
L 12.53146998 3.3452 12.52276004 3.34366004 1 P 0 
L 12.52276004 3.34366004 12.50803996 3.33336004 1 P 0 
L 12.50803996 3.33336004 12.35643002 3.11683002 1 P 0 
L 12.35643002 3.11683002 12.35641004 3.1168 1 P 0 
L 12.35641004 3.1168 12.34393002 3.09898996 1 P 0 
L 12.34393002 3.09898996 12.22996004 2.4526 1 P 0 
L 12.22996004 2.4526 12.10886998 2.27968002 1 P 0 
L 12.10886998 2.27968002 11.84563996 2.09536004 1 P 0 
L 11.84563996 2.09536004 11.71268996 2.07191004 1 P 0 
L 11.71268996 2.07191004 11.68013996 2.07763996 1 P 0 
L 11.68013996 2.07763996 11.61231004 2.06568996 1 P 0 
L 11.61231004 2.06568996 11.5848 2.04643002 1 P 0 
L 11.5848 2.04643002 11.57356004 2.03038002 1 P 0 
L 11.57356004 2.03038002 11.56613002 1.98825 1 P 0 
L 11.56613002 1.98825 11.57338996 1.94708996 1 P 0 
L 11.57338996 1.94708996 11.56948996 1.92493996 1 P 0 
L 11.56948996 1.92493996 11.56558996 1.91936998 1 P 0 
L 11.56558996 1.91936998 11.56295 1.91751998 1 P 0 
L 11.56295 1.91751998 11.55303996 1.91575 1 P 0 
L 11.55303996 1.91575 11.54941004 1.91575 1 P 0 
L 11.54941004 1.91575 11.53316004 1.932 1 P 0 
P 11.73316004 1.492 5 P 0 0;3=1,5=1
P 12.63778996 2.24016004 7 P 0 0;3=2,5=0
L 12.63778996 2.24016004 12.63275 2.2452 1 P 0 
L 12.63275 2.2452 12.59278996 2.2452 1 P 0 
L 12.59278996 2.2452 12.58438996 2.2368 1 P 0 
L 12.58438996 2.2368 12.5253 2.2368 1 P 0 
L 12.5253 2.2368 12.49393996 2.23126998 1 P 0 
L 12.49393996 2.23126998 12.19973002 2.02523002 1 P 0 
L 12.19973002 2.02523002 12.1547 1.9609 1 P 0 
L 12.1547 1.9609 11.84563996 1.74451998 1 P 0 
L 11.84563996 1.74451998 11.7327 1.72461004 1 P 0 
L 11.7327 1.72461004 11.7254 1.7195 1 P 0 
L 11.7254 1.7195 11.72128002 1.71361998 1 P 0 
L 11.72128002 1.71361998 11.71443002 1.67476004 1 P 0 
L 11.71443002 1.67476004 11.7229 1.62676004 1 P 0 
L 11.7229 1.62676004 11.77436998 1.55326004 1 P 0 
L 11.77436998 1.55326004 11.7766 1.5406 1 P 0 
L 11.7766 1.5406 11.7766 1.51633996 1 P 0 
L 11.7766 1.51633996 11.76851004 1.50825 1 P 0 
L 11.76851004 1.50825 11.74941004 1.50825 1 P 0 
L 11.74941004 1.50825 11.73316004 1.492 1 P 0 
P 12.55905 4.09055 7 P 0 0;3=2,5=0
P 11.53316004 2.412 5 P 0 0;3=1,5=1
L 12.55905 4.09055 12.57651998 4.10801998 1 P 0 
L 12.57651998 4.10801998 12.59676998 4.10801998 1 P 0 
L 12.59676998 4.10801998 12.60046998 4.10431998 1 P 0 
L 12.60046998 4.10431998 12.60046998 4.0713 1 P 0 
L 12.60046998 4.0713 12.58508996 4.05591998 1 P 0 
L 12.58508996 4.05591998 12.55093996 4.05591998 1 P 0 
L 12.55093996 4.05591998 12.50605 4.04801004 1 P 0 
L 12.50605 4.04801004 12.44605 4.006 1 P 0 
L 12.44605 4.006 12.39293996 3.93015 1 P 0 
L 12.39293996 3.93015 12.2751 3.26196998 1 P 0 
L 12.2751 3.26196998 11.93056998 2.76993996 1 P 0 
L 11.93056998 2.76993996 11.88788996 2.52788996 1 P 0 
L 11.88788996 2.52788996 11.83538996 2.4529 1 P 0 
L 11.83538996 2.4529 11.77825 2.41288996 1 P 0 
L 11.77825 2.41288996 11.70206004 2.39946004 1 P 0 
L 11.70206004 2.39946004 11.65698996 2.4074 1 P 0 
L 11.65698996 2.4074 11.59091998 2.39575 1 P 0 
L 11.59091998 2.39575 11.54941004 2.39575 1 P 0 
L 11.54941004 2.39575 11.53316004 2.412 1 P 0 
P 11.78316004 1.692 5 P 0 0;3=1,5=1
P 12.55905 2.04331004 7 P 0 0;3=2,5=0
L 11.78316004 1.692 11.79941004 1.67575 1 P 0 
L 11.79941004 1.67575 11.82891998 1.67575 1 P 0 
L 11.82891998 1.67575 11.84623996 1.6727 1 P 0 
L 11.84623996 1.6727 11.85956998 1.66338002 1 P 0 
L 11.85956998 1.66338002 11.8878 1.62305 1 P 0 
L 11.8878 1.62305 11.92263002 1.42561998 1 P 0 
L 11.92263002 1.42561998 11.97993996 1.34381004 1 P 0 
L 11.97993996 1.34381004 11.9866 1.33913996 1 P 0 
L 11.9866 1.33913996 11.98663002 1.33913002 1 P 0 
L 11.98663002 1.33913002 12.04153996 1.30068002 1 P 0 
L 12.04153996 1.30068002 12.1168 1.28741004 1 P 0 
L 12.1168 1.28741004 12.1939 1.301 1 P 0 
L 12.1939 1.301 12.2821 1.36276004 1 P 0 
L 12.2821 1.36276004 12.35751004 1.47046004 1 P 0 
L 12.35751004 1.47046004 12.37413002 1.56468996 1 P 0 
L 12.37413002 1.56468996 12.35753996 1.65878002 1 P 0 
L 12.35753996 1.65878002 12.39853996 1.89135 1 P 0 
L 12.39853996 1.89135 12.44498002 1.95766998 1 P 0 
L 12.44498002 1.95766998 12.50616998 2.00051998 1 P 0 
L 12.50616998 2.00051998 12.5452 2.0074 1 P 0 
L 12.5452 2.0074 12.5817 2.0074 1 P 0 
L 12.5817 2.0074 12.6023 2.028 1 P 0 
L 12.6023 2.028 12.6023 2.05528996 1 P 0 
L 12.6023 2.05528996 12.5979 2.05968996 1 P 0 
L 12.5979 2.05968996 12.57543002 2.05968996 1 P 0 
L 12.57543002 2.05968996 12.55905 2.04331004 1 P 0 
P 11.78316004 1.652 5 P 0 0;3=1,5=1
P 12.63778996 2.08268002 7 P 0 0;3=2,5=0
L 11.78316004 1.652 11.79941004 1.66825 1 P 0 
L 11.79941004 1.66825 11.82826004 1.66825 1 P 0 
L 11.82826004 1.66825 11.8433 1.6656 1 P 0 
L 11.8433 1.6656 11.85418002 1.65798996 1 P 0 
L 11.85418002 1.65798996 11.8807 1.62011004 1 P 0 
L 11.8807 1.62011004 11.91553002 1.42268002 1 P 0 
L 11.91553002 1.42268002 11.97455 1.33841998 1 P 0 
L 11.97455 1.33841998 11.98228996 1.333 1 P 0 
L 11.98228996 1.333 11.98228002 1.333 1 P 0 
L 11.98228002 1.333 11.9823 1.33298996 1 P 0 
L 11.9823 1.33298996 11.98233996 1.33296004 1 P 0 
L 11.98233996 1.33296004 11.98318996 1.33236998 1 P 0 
L 11.98318996 1.33236998 11.98318002 1.33236998 1 P 0 
L 11.98318002 1.33236998 12.0386 1.29358002 1 P 0 
L 12.0386 1.29358002 12.1168 1.27978996 1 P 0 
L 12.1168 1.27978996 12.19683996 1.2939 1 P 0 
L 12.19683996 1.2939 12.28748996 1.35736998 1 P 0 
L 12.28748996 1.35736998 12.36461004 1.46751998 1 P 0 
L 12.36461004 1.46751998 12.38175 1.56468996 1 P 0 
L 12.38175 1.56468996 12.36516004 1.65878002 1 P 0 
L 12.36516004 1.65878002 12.40563996 1.88841004 1 P 0 
L 12.40563996 1.88841004 12.45036998 1.95228002 1 P 0 
L 12.45036998 1.95228002 12.50911004 1.99341998 1 P 0 
L 12.50911004 1.99341998 12.54586004 1.9999 1 P 0 
L 12.54586004 1.9999 12.58481004 1.9999 1 P 0 
L 12.58481004 1.9999 12.6098 2.02488996 1 P 0 
L 12.6098 2.02488996 12.6098 2.05468996 1 P 0 
L 12.6098 2.05468996 12.63778996 2.08268002 1 P 0 
P 11.83316004 2.252 5 P 0 0;3=1,5=1
P 12.55905 3.61811004 7 P 0 0;3=2,5=0
L 11.83316004 2.252 11.84941004 2.23575 1 P 0 
L 11.84941004 2.23575 11.88306004 2.23575 1 P 0 
L 11.88306004 2.23575 11.91406998 2.24121998 1 P 0 
L 11.91406998 2.24121998 12.06365 2.34598002 1 P 0 
L 12.06365 2.34598002 12.1746 2.50441004 1 P 0 
L 12.1746 2.50441004 12.2829 3.11863002 1 P 0 
L 12.2829 3.11863002 12.36946004 3.24223996 1 P 0 
L 12.36946004 3.24223996 12.41203002 3.4836 1 P 0 
L 12.41203002 3.4836 12.45175 3.54033996 1 P 0 
L 12.45175 3.54033996 12.50128002 3.57501998 1 P 0 
L 12.50128002 3.57501998 12.55093996 3.58378002 1 P 0 
L 12.55093996 3.58378002 12.58538996 3.58378002 1 P 0 
L 12.58538996 3.58378002 12.60046998 3.59886004 1 P 0 
L 12.60046998 3.59886004 12.60046998 3.63188002 1 P 0 
L 12.60046998 3.63188002 12.59676998 3.63558002 1 P 0 
L 12.59676998 3.63558002 12.57651998 3.63558002 1 P 0 
L 12.57651998 3.63558002 12.55905 3.61811004 1 P 0 
P 11.53316004 2.572 5 P 0 0;3=1,5=1
P 12.55905 4.56298996 7 P 0 0;3=2,5=0
L 12.55905 4.56298996 12.57653002 4.58046998 1 P 0 
L 12.57653002 4.58046998 12.59676998 4.58046998 1 P 0 
L 12.59676998 4.58046998 12.60046998 4.57676998 1 P 0 
L 12.60046998 4.57676998 12.60046998 4.54666998 1 P 0 
L 12.60046998 4.54666998 12.5824 4.5286 1 P 0 
L 12.5824 4.5286 12.539 4.5286 1 P 0 
L 12.539 4.5286 12.4914 4.52021004 1 P 0 
L 12.4914 4.52021004 12.42335 4.47256004 1 P 0 
L 12.42335 4.47256004 12.37651998 4.4057 1 P 0 
L 12.37651998 4.4057 12.1743 3.25888996 1 P 0 
L 12.1743 3.25888996 11.88836998 2.85053996 1 P 0 
L 11.88836998 2.85053996 11.71141004 2.72661998 1 P 0 
L 11.71141004 2.72661998 11.60683996 2.70818996 1 P 0 
L 11.60683996 2.70818996 11.59251998 2.69816998 1 P 0 
L 11.59251998 2.69816998 11.57901004 2.67886004 1 P 0 
L 11.57901004 2.67886004 11.57 2.62788996 1 P 0 
L 11.57 2.62788996 11.57806998 2.58211998 1 P 0 
L 11.57806998 2.58211998 11.57581998 2.56936004 1 P 0 
L 11.57581998 2.56936004 11.57033002 2.56153002 1 P 0 
L 11.57033002 2.56153002 11.56365 2.55685 1 P 0 
L 11.56365 2.55685 11.5574 2.55575 1 P 0 
L 11.5574 2.55575 11.54941004 2.55575 1 P 0 
L 11.54941004 2.55575 11.53316004 2.572 1 P 0 
P 12.63778996 2.55511998 7 P 0 0;3=2,5=0
P 11.53316004 1.612 5 P 0 0;3=1,5=1
L 12.63778996 2.55511998 12.60576998 2.58713996 1 P 0 
L 12.60576998 2.58713996 12.60576998 2.61393002 1 P 0 
L 12.60576998 2.61393002 12.5818 2.6379 1 P 0 
L 12.5818 2.6379 12.54006998 2.6379 1 P 0 
L 12.54006998 2.6379 12.4999 2.63083002 1 P 0 
L 12.4999 2.63083002 12.46593002 2.60705 1 P 0 
L 12.46593002 2.60705 12.36066004 2.4567 1 P 0 
L 12.36066004 2.4567 12.34481004 2.36676998 1 P 0 
L 12.34481004 2.36676998 12.0958 2.01121004 1 P 0 
L 12.0958 2.01121004 11.77463002 1.78631998 1 P 0 
L 11.77463002 1.78631998 11.62143996 1.75928002 1 P 0 
L 11.62143996 1.75928002 11.59141004 1.73825 1 P 0 
L 11.59141004 1.73825 11.5764 1.7168 1 P 0 
L 11.5764 1.7168 11.56721004 1.66466004 1 P 0 
L 11.56721004 1.66466004 11.57241004 1.63515 1 P 0 
L 11.57241004 1.63515 11.5699 1.62091998 1 P 0 
L 11.5699 1.62091998 11.56988996 1.62091998 1 P 0 
L 11.56988996 1.62091998 11.5674 1.60671004 1 P 0 
L 11.5674 1.60671004 11.56235 1.5995 1 P 0 
L 11.56235 1.5995 11.557 1.59575 1 P 0 
L 11.557 1.59575 11.54941004 1.59575 1 P 0 
L 11.54941004 1.59575 11.53316004 1.612 1 P 0 
P 11.53316004 2.532 5 P 0 0;3=1,5=1
P 12.63778996 4.60236998 7 P 0 0;3=2,5=0
L 12.63778996 4.60236998 12.60796998 4.57255 1 P 0 
L 12.60796998 4.57255 12.60796998 4.54356004 1 P 0 
L 12.60796998 4.54356004 12.58551004 4.5211 1 P 0 
L 12.58551004 4.5211 12.53966004 4.5211 1 P 0 
L 12.53966004 4.5211 12.49433996 4.51311004 1 P 0 
L 12.49433996 4.51311004 12.42873996 4.46716998 1 P 0 
L 12.42873996 4.46716998 12.38361998 4.40276004 1 P 0 
L 12.38361998 4.40276004 12.1814 3.25595 1 P 0 
L 12.1814 3.25595 11.89376004 2.84515 1 P 0 
L 11.89376004 2.84515 11.71435 2.71951998 1 P 0 
L 11.71435 2.71951998 11.60978002 2.70108996 1 P 0 
L 11.60978002 2.70108996 11.59791004 2.69278002 1 P 0 
L 11.59791004 2.69278002 11.58611004 2.67591998 1 P 0 
L 11.58611004 2.67591998 11.57761998 2.62788996 1 P 0 
L 11.57761998 2.62788996 11.58568996 2.58211998 1 P 0 
L 11.58568996 2.58211998 11.58291998 2.56641998 1 P 0 
L 11.58291998 2.56641998 11.57571998 2.55613996 1 P 0 
L 11.57571998 2.55613996 11.56796004 2.55071004 1 P 0 
L 11.56796004 2.55071004 11.56671004 2.54946004 1 P 0 
L 11.56671004 2.54946004 11.56493996 2.54946004 1 P 0 
L 11.56493996 2.54946004 11.55806004 2.54825 1 P 0 
L 11.55806004 2.54825 11.54941004 2.54825 1 P 0 
L 11.54941004 2.54825 11.53316004 2.532 1 P 0 
P 5.03268002 3.81615 5 P 0 0;3=1,5=1
L 4.07408002 4.01978996 4.32488996 3.97556998 2 P 0 
L 4.32488996 3.97556998 4.56333002 3.93353002 2 P 0 
L 4.56333002 3.93353002 4.62238996 3.94393996 2 P 0 
L 4.62238996 3.94393996 4.83128002 3.90711998 2 P 0 
L 4.83128002 3.90711998 4.9246 3.92356998 2 P 0 
L 4.9246 3.92356998 5.06293002 3.89918002 2 P 0 
L 5.06293002 3.89918002 5.07908996 3.88786998 2 P 0 
L 5.07908996 3.88786998 5.09143002 3.87025 2 P 0 
L 5.09143002 3.87025 5.095 3.85 2 P 0 
L 5.095 3.85 5.095 3.83 2 P 0 
L 5.095 3.83 5.08115 3.81615 2 P 0 
L 5.08115 3.81615 5.03268002 3.81615 2 P 0 
P 4.07408002 4.01978996 6 P 0 0;3=4,5=1
P 10.82676998 5.49685 8 P 0 0;3=5,5=0
P 10.99213002 5.49685 8 P 0 0;3=5,5=0
P 11.15748002 5.49685 8 P 0 0;3=5,5=0
P 11.32283996 5.49685 8 P 0 0;3=5,5=0
P 11.48818996 5.49685 8 P 0 0;3=5,5=0
P 11.65353996 5.49685 8 P 0 0;3=5,5=0
P 11.8189 5.49685 8 P 0 0;3=5,5=0
P 11.98425 5.49685 8 P 0 0;3=5,5=0
P 12.14961004 5.49685 8 P 0 0;3=6,5=0
P 10.80498996 5.56656004 6 P 0 0;3=3,5=1
P 10.84498996 5.56656004 6 P 0 0;3=3,5=1
P 10.80498996 5.42656004 6 P 0 0;3=3,5=1
P 10.84498996 5.42656004 6 P 0 0;3=3,5=1
P 11.01035 5.42656004 6 P 0 0;3=3,5=1
P 10.97035 5.42656004 6 P 0 0;3=3,5=1
P 11.01035 5.56656004 6 P 0 0;3=3,5=1
P 10.97035 5.56656004 6 P 0 0;3=3,5=1
P 11.17571004 5.42656004 6 P 0 0;3=3,5=1
P 11.13571004 5.42656004 6 P 0 0;3=3,5=1
P 11.17571004 5.56656004 6 P 0 0;3=3,5=1
P 11.13571004 5.56656004 6 P 0 0;3=3,5=1
P 11.34106998 5.42656004 6 P 0 0;3=3,5=1
P 11.30106998 5.42656004 6 P 0 0;3=3,5=1
P 11.34106998 5.56656004 6 P 0 0;3=3,5=1
P 11.30106998 5.56656004 6 P 0 0;3=3,5=1
P 11.50643002 5.42656004 6 P 0 0;3=3,5=1
P 11.46643002 5.42656004 6 P 0 0;3=3,5=1
P 11.50643002 5.56656004 6 P 0 0;3=3,5=1
P 11.46643002 5.56656004 6 P 0 0;3=3,5=1
P 11.67178996 5.42656004 6 P 0 0;3=3,5=1
P 11.63178996 5.42656004 6 P 0 0;3=3,5=1
P 11.67178996 5.56656004 6 P 0 0;3=3,5=1
P 11.63178996 5.56656004 6 P 0 0;3=3,5=1
P 11.83715 5.42656004 6 P 0 0;3=3,5=1
P 11.79715 5.42656004 6 P 0 0;3=3,5=1
P 11.83715 5.56656004 6 P 0 0;3=3,5=1
P 11.79715 5.56656004 6 P 0 0;3=3,5=1
P 12.00251004 5.42656004 6 P 0 0;3=3,5=1
P 11.96251004 5.42656004 6 P 0 0;3=3,5=1
P 12.00251004 5.56656004 6 P 0 0;3=3,5=1
P 11.96251004 5.56656004 6 P 0 0;3=3,5=1
P 12.16786998 5.42656004 6 P 0 0;3=3,5=1
P 12.12786998 5.42656004 6 P 0 0;3=3,5=1
P 12.16786998 5.56656004 6 P 0 0;3=3,5=1
P 12.12786998 5.56656004 6 P 0 0;3=3,5=1
S P 0
OB 10.78 5.565 I
OS 10.8 5.585
OS 12.19 5.585
OS 12.205 5.57
OS 12.205 5.42
OS 12.19 5.405
OS 10.8 5.405
OS 10.78 5.425
OS 10.78 5.565
OE
SE
P 10.99998996 4.9531 6 P 0 0;3=3,5=1
P 11.03998996 4.9531 6 P 0 0;3=3,5=1
P 10.99998996 4.9131 6 P 0 0;3=3,5=1
P 11.03998996 4.9131 6 P 0 0;3=3,5=1
P 11.21998996 4.9531 6 P 0 0;3=3,5=1
P 11.17998996 4.9531 6 P 0 0;3=3,5=1
P 11.13498996 4.9531 6 P 0 0;3=3,5=1
P 11.08498996 4.9531 6 P 0 0;3=3,5=1
P 11.21998996 4.9131 6 P 0 0;3=3,5=1
P 11.17998996 4.9131 6 P 0 0;3=3,5=1
P 11.08498996 4.9131 6 P 0 0;3=3,5=1
P 11.13498996 4.9131 6 P 0 0;3=3,5=1
P 10.99998996 5.1631 6 P 0 0;3=3,5=1
P 11.03998996 5.1631 6 P 0 0;3=3,5=1
P 10.99998996 5.1231 6 P 0 0;3=3,5=1
P 10.99998996 5.0381 6 P 0 0;3=3,5=1
P 10.99998996 5.0831 6 P 0 0;3=3,5=1
P 10.99998996 4.9931 6 P 0 0;3=3,5=1
P 11.03998996 4.9931 6 P 0 0;3=3,5=1
P 11.03998996 5.0831 6 P 0 0;3=3,5=1
P 11.03998996 5.0381 6 P 0 0;3=3,5=1
P 11.03998996 5.1231 6 P 0 0;3=3,5=1
P 11.21998996 5.1631 6 P 0 0;3=3,5=1
P 11.17998996 5.1631 6 P 0 0;3=3,5=1
P 11.08498996 5.1631 6 P 0 0;3=3,5=1
P 11.13498996 5.1631 6 P 0 0;3=3,5=1
P 11.21998996 5.1231 6 P 0 0;3=3,5=1
P 11.21998996 5.0381 6 P 0 0;3=3,5=1
P 11.21998996 5.0831 6 P 0 0;3=3,5=1
P 11.21998996 4.9931 6 P 0 0;3=3,5=1
P 11.17998996 4.9931 6 P 0 0;3=3,5=1
P 11.17998996 5.1231 6 P 0 0;3=3,5=1
P 11.17998996 5.0831 6 P 0 0;3=3,5=1
P 11.17998996 5.0381 6 P 0 0;3=3,5=1
P 11.13498996 5.1231 6 P 0 0;3=3,5=1
P 11.08498996 5.1231 6 P 0 0;3=3,5=1
P 11.6269 4.90498996 6 P 0 0;3=3,5=1
P 11.6269 4.85498996 6 P 0 0;3=3,5=1
P 11.4269 4.80998996 6 P 0 0;3=3,5=1
P 11.4269 4.85498996 6 P 0 0;3=3,5=1
P 11.4269 4.90498996 6 P 0 0;3=3,5=1
P 11.4269 4.94998996 6 P 0 0;3=3,5=1
P 11.4769 4.94998996 6 P 0 0;3=3,5=1
P 11.4769 4.80998996 6 P 0 0;3=3,5=1
P 11.5269 4.94998996 6 P 0 0;3=3,5=1
P 11.5269 4.80998996 6 P 0 0;3=3,5=1
P 11.5769 4.94998996 6 P 0 0;3=3,5=1
P 11.6269 4.94998996 6 P 0 0;3=3,5=1
P 11.6269 4.80998996 6 P 0 0;3=3,5=1
P 11.5769 4.80998996 6 P 0 0;3=3,5=1
P 10.82676998 5.71338996 8 P 0 0;3=5,5=0
P 10.99213002 5.71338996 8 P 0 0;3=5,5=0
P 11.15748002 5.71338996 8 P 0 0;3=5,5=0
P 11.32283996 5.71338996 8 P 0 0;3=5,5=0
P 11.48818996 5.71338996 8 P 0 0;3=5,5=0
P 11.65353996 5.71338996 8 P 0 0;3=5,5=0
P 11.8189 5.71338996 8 P 0 0;3=5,5=0
P 11.98425 5.71338996 8 P 0 0;3=5,5=0
P 12.14961004 5.71338996 8 P 0 0;3=5,5=0
P 10.80498996 5.7831 6 P 0 0;3=3,5=1
P 10.84498996 5.7831 6 P 0 0;3=3,5=1
P 10.80498996 5.6431 6 P 0 0;3=3,5=1
P 10.84498996 5.6431 6 P 0 0;3=3,5=1
P 11.01035 5.6431 6 P 0 0;3=3,5=1
P 10.97035 5.6431 6 P 0 0;3=3,5=1
P 11.01035 5.7831 6 P 0 0;3=3,5=1
P 10.97035 5.7831 6 P 0 0;3=3,5=1
P 11.17571004 5.6431 6 P 0 0;3=3,5=1
P 11.13571004 5.6431 6 P 0 0;3=3,5=1
P 11.17571004 5.7831 6 P 0 0;3=3,5=1
P 11.13571004 5.7831 6 P 0 0;3=3,5=1
P 11.34106998 5.6431 6 P 0 0;3=3,5=1
P 11.30106998 5.6431 6 P 0 0;3=3,5=1
P 11.34106998 5.7831 6 P 0 0;3=3,5=1
P 11.30106998 5.7831 6 P 0 0;3=3,5=1
P 11.50643002 5.6431 6 P 0 0;3=3,5=1
P 11.46643002 5.6431 6 P 0 0;3=3,5=1
P 11.50643002 5.7831 6 P 0 0;3=3,5=1
P 11.46643002 5.7831 6 P 0 0;3=3,5=1
P 11.67178996 5.6431 6 P 0 0;3=3,5=1
P 11.63178996 5.6431 6 P 0 0;3=3,5=1
P 11.67178996 5.7831 6 P 0 0;3=3,5=1
P 11.63178996 5.7831 6 P 0 0;3=3,5=1
P 11.83715 5.6431 6 P 0 0;3=3,5=1
P 11.79715 5.6431 6 P 0 0;3=3,5=1
P 11.83715 5.7831 6 P 0 0;3=3,5=1
P 11.79715 5.7831 6 P 0 0;3=3,5=1
P 12.00251004 5.6431 6 P 0 0;3=3,5=1
P 11.96251004 5.6431 6 P 0 0;3=3,5=1
P 12.00251004 5.7831 6 P 0 0;3=3,5=1
P 11.96251004 5.7831 6 P 0 0;3=3,5=1
P 12.16786998 5.6431 6 P 0 0;3=3,5=1
P 12.12786998 5.6431 6 P 0 0;3=3,5=1
P 12.16786998 5.7831 6 P 0 0;3=3,5=1
P 12.12786998 5.7831 6 P 0 0;3=3,5=1
S P 0
OB 11.31405 4.78405 I
OS 11.195 4.9031
OS 10.99498996063 4.9031
OS 10.98998996063 4.9081
OS 10.98998996063 5.12
OS 10.95498996063 5.155
OS 10.577 5.155
OS 10.567 5.165
OS 10.567 5.836
OS 10.616 5.885
OS 12.49 5.885
OS 12.52 5.855
OS 12.52 5.285
OS 12.255 5.02
OS 11.730969980315 5.02
OS 11.7 4.989030019685
OS 11.7 4.825
OS 11.65905 4.78405
OS 11.31405 4.78405
OE
OB 10.79585 5.394980019685 H
OS 12.19415 5.394980019685
OS 12.215019980315 5.41585
OS 12.215019980315 5.57415
OS 12.19415 5.595019980315
OS 10.79585 5.595019980315
OS 10.769980019685 5.56915
OS 10.769980019685 5.42085
OS 10.79585 5.394980019685
OE
OB 12.415380019685 5.695280019685 H
OC 12.415380019685 5.695280019685 12.33465 5.695280019685 N
OE
SE
L 0.64808996 1.655 0.67968002 1.47583996 2 P 0 
L 0.67968002 1.47583996 0.76828996 1.34928996 2 P 0 
L 0.76828996 1.34928996 1.10405 1.11418996 2 P 0 
L 1.10405 1.11418996 2.21325 0.91861004 2 P 0 
L 2.21325 0.91861004 3.75861998 0.64611004 2 P 0 
L 3.75861998 0.64611004 4.69631004 0.81145 2 P 0 
L 4.69631004 0.81145 5.53766998 1.40056998 2 P 0 
L 5.53766998 1.40056998 5.70983996 1.64645 2 P 0 
L 5.70983996 1.64645 5.76 1.93095 2 P 0 
L 5.76 1.93095 5.76 2.66 2 P 0 
P 0.64808996 1.655 6 P 0 0;3=3,5=1
P 5.76 2.66 6 P 0 0;3=4,5=1
P 11.73316004 2.652 5 P 0 0;3=1,5=1
P 12.55905 4.40551004 7 P 0 0;3=2,5=0
L 11.73316004 2.652 11.74941004 2.63575 1 P 0 
L 11.74941004 2.63575 11.75995 2.63575 1 P 0 
L 11.75995 2.63575 11.77696004 2.64766004 1 P 0 
L 11.77696004 2.64766004 12.20908996 3.26481004 1 P 0 
L 12.20908996 3.26481004 12.37323002 4.1959 1 P 0 
L 12.37323002 4.1959 12.46986998 4.33391998 1 P 0 
L 12.46986998 4.33391998 12.51223996 4.36358002 1 P 0 
L 12.51223996 4.36358002 12.55093996 4.3704 1 P 0 
L 12.55093996 4.3704 12.58461004 4.3704 1 P 0 
L 12.58461004 4.3704 12.60046998 4.38626004 1 P 0 
L 12.60046998 4.38626004 12.60046998 4.41928002 1 P 0 
L 12.60046998 4.41928002 12.59676998 4.42298002 1 P 0 
L 12.59676998 4.42298002 12.57651998 4.42298002 1 P 0 
L 12.57651998 4.42298002 12.55905 4.40551004 1 P 0 
P 11.73316004 2.612 5 P 0 0;3=1,5=1
P 12.63778996 4.44488002 7 P 0 0;3=2,5=0
L 11.73316004 2.612 11.74941004 2.62825 1 P 0 
L 11.74941004 2.62825 11.76231998 2.62825 1 P 0 
L 11.76231998 2.62825 11.78235 2.64226998 1 P 0 
L 11.78235 2.64226998 12.21618996 3.26186998 1 P 0 
L 12.21618996 3.26186998 12.38033002 4.19296004 1 P 0 
L 12.38033002 4.19296004 12.47526004 4.32853002 1 P 0 
L 12.47526004 4.32853002 12.51518002 4.35648002 1 P 0 
L 12.51518002 4.35648002 12.5516 4.3629 1 P 0 
L 12.5516 4.3629 12.58771998 4.3629 1 P 0 
L 12.58771998 4.3629 12.60796998 4.38315 1 P 0 
L 12.60796998 4.38315 12.60796998 4.41506004 1 P 0 
L 12.60796998 4.41506004 12.63778996 4.44488002 1 P 0 
P 11.73316004 2.492 5 P 0 0;3=1,5=1
P 12.55905 4.24803002 7 P 0 0;3=2,5=0
L 11.73316004 2.492 11.74941004 2.47575 1 P 0 
L 11.74941004 2.47575 11.76951004 2.47575 1 P 0 
L 11.76951004 2.47575 11.79588002 2.4804 1 P 0 
L 11.79588002 2.4804 11.82156004 2.49838996 1 P 0 
L 11.82156004 2.49838996 11.86035 2.55378996 1 P 0 
L 11.86035 2.55378996 11.89875 2.77171004 1 P 0 
L 11.89875 2.77171004 12.24138996 3.26101998 1 P 0 
L 12.24138996 3.26101998 12.38626004 4.0825 1 P 0 
L 12.38626004 4.0825 12.43611998 4.15373002 1 P 0 
L 12.43611998 4.15373002 12.5131 4.20763002 1 P 0 
L 12.5131 4.20763002 12.55093996 4.2143 1 P 0 
L 12.55093996 4.2143 12.58598996 4.2143 1 P 0 
L 12.58598996 4.2143 12.60046998 4.22878002 1 P 0 
L 12.60046998 4.22878002 12.60046998 4.2618 1 P 0 
L 12.60046998 4.2618 12.59676998 4.2655 1 P 0 
L 12.59676998 4.2655 12.57651998 4.2655 1 P 0 
L 12.57651998 4.2655 12.55905 4.24803002 1 P 0 
P 11.73316004 2.452 5 P 0 0;3=1,5=1
P 12.63778996 4.2874 7 P 0 0;3=2,5=0
L 11.73316004 2.452 11.74941004 2.46825 1 P 0 
L 11.74941004 2.46825 11.77016998 2.46825 1 P 0 
L 11.77016998 2.46825 11.79881998 2.4733 1 P 0 
L 11.79881998 2.4733 11.82695 2.493 1 P 0 
L 11.82695 2.493 11.86745 2.55085 1 P 0 
L 11.86745 2.55085 11.90585 2.76876998 1 P 0 
L 11.90585 2.76876998 12.24848996 3.25808002 1 P 0 
L 12.24848996 3.25808002 12.39336004 4.07956004 1 P 0 
L 12.39336004 4.07956004 12.44151004 4.14833996 1 P 0 
L 12.44151004 4.14833996 12.51603996 4.20053002 1 P 0 
L 12.51603996 4.20053002 12.5516 4.2068 1 P 0 
L 12.5516 4.2068 12.5891 4.2068 1 P 0 
L 12.5891 4.2068 12.60796998 4.22566998 1 P 0 
L 12.60796998 4.22566998 12.60796998 4.25758002 1 P 0 
L 12.60796998 4.25758002 12.63778996 4.2874 1 P 0 
P 12.55905 3.93306998 7 P 0 0;3=2,5=0
P 11.73316004 2.332 5 P 0 0;3=1,5=1
L 12.55905 3.93306998 12.57651998 3.95053996 1 P 0 
L 12.57651998 3.95053996 12.59676998 3.95053996 1 P 0 
L 12.59676998 3.95053996 12.60046998 3.94683996 1 P 0 
L 12.60046998 3.94683996 12.60046998 3.91381998 1 P 0 
L 12.60046998 3.91381998 12.58438996 3.89773996 1 P 0 
L 12.58438996 3.89773996 12.55093996 3.89773996 1 P 0 
L 12.55093996 3.89773996 12.52523996 3.89321004 1 P 0 
L 12.52523996 3.89321004 12.46713996 3.85253002 1 P 0 
L 12.46713996 3.85253002 12.39278996 3.74633002 1 P 0 
L 12.39278996 3.74633002 12.30658996 3.2575 1 P 0 
L 12.30658996 3.2575 11.96423002 2.76856004 1 P 0 
L 11.96423002 2.76856004 11.91333996 2.47995 1 P 0 
L 11.91333996 2.47995 11.82076004 2.34776004 1 P 0 
L 11.82076004 2.34776004 11.77906004 2.31856004 1 P 0 
L 11.77906004 2.31856004 11.76313002 2.31575 1 P 0 
L 11.76313002 2.31575 11.74941004 2.31575 1 P 0 
L 11.74941004 2.31575 11.73316004 2.332 1 P 0 
P 12.63778996 3.97243996 7 P 0 0;3=2,5=0
P 11.73316004 2.292 5 P 0 0;3=1,5=1
L 12.63778996 3.97243996 12.60796998 3.94261998 1 P 0 
L 12.60796998 3.94261998 12.60796998 3.91071004 1 P 0 
L 12.60796998 3.91071004 12.5875 3.89023996 1 P 0 
L 12.5875 3.89023996 12.5516 3.89023996 1 P 0 
L 12.5516 3.89023996 12.52818002 3.88611004 1 P 0 
L 12.52818002 3.88611004 12.47253002 3.84713996 1 P 0 
L 12.47253002 3.84713996 12.39988996 3.74338996 1 P 0 
L 12.39988996 3.74338996 12.31368996 3.25456004 1 P 0 
L 12.31368996 3.25456004 11.97133002 2.76561998 1 P 0 
L 11.97133002 2.76561998 11.92043996 2.47701004 1 P 0 
L 11.92043996 2.47701004 11.82615 2.34236998 1 P 0 
L 11.82615 2.34236998 11.782 2.31146004 1 P 0 
L 11.782 2.31146004 11.76378996 2.30825 1 P 0 
L 11.76378996 2.30825 11.74941004 2.30825 1 P 0 
L 11.74941004 2.30825 11.73316004 2.292 1 P 0 
P 11.53316004 2.092 5 P 0 0;3=1,5=1
P 12.55905 3.77558996 7 P 0 0;3=2,5=0
L 11.53316004 2.092 11.54941004 2.07575 1 P 0 
L 11.54941004 2.07575 11.5602 2.07575 1 P 0 
L 11.5602 2.07575 11.56021004 2.07576004 1 P 0 
L 11.56021004 2.07576004 11.56791998 2.07711998 1 P 0 
L 11.56791998 2.07711998 11.57461004 2.0818 1 P 0 
L 11.57461004 2.0818 11.57873002 2.0877 1 P 0 
L 11.57873002 2.0877 11.58218002 2.10713002 1 P 0 
L 11.58218002 2.10713002 11.57243002 2.1625 1 P 0 
L 11.57243002 2.1625 11.58011998 2.20626004 1 P 0 
L 11.58011998 2.20626004 11.58811004 2.21768996 1 P 0 
L 11.58811004 2.21768996 11.60908996 2.2323 1 P 0 
L 11.60908996 2.2323 11.66788996 2.24268996 1 P 0 
L 11.66788996 2.24268996 11.66788996 2.2427 1 P 0 
L 11.66788996 2.2427 11.72666998 2.25306998 1 P 0 
L 11.72666998 2.25306998 11.78578002 2.29445 1 P 0 
L 11.78578002 2.29445 11.93901004 2.32146998 1 P 0 
L 11.93901004 2.32146998 12.05795 2.40471998 1 P 0 
L 12.05795 2.40471998 12.14758996 2.53278996 1 P 0 
L 12.14758996 2.53278996 12.2525 3.12771998 1 P 0 
L 12.2525 3.12771998 12.33648002 3.24765 1 P 0 
L 12.33648002 3.24765 12.39845 3.59911004 1 P 0 
L 12.39845 3.59911004 12.4617 3.68945 1 P 0 
L 12.4617 3.68945 12.52866998 3.73633996 1 P 0 
L 12.52866998 3.73633996 12.55093996 3.74026004 1 P 0 
L 12.55093996 3.74026004 12.58438996 3.74026004 1 P 0 
L 12.58438996 3.74026004 12.60046998 3.75633996 1 P 0 
L 12.60046998 3.75633996 12.60046998 3.78936004 1 P 0 
L 12.60046998 3.78936004 12.59676998 3.79306004 1 P 0 
L 12.59676998 3.79306004 12.57651998 3.79306004 1 P 0 
L 12.57651998 3.79306004 12.55905 3.77558996 1 P 0 
P 11.53316004 2.052 5 P 0 0;3=1,5=1
P 12.63778996 3.81496004 7 P 0 0;3=2,5=0
L 11.53316004 2.052 11.54941004 2.06825 1 P 0 
L 11.54941004 2.06825 11.56086998 2.06825 1 P 0 
L 11.56086998 2.06825 11.57086004 2.07001004 1 P 0 
L 11.57086004 2.07001004 11.58001004 2.07641004 1 P 0 
L 11.58001004 2.07641004 11.58583002 2.08476004 1 P 0 
L 11.58583002 2.08476004 11.5898 2.10713002 1 P 0 
L 11.5898 2.10713002 11.58005 2.1625 1 P 0 
L 11.58005 2.1625 11.58721998 2.20331998 1 P 0 
L 11.58721998 2.20331998 11.5935 2.21228996 1 P 0 
L 11.5935 2.21228996 11.61201998 2.2252 1 P 0 
L 11.61201998 2.2252 11.72961004 2.24596998 1 P 0 
L 11.72961004 2.24596998 11.78871998 2.28735 1 P 0 
L 11.78871998 2.28735 11.94195 2.31436998 1 P 0 
L 11.94195 2.31436998 12.06333996 2.39933002 1 P 0 
L 12.06333996 2.39933002 12.15468996 2.52985 1 P 0 
L 12.15468996 2.52985 12.2596 3.12478002 1 P 0 
L 12.2596 3.12478002 12.34358002 3.24471004 1 P 0 
L 12.34358002 3.24471004 12.40555 3.59616998 1 P 0 
L 12.40555 3.59616998 12.46708996 3.68406004 1 P 0 
L 12.46708996 3.68406004 12.53161004 3.72923996 1 P 0 
L 12.53161004 3.72923996 12.5516 3.73276004 1 P 0 
L 12.5516 3.73276004 12.5875 3.73276004 1 P 0 
L 12.5875 3.73276004 12.60796998 3.75323002 1 P 0 
L 12.60796998 3.75323002 12.60796998 3.78513996 1 P 0 
L 12.60796998 3.78513996 12.63778996 3.81496004 1 P 0 
P 11.73316004 1.532 5 P 0 0;3=1,5=1
P 12.55905 2.27953002 7 P 0 0;3=2,5=0
L 12.55905 2.27953002 12.57826998 2.27953002 1 P 0 
L 12.57826998 2.27953002 12.5892 2.2686 1 P 0 
L 12.5892 2.2686 12.5892 2.25221998 1 P 0 
L 12.5892 2.25221998 12.58128002 2.2443 1 P 0 
L 12.58128002 2.2443 12.52463996 2.2443 1 P 0 
L 12.52463996 2.2443 12.491 2.23836998 1 P 0 
L 12.491 2.23836998 12.19433996 2.03061998 1 P 0 
L 12.19433996 2.03061998 12.14931004 1.96628996 1 P 0 
L 12.14931004 1.96628996 11.8427 1.75161998 1 P 0 
L 11.8427 1.75161998 11.72976004 1.73171004 1 P 0 
L 11.72976004 1.73171004 11.72001004 1.72488996 1 P 0 
L 11.72001004 1.72488996 11.71418002 1.71656004 1 P 0 
L 11.71418002 1.71656004 11.70681004 1.67476004 1 P 0 
L 11.70681004 1.67476004 11.7158 1.62381998 1 P 0 
L 11.7158 1.62381998 11.76726998 1.55031998 1 P 0 
L 11.76726998 1.55031998 11.7691 1.53993996 1 P 0 
L 11.7691 1.53993996 11.7691 1.51945 1 P 0 
L 11.7691 1.51945 11.7654 1.51575 1 P 0 
L 11.7654 1.51575 11.74941004 1.51575 1 P 0 
L 11.74941004 1.51575 11.73316004 1.532 1 P 0 
P 11.73316004 2.172 5 P 0 0;3=1,5=1
P 12.55905 3.46063002 7 P 0 0;3=2,5=0
L 11.73316004 2.172 11.74941004 2.15575 1 P 0 
L 11.74941004 2.15575 11.81758996 2.15575 1 P 0 
L 11.81758996 2.15575 11.87635 2.16611004 1 P 0 
L 11.87635 2.16611004 12.08885 2.31488002 1 P 0 
L 12.08885 2.31488002 12.203 2.47791998 1 P 0 
L 12.203 2.47791998 12.31551998 3.11593996 1 P 0 
L 12.31551998 3.11593996 12.40503996 3.24378996 1 P 0 
L 12.40503996 3.24378996 12.417 3.31163002 1 P 0 
L 12.417 3.31163002 12.47315 3.39183996 1 P 0 
L 12.47315 3.39183996 12.51238002 3.4193 1 P 0 
L 12.51238002 3.4193 12.55093996 3.4261 1 P 0 
L 12.55093996 3.4261 12.58518996 3.4261 1 P 0 
L 12.58518996 3.4261 12.60046998 3.44138002 1 P 0 
L 12.60046998 3.44138002 12.60046998 3.4744 1 P 0 
L 12.60046998 3.4744 12.59676998 3.4781 1 P 0 
L 12.59676998 3.4781 12.57651998 3.4781 1 P 0 
L 12.57651998 3.4781 12.55905 3.46063002 1 P 0 
P 11.73316004 2.132 5 P 0 0;3=1,5=1
P 12.63778996 3.5 7 P 0 0;3=2,5=0
L 11.73316004 2.132 11.74941004 2.14825 1 P 0 
L 11.74941004 2.14825 11.81825 2.14825 1 P 0 
L 11.81825 2.14825 11.87928996 2.15901004 1 P 0 
L 11.87928996 2.15901004 12.09423996 2.30948996 1 P 0 
L 12.09423996 2.30948996 12.2101 2.47498002 1 P 0 
L 12.2101 2.47498002 12.32261998 3.113 1 P 0 
L 12.32261998 3.113 12.41213996 3.24085 1 P 0 
L 12.41213996 3.24085 12.4241 3.30868996 1 P 0 
L 12.4241 3.30868996 12.47853996 3.38645 1 P 0 
L 12.47853996 3.38645 12.51531998 3.4122 1 P 0 
L 12.51531998 3.4122 12.5516 3.4186 1 P 0 
L 12.5516 3.4186 12.5883 3.4186 1 P 0 
L 12.5883 3.4186 12.60796998 3.43826998 1 P 0 
L 12.60796998 3.43826998 12.60796998 3.47018002 1 P 0 
L 12.60796998 3.47018002 12.63778996 3.5 1 P 0 
P 11.73316004 2.012 5 P 0 0;3=1,5=1
P 12.63778996 3.1063 7 P 0 0;3=2,5=0
L 12.63778996 3.1063 12.60576998 3.13831998 1 P 0 
L 12.60576998 3.13831998 12.60576998 3.16511004 1 P 0 
L 12.60576998 3.16511004 12.5818 3.18908002 1 P 0 
L 12.5818 3.18908002 12.54678002 3.18908002 1 P 0 
L 12.54678002 3.18908002 12.51575 3.1836 1 P 0 
L 12.51575 3.1836 12.48551004 3.16243002 1 P 0 
L 12.48551004 3.16243002 12.35395 2.97453996 1 P 0 
L 12.35395 2.97453996 12.25681998 2.42356004 1 P 0 
L 12.25681998 2.42356004 12.12816004 2.23978996 1 P 0 
L 12.12816004 2.23978996 11.78583002 2.00008996 1 P 0 
L 11.78583002 2.00008996 11.76121004 1.99575 1 P 0 
L 11.76121004 1.99575 11.74941004 1.99575 1 P 0 
L 11.74941004 1.99575 11.73316004 2.012 1 P 0 
P 11.73316004 1.972 5 P 0 0;3=1,5=1
P 12.55905 3.14566998 7 P 0 0;3=2,5=0
L 12.55905 3.14566998 12.57933996 3.12538002 1 P 0 
L 12.57933996 3.12538002 12.59301004 3.12538002 1 P 0 
L 12.59301004 3.12538002 12.59826998 3.13063996 1 P 0 
L 12.59826998 3.13063996 12.59826998 3.162 1 P 0 
L 12.59826998 3.162 12.57868996 3.18158002 1 P 0 
L 12.57868996 3.18158002 12.54743996 3.18158002 1 P 0 
L 12.54743996 3.18158002 12.51868996 3.1765 1 P 0 
L 12.51868996 3.1765 12.51866998 3.17648002 1 P 0 
L 12.51866998 3.17648002 12.5048 3.16676004 1 P 0 
L 12.5048 3.16676004 12.5048 3.16676998 1 P 0 
L 12.5048 3.16676998 12.4909 3.15703996 1 P 0 
L 12.4909 3.15703996 12.36105 2.9716 1 P 0 
L 12.36105 2.9716 12.26391998 2.42061998 1 P 0 
L 12.26391998 2.42061998 12.13355 2.2344 1 P 0 
L 12.13355 2.2344 11.78876998 1.99298996 1 P 0 
L 11.78876998 1.99298996 11.76186998 1.98825 1 P 0 
L 11.76186998 1.98825 11.74941004 1.98825 1 P 0 
L 11.74941004 1.98825 11.73316004 1.972 1 P 0 
P 11.53316004 1.732 5 P 0 0;3=1,5=1
P 12.55905 2.98818996 7 P 0 0;3=2,5=0
L 11.53316004 1.732 11.54941004 1.74825 1 P 0 
L 11.54941004 1.74825 11.56071998 1.74825 1 P 0 
L 11.56071998 1.74825 11.57316998 1.75696004 1 P 0 
L 11.57316998 1.75696004 11.5819 1.76941998 1 P 0 
L 11.5819 1.76941998 11.58508996 1.7875 1 P 0 
L 11.58508996 1.7875 11.57881998 1.82301004 1 P 0 
L 11.57881998 1.82301004 11.58688996 1.86868002 1 P 0 
L 11.58688996 1.86868002 11.60023002 1.88776998 1 P 0 
L 11.60023002 1.88776998 11.60953996 1.89428002 1 P 0 
L 11.60953996 1.89428002 11.76841998 1.9223 1 P 0 
L 11.76841998 1.9223 12.13908002 2.18181998 1 P 0 
L 12.13908002 2.18181998 12.29508002 2.40461004 1 P 0 
L 12.29508002 2.40461004 12.37648002 2.86633996 1 P 0 
L 12.37648002 2.86633996 12.46238996 2.98903996 1 P 0 
L 12.46238996 2.98903996 12.50313996 3.01756998 1 P 0 
L 12.50313996 3.01756998 12.5402 3.0241 1 P 0 
L 12.5402 3.0241 12.57868996 3.0241 1 P 0 
L 12.57868996 3.0241 12.59826998 3.00451998 1 P 0 
L 12.59826998 3.00451998 12.59826998 2.97316004 1 P 0 
L 12.59826998 2.97316004 12.59301004 2.9679 1 P 0 
L 12.59301004 2.9679 12.57933996 2.9679 1 P 0 
L 12.57933996 2.9679 12.55905 2.98818996 1 P 0 
P 11.53316004 1.772 5 P 0 0;3=1,5=1
P 12.63778996 2.94881998 7 P 0 0;3=2,5=0
L 11.53316004 1.772 11.54941004 1.75575 1 P 0 
L 11.54941004 1.75575 11.55833996 1.75575 1 P 0 
L 11.55833996 1.75575 11.56778002 1.76235 1 P 0 
L 11.56778002 1.76235 11.5748 1.77236004 1 P 0 
L 11.5748 1.77236004 11.57746998 1.7875 1 P 0 
L 11.57746998 1.7875 11.5712 1.82301004 1 P 0 
L 11.5712 1.82301004 11.57978996 1.87161998 1 P 0 
L 11.57978996 1.87161998 11.59483996 1.89316004 1 P 0 
L 11.59483996 1.89316004 11.6066 1.90138002 1 P 0 
L 11.6066 1.90138002 11.76548002 1.9294 1 P 0 
L 11.76548002 1.9294 12.13368996 2.18721004 1 P 0 
L 12.13368996 2.18721004 12.28798002 2.40755 1 P 0 
L 12.28798002 2.40755 12.36938002 2.86928002 1 P 0 
L 12.36938002 2.86928002 12.457 2.99443002 1 P 0 
L 12.457 2.99443002 12.5002 3.02466998 1 P 0 
L 12.5002 3.02466998 12.53953996 3.0316 1 P 0 
L 12.53953996 3.0316 12.5818 3.0316 1 P 0 
L 12.5818 3.0316 12.60576998 3.00763002 1 P 0 
L 12.60576998 3.00763002 12.60576998 2.98083996 1 P 0 
L 12.60576998 2.98083996 12.63778996 2.94881998 1 P 0 
P 12.63778996 2.79133996 7 P 0 0;3=2,5=0
P 11.73316004 1.852 5 P 0 0;3=1,5=1
L 11.73316004 1.852 11.74941004 1.83575 1 P 0 
L 11.74941004 1.83575 11.77016998 1.83575 1 P 0 
L 11.77016998 1.83575 11.78843996 1.83898002 1 P 0 
L 11.78843996 1.83898002 12.0761 2.0404 1 P 0 
L 12.0761 2.0404 12.31631998 2.38343002 1 P 0 
L 12.31631998 2.38343002 12.3726 2.70261998 1 P 0 
L 12.3726 2.70261998 12.47433996 2.84791004 1 P 0 
L 12.47433996 2.84791004 12.50243996 2.86758002 1 P 0 
L 12.50243996 2.86758002 12.53953996 2.87411998 1 P 0 
L 12.53953996 2.87411998 12.5818 2.87411998 1 P 0 
L 12.5818 2.87411998 12.60576998 2.85015 1 P 0 
L 12.60576998 2.85015 12.60576998 2.82336004 1 P 0 
L 12.60576998 2.82336004 12.63778996 2.79133996 1 P 0 
P 12.55905 2.83071004 7 P 0 0;3=2,5=0
P 11.73316004 1.812 5 P 0 0;3=1,5=1
L 11.73316004 1.812 11.74941004 1.82825 1 P 0 
L 11.74941004 1.82825 11.77083002 1.82825 1 P 0 
L 11.77083002 1.82825 11.79138002 1.83188002 1 P 0 
L 11.79138002 1.83188002 12.08148996 2.03501004 1 P 0 
L 12.08148996 2.03501004 12.32341998 2.38048996 1 P 0 
L 12.32341998 2.38048996 12.3797 2.69968002 1 P 0 
L 12.3797 2.69968002 12.47973002 2.84251998 1 P 0 
L 12.47973002 2.84251998 12.50538002 2.86048002 1 P 0 
L 12.50538002 2.86048002 12.5402 2.86661998 1 P 0 
L 12.5402 2.86661998 12.57868996 2.86661998 1 P 0 
L 12.57868996 2.86661998 12.59826998 2.84703996 1 P 0 
L 12.59826998 2.84703996 12.59826998 2.81568002 1 P 0 
L 12.59826998 2.81568002 12.59301004 2.81041998 1 P 0 
L 12.59301004 2.81041998 12.57933996 2.81041998 1 P 0 
L 12.57933996 2.81041998 12.55905 2.83071004 1 P 0 
L 1.88908002 -1.91246004 1.89293002 -1.91246004 0 P 0 ;0
L 1.89126998 -1.91146004 1.89656998 -1.91146004 0 P 0 ;0
L 1.89393996 -1.91046004 1.9155 -1.91046004 0 P 0 ;0
L 1.91593996 -1.91246004 1.92048996 -1.91246004 0 P 0 ;0
L 1.9126 -1.91146004 1.9184 -1.91146004 0 P 0 ;0
L 1.89763002 -1.90946004 1.91016998 -1.90946004 0 P 0 ;0
L 1.89053002 -1.96001004 1.8974 -1.96001004 0 P 0 ;0
L 1.89053002 -1.95901004 1.8974 -1.95901004 0 P 0 ;0
L 1.89053002 -1.95801004 1.8974 -1.95801004 0 P 0 ;0
L 1.89053002 -1.95701004 1.8974 -1.95701004 0 P 0 ;0
L 1.89053002 -1.95601004 1.8974 -1.95601004 0 P 0 ;0
L 1.89053002 -1.95501004 1.8974 -1.95501004 0 P 0 ;0
L 1.89053002 -1.95401004 1.8974 -1.95401004 0 P 0 ;0
L 1.89053002 -1.95301004 1.89741004 -1.95301004 0 P 0 ;0
L 1.89053002 -1.95201004 1.89741998 -1.95201004 0 P 0 ;0
L 1.89053002 -1.95101004 1.89743996 -1.95101004 0 P 0 ;0
L 1.89053002 -1.95001004 1.89745 -1.95001004 0 P 0 ;0
L 1.89053002 -1.94901004 1.89746004 -1.94901004 0 P 0 ;0
L 1.89053002 -1.94801004 1.89753002 -1.94801004 0 P 0 ;0
L 1.89053002 -1.94701004 1.8977 -1.94701004 0 P 0 ;0
L 1.89053002 -1.94601004 1.89798002 -1.94601004 0 P 0 ;0
L 1.89053002 -1.94501004 1.89861004 -1.94501004 0 P 0 ;0
L 1.89053002 -1.94401004 1.90005 -1.94401004 0 P 0 ;0
L 1.89053002 -1.94301004 1.9113 -1.94301004 0 P 0 ;0
L 1.89053002 -1.94201004 1.91168002 -1.94201004 0 P 0 ;0
L 1.89053002 -1.94101004 1.91246998 -1.94101004 0 P 0 ;0
L 1.89053002 -1.94001004 1.90093996 -1.94001004 0 P 0 ;0
L 1.89053002 -1.93901004 1.89856004 -1.93901004 0 P 0 ;0
L 1.89053002 -1.93801004 1.89786998 -1.93801004 0 P 0 ;0
L 1.89053002 -1.93701004 1.89753996 -1.93701004 0 P 0 ;0
L 1.89053002 -1.93601004 1.89746998 -1.93601004 0 P 0 ;0
L 1.89053002 -1.93501004 1.89743996 -1.93501004 0 P 0 ;0
L 1.89053002 -1.93401004 1.89741998 -1.93401004 0 P 0 ;0
L 1.89053002 -1.93301004 1.8974 -1.93301004 0 P 0 ;0
L 1.89053002 -1.93201004 1.8974 -1.93201004 0 P 0 ;0
L 1.89053002 -1.93101004 1.8974 -1.93101004 0 P 0 ;0
L 1.89053002 -1.93001004 1.8974 -1.93001004 0 P 0 ;0
L 1.89053002 -1.92901004 1.8974 -1.92901004 0 P 0 ;0
L 1.89053002 -1.92801004 1.89753002 -1.92801004 0 P 0 ;0
L 1.89053002 -1.92701004 1.89793996 -1.92701004 0 P 0 ;0
L 1.89053002 -1.92601004 1.91713002 -1.92601004 0 P 0 ;0
L 1.89053002 -1.92501004 1.91628996 -1.92501004 0 P 0 ;0
L 1.89053002 -1.92401004 1.91513996 -1.92401004 0 P 0 ;0
L 1.89053002 -1.92301004 1.91321998 -1.92301004 0 P 0 ;0
L 1.89053002 -1.92201004 1.90551004 -1.92201004 0 P 0 ;0
L 1.89438996 -1.97246004 1.91331004 -1.97246004 0 P 0 ;0
L 1.89106998 -1.97146004 1.89973002 -1.97146004 0 P 0 ;0
L 1.88878002 -1.97046004 1.8949 -1.97046004 0 P 0 ;0
L 1.88698002 -1.96946004 1.89206998 -1.96946004 0 P 0 ;0
L 1.88546004 -1.96846004 1.88986998 -1.96846004 0 P 0 ;0
L 1.88416998 -1.96746004 1.88808996 -1.96746004 0 P 0 ;0
L 1.88288002 -1.96646004 1.88655 -1.96646004 0 P 0 ;0
L 1.88176998 -1.96546004 1.88518002 -1.96546004 0 P 0 ;0
L 1.88068996 -1.96446004 1.88393996 -1.96446004 0 P 0 ;0
L 1.87968996 -1.96346004 1.88286004 -1.96346004 0 P 0 ;0
L 1.87878002 -1.96246004 1.88186004 -1.96246004 0 P 0 ;0
L 1.8786 -1.92046004 1.88126998 -1.92046004 0 P 0 ;0
L 1.87946998 -1.91946004 1.88223002 -1.91946004 0 P 0 ;0
L 1.88048002 -1.91846004 1.88321004 -1.91846004 0 P 0 ;0
L 1.88153996 -1.91746004 1.88436998 -1.91746004 0 P 0 ;0
L 1.88273002 -1.91646004 1.88558996 -1.91646004 0 P 0 ;0
L 1.88406004 -1.91546004 1.88696998 -1.91546004 0 P 0 ;0
L 1.88548996 -1.91446004 1.88853002 -1.91446004 0 P 0 ;0
L 1.88718002 -1.91346004 1.89041998 -1.91346004 0 P 0 ;0
L 1.90896004 -1.92963996 1.90921998 -1.92991998 0 P 0 ;0
L 1.90921998 -1.92991998 1.90945 -1.93021998 0 P 0 ;0
L 1.90945 -1.93021998 1.90966004 -1.93053002 0 P 0 ;0
L 1.90966004 -1.93053002 1.90983002 -1.93086004 0 P 0 ;0
L 1.90983002 -1.93086004 1.90998002 -1.93121004 0 P 0 ;0
L 1.90998002 -1.93121004 1.9101 -1.93156998 0 P 0 ;0
L 1.9101 -1.93156998 1.91018996 -1.93193996 0 P 0 ;0
L 1.91018996 -1.93193996 1.91023996 -1.93231004 0 P 0 ;0
L 1.91023996 -1.93231004 1.91026998 -1.93265 0 P 0 ;0
L 1.91026998 -1.93265 1.91026004 -1.93298002 0 P 0 ;0
L 1.91026004 -1.93298002 1.91023002 -1.93331004 0 P 0 ;0
L 1.91023002 -1.93331004 1.91016998 -1.93363996 0 P 0 ;0
L 1.91016998 -1.93363996 1.91008996 -1.93396004 0 P 0 ;0
L 1.91008996 -1.93396004 1.90998002 -1.93428002 0 P 0 ;0
L 1.90998002 -1.93428002 1.90983996 -1.93458002 0 P 0 ;0
L 1.90983996 -1.93458002 1.90968996 -1.93486998 0 P 0 ;0
L 1.90968996 -1.93486998 1.90951004 -1.93516004 0 P 0 ;0
L 1.90951004 -1.93516004 1.90921004 -1.93556004 0 P 0 ;0
L 1.90921004 -1.93556004 1.90888002 -1.93593002 0 P 0 ;0
L 1.90888002 -1.93593002 1.90853002 -1.93626998 0 P 0 ;0
L 1.90853002 -1.93626998 1.90815 -1.93658996 0 P 0 ;0
L 1.90815 -1.93658996 1.90773996 -1.93686998 0 P 0 ;0
L 1.90773996 -1.93686998 1.90731998 -1.93711998 0 P 0 ;0
L 1.90731998 -1.93711998 1.90686998 -1.93733996 0 P 0 ;0
L 1.90686998 -1.93733996 1.90615 -1.93761004 0 P 0 ;0
L 1.90615 -1.93761004 1.90541998 -1.93783002 0 P 0 ;0
L 1.90541998 -1.93783002 1.90466004 -1.93798002 0 P 0 ;0
L 1.90466004 -1.93798002 1.9039 -1.93808002 0 P 0 ;0
L 1.9039 -1.93808002 1.90311998 -1.9381 0 P 0 ;0
L 1.90311998 -1.9381 1.90196004 -1.93808002 0 P 0 ;0
L 1.90196004 -1.93808002 1.90078996 -1.93798996 0 P 0 ;0
L 1.90078996 -1.93798996 1.90068002 -1.93798002 0 P 0 ;0
L 1.90068002 -1.93798002 1.90058002 -1.93795 0 P 0 ;0
L 1.90058002 -1.93795 1.90046998 -1.93791998 0 P 0 ;0
L 1.90046998 -1.93791998 1.90038002 -1.93788002 0 P 0 ;0
L 1.90038002 -1.93788002 1.90028002 -1.93783002 0 P 0 ;0
L 1.90028002 -1.93783002 1.90018996 -1.93778002 0 P 0 ;0
L 1.90018996 -1.93778002 1.9001 -1.93771004 0 P 0 ;0
L 1.9001 -1.93771004 1.90001998 -1.93763996 0 P 0 ;0
L 1.90001998 -1.93763996 1.89988002 -1.93748002 0 P 0 ;0
L 1.89988002 -1.93748002 1.89978002 -1.93733996 0 P 0 ;0
L 1.89978002 -1.93733996 1.89961998 -1.93703996 0 P 0 ;0
L 1.89961998 -1.93703996 1.89956998 -1.93688002 0 P 0 ;0
L 1.89956998 -1.93688002 1.89951998 -1.93671004 0 P 0 ;0
L 1.89951998 -1.93671004 1.89948996 -1.93655 0 P 0 ;0
L 1.89948996 -1.93655 1.89946998 -1.93636998 0 P 0 ;0
L 1.89946998 -1.93636998 1.8994 -1.93323002 0 P 0 ;0
L 1.8994 -1.93323002 1.8994 -1.92833002 0 P 0 ;0
L 1.8994 -1.92833002 1.90353996 -1.92833002 0 P 0 ;0
L 1.90353996 -1.92833002 1.90436998 -1.92835 0 P 0 ;0
L 1.90436998 -1.92835 1.9052 -1.92843002 0 P 0 ;0
L 1.9052 -1.92843002 1.90603002 -1.92853996 0 P 0 ;0
L 1.90603002 -1.92853996 1.90683996 -1.92871004 0 P 0 ;0
L 1.90683996 -1.92871004 1.90751004 -1.9289 0 P 0 ;0
L 1.90751004 -1.9289 1.90818002 -1.92913002 0 P 0 ;0
L 1.90818002 -1.92913002 1.90851998 -1.92928996 0 P 0 ;0
L 1.90851998 -1.92928996 1.90868002 -1.92938996 0 P 0 ;0
L 1.90868002 -1.92938996 1.90883002 -1.92951004 0 P 0 ;0
L 1.90883002 -1.92951004 1.90896004 -1.92963996 0 P 0 ;0
L 1.91188996 -1.96001004 1.91638996 -1.96001004 0 P 0 ;0
L 1.91156998 -1.95901004 1.91926998 -1.95901004 0 P 0 ;0
L 1.91125 -1.95801004 1.91891998 -1.95801004 0 P 0 ;0
L 1.91091998 -1.95701004 1.91853002 -1.95701004 0 P 0 ;0
L 1.9106 -1.95601004 1.91811004 -1.95601004 0 P 0 ;0
L 1.91025 -1.95501004 1.91765 -1.95501004 0 P 0 ;0
L 1.90988996 -1.95401004 1.91718996 -1.95401004 0 P 0 ;0
L 1.90953002 -1.95301004 1.91673002 -1.95301004 0 P 0 ;0
L 1.90918002 -1.95201004 1.91626998 -1.95201004 0 P 0 ;0
L 1.90881998 -1.95101004 1.91576004 -1.95101004 0 P 0 ;0
L 1.90841004 -1.95001004 1.91523996 -1.95001004 0 P 0 ;0
L 1.90793996 -1.94901004 1.91471004 -1.94901004 0 P 0 ;0
L 1.90738996 -1.94801004 1.91418002 -1.94801004 0 P 0 ;0
L 1.90676998 -1.94701004 1.9136 -1.94701004 0 P 0 ;0
L 1.90598996 -1.94601004 1.91261004 -1.94601004 0 P 0 ;0
L 1.90495 -1.94501004 1.91175 -1.94501004 0 P 0 ;0
L 1.90325 -1.94401004 1.91133002 -1.94401004 0 P 0 ;0
L 1.90456004 -1.94001004 1.91383002 -1.94001004 0 P 0 ;0
L 1.90801004 -1.93901004 1.91523002 -1.93901004 0 P 0 ;0
L 1.90956998 -1.93801004 1.91635 -1.93801004 0 P 0 ;0
L 1.9106 -1.93701004 1.91718002 -1.93701004 0 P 0 ;0
L 1.91133996 -1.93601004 1.91781004 -1.93601004 0 P 0 ;0
L 1.91183996 -1.93501004 1.91826004 -1.93501004 0 P 0 ;0
L 1.91213002 -1.93401004 1.9186 -1.93401004 0 P 0 ;0
L 1.91226004 -1.93301004 1.9188 -1.93301004 0 P 0 ;0
L 1.91221998 -1.93201004 1.9189 -1.93201004 0 P 0 ;0
L 1.91201998 -1.93101004 1.9189 -1.93101004 0 P 0 ;0
L 1.91163996 -1.93001004 1.91878996 -1.93001004 0 P 0 ;0
L 1.91105 -1.92901004 1.91856998 -1.92901004 0 P 0 ;0
L 1.91013996 -1.92801004 1.91823002 -1.92801004 0 P 0 ;0
L 1.90816998 -1.92701004 1.91776004 -1.92701004 0 P 0 ;0
L 1.90313996 -1.94011004 1.90316998 -1.9401 0 P 0 ;0
L 1.90316998 -1.9401 1.9032 -1.9401 0 P 0 ;0
L 1.9032 -1.9401 1.90398002 -1.94006998 0 P 0 ;0
L 1.90398002 -1.94006998 1.90406004 -1.94006998 0 P 0 ;0
L 1.90406004 -1.94006998 1.90413996 -1.94006004 0 P 0 ;0
L 1.90413996 -1.94006004 1.9049 -1.93996998 0 P 0 ;0
L 1.9049 -1.93996998 1.90493996 -1.93996004 0 P 0 ;0
L 1.90493996 -1.93996004 1.90498996 -1.93996004 0 P 0 ;0
L 1.90498996 -1.93996004 1.90506998 -1.93993996 0 P 0 ;0
L 1.90506998 -1.93993996 1.90581998 -1.93978002 0 P 0 ;0
L 1.90581998 -1.93978002 1.90586004 -1.93978002 0 P 0 ;0
L 1.90586004 -1.93978002 1.90593996 -1.93976004 0 P 0 ;0
L 1.90593996 -1.93976004 1.90596998 -1.93973996 0 P 0 ;0
L 1.90596998 -1.93973996 1.90671004 -1.93953002 0 P 0 ;0
L 1.90671004 -1.93953002 1.90678996 -1.93951004 0 P 0 ;0
L 1.90678996 -1.93951004 1.90758996 -1.93921004 0 P 0 ;0
L 1.90758996 -1.93921004 1.90766004 -1.93916998 0 P 0 ;0
L 1.90766004 -1.93916998 1.9077 -1.93915 0 P 0 ;0
L 1.9077 -1.93915 1.90773996 -1.93913996 0 P 0 ;0
L 1.90773996 -1.93913996 1.90818996 -1.93891998 0 P 0 ;0
L 1.90818996 -1.93891998 1.90821998 -1.9389 0 P 0 ;0
L 1.90821998 -1.9389 1.90826004 -1.93888996 0 P 0 ;0
L 1.90826004 -1.93888996 1.90828996 -1.93886998 0 P 0 ;0
L 1.90828996 -1.93886998 1.90833002 -1.93885 0 P 0 ;0
L 1.90833002 -1.93885 1.90875 -1.9386 0 P 0 ;0
L 1.90875 -1.9386 1.90883002 -1.93856004 0 P 0 ;0
L 1.90883002 -1.93856004 1.90888996 -1.93851004 0 P 0 ;0
L 1.90888996 -1.93851004 1.90928996 -1.93823002 0 P 0 ;0
L 1.90928996 -1.93823002 1.90933002 -1.9382 0 P 0 ;0
L 1.90933002 -1.9382 1.90936004 -1.93818002 0 P 0 ;0
L 1.90936004 -1.93818002 1.90938996 -1.93815 0 P 0 ;0
L 1.90938996 -1.93815 1.90941998 -1.93813002 0 P 0 ;0
L 1.90941998 -1.93813002 1.9098 -1.93781998 0 P 0 ;0
L 1.9098 -1.93781998 1.90986004 -1.93776004 0 P 0 ;0
L 1.90986004 -1.93776004 1.90988996 -1.93773996 0 P 0 ;0
L 1.90988996 -1.93773996 1.90991998 -1.93771004 0 P 0 ;0
L 1.90991998 -1.93771004 1.91028002 -1.93736004 0 P 0 ;0
L 1.91028002 -1.93736004 1.91038996 -1.93725 0 P 0 ;0
L 1.91038996 -1.93725 1.91071004 -1.93688002 0 P 0 ;0
L 1.91071004 -1.93688002 1.91073996 -1.93685 0 P 0 ;0
L 1.91073996 -1.93685 1.91116004 -1.9363 0 P 0 ;0
L 1.91116004 -1.9363 1.9112 -1.93623002 0 P 0 ;0
L 1.9112 -1.93623002 1.91138002 -1.93595 0 P 0 ;0
L 1.91138002 -1.93595 1.9114 -1.93591004 0 P 0 ;0
L 1.9114 -1.93591004 1.91143996 -1.93585 0 P 0 ;0
L 1.91143996 -1.93585 1.91146004 -1.93581004 0 P 0 ;0
L 1.91146004 -1.93581004 1.91161004 -1.93551998 0 P 0 ;0
L 1.91161004 -1.93551998 1.91163002 -1.93548996 0 P 0 ;0
L 1.91163002 -1.93548996 1.91165 -1.93545 0 P 0 ;0
L 1.91165 -1.93545 1.91166004 -1.93541004 0 P 0 ;0
L 1.91166004 -1.93541004 1.91168002 -1.93538002 0 P 0 ;0
L 1.91168002 -1.93538002 1.91181004 -1.93506998 0 P 0 ;0
L 1.91181004 -1.93506998 1.91183996 -1.935 0 P 0 ;0
L 1.91183996 -1.935 1.91186004 -1.93496004 0 P 0 ;0
L 1.91186004 -1.93496004 1.91186998 -1.93493002 0 P 0 ;0
L 1.91186998 -1.93493002 1.91198002 -1.93461004 0 P 0 ;0
L 1.91198002 -1.93461004 1.91198996 -1.93456998 0 P 0 ;0
L 1.91198996 -1.93456998 1.912 -1.93453996 0 P 0 ;0
L 1.912 -1.93453996 1.9121 -1.93413996 0 P 0 ;0
L 1.9121 -1.93413996 1.91211998 -1.9341 0 P 0 ;0
L 1.91211998 -1.9341 1.91211998 -1.93406004 0 P 0 ;0
L 1.91211998 -1.93406004 1.91213002 -1.93401998 0 P 0 ;0
L 1.91213002 -1.93401998 1.91213996 -1.93398996 0 P 0 ;0
L 1.91213996 -1.93398996 1.9122 -1.93366004 0 P 0 ;0
L 1.9122 -1.93366004 1.91221004 -1.93358002 0 P 0 ;0
L 1.91221004 -1.93358002 1.91221004 -1.93353996 0 P 0 ;0
L 1.91221004 -1.93353996 1.91221998 -1.9335 0 P 0 ;0
L 1.91221998 -1.9335 1.91225 -1.93316998 0 P 0 ;0
L 1.91225 -1.93316998 1.91226004 -1.93308996 0 P 0 ;0
L 1.91226004 -1.93308996 1.91226004 -1.93268002 0 P 0 ;0
L 1.91226004 -1.93268002 1.91226998 -1.93263996 0 P 0 ;0
L 1.91226998 -1.93263996 1.91226998 -1.9326 0 P 0 ;0
L 1.91226998 -1.9326 1.91226004 -1.93251998 0 P 0 ;0
L 1.91226004 -1.93251998 1.91223996 -1.93218996 0 P 0 ;0
L 1.91223996 -1.93218996 1.91223996 -1.93215 0 P 0 ;0
L 1.91223996 -1.93215 1.91223002 -1.9321 0 P 0 ;0
L 1.91223002 -1.9321 1.91223002 -1.93206004 0 P 0 ;0
L 1.91223002 -1.93206004 1.91221998 -1.93201998 0 P 0 ;0
L 1.91221998 -1.93201998 1.91216998 -1.93163996 0 P 0 ;0
L 1.91216998 -1.93163996 1.91216004 -1.9316 0 P 0 ;0
L 1.91216004 -1.9316 1.91213996 -1.93151004 0 P 0 ;0
L 1.91213996 -1.93151004 1.91213002 -1.93146998 0 P 0 ;0
L 1.91213002 -1.93146998 1.91205 -1.93111004 0 P 0 ;0
L 1.91205 -1.93111004 1.91203996 -1.93106004 0 P 0 ;0
L 1.91203996 -1.93106004 1.91203002 -1.93101998 0 P 0 ;0
L 1.91203002 -1.93101998 1.91201004 -1.93098002 0 P 0 ;0
L 1.91201004 -1.93098002 1.912 -1.93093996 0 P 0 ;0
L 1.912 -1.93093996 1.91188002 -1.93058002 0 P 0 ;0
L 1.91188002 -1.93058002 1.91186998 -1.93053996 0 P 0 ;0
L 1.91186998 -1.93053996 1.91185 -1.9305 0 P 0 ;0
L 1.91185 -1.9305 1.91183996 -1.93046004 0 P 0 ;0
L 1.91183996 -1.93046004 1.91181998 -1.93043002 0 P 0 ;0
L 1.91181998 -1.93043002 1.91166998 -1.93008002 0 P 0 ;0
L 1.91166998 -1.93008002 1.91166004 -1.93003996 0 P 0 ;0
L 1.91166004 -1.93003996 1.9116 -1.92991998 0 P 0 ;0
L 1.9116 -1.92991998 1.91141998 -1.92958996 0 P 0 ;0
L 1.91141998 -1.92958996 1.9114 -1.92955 0 P 0 ;0
L 1.9114 -1.92955 1.91138002 -1.92951998 0 P 0 ;0
L 1.91138002 -1.92951998 1.91133002 -1.92945 0 P 0 ;0
L 1.91133002 -1.92945 1.91113002 -1.92913002 0 P 0 ;0
L 1.91113002 -1.92913002 1.91111004 -1.92908996 0 P 0 ;0
L 1.91111004 -1.92908996 1.91108996 -1.92906004 0 P 0 ;0
L 1.91108996 -1.92906004 1.91106004 -1.92901998 0 P 0 ;0
L 1.91106004 -1.92901998 1.91103002 -1.92898996 0 P 0 ;0
L 1.91103002 -1.92898996 1.9108 -1.92868996 0 P 0 ;0
L 1.9108 -1.92868996 1.91076998 -1.92866004 0 P 0 ;0
L 1.91076998 -1.92866004 1.91075 -1.92861998 0 P 0 ;0
L 1.91075 -1.92861998 1.91068996 -1.92856004 0 P 0 ;0
L 1.91068996 -1.92856004 1.91043002 -1.92828002 0 P 0 ;0
L 1.91043002 -1.92828002 1.91035 -1.9282 0 P 0 ;0
L 1.91035 -1.9282 1.91033002 -1.92816998 0 P 0 ;0
L 1.91033002 -1.92816998 1.91018996 -1.92803996 0 P 0 ;0
L 1.91018996 -1.92803996 1.91018002 -1.92803996 0 P 0 ;0
L 1.91018002 -1.92803996 1.91016004 -1.92801998 0 P 0 ;0
L 1.91016004 -1.92801998 1.91011998 -1.92798996 0 P 0 ;0
L 1.91011998 -1.92798996 1.91006004 -1.92793002 0 P 0 ;0
L 1.91006004 -1.92793002 1.90991004 -1.92781998 0 P 0 ;0
L 1.90991004 -1.92781998 1.90988002 -1.9278 0 P 0 ;0
L 1.90988002 -1.9278 1.90983996 -1.92776998 0 P 0 ;0
L 1.90983996 -1.92776998 1.90976998 -1.92771998 0 P 0 ;0
L 1.90976998 -1.92771998 1.90961004 -1.92761998 0 P 0 ;0
L 1.90961004 -1.92761998 1.90953996 -1.92756998 0 P 0 ;0
L 1.90953996 -1.92756998 1.9095 -1.92755 0 P 0 ;0
L 1.9095 -1.92755 1.90946998 -1.92753002 0 P 0 ;0
L 1.90946998 -1.92753002 1.9093 -1.92743996 0 P 0 ;0
L 1.9093 -1.92743996 1.90926004 -1.92741998 0 P 0 ;0
L 1.90926004 -1.92741998 1.90923002 -1.9274 0 P 0 ;0
L 1.90923002 -1.9274 1.90915 -1.92736998 0 P 0 ;0
L 1.90915 -1.92736998 1.90896998 -1.92728996 0 P 0 ;0
L 1.90896998 -1.92728996 1.90893996 -1.92728002 0 P 0 ;0
L 1.90893996 -1.92728002 1.9089 -1.92726004 0 P 0 ;0
L 1.9089 -1.92726004 1.90886998 -1.92725 0 P 0 ;0
L 1.90886998 -1.92725 1.90883002 -1.92723996 0 P 0 ;0
L 1.90883002 -1.92723996 1.90816004 -1.92701004 0 P 0 ;0
L 1.90816004 -1.92701004 1.90813996 -1.927 0 P 0 ;0
L 1.90813996 -1.927 1.9081 -1.92698996 0 P 0 ;0
L 1.9081 -1.92698996 1.90803996 -1.92696998 0 P 0 ;0
L 1.90803996 -1.92696998 1.90736998 -1.92678002 0 P 0 ;0
L 1.90736998 -1.92678002 1.90723996 -1.92675 0 P 0 ;0
L 1.90723996 -1.92675 1.90643002 -1.92658996 0 P 0 ;0
L 1.90643002 -1.92658996 1.90636998 -1.92656998 0 P 0 ;0
L 1.90636998 -1.92656998 1.90633996 -1.92656998 0 P 0 ;0
L 1.90633996 -1.92656998 1.90631004 -1.92656004 0 P 0 ;0
L 1.90631004 -1.92656004 1.90548996 -1.92645 0 P 0 ;0
L 1.90548996 -1.92645 1.90543996 -1.92643996 0 P 0 ;0
L 1.90543996 -1.92643996 1.9054 -1.92643002 0 P 0 ;0
L 1.9054 -1.92643002 1.90538002 -1.92643002 0 P 0 ;0
L 1.90538002 -1.92643002 1.90455 -1.92636004 0 P 0 ;0
L 1.90455 -1.92636004 1.90443002 -1.92636004 0 P 0 ;0
L 1.90443002 -1.92636004 1.9036 -1.92633002 0 P 0 ;0
L 1.9036 -1.92633002 1.8994 -1.92633002 0 P 0 ;0
L 1.8994 -1.92633002 1.89798002 -1.92691004 0 P 0 ;0
L 1.89798002 -1.92691004 1.8974 -1.92833002 0 P 0 ;0
L 1.8974 -1.92833002 1.8974 -1.93328002 0 P 0 ;0
L 1.8974 -1.93328002 1.89748002 -1.93643002 0 P 0 ;0
L 1.89748002 -1.93643002 1.89748002 -1.93656004 0 P 0 ;0
L 1.89748002 -1.93656004 1.8975 -1.93673002 0 P 0 ;0
L 1.8975 -1.93673002 1.89751004 -1.93681004 0 P 0 ;0
L 1.89751004 -1.93681004 1.89751998 -1.9369 0 P 0 ;0
L 1.89751998 -1.9369 1.89755 -1.93706004 0 P 0 ;0
L 1.89755 -1.93706004 1.89758002 -1.93718996 0 P 0 ;0
L 1.89758002 -1.93718996 1.89758996 -1.93723002 0 P 0 ;0
L 1.89758996 -1.93723002 1.89763002 -1.9374 0 P 0 ;0
L 1.89763002 -1.9374 1.89763996 -1.93743996 0 P 0 ;0
L 1.89763996 -1.93743996 1.89766004 -1.93748002 0 P 0 ;0
L 1.89766004 -1.93748002 1.89768002 -1.93756004 0 P 0 ;0
L 1.89768002 -1.93756004 1.89773996 -1.93771998 0 P 0 ;0
L 1.89773996 -1.93771998 1.89776004 -1.93776004 0 P 0 ;0
L 1.89776004 -1.93776004 1.89776998 -1.9378 0 P 0 ;0
L 1.89776998 -1.9378 1.89781004 -1.93788002 0 P 0 ;0
L 1.89781004 -1.93788002 1.89788002 -1.93803996 0 P 0 ;0
L 1.89788002 -1.93803996 1.8979 -1.93808002 0 P 0 ;0
L 1.8979 -1.93808002 1.89791998 -1.93811004 0 P 0 ;0
L 1.89791998 -1.93811004 1.89796004 -1.93818996 0 P 0 ;0
L 1.89796004 -1.93818996 1.89803996 -1.93833996 0 P 0 ;0
L 1.89803996 -1.93833996 1.89813996 -1.93848002 0 P 0 ;0
L 1.89813996 -1.93848002 1.89823002 -1.93861998 0 P 0 ;0
L 1.89823002 -1.93861998 1.89828002 -1.93868996 0 P 0 ;0
L 1.89828002 -1.93868996 1.89831004 -1.93873002 0 P 0 ;0
L 1.89831004 -1.93873002 1.89833996 -1.93876004 0 P 0 ;0
L 1.89833996 -1.93876004 1.8984 -1.93883996 0 P 0 ;0
L 1.8984 -1.93883996 1.89848996 -1.93893002 0 P 0 ;0
L 1.89848996 -1.93893002 1.89851004 -1.93896004 0 P 0 ;0
L 1.89851004 -1.93896004 1.89868002 -1.93913002 0 P 0 ;0
L 1.89868002 -1.93913002 1.89871004 -1.93915 0 P 0 ;0
L 1.89871004 -1.93915 1.89878996 -1.93921998 0 P 0 ;0
L 1.89878996 -1.93921998 1.89885 -1.93928002 0 P 0 ;0
L 1.89885 -1.93928002 1.89888002 -1.9393 0 P 0 ;0
L 1.89888002 -1.9393 1.89891998 -1.93931998 0 P 0 ;0
L 1.89891998 -1.93931998 1.89901004 -1.93938996 0 P 0 ;0
L 1.89901004 -1.93938996 1.89903996 -1.93941004 0 P 0 ;0
L 1.89903996 -1.93941004 1.89906998 -1.93943996 0 P 0 ;0
L 1.89906998 -1.93943996 1.8991 -1.93946004 0 P 0 ;0
L 1.8991 -1.93946004 1.89913996 -1.93948002 0 P 0 ;0
L 1.89913996 -1.93948002 1.89923002 -1.93953996 0 P 0 ;0
L 1.89923002 -1.93953996 1.89926998 -1.93956004 0 P 0 ;0
L 1.89926998 -1.93956004 1.8993 -1.93958002 0 P 0 ;0
L 1.8993 -1.93958002 1.89933996 -1.9396 0 P 0 ;0
L 1.89933996 -1.9396 1.89936998 -1.93961004 0 P 0 ;0
L 1.89936998 -1.93961004 1.89938002 -1.93961004 0 P 0 ;0
L 1.89938002 -1.93961004 1.89946998 -1.93966004 0 P 0 ;0
L 1.89946998 -1.93966004 1.89953996 -1.9397 0 P 0 ;0
L 1.89953996 -1.9397 1.89971998 -1.93976998 0 P 0 ;0
L 1.89971998 -1.93976998 1.89975 -1.93978996 0 P 0 ;0
L 1.89975 -1.93978996 1.89978996 -1.9398 0 P 0 ;0
L 1.89978996 -1.9398 1.89986998 -1.93983002 0 P 0 ;0
L 1.89986998 -1.93983002 1.89996998 -1.93986004 0 P 0 ;0
L 1.89996998 -1.93986004 1.90001004 -1.93986998 0 P 0 ;0
L 1.90001004 -1.93986998 1.90005 -1.93988996 0 P 0 ;0
L 1.90005 -1.93988996 1.90013002 -1.9399 0 P 0 ;0
L 1.90013002 -1.9399 1.90023002 -1.93993002 0 P 0 ;0
L 1.90023002 -1.93993002 1.90023996 -1.93993002 0 P 0 ;0
L 1.90023996 -1.93993002 1.90028002 -1.93993996 0 P 0 ;0
L 1.90028002 -1.93993996 1.90031004 -1.93995 0 P 0 ;0
L 1.90031004 -1.93995 1.90036004 -1.93995 0 P 0 ;0
L 1.90036004 -1.93995 1.9004 -1.93996004 0 P 0 ;0
L 1.9004 -1.93996004 1.9005 -1.93996998 0 P 0 ;0
L 1.9005 -1.93996998 1.90061004 -1.93998996 0 P 0 ;0
L 1.90061004 -1.93998996 1.90063996 -1.93998996 0 P 0 ;0
L 1.90063996 -1.93998996 1.90181004 -1.94006998 0 P 0 ;0
L 1.90181004 -1.94006998 1.90183996 -1.94008002 0 P 0 ;0
L 1.90183996 -1.94008002 1.90191004 -1.94008002 0 P 0 ;0
L 1.90191004 -1.94008002 1.90308002 -1.9401 0 P 0 ;0
L 1.90308002 -1.9401 1.90311004 -1.9401 0 P 0 ;0
L 1.90311004 -1.9401 1.90313996 -1.94011004 0 P 0 ;0
L 1.90841004 -1.97146004 1.91683996 -1.97146004 0 P 0 ;0
L 1.9135 -1.97046004 1.91931004 -1.97046004 0 P 0 ;0
L 1.91655 -1.96946004 1.92131004 -1.96946004 0 P 0 ;0
L 1.91891998 -1.96846004 1.92301004 -1.96846004 0 P 0 ;0
L 1.92088996 -1.96746004 1.9245 -1.96746004 0 P 0 ;0
L 1.92251004 -1.96646004 1.9258 -1.96646004 0 P 0 ;0
L 1.92391004 -1.96546004 1.92696004 -1.96546004 0 P 0 ;0
L 1.92513002 -1.96446004 1.92803002 -1.96446004 0 P 0 ;0
L 1.9262 -1.96346004 1.92898996 -1.96346004 0 P 0 ;0
L 1.92713996 -1.96246004 1.92986004 -1.96246004 0 P 0 ;0
L 1.928 -1.96146004 1.93068996 -1.96146004 0 P 0 ;0
L 1.92878002 -1.96046004 1.93143002 -1.96046004 0 P 0 ;0
L 1.92951004 -1.95946004 1.93216004 -1.95946004 0 P 0 ;0
L 1.93016998 -1.95846004 1.93278996 -1.95846004 0 P 0 ;0
L 1.93078002 -1.95746004 1.93341004 -1.95746004 0 P 0 ;0
L 1.93133002 -1.95646004 1.93396004 -1.95646004 0 P 0 ;0
L 1.93185 -1.95546004 1.93448996 -1.95546004 0 P 0 ;0
L 1.93231004 -1.95446004 1.93495 -1.95446004 0 P 0 ;0
L 1.93275 -1.95346004 1.93541004 -1.95346004 0 P 0 ;0
L 1.93311998 -1.95246004 1.93586004 -1.95246004 0 P 0 ;0
L 1.93348002 -1.95146004 1.93628996 -1.95146004 0 P 0 ;0
L 1.93376998 -1.95046004 1.93666004 -1.95046004 0 P 0 ;0
L 1.93405 -1.94946004 1.93693002 -1.94946004 0 P 0 ;0
L 1.93428002 -1.94846004 1.93715 -1.94846004 0 P 0 ;0
L 1.93446998 -1.94746004 1.93733002 -1.94746004 0 P 0 ;0
L 1.93466004 -1.94646004 1.93743002 -1.94646004 0 P 0 ;0
L 1.93478996 -1.94546004 1.93748996 -1.94546004 0 P 0 ;0
L 1.9349 -1.94446998 1.93751998 -1.94446998 0 P 0 ;0
L 1.93496998 -1.94346004 1.93755 -1.94346004 0 P 0 ;0
L 1.93501998 -1.94246004 1.93758002 -1.94246004 0 P 0 ;0
L 1.93505 -1.94146998 1.93758996 -1.94146998 0 P 0 ;0
L 1.93503002 -1.94046004 1.93755 -1.94046004 0 P 0 ;0
L 1.935 -1.93946004 1.93751998 -1.93946004 0 P 0 ;0
L 1.93491998 -1.93846004 1.93748002 -1.93846004 0 P 0 ;0
L 1.93481004 -1.93746004 1.93738996 -1.93746004 0 P 0 ;0
L 1.93468996 -1.93646004 1.93726998 -1.93646004 0 P 0 ;0
L 1.93451004 -1.93546004 1.93716004 -1.93546004 0 P 0 ;0
L 1.93433002 -1.93446004 1.93703996 -1.93446004 0 P 0 ;0
L 1.93408996 -1.93346004 1.93685 -1.93346004 0 P 0 ;0
L 1.93383002 -1.93246004 1.93666004 -1.93246004 0 P 0 ;0
L 1.93353002 -1.93146004 1.93638996 -1.93146004 0 P 0 ;0
L 1.9332 -1.93046004 1.93611998 -1.93046004 0 P 0 ;0
L 1.93283996 -1.92946004 1.93576998 -1.92946004 0 P 0 ;0
L 1.93241004 -1.92846004 1.93541004 -1.92846004 0 P 0 ;0
L 1.93198996 -1.92746004 1.93498002 -1.92746004 0 P 0 ;0
L 1.93146998 -1.92646004 1.93451004 -1.92646004 0 P 0 ;0
L 1.93096004 -1.92546004 1.93398002 -1.92546004 0 P 0 ;0
L 1.93035 -1.92446998 1.93338002 -1.92446998 0 P 0 ;0
L 1.92973002 -1.92346004 1.93275 -1.92346004 0 P 0 ;0
L 1.92903002 -1.92246004 1.93201004 -1.92246004 0 P 0 ;0
L 1.92831004 -1.92146004 1.93125 -1.92146004 0 P 0 ;0
L 1.92746998 -1.92046004 1.93041004 -1.92046004 0 P 0 ;0
L 1.92661004 -1.91946004 1.92948996 -1.91946004 0 P 0 ;0
L 1.92558996 -1.91846004 1.92851004 -1.91846004 0 P 0 ;0
L 1.9245 -1.91746004 1.92741998 -1.91746004 0 P 0 ;0
L 1.92328996 -1.91646004 1.92621998 -1.91646004 0 P 0 ;0
L 1.92188002 -1.91546004 1.92491998 -1.91546004 0 P 0 ;0
L 1.92026004 -1.91446004 1.92358996 -1.91446004 0 P 0 ;0
L 1.91835 -1.91346004 1.92208002 -1.91346004 0 P 0 ;0
L 1.82446998 -2.08323996 1.87608002 -2.08323996 0 P 0 ;0
L 1.82403002 -2.08223996 1.87601004 -2.08223996 0 P 0 ;0
L 1.8234 -2.08123996 1.87591004 -2.08123996 0 P 0 ;0
L 1.82256004 -2.08023996 1.87578002 -2.08023996 0 P 0 ;0
L 1.82166004 -2.07923996 1.87558996 -2.07923996 0 P 0 ;0
L 1.82061998 -2.07823996 1.87533002 -2.07823996 0 P 0 ;0
L 1.81946004 -2.07723996 1.87498996 -2.07723996 0 P 0 ;0
L 1.81818002 -2.07623996 1.8746 -2.07623996 0 P 0 ;0
L 1.8168 -2.07523996 1.87416998 -2.07523996 0 P 0 ;0
L 1.81541998 -2.07423996 1.87371004 -2.07423996 0 P 0 ;0
L 1.81403002 -2.07323996 1.87316998 -2.07323996 0 P 0 ;0
L 1.81265 -2.07223996 1.87261004 -2.07223996 0 P 0 ;0
L 1.81126998 -2.07123996 1.87196004 -2.07123996 0 P 0 ;0
L 1.80986004 -2.07023996 1.87128002 -2.07023996 0 P 0 ;0
L 1.80843996 -2.06923996 1.87051998 -2.06923996 0 P 0 ;0
L 1.80703002 -2.06823996 1.8697 -2.06823996 0 P 0 ;0
L 1.80561004 -2.06723996 1.86883002 -2.06723996 0 P 0 ;0
L 1.8042 -2.06623996 1.86796004 -2.06623996 0 P 0 ;0
L 1.80278002 -2.06523996 1.86705 -2.06523996 0 P 0 ;0
L 1.80136004 -2.06423996 1.86608002 -2.06423996 0 P 0 ;0
L 1.79995 -2.06323996 1.8651 -2.06323996 0 P 0 ;0
L 1.79865 -2.06223996 1.86411004 -2.06223996 0 P 0 ;0
L 1.79735 -2.06123996 1.86301998 -2.06123996 0 P 0 ;0
L 1.79605 -2.06023996 1.86193002 -2.06023996 0 P 0 ;0
L 1.79475 -2.05923996 1.86083996 -2.05923996 0 P 0 ;0
L 1.79345 -2.05823996 1.85966998 -2.05823996 0 P 0 ;0
L 1.79215 -2.05723996 1.85846004 -2.05723996 0 P 0 ;0
L 1.79088002 -2.05623996 1.85726004 -2.05623996 0 P 0 ;0
L 1.78971998 -2.05523996 1.85598996 -2.05523996 0 P 0 ;0
L 1.78856004 -2.05423996 1.85461998 -2.05423996 0 P 0 ;0
L 1.7874 -2.05323996 1.85326004 -2.05323996 0 P 0 ;0
L 1.78623002 -2.05223996 1.8519 -2.05223996 0 P 0 ;0
L 1.78506998 -2.05123996 1.85053996 -2.05123996 0 P 0 ;0
L 1.78398002 -2.05023996 1.84918002 -2.05023996 0 P 0 ;0
L 1.783 -2.04923996 1.84781004 -2.04923996 0 P 0 ;0
L 1.87086004 -2.03023996 1.87535 -2.03023996 0 P 0 ;0
L 1.91633002 -1.91473002 1.9183 -1.91565 0 P 0 ;0
L 1.9183 -1.91565 1.92018996 -1.91673002 0 P 0 ;0
L 1.92018996 -1.91673002 1.92196998 -1.91796998 0 P 0 ;0
L 1.92196998 -1.91796998 1.92365 -1.91936004 0 P 0 ;0
L 1.92365 -1.91936004 1.9252 -1.92088002 0 P 0 ;0
L 1.9252 -1.92088002 1.92661004 -1.92253996 0 P 0 ;0
L 1.92661004 -1.92253996 1.92795 -1.92436998 0 P 0 ;0
L 1.92795 -1.92436998 1.92913996 -1.9263 0 P 0 ;0
L 1.92913996 -1.9263 1.93018002 -1.92831998 0 P 0 ;0
L 1.93018002 -1.92831998 1.93106998 -1.93041004 0 P 0 ;0
L 1.93106998 -1.93041004 1.93178996 -1.93256004 0 P 0 ;0
L 1.93178996 -1.93256004 1.93236004 -1.93476004 0 P 0 ;0
L 1.93236004 -1.93476004 1.93276004 -1.93703996 0 P 0 ;0
L 1.93276004 -1.93703996 1.93298996 -1.93933996 0 P 0 ;0
L 1.93298996 -1.93933996 1.93306004 -1.94165 0 P 0 ;0
L 1.93306004 -1.94165 1.93295 -1.94396998 0 P 0 ;0
L 1.93295 -1.94396998 1.93268002 -1.94626004 0 P 0 ;0
L 1.93268002 -1.94626004 1.93223002 -1.94853996 0 P 0 ;0
L 1.93223002 -1.94853996 1.93161998 -1.95071998 0 P 0 ;0
L 1.93161998 -1.95071998 1.93085 -1.95285 0 P 0 ;0
L 1.93085 -1.95285 1.92991004 -1.95491004 0 P 0 ;0
L 1.92991004 -1.95491004 1.92881004 -1.95688996 0 P 0 ;0
L 1.92881004 -1.95688996 1.92756004 -1.95878002 0 P 0 ;0
L 1.92756004 -1.95878002 1.92616004 -1.96056998 0 P 0 ;0
L 1.92616004 -1.96056998 1.92493996 -1.9619 0 P 0 ;0
L 1.92493996 -1.9619 1.92361998 -1.96313996 0 P 0 ;0
L 1.92361998 -1.96313996 1.9222 -1.96426004 0 P 0 ;0
L 1.9222 -1.96426004 1.9207 -1.96526998 0 P 0 ;0
L 1.9207 -1.96526998 1.91911004 -1.96616998 0 P 0 ;0
L 1.91911004 -1.96616998 1.91686998 -1.96721004 0 P 0 ;0
L 1.91686998 -1.96721004 1.91456004 -1.96806998 0 P 0 ;0
L 1.91456004 -1.96806998 1.91218996 -1.96876004 0 P 0 ;0
L 1.91218996 -1.96876004 1.90975 -1.96926998 0 P 0 ;0
L 1.90975 -1.96926998 1.90725 -1.9696 0 P 0 ;0
L 1.90725 -1.9696 1.90473002 -1.96973996 0 P 0 ;0
L 1.90473002 -1.96973996 1.9022 -1.96968996 0 P 0 ;0
L 1.9022 -1.96968996 1.89966998 -1.96945 0 P 0 ;0
L 1.89966998 -1.96945 1.89778002 -1.96913002 0 P 0 ;0
L 1.89778002 -1.96913002 1.89591998 -1.96868996 0 P 0 ;0
L 1.89591998 -1.96868996 1.8941 -1.96811004 0 P 0 ;0
L 1.8941 -1.96811004 1.89231004 -1.96741004 0 P 0 ;0
L 1.89231004 -1.96741004 1.89058002 -1.96658002 0 P 0 ;0
L 1.89058002 -1.96658002 1.88875 -1.96553996 0 P 0 ;0
L 1.88875 -1.96553996 1.88698996 -1.96435 0 P 0 ;0
L 1.88698996 -1.96435 1.88533996 -1.96303002 0 P 0 ;0
L 1.88533996 -1.96303002 1.88378996 -1.9616 0 P 0 ;0
L 1.88378996 -1.9616 1.88235 -1.96003996 0 P 0 ;0
L 1.88235 -1.96003996 1.88103002 -1.95838996 0 P 0 ;0
L 1.88103002 -1.95838996 1.87983996 -1.95663002 0 P 0 ;0
L 1.87983996 -1.95663002 1.87861998 -1.95446998 0 P 0 ;0
L 1.87861998 -1.95446998 1.87758002 -1.9522 0 P 0 ;0
L 1.87758002 -1.9522 1.87673996 -1.94986004 0 P 0 ;0
L 1.87673996 -1.94986004 1.8761 -1.94745 0 P 0 ;0
L 1.8761 -1.94745 1.87568002 -1.945 0 P 0 ;0
L 1.87568002 -1.945 1.87546004 -1.94248996 0 P 0 ;0
L 1.87546004 -1.94248996 1.87546004 -1.93998996 0 P 0 ;0
L 1.87546004 -1.93998996 1.87566998 -1.93748996 0 P 0 ;0
L 1.87566998 -1.93748996 1.87608996 -1.93501998 0 P 0 ;0
L 1.87608996 -1.93501998 1.87671998 -1.9326 0 P 0 ;0
L 1.87671998 -1.9326 1.87755 -1.93023002 0 P 0 ;0
L 1.87755 -1.93023002 1.8786 -1.92793002 0 P 0 ;0
L 1.8786 -1.92793002 1.87981998 -1.92575 0 P 0 ;0
L 1.87981998 -1.92575 1.88123002 -1.92368002 0 P 0 ;0
L 1.88123002 -1.92368002 1.88281004 -1.92175 0 P 0 ;0
L 1.88281004 -1.92175 1.88455 -1.91996004 0 P 0 ;0
L 1.88455 -1.91996004 1.88643002 -1.91831998 0 P 0 ;0
L 1.88643002 -1.91831998 1.88845 -1.91686004 0 P 0 ;0
L 1.88845 -1.91686004 1.88986998 -1.91598996 0 P 0 ;0
L 1.88986998 -1.91598996 1.89135 -1.91523002 0 P 0 ;0
L 1.89135 -1.91523002 1.89288002 -1.91458996 0 P 0 ;0
L 1.89288002 -1.91458996 1.89446998 -1.91406004 0 P 0 ;0
L 1.89446998 -1.91406004 1.89688996 -1.91343996 0 P 0 ;0
L 1.89688996 -1.91343996 1.89935 -1.91298996 0 P 0 ;0
L 1.89935 -1.91298996 1.90183996 -1.91271004 0 P 0 ;0
L 1.90183996 -1.91271004 1.9044 -1.91261004 0 P 0 ;0
L 1.9044 -1.91261004 1.90695 -1.91268002 0 P 0 ;0
L 1.90695 -1.91268002 1.90948996 -1.91291998 0 P 0 ;0
L 1.90948996 -1.91291998 1.91181998 -1.91331998 0 P 0 ;0
L 1.91181998 -1.91331998 1.91408996 -1.91393002 0 P 0 ;0
L 1.91408996 -1.91393002 1.91633002 -1.91473002 0 P 0 ;0
L 1.89498002 -1.90801998 1.8922 -1.90893002 0 P 0 ;0
L 1.8922 -1.90893002 1.88948002 -1.91003002 0 P 0 ;0
L 1.88948002 -1.91003002 1.88686004 -1.91133002 0 P 0 ;0
L 1.88686004 -1.91133002 1.88431004 -1.91283996 0 P 0 ;0
L 1.88431004 -1.91283996 1.88201004 -1.91446004 0 P 0 ;0
L 1.88201004 -1.91446004 1.87985 -1.91626998 0 P 0 ;0
L 1.87985 -1.91626998 1.87785 -1.91826004 0 P 0 ;0
L 1.87785 -1.91826004 1.87601998 -1.92041004 0 P 0 ;0
L 1.87601998 -1.92041004 1.87441004 -1.92266998 0 P 0 ;0
L 1.87441004 -1.92266998 1.87298996 -1.92505 0 P 0 ;0
L 1.87298996 -1.92505 1.87178002 -1.92756004 0 P 0 ;0
L 1.87178002 -1.92756004 1.87078996 -1.93015 0 P 0 ;0
L 1.87078996 -1.93015 1.87 -1.93286998 0 P 0 ;0
L 1.87 -1.93286998 1.86943996 -1.93563996 0 P 0 ;0
L 1.86943996 -1.93563996 1.86908996 -1.93845 0 P 0 ;0
L 1.86908996 -1.93845 1.86898002 -1.94128996 0 P 0 ;0
L 1.86898002 -1.94128996 1.86911998 -1.94485 0 P 0 ;0
L 1.86911998 -1.94485 1.86953996 -1.94841004 0 P 0 ;0
L 1.86953996 -1.94841004 1.86996004 -1.95048996 0 P 0 ;0
L 1.86996004 -1.95048996 1.87053002 -1.95251998 0 P 0 ;0
L 1.87053002 -1.95251998 1.87125 -1.95451998 0 P 0 ;0
L 1.87125 -1.95451998 1.87211004 -1.95643002 0 P 0 ;0
L 1.87211004 -1.95643002 1.8731 -1.95826004 0 P 0 ;0
L 1.8731 -1.95826004 1.87423996 -1.96001998 0 P 0 ;0
L 1.87423996 -1.96001998 1.87636998 -1.96278996 0 P 0 ;0
L 1.87636998 -1.96278996 1.87871998 -1.96536998 0 P 0 ;0
L 1.87871998 -1.96536998 1.88145 -1.96788002 0 P 0 ;0
L 1.88145 -1.96788002 1.88436998 -1.97015 0 P 0 ;0
L 1.88436998 -1.97015 1.88621004 -1.97135 0 P 0 ;0
L 1.88621004 -1.97135 1.88813002 -1.97238002 0 P 0 ;0
L 1.88813002 -1.97238002 1.89013002 -1.97326004 0 P 0 ;0
L 1.89013002 -1.97326004 1.89228002 -1.97398996 0 P 0 ;0
L 1.89228002 -1.97398996 1.89446998 -1.97455 0 P 0 ;0
L 1.89446998 -1.97455 1.89671004 -1.97493996 0 P 0 ;0
L 1.89671004 -1.97493996 1.90076998 -1.97533996 0 P 0 ;0
L 1.90076998 -1.97533996 1.90485 -1.97546998 0 P 0 ;0
L 1.90485 -1.97546998 1.90821004 -1.97531998 0 P 0 ;0
L 1.90821004 -1.97531998 1.91153996 -1.97488996 0 P 0 ;0
L 1.91153996 -1.97488996 1.91481998 -1.97418996 0 P 0 ;0
L 1.91481998 -1.97418996 1.9171 -1.9735 0 P 0 ;0
L 1.9171 -1.9735 1.91933002 -1.97266004 0 P 0 ;0
L 1.91933002 -1.97266004 1.92148002 -1.97166004 0 P 0 ;0
L 1.92148002 -1.97166004 1.92356998 -1.97048996 0 P 0 ;0
L 1.92356998 -1.97048996 1.92553996 -1.96918996 0 P 0 ;0
L 1.92553996 -1.96918996 1.92741004 -1.96773996 0 P 0 ;0
L 1.92741004 -1.96773996 1.92916004 -1.96616998 0 P 0 ;0
L 1.92916004 -1.96616998 1.93081004 -1.96446004 0 P 0 ;0
L 1.93081004 -1.96446004 1.93236998 -1.96256998 0 P 0 ;0
L 1.93236998 -1.96256998 1.93381004 -1.96058996 0 P 0 ;0
L 1.93381004 -1.96058996 1.93511998 -1.95851004 0 P 0 ;0
L 1.93511998 -1.95851004 1.93628996 -1.95633996 0 P 0 ;0
L 1.93628996 -1.95633996 1.93803996 -1.95251998 0 P 0 ;0
L 1.93803996 -1.95251998 1.93858002 -1.95101998 0 P 0 ;0
L 1.93858002 -1.95101998 1.93898996 -1.94948002 0 P 0 ;0
L 1.93898996 -1.94948002 1.93928996 -1.94786998 0 P 0 ;0
L 1.93928996 -1.94786998 1.93946004 -1.94625 0 P 0 ;0
L 1.93946004 -1.94625 1.9396 -1.94178002 0 P 0 ;0
L 1.9396 -1.94178002 1.93946004 -1.93803996 0 P 0 ;0
L 1.93946004 -1.93803996 1.93905 -1.9343 0 P 0 ;0
L 1.93905 -1.9343 1.93863996 -1.93213996 0 P 0 ;0
L 1.93863996 -1.93213996 1.93808002 -1.93001998 0 P 0 ;0
L 1.93808002 -1.93001998 1.93736004 -1.92795 0 P 0 ;0
L 1.93736004 -1.92795 1.93653002 -1.92601004 0 P 0 ;0
L 1.93653002 -1.92601004 1.93555 -1.92415 0 P 0 ;0
L 1.93555 -1.92415 1.93441998 -1.92236004 0 P 0 ;0
L 1.93441998 -1.92236004 1.9331 -1.92056004 0 P 0 ;0
L 1.9331 -1.92056004 1.93166998 -1.91885 0 P 0 ;0
L 1.93166998 -1.91885 1.93011998 -1.91723002 0 P 0 ;0
L 1.93011998 -1.91723002 1.92896004 -1.91615 0 P 0 ;0
L 1.92896004 -1.91615 1.92775 -1.91511004 0 P 0 ;0
L 1.92775 -1.91511004 1.92493002 -1.91295 0 P 0 ;0
L 1.92493002 -1.91295 1.9221 -1.91108002 0 P 0 ;0
L 1.9221 -1.91108002 1.92095 -1.91043002 0 P 0 ;0
L 1.92095 -1.91043002 1.91975 -1.90985 0 P 0 ;0
L 1.91975 -1.90985 1.91796004 -1.90913996 0 P 0 ;0
L 1.91796004 -1.90913996 1.91613002 -1.90856004 0 P 0 ;0
L 1.91613002 -1.90856004 1.91423996 -1.9081 0 P 0 ;0
L 1.91423996 -1.9081 1.91086004 -1.90751998 0 P 0 ;0
L 1.91086004 -1.90751998 1.90743002 -1.90716004 0 P 0 ;0
L 1.90743002 -1.90716004 1.90401004 -1.90701004 0 P 0 ;0
L 1.90401004 -1.90701004 1.90058002 -1.90708002 0 P 0 ;0
L 1.90058002 -1.90708002 1.8987 -1.90726004 0 P 0 ;0
L 1.8987 -1.90726004 1.89683002 -1.90756998 0 P 0 ;0
L 1.89683002 -1.90756998 1.89498002 -1.90801998 0 P 0 ;0
L 1.86643002 -2.02923996 1.87525 -2.02923996 0 P 0 ;0
L 1.86176998 -2.02823996 1.87515 -2.02823996 0 P 0 ;0
L 1.85588996 -2.02723996 1.87505 -2.02723996 0 P 0 ;0
L 1.78365 -2.00523996 1.87281004 -2.00523996 0 P 0 ;0
L 1.78451004 -2.00423996 1.87271004 -2.00423996 0 P 0 ;0
L 1.78546998 -2.00323996 1.87261004 -2.00323996 0 P 0 ;0
L 1.78655 -2.00223996 1.8725 -2.00223996 0 P 0 ;0
L 1.78776004 -2.00123996 1.8724 -2.00123996 0 P 0 ;0
L 1.78915 -2.00023996 1.8723 -2.00023996 0 P 0 ;0
L 1.79078996 -1.99923996 1.8722 -1.99923996 0 P 0 ;0
L 1.79263996 -1.99823996 1.87208996 -1.99823996 0 P 0 ;0
L 1.79458996 -1.99723996 1.87198996 -1.99723996 0 P 0 ;0
L 1.79686998 -1.99623996 1.87188002 -1.99623996 0 P 0 ;0
L 1.79946004 -1.99523996 1.87178002 -1.99523996 0 P 0 ;0
L 1.80231004 -1.99423996 1.86961998 -1.99423996 0 P 0 ;0
L 1.80596004 -1.99323996 1.86218002 -1.99323996 0 P 0 ;0
L 1.81051004 -1.99223996 1.85398002 -1.99223996 0 P 0 ;0
L 1.81676004 -1.99123996 1.84395 -1.99123996 0 P 0 ;0
L 1.87786998 -1.96146004 1.88093996 -1.96146004 0 P 0 ;0
L 1.8771 -1.96046004 1.88013002 -1.96046004 0 P 0 ;0
L 1.87633996 -1.95946004 1.87933996 -1.95946004 0 P 0 ;0
L 1.87561998 -1.95846004 1.87866998 -1.95846004 0 P 0 ;0
L 1.87496998 -1.95746004 1.87801998 -1.95746004 0 P 0 ;0
L 1.8744 -1.95646004 1.87745 -1.95646004 0 P 0 ;0
L 1.87386998 -1.95546004 1.87688002 -1.95546004 0 P 0 ;0
L 1.87341998 -1.95446004 1.87641998 -1.95446004 0 P 0 ;0
L 1.87298996 -1.95346004 1.87596004 -1.95346004 0 P 0 ;0
L 1.87263002 -1.95246004 1.87555 -1.95246004 0 P 0 ;0
L 1.87231004 -1.95146004 1.87518996 -1.95146004 0 P 0 ;0
L 1.87203002 -1.95046004 1.87483002 -1.95046004 0 P 0 ;0
L 1.87178996 -1.94946004 1.87456998 -1.94946004 0 P 0 ;0
L 1.87158996 -1.94846004 1.87431004 -1.94846004 0 P 0 ;0
L 1.87143996 -1.94746004 1.87408002 -1.94746004 0 P 0 ;0
L 1.87133002 -1.94646004 1.8739 -1.94646004 0 P 0 ;0
L 1.87121004 -1.94546004 1.87373002 -1.94546004 0 P 0 ;0
L 1.8711 -1.94446998 1.87361998 -1.94446998 0 P 0 ;0
L 1.87106998 -1.94346004 1.87353996 -1.94346004 0 P 0 ;0
L 1.87103002 -1.94246004 1.87346004 -1.94246004 0 P 0 ;0
L 1.87098996 -1.94146998 1.87346004 -1.94146998 0 P 0 ;0
L 1.87101004 -1.94046004 1.87346004 -1.94046004 0 P 0 ;0
L 1.87106004 -1.93946004 1.87348996 -1.93946004 0 P 0 ;0
L 1.87111004 -1.93846004 1.87358002 -1.93846004 0 P 0 ;0
L 1.87123002 -1.93746004 1.87366004 -1.93746004 0 P 0 ;0
L 1.87135 -1.93646004 1.87381998 -1.93646004 0 P 0 ;0
L 1.87151004 -1.93546004 1.87398996 -1.93546004 0 P 0 ;0
L 1.87171998 -1.93446004 1.87416998 -1.93446004 0 P 0 ;0
L 1.87191998 -1.93346004 1.87443002 -1.93346004 0 P 0 ;0
L 1.8722 -1.93246004 1.87468996 -1.93246004 0 P 0 ;0
L 1.87248996 -1.93146004 1.875 -1.93146004 0 P 0 ;0
L 1.87281004 -1.93046004 1.87535 -1.93046004 0 P 0 ;0
L 1.87318996 -1.92946004 1.87571004 -1.92946004 0 P 0 ;0
L 1.87356998 -1.92846004 1.87616004 -1.92846004 0 P 0 ;0
L 1.87405 -1.92746004 1.87661004 -1.92746004 0 P 0 ;0
L 1.87453002 -1.92646004 1.87711998 -1.92646004 0 P 0 ;0
L 1.87506998 -1.92546004 1.87768996 -1.92546004 0 P 0 ;0
L 1.87566004 -1.92446998 1.87826998 -1.92446998 0 P 0 ;0
L 1.87628996 -1.92346004 1.87896004 -1.92346004 0 P 0 ;0
L 1.87701004 -1.92246004 1.87963996 -1.92246004 0 P 0 ;0
L 1.87775 -1.92146004 1.88046004 -1.92146004 0 P 0 ;0
L 1.90483996 -1.97346004 1.9009 -1.97333996 0 P 0 ;0
L 1.9009 -1.97333996 1.89698002 -1.97295 0 P 0 ;0
L 1.89698002 -1.97295 1.89488996 -1.97258996 0 P 0 ;0
L 1.89488996 -1.97258996 1.89285 -1.97206998 0 P 0 ;0
L 1.89285 -1.97206998 1.89086004 -1.97138996 0 P 0 ;0
L 1.89086004 -1.97138996 1.889 -1.97058002 0 P 0 ;0
L 1.889 -1.97058002 1.88723002 -1.96961998 0 P 0 ;0
L 1.88723002 -1.96961998 1.88553002 -1.96851998 0 P 0 ;0
L 1.88553002 -1.96851998 1.88273996 -1.96636004 0 P 0 ;0
L 1.88273996 -1.96636004 1.88013996 -1.96396004 0 P 0 ;0
L 1.88013996 -1.96396004 1.8779 -1.9615 0 P 0 ;0
L 1.8779 -1.9615 1.87588002 -1.95886998 0 P 0 ;0
L 1.87588002 -1.95886998 1.87483002 -1.95723996 0 P 0 ;0
L 1.87483002 -1.95723996 1.8739 -1.95553996 0 P 0 ;0
L 1.8739 -1.95553996 1.87311004 -1.95376998 0 P 0 ;0
L 1.87311004 -1.95376998 1.87243002 -1.95191004 0 P 0 ;0
L 1.87243002 -1.95191004 1.8719 -1.95001998 0 P 0 ;0
L 1.8719 -1.95001998 1.87151998 -1.9481 0 P 0 ;0
L 1.87151998 -1.9481 1.87111004 -1.94468996 0 P 0 ;0
L 1.87111004 -1.94468996 1.87098002 -1.94128996 0 P 0 ;0
L 1.87098002 -1.94128996 1.87108996 -1.93861004 0 P 0 ;0
L 1.87108996 -1.93861004 1.87141004 -1.93596998 0 P 0 ;0
L 1.87141004 -1.93596998 1.87195 -1.93335 0 P 0 ;0
L 1.87195 -1.93335 1.87268996 -1.93078996 0 P 0 ;0
L 1.87268996 -1.93078996 1.87361998 -1.92835 0 P 0 ;0
L 1.87361998 -1.92835 1.87475 -1.926 0 P 0 ;0
L 1.87475 -1.926 1.87608996 -1.92376004 0 P 0 ;0
L 1.87608996 -1.92376004 1.8776 -1.92163996 0 P 0 ;0
L 1.8776 -1.92163996 1.87931998 -1.91961998 0 P 0 ;0
L 1.87931998 -1.91961998 1.8812 -1.91775 0 P 0 ;0
L 1.8812 -1.91775 1.88323002 -1.91605 0 P 0 ;0
L 1.88323002 -1.91605 1.8854 -1.91451998 0 P 0 ;0
L 1.8854 -1.91451998 1.88781004 -1.91308996 0 P 0 ;0
L 1.88781004 -1.91308996 1.89031004 -1.91186004 0 P 0 ;0
L 1.89031004 -1.91186004 1.89288002 -1.9108 0 P 0 ;0
L 1.89288002 -1.9108 1.89553002 -1.90995 0 P 0 ;0
L 1.89553002 -1.90995 1.89723002 -1.90953002 0 P 0 ;0
L 1.89723002 -1.90953002 1.89896004 -1.90923996 0 P 0 ;0
L 1.89896004 -1.90923996 1.90068996 -1.90908002 0 P 0 ;0
L 1.90068996 -1.90908002 1.90398996 -1.90901004 0 P 0 ;0
L 1.90398996 -1.90901004 1.90728002 -1.90915 0 P 0 ;0
L 1.90728002 -1.90915 1.91058996 -1.90951004 0 P 0 ;0
L 1.91058996 -1.90951004 1.91383996 -1.91006004 0 P 0 ;0
L 1.91383996 -1.91006004 1.91558996 -1.91048996 0 P 0 ;0
L 1.91558996 -1.91048996 1.91728996 -1.91101998 0 P 0 ;0
L 1.91728996 -1.91101998 1.91895 -1.91168002 0 P 0 ;0
L 1.91895 -1.91168002 1.92001998 -1.9122 0 P 0 ;0
L 1.92001998 -1.9122 1.92105 -1.91278996 0 P 0 ;0
L 1.92105 -1.91278996 1.92376998 -1.91458002 0 P 0 ;0
L 1.92376998 -1.91458002 1.92648996 -1.91666998 0 P 0 ;0
L 1.92648996 -1.91666998 1.92763002 -1.91763996 0 P 0 ;0
L 1.92763002 -1.91763996 1.92871004 -1.91865 0 P 0 ;0
L 1.92871004 -1.91865 1.93018002 -1.92018996 0 P 0 ;0
L 1.93018002 -1.92018996 1.93153002 -1.9218 0 P 0 ;0
L 1.93153002 -1.9218 1.93276998 -1.92348996 0 P 0 ;0
L 1.93276998 -1.92348996 1.93381004 -1.92515 0 P 0 ;0
L 1.93381004 -1.92515 1.93471998 -1.92686998 0 P 0 ;0
L 1.93471998 -1.92686998 1.9355 -1.92866998 0 P 0 ;0
L 1.9355 -1.92866998 1.93616998 -1.93061004 0 P 0 ;0
L 1.93616998 -1.93061004 1.93668996 -1.93258002 0 P 0 ;0
L 1.93668996 -1.93258002 1.93706998 -1.93458996 0 P 0 ;0
L 1.93706998 -1.93458996 1.93746998 -1.93818996 0 P 0 ;0
L 1.93746998 -1.93818996 1.9376 -1.94178996 0 P 0 ;0
L 1.9376 -1.94178996 1.93746004 -1.94611004 0 P 0 ;0
L 1.93746004 -1.94611004 1.93731004 -1.94758996 0 P 0 ;0
L 1.93731004 -1.94758996 1.93705 -1.94903996 0 P 0 ;0
L 1.93705 -1.94903996 1.93666998 -1.95041998 0 P 0 ;0
L 1.93666998 -1.95041998 1.93618002 -1.95176004 0 P 0 ;0
L 1.93618002 -1.95176004 1.9345 -1.95545 0 P 0 ;0
L 1.9345 -1.95545 1.93338996 -1.9575 0 P 0 ;0
L 1.93338996 -1.9575 1.93216004 -1.95946998 0 P 0 ;0
L 1.93216004 -1.95946998 1.93078996 -1.96133996 0 P 0 ;0
L 1.93078996 -1.96133996 1.92931004 -1.96311998 0 P 0 ;0
L 1.92931004 -1.96311998 1.92776998 -1.96473002 0 P 0 ;0
L 1.92776998 -1.96473002 1.92613002 -1.96621004 0 P 0 ;0
L 1.92613002 -1.96621004 1.92438002 -1.96756004 0 P 0 ;0
L 1.92438002 -1.96756004 1.92253002 -1.96878002 0 P 0 ;0
L 1.92253002 -1.96878002 1.92056998 -1.96986998 0 P 0 ;0
L 1.92056998 -1.96986998 1.91855 -1.97081998 0 P 0 ;0
L 1.91855 -1.97081998 1.91646004 -1.97161004 0 P 0 ;0
L 1.91646004 -1.97161004 1.91433002 -1.97223996 0 P 0 ;0
L 1.91433002 -1.97223996 1.9112 -1.97291004 0 P 0 ;0
L 1.9112 -1.97291004 1.90803996 -1.97331998 0 P 0 ;0
L 1.90803996 -1.97331998 1.90483996 -1.97346004 0 P 0 ;0
L 1.90476004 -1.97173996 1.9048 -1.97173996 0 P 0 ;0
L 1.9048 -1.97173996 1.90483996 -1.97173002 0 P 0 ;0
L 1.90483996 -1.97173002 1.90736004 -1.9716 0 P 0 ;0
L 1.90736004 -1.9716 1.9074 -1.97158996 0 P 0 ;0
L 1.9074 -1.97158996 1.90746998 -1.97158996 0 P 0 ;0
L 1.90746998 -1.97158996 1.90751004 -1.97158002 0 P 0 ;0
L 1.90751004 -1.97158002 1.91001004 -1.97126004 0 P 0 ;0
L 1.91001004 -1.97126004 1.91005 -1.97125 0 P 0 ;0
L 1.91005 -1.97125 1.91008002 -1.97123996 0 P 0 ;0
L 1.91008002 -1.97123996 1.91011998 -1.97123996 0 P 0 ;0
L 1.91011998 -1.97123996 1.91016004 -1.97123002 0 P 0 ;0
L 1.91016004 -1.97123002 1.9126 -1.97071998 0 P 0 ;0
L 1.9126 -1.97071998 1.9126 -1.97071004 0 P 0 ;0
L 1.9126 -1.97071004 1.91266998 -1.97071004 0 P 0 ;0
L 1.91266998 -1.97071004 1.91271004 -1.97068996 0 P 0 ;0
L 1.91271004 -1.97068996 1.91275 -1.97068002 0 P 0 ;0
L 1.91275 -1.97068002 1.91511998 -1.96998996 0 P 0 ;0
L 1.91511998 -1.96998996 1.91515 -1.96998996 0 P 0 ;0
L 1.91515 -1.96998996 1.91518996 -1.96996998 0 P 0 ;0
L 1.91518996 -1.96996998 1.91523002 -1.96996004 0 P 0 ;0
L 1.91523002 -1.96996004 1.91526004 -1.96995 0 P 0 ;0
L 1.91526004 -1.96995 1.91756998 -1.96908002 0 P 0 ;0
L 1.91756998 -1.96908002 1.91761004 -1.96906998 0 P 0 ;0
L 1.91761004 -1.96906998 1.91768002 -1.96903996 0 P 0 ;0
L 1.91768002 -1.96903996 1.91771004 -1.96901998 0 P 0 ;0
L 1.91771004 -1.96901998 1.91995 -1.96798002 0 P 0 ;0
L 1.91995 -1.96798002 1.92001998 -1.96795 0 P 0 ;0
L 1.92001998 -1.96795 1.92005 -1.96793002 0 P 0 ;0
L 1.92005 -1.96793002 1.92008996 -1.96791004 0 P 0 ;0
L 1.92008996 -1.96791004 1.92168002 -1.96701998 0 P 0 ;0
L 1.92168002 -1.96701998 1.92171998 -1.967 0 P 0 ;0
L 1.92171998 -1.967 1.92175 -1.96698002 0 P 0 ;0
L 1.92175 -1.96698002 1.92178996 -1.96695 0 P 0 ;0
L 1.92178996 -1.96695 1.92181998 -1.96693002 0 P 0 ;0
L 1.92181998 -1.96693002 1.92331998 -1.96591998 0 P 0 ;0
L 1.92331998 -1.96591998 1.92336004 -1.9659 0 P 0 ;0
L 1.92336004 -1.9659 1.92341998 -1.96586004 0 P 0 ;0
L 1.92341998 -1.96586004 1.92345 -1.96583002 0 P 0 ;0
L 1.92345 -1.96583002 1.92486004 -1.9647 0 P 0 ;0
L 1.92486004 -1.9647 1.92493002 -1.96465 0 P 0 ;0
L 1.92493002 -1.96465 1.92496004 -1.96463002 0 P 0 ;0
L 1.92496004 -1.96463002 1.92498996 -1.9646 0 P 0 ;0
L 1.92498996 -1.9646 1.92631004 -1.96336998 0 P 0 ;0
L 1.92631004 -1.96336998 1.9264 -1.96328002 0 P 0 ;0
L 1.9264 -1.96328002 1.92641998 -1.96325 0 P 0 ;0
L 1.92641998 -1.96325 1.92763996 -1.96191998 0 P 0 ;0
L 1.92763996 -1.96191998 1.92766998 -1.96188996 0 P 0 ;0
L 1.92766998 -1.96188996 1.92768996 -1.96186004 0 P 0 ;0
L 1.92768996 -1.96186004 1.92771998 -1.96183002 0 P 0 ;0
L 1.92771998 -1.96183002 1.92773996 -1.9618 0 P 0 ;0
L 1.92773996 -1.9618 1.92913996 -1.96001004 0 P 0 ;0
L 1.92913996 -1.96001004 1.92918996 -1.95995 0 P 0 ;0
L 1.92918996 -1.95995 1.92921004 -1.95991004 0 P 0 ;0
L 1.92921004 -1.95991004 1.92923002 -1.95988002 0 P 0 ;0
L 1.92923002 -1.95988002 1.93048002 -1.95798996 0 P 0 ;0
L 1.93048002 -1.95798996 1.93051998 -1.95793002 0 P 0 ;0
L 1.93051998 -1.95793002 1.93053996 -1.95788996 0 P 0 ;0
L 1.93053996 -1.95788996 1.93056004 -1.95786004 0 P 0 ;0
L 1.93056004 -1.95786004 1.93166004 -1.95588002 0 P 0 ;0
L 1.93166004 -1.95588002 1.93171004 -1.95576998 0 P 0 ;0
L 1.93171004 -1.95576998 1.93173002 -1.95573996 0 P 0 ;0
L 1.93173002 -1.95573996 1.93266998 -1.95366998 0 P 0 ;0
L 1.93266998 -1.95366998 1.93271004 -1.95356998 0 P 0 ;0
L 1.93271004 -1.95356998 1.93273002 -1.95353002 0 P 0 ;0
L 1.93273002 -1.95353002 1.9335 -1.9514 0 P 0 ;0
L 1.9335 -1.9514 1.93351004 -1.95136998 0 P 0 ;0
L 1.93351004 -1.95136998 1.93353002 -1.95133002 0 P 0 ;0
L 1.93353002 -1.95133002 1.93355 -1.95125 0 P 0 ;0
L 1.93355 -1.95125 1.93416004 -1.94906998 0 P 0 ;0
L 1.93416004 -1.94906998 1.93416998 -1.94903002 0 P 0 ;0
L 1.93416998 -1.94903002 1.93418002 -1.949 0 P 0 ;0
L 1.93418002 -1.949 1.93418002 -1.94896004 0 P 0 ;0
L 1.93418002 -1.94896004 1.93418996 -1.94891998 0 P 0 ;0
L 1.93418996 -1.94891998 1.93463996 -1.94665 0 P 0 ;0
L 1.93463996 -1.94665 1.93463996 -1.94661004 0 P 0 ;0
L 1.93463996 -1.94661004 1.93465 -1.94656998 0 P 0 ;0
L 1.93465 -1.94656998 1.93466004 -1.9465 0 P 0 ;0
L 1.93466004 -1.9465 1.93493996 -1.9442 0 P 0 ;0
L 1.93493996 -1.9442 1.93493996 -1.94413002 0 P 0 ;0
L 1.93493996 -1.94413002 1.93495 -1.94408996 0 P 0 ;0
L 1.93495 -1.94408996 1.93495 -1.94406004 0 P 0 ;0
L 1.93495 -1.94406004 1.93505 -1.94173996 0 P 0 ;0
L 1.93505 -1.94173996 1.93506004 -1.94171004 0 P 0 ;0
L 1.93506004 -1.94171004 1.93506004 -1.9416 0 P 0 ;0
L 1.93506004 -1.9416 1.93498996 -1.93928996 0 P 0 ;0
L 1.93498996 -1.93928996 1.93498996 -1.93921004 0 P 0 ;0
L 1.93498996 -1.93921004 1.93498002 -1.93913996 0 P 0 ;0
L 1.93498002 -1.93913996 1.93475 -1.93683996 0 P 0 ;0
L 1.93475 -1.93683996 1.93473996 -1.93676998 0 P 0 ;0
L 1.93473996 -1.93676998 1.93473002 -1.93673002 0 P 0 ;0
L 1.93473002 -1.93673002 1.93473002 -1.93668996 0 P 0 ;0
L 1.93473002 -1.93668996 1.93433002 -1.93441004 0 P 0 ;0
L 1.93433002 -1.93441004 1.93431998 -1.93436998 0 P 0 ;0
L 1.93431998 -1.93436998 1.93431004 -1.93433996 0 P 0 ;0
L 1.93431004 -1.93433996 1.93428996 -1.93426004 0 P 0 ;0
L 1.93428996 -1.93426004 1.93373002 -1.93206004 0 P 0 ;0
L 1.93373002 -1.93206004 1.93368996 -1.93191998 0 P 0 ;0
L 1.93368996 -1.93191998 1.93296004 -1.92976998 0 P 0 ;0
L 1.93296004 -1.92976998 1.93293996 -1.9297 0 P 0 ;0
L 1.93293996 -1.9297 1.93291004 -1.92963002 0 P 0 ;0
L 1.93291004 -1.92963002 1.93201998 -1.92753996 0 P 0 ;0
L 1.93201998 -1.92753996 1.93196998 -1.92743002 0 P 0 ;0
L 1.93196998 -1.92743002 1.93196004 -1.9274 0 P 0 ;0
L 1.93196004 -1.9274 1.93091998 -1.92538996 0 P 0 ;0
L 1.93091998 -1.92538996 1.9309 -1.92536004 0 P 0 ;0
L 1.9309 -1.92536004 1.93088002 -1.92531998 0 P 0 ;0
L 1.93088002 -1.92531998 1.93086004 -1.92528996 0 P 0 ;0
L 1.93086004 -1.92528996 1.93083996 -1.92525 0 P 0 ;0
L 1.93083996 -1.92525 1.92965 -1.92331998 0 P 0 ;0
L 1.92965 -1.92331998 1.92956998 -1.9232 0 P 0 ;0
L 1.92956998 -1.9232 1.92823002 -1.92136004 0 P 0 ;0
L 1.92823002 -1.92136004 1.92818002 -1.9213 0 P 0 ;0
L 1.92818002 -1.9213 1.92816004 -1.92126998 0 P 0 ;0
L 1.92816004 -1.92126998 1.92813002 -1.92123996 0 P 0 ;0
L 1.92813002 -1.92123996 1.92671998 -1.91958002 0 P 0 ;0
L 1.92671998 -1.91958002 1.9266 -1.91946004 0 P 0 ;0
L 1.9266 -1.91946004 1.92505 -1.91793002 0 P 0 ;0
L 1.92505 -1.91793002 1.92498996 -1.91786998 0 P 0 ;0
L 1.92498996 -1.91786998 1.92493002 -1.91781998 0 P 0 ;0
L 1.92493002 -1.91781998 1.92325 -1.91643002 0 P 0 ;0
L 1.92325 -1.91643002 1.92318996 -1.91636998 0 P 0 ;0
L 1.92318996 -1.91636998 1.92311998 -1.91631998 0 P 0 ;0
L 1.92311998 -1.91631998 1.92133002 -1.91508002 0 P 0 ;0
L 1.92133002 -1.91508002 1.92126004 -1.91503996 0 P 0 ;0
L 1.92126004 -1.91503996 1.92121998 -1.91501004 0 P 0 ;0
L 1.92121998 -1.91501004 1.92118002 -1.91498996 0 P 0 ;0
L 1.92118002 -1.91498996 1.91928996 -1.91391004 0 P 0 ;0
L 1.91928996 -1.91391004 1.91926004 -1.91388996 0 P 0 ;0
L 1.91926004 -1.91388996 1.91913996 -1.91383002 0 P 0 ;0
L 1.91913996 -1.91383002 1.91716998 -1.91291004 0 P 0 ;0
L 1.91716998 -1.91291004 1.91711998 -1.91288996 0 P 0 ;0
L 1.91711998 -1.91288996 1.91705 -1.91286004 0 P 0 ;0
L 1.91705 -1.91286004 1.917 -1.91285 0 P 0 ;0
L 1.917 -1.91285 1.91476998 -1.91203996 0 P 0 ;0
L 1.91476998 -1.91203996 1.91468996 -1.91201998 0 P 0 ;0
L 1.91468996 -1.91201998 1.91465 -1.912 0 P 0 ;0
L 1.91465 -1.912 1.9146 -1.91198996 0 P 0 ;0
L 1.9146 -1.91198996 1.91233002 -1.91138996 0 P 0 ;0
L 1.91233002 -1.91138996 1.91228002 -1.91138002 0 P 0 ;0
L 1.91228002 -1.91138002 1.91223996 -1.91136998 0 P 0 ;0
L 1.91223996 -1.91136998 1.91216004 -1.91136004 0 P 0 ;0
L 1.91216004 -1.91136004 1.90983002 -1.91095 0 P 0 ;0
L 1.90983002 -1.91095 1.9098 -1.91093996 0 P 0 ;0
L 1.9098 -1.91093996 1.90976004 -1.91093996 0 P 0 ;0
L 1.90976004 -1.91093996 1.90971998 -1.91093002 0 P 0 ;0
L 1.90971998 -1.91093002 1.90968002 -1.91093002 0 P 0 ;0
L 1.90968002 -1.91093002 1.90713996 -1.91068996 0 P 0 ;0
L 1.90713996 -1.91068996 1.9071 -1.91068002 0 P 0 ;0
L 1.9071 -1.91068002 1.907 -1.91068002 0 P 0 ;0
L 1.907 -1.91068002 1.90445 -1.91061004 0 P 0 ;0
L 1.90445 -1.91061004 1.90431004 -1.91061004 0 P 0 ;0
L 1.90431004 -1.91061004 1.90176004 -1.91071004 0 P 0 ;0
L 1.90176004 -1.91071004 1.90173002 -1.91071998 0 P 0 ;0
L 1.90173002 -1.91071998 1.90166004 -1.91071998 0 P 0 ;0
L 1.90166004 -1.91071998 1.90161998 -1.91073002 0 P 0 ;0
L 1.90161998 -1.91073002 1.89913002 -1.911 0 P 0 ;0
L 1.89913002 -1.911 1.89906004 -1.91101004 0 P 0 ;0
L 1.89906004 -1.91101004 1.89901998 -1.91101998 0 P 0 ;0
L 1.89901998 -1.91101998 1.89898996 -1.91101998 0 P 0 ;0
L 1.89898996 -1.91101998 1.89653002 -1.91146998 0 P 0 ;0
L 1.89653002 -1.91146998 1.8965 -1.91148002 0 P 0 ;0
L 1.8965 -1.91148002 1.89646004 -1.91148002 0 P 0 ;0
L 1.89646004 -1.91148002 1.8964 -1.9115 0 P 0 ;0
L 1.8964 -1.9115 1.89396998 -1.91211998 0 P 0 ;0
L 1.89396998 -1.91211998 1.89393996 -1.91213002 0 P 0 ;0
L 1.89393996 -1.91213002 1.89383002 -1.91216004 0 P 0 ;0
L 1.89383002 -1.91216004 1.89225 -1.91268996 0 P 0 ;0
L 1.89225 -1.91268996 1.89218002 -1.91271998 0 P 0 ;0
L 1.89218002 -1.91271998 1.89211004 -1.91273996 0 P 0 ;0
L 1.89211004 -1.91273996 1.8921 -1.91273996 0 P 0 ;0
L 1.8921 -1.91273996 1.89058002 -1.91338996 0 P 0 ;0
L 1.89058002 -1.91338996 1.89043996 -1.91345 0 P 0 ;0
L 1.89043996 -1.91345 1.88896004 -1.91421004 0 P 0 ;0
L 1.88896004 -1.91421004 1.88893002 -1.91423002 0 P 0 ;0
L 1.88893002 -1.91423002 1.8889 -1.91423996 0 P 0 ;0
L 1.8889 -1.91423996 1.88886004 -1.91426004 0 P 0 ;0
L 1.88886004 -1.91426004 1.88883002 -1.91428002 0 P 0 ;0
L 1.88883002 -1.91428002 1.88741004 -1.91515 0 P 0 ;0
L 1.88741004 -1.91515 1.88733996 -1.91518996 0 P 0 ;0
L 1.88733996 -1.91518996 1.88728002 -1.91523996 0 P 0 ;0
L 1.88728002 -1.91523996 1.88526004 -1.9167 0 P 0 ;0
L 1.88526004 -1.9167 1.88521998 -1.91673002 0 P 0 ;0
L 1.88521998 -1.91673002 1.88518996 -1.91675 0 P 0 ;0
L 1.88518996 -1.91675 1.88516004 -1.91678002 0 P 0 ;0
L 1.88516004 -1.91678002 1.88511998 -1.91681004 0 P 0 ;0
L 1.88511998 -1.91681004 1.88323002 -1.91845 0 P 0 ;0
L 1.88323002 -1.91845 1.8832 -1.91846998 0 P 0 ;0
L 1.8832 -1.91846998 1.88311004 -1.91856004 0 P 0 ;0
L 1.88311004 -1.91856004 1.88136998 -1.92036004 0 P 0 ;0
L 1.88136998 -1.92036004 1.88128002 -1.92045 0 P 0 ;0
L 1.88128002 -1.92045 1.88125 -1.92048996 0 P 0 ;0
L 1.88125 -1.92048996 1.87968002 -1.92241998 0 P 0 ;0
L 1.87968002 -1.92241998 1.87965 -1.92245 0 P 0 ;0
L 1.87965 -1.92245 1.87961998 -1.92248996 0 P 0 ;0
L 1.87961998 -1.92248996 1.87956998 -1.92256004 0 P 0 ;0
L 1.87956998 -1.92256004 1.87816998 -1.92461998 0 P 0 ;0
L 1.87816998 -1.92461998 1.8781 -1.92473002 0 P 0 ;0
L 1.8781 -1.92473002 1.87808002 -1.92476998 0 P 0 ;0
L 1.87808002 -1.92476998 1.87685 -1.92695 0 P 0 ;0
L 1.87685 -1.92695 1.87683002 -1.92698996 0 P 0 ;0
L 1.87683002 -1.92698996 1.87681004 -1.92701998 0 P 0 ;0
L 1.87681004 -1.92701998 1.87678996 -1.92706998 0 P 0 ;0
L 1.87678996 -1.92706998 1.87676998 -1.92711004 0 P 0 ;0
L 1.87676998 -1.92711004 1.87573002 -1.92941004 0 P 0 ;0
L 1.87573002 -1.92941004 1.87571004 -1.92945 0 P 0 ;0
L 1.87571004 -1.92945 1.8757 -1.92948996 0 P 0 ;0
L 1.8757 -1.92948996 1.87568002 -1.92951998 0 P 0 ;0
L 1.87568002 -1.92951998 1.87566998 -1.92956998 0 P 0 ;0
L 1.87566998 -1.92956998 1.87483996 -1.93193002 0 P 0 ;0
L 1.87483996 -1.93193002 1.87481004 -1.93201004 0 P 0 ;0
L 1.87481004 -1.93201004 1.87478996 -1.93208996 0 P 0 ;0
L 1.87478996 -1.93208996 1.87416004 -1.93451998 0 P 0 ;0
L 1.87416004 -1.93451998 1.87413996 -1.93456004 0 P 0 ;0
L 1.87413996 -1.93456004 1.87413002 -1.9346 0 P 0 ;0
L 1.87413002 -1.9346 1.87413002 -1.93463996 0 P 0 ;0
L 1.87413002 -1.93463996 1.87411998 -1.93468002 0 P 0 ;0
L 1.87411998 -1.93468002 1.8737 -1.93715 0 P 0 ;0
L 1.8737 -1.93715 1.87368996 -1.93718996 0 P 0 ;0
L 1.87368996 -1.93718996 1.87368002 -1.93723996 0 P 0 ;0
L 1.87368002 -1.93723996 1.87368002 -1.93731998 0 P 0 ;0
L 1.87368002 -1.93731998 1.87346998 -1.93981998 0 P 0 ;0
L 1.87346998 -1.93981998 1.87346004 -1.93986004 0 P 0 ;0
L 1.87346004 -1.93986004 1.87346004 -1.94258002 0 P 0 ;0
L 1.87346004 -1.94258002 1.87346998 -1.94266004 0 P 0 ;0
L 1.87346998 -1.94266004 1.87368002 -1.94516998 0 P 0 ;0
L 1.87368002 -1.94516998 1.87368996 -1.94521004 0 P 0 ;0
L 1.87368996 -1.94521004 1.87368996 -1.94525 0 P 0 ;0
L 1.87368996 -1.94525 1.87371004 -1.94533996 0 P 0 ;0
L 1.87371004 -1.94533996 1.87413996 -1.94778996 0 P 0 ;0
L 1.87413996 -1.94778996 1.87413996 -1.94783996 0 P 0 ;0
L 1.87413996 -1.94783996 1.87416998 -1.94796004 0 P 0 ;0
L 1.87416998 -1.94796004 1.87481004 -1.95036998 0 P 0 ;0
L 1.87481004 -1.95036998 1.87483996 -1.95048996 0 P 0 ;0
L 1.87483996 -1.95048996 1.87486004 -1.95053002 0 P 0 ;0
L 1.87486004 -1.95053002 1.8757 -1.95288002 0 P 0 ;0
L 1.8757 -1.95288002 1.87571004 -1.95291998 0 P 0 ;0
L 1.87571004 -1.95291998 1.87575 -1.953 0 P 0 ;0
L 1.87575 -1.953 1.87576004 -1.95303996 0 P 0 ;0
L 1.87576004 -1.95303996 1.8768 -1.9553 0 P 0 ;0
L 1.8768 -1.9553 1.87686004 -1.95541998 0 P 0 ;0
L 1.87686004 -1.95541998 1.87688002 -1.95545 0 P 0 ;0
L 1.87688002 -1.95545 1.8781 -1.95761004 0 P 0 ;0
L 1.8781 -1.95761004 1.87811998 -1.95761004 0 P 0 ;0
L 1.87811998 -1.95761004 1.8781 -1.95761998 0 P 0 ;0
L 1.8781 -1.95761998 1.87813996 -1.95768996 0 P 0 ;0
L 1.87813996 -1.95768996 1.87816998 -1.95771998 0 P 0 ;0
L 1.87816998 -1.95771998 1.87818996 -1.95775 0 P 0 ;0
L 1.87818996 -1.95775 1.87938002 -1.95951004 0 P 0 ;0
L 1.87938002 -1.95951004 1.87943996 -1.9596 0 P 0 ;0
L 1.87943996 -1.9596 1.87946998 -1.95963002 0 P 0 ;0
L 1.87946998 -1.95963002 1.88078002 -1.96128996 0 P 0 ;0
L 1.88078002 -1.96128996 1.88081004 -1.96131998 0 P 0 ;0
L 1.88081004 -1.96131998 1.88083002 -1.96135 0 P 0 ;0
L 1.88083002 -1.96135 1.88086004 -1.96136998 0 P 0 ;0
L 1.88086004 -1.96136998 1.88088002 -1.9614 0 P 0 ;0
L 1.88088002 -1.9614 1.88231998 -1.96295 0 P 0 ;0
L 1.88231998 -1.96295 1.88233996 -1.96298002 0 P 0 ;0
L 1.88233996 -1.96298002 1.8824 -1.96303996 0 P 0 ;0
L 1.8824 -1.96303996 1.88243002 -1.96306004 0 P 0 ;0
L 1.88243002 -1.96306004 1.88398002 -1.9645 0 P 0 ;0
L 1.88398002 -1.9645 1.88401004 -1.96451998 0 P 0 ;0
L 1.88401004 -1.96451998 1.88403002 -1.96455 0 P 0 ;0
L 1.88403002 -1.96455 1.88406998 -1.96458002 0 P 0 ;0
L 1.88406998 -1.96458002 1.88408996 -1.9646 0 P 0 ;0
L 1.88408996 -1.9646 1.88575 -1.96591004 0 P 0 ;0
L 1.88575 -1.96591004 1.88578002 -1.96593996 0 P 0 ;0
L 1.88578002 -1.96593996 1.88586998 -1.966 0 P 0 ;0
L 1.88586998 -1.966 1.88761998 -1.96718996 0 P 0 ;0
L 1.88761998 -1.96718996 1.88766004 -1.96721004 0 P 0 ;0
L 1.88766004 -1.96721004 1.88775 -1.96726998 0 P 0 ;0
L 1.88775 -1.96726998 1.88958996 -1.96831998 0 P 0 ;0
L 1.88958996 -1.96831998 1.88965 -1.96836004 0 P 0 ;0
L 1.88965 -1.96836004 1.88968002 -1.96836998 0 P 0 ;0
L 1.88968002 -1.96836998 1.88971998 -1.96838996 0 P 0 ;0
L 1.88971998 -1.96838996 1.89145 -1.96921998 0 P 0 ;0
L 1.89145 -1.96921998 1.89151004 -1.96925 0 P 0 ;0
L 1.89151004 -1.96925 1.89155 -1.96926004 0 P 0 ;0
L 1.89155 -1.96926004 1.89158002 -1.96926998 0 P 0 ;0
L 1.89158002 -1.96926998 1.89336004 -1.96996998 0 P 0 ;0
L 1.89336004 -1.96996998 1.89336004 -1.96998002 0 P 0 ;0
L 1.89336004 -1.96998002 1.89346004 -1.97001004 0 P 0 ;0
L 1.89346004 -1.97001004 1.89348996 -1.97001998 0 P 0 ;0
L 1.89348996 -1.97001998 1.89531998 -1.9706 0 P 0 ;0
L 1.89531998 -1.9706 1.89536004 -1.97061004 0 P 0 ;0
L 1.89536004 -1.97061004 1.89541998 -1.97063002 0 P 0 ;0
L 1.89541998 -1.97063002 1.89546004 -1.97063002 0 P 0 ;0
L 1.89546004 -1.97063002 1.89731998 -1.97108002 0 P 0 ;0
L 1.89731998 -1.97108002 1.89741998 -1.9711 0 P 0 ;0
L 1.89741998 -1.9711 1.89746004 -1.9711 0 P 0 ;0
L 1.89746004 -1.9711 1.89746004 -1.97111004 0 P 0 ;0
L 1.89746004 -1.97111004 1.89933996 -1.97141998 0 P 0 ;0
L 1.89933996 -1.97141998 1.89936998 -1.97143002 0 P 0 ;0
L 1.89936998 -1.97143002 1.89941004 -1.97143002 0 P 0 ;0
L 1.89941004 -1.97143002 1.89945 -1.97143996 0 P 0 ;0
L 1.89945 -1.97143996 1.89948002 -1.97143996 0 P 0 ;0
L 1.89948002 -1.97143996 1.90201004 -1.97168002 0 P 0 ;0
L 1.90201004 -1.97168002 1.90205 -1.97168002 0 P 0 ;0
L 1.90205 -1.97168002 1.90208996 -1.97168996 0 P 0 ;0
L 1.90208996 -1.97168996 1.90216004 -1.97168996 0 P 0 ;0
L 1.90216004 -1.97168996 1.90468996 -1.97173996 0 P 0 ;0
L 1.90468996 -1.97173996 1.90476004 -1.97173996 0 P 0 ;0
L 1.80616004 -2.12823996 1.83348996 -2.12823996 0 P 0 ;0
L 1.79591998 -2.12723996 1.8396 -2.12723996 0 P 0 ;0
L 1.78818002 -2.12623996 1.84465 -2.12623996 0 P 0 ;0
L 1.82003996 -2.09123996 1.87618996 -2.09123996 0 P 0 ;0
L 1.82198996 -2.09023996 1.8762 -2.09023996 0 P 0 ;0
L 1.82325 -2.08923996 1.8762 -2.08923996 0 P 0 ;0
L 1.82411998 -2.08823996 1.87618996 -2.08823996 0 P 0 ;0
L 1.82463002 -2.08723996 1.87616998 -2.08723996 0 P 0 ;0
L 1.82488002 -2.08623996 1.87615 -2.08623996 0 P 0 ;0
L 1.82493002 -2.08523996 1.87613002 -2.08523996 0 P 0 ;0
L 1.82476998 -2.08423996 1.87611004 -2.08423996 0 P 0 ;0
L 1.64846004 -2.08295 1.73316998 -2.08295 0 P 0 ;0
L 1.64811998 -2.08195 1.73356998 -2.08195 0 P 0 ;0
L 1.64776998 -2.08095 1.73398002 -2.08095 0 P 0 ;0
L 1.64743002 -2.07995 1.73438002 -2.07995 0 P 0 ;0
L 1.64708996 -2.07895 1.73478996 -2.07895 0 P 0 ;0
L 1.64673996 -2.07795 1.7352 -2.07795 0 P 0 ;0
L 1.6464 -2.07695 1.7356 -2.07695 0 P 0 ;0
L 1.64605 -2.07595 1.73601004 -2.07595 0 P 0 ;0
L 1.64571004 -2.07495 1.73641004 -2.07495 0 P 0 ;0
L 1.64536004 -2.07395 1.73681004 -2.07395 0 P 0 ;0
L 1.64501998 -2.07295 1.73721998 -2.07295 0 P 0 ;0
L 1.64466998 -2.07195 1.73761998 -2.07195 0 P 0 ;0
L 1.64433002 -2.07095 1.73803002 -2.07095 0 P 0 ;0
L 1.64398002 -2.06995 1.69251004 -2.06995 0 P 0 ;0
L 1.69583002 -2.06995 1.73843996 -2.06995 0 P 0 ;0
L 1.64363002 -2.06895 1.69168002 -2.06895 0 P 0 ;0
L 1.69671998 -2.06895 1.73883996 -2.06895 0 P 0 ;0
L 1.64328996 -2.06795 1.69136004 -2.06795 0 P 0 ;0
L 1.69708996 -2.06795 1.73925 -2.06795 0 P 0 ;0
L 1.64293996 -2.06695 1.69108002 -2.06695 0 P 0 ;0
L 1.69738002 -2.06695 1.73965 -2.06695 0 P 0 ;0
L 1.64258996 -2.06595 1.6908 -2.06595 0 P 0 ;0
L 1.69768002 -2.06595 1.74006004 -2.06595 0 P 0 ;0
L 1.64223996 -2.06495 1.69051998 -2.06495 0 P 0 ;0
L 1.69796998 -2.06495 1.74046004 -2.06495 0 P 0 ;0
L 1.6419 -2.06395 1.69023002 -2.06395 0 P 0 ;0
L 1.69826998 -2.06395 1.74086004 -2.06395 0 P 0 ;0
L 1.64155 -2.06295 1.68996004 -2.06295 0 P 0 ;0
L 1.69856004 -2.06295 1.74126998 -2.06295 0 P 0 ;0
L 1.6412 -2.06195 1.68966998 -2.06195 0 P 0 ;0
L 1.69886004 -2.06195 1.74168002 -2.06195 0 P 0 ;0
L 1.64085 -2.06095 1.68938996 -2.06095 0 P 0 ;0
L 1.69915 -2.06095 1.74208002 -2.06095 0 P 0 ;0
L 1.6405 -2.05995 1.68911004 -2.05995 0 P 0 ;0
L 1.69945 -2.05995 1.74248002 -2.05995 0 P 0 ;0
L 1.64016004 -2.05895 1.68883002 -2.05895 0 P 0 ;0
L 1.69973996 -2.05895 1.74288996 -2.05895 0 P 0 ;0
L 1.63981004 -2.05795 1.68855 -2.05795 0 P 0 ;0
L 1.70003996 -2.05795 1.74328996 -2.05795 0 P 0 ;0
L 1.63946004 -2.05695 1.68826998 -2.05695 0 P 0 ;0
L 1.70033002 -2.05695 1.7437 -2.05695 0 P 0 ;0
L 1.63911004 -2.05595 1.68798996 -2.05595 0 P 0 ;0
L 1.70063002 -2.05595 1.7441 -2.05595 0 P 0 ;0
L 1.63876998 -2.05495 1.68771004 -2.05495 0 P 0 ;0
L 1.70091998 -2.05495 1.74451004 -2.05495 0 P 0 ;0
L 1.63841998 -2.05395 1.68741998 -2.05395 0 P 0 ;0
L 1.70121998 -2.05395 1.74491004 -2.05395 0 P 0 ;0
L 1.63806998 -2.05295 1.68713996 -2.05295 0 P 0 ;0
L 1.70151004 -2.05295 1.74531004 -2.05295 0 P 0 ;0
L 1.63771998 -2.05195 1.68686004 -2.05195 0 P 0 ;0
L 1.70181004 -2.05195 1.74571998 -2.05195 0 P 0 ;0
L 1.63738002 -2.05095 1.68658002 -2.05095 0 P 0 ;0
L 1.7021 -2.05095 1.74611998 -2.05095 0 P 0 ;0
L 1.63703002 -2.04995 1.6863 -2.04995 0 P 0 ;0
L 1.7024 -2.04995 1.74653002 -2.04995 0 P 0 ;0
L 1.63668002 -2.04895 1.68601998 -2.04895 0 P 0 ;0
L 1.70268996 -2.04895 1.74693002 -2.04895 0 P 0 ;0
L 1.63633002 -2.04795 1.68573996 -2.04795 0 P 0 ;0
L 1.70298996 -2.04795 1.74733002 -2.04795 0 P 0 ;0
L 1.63598002 -2.04695 1.68546004 -2.04695 0 P 0 ;0
L 1.70328002 -2.04695 1.74773996 -2.04695 0 P 0 ;0
L 1.63563996 -2.04595 1.68518002 -2.04595 0 P 0 ;0
L 1.70358002 -2.04595 1.74813996 -2.04595 0 P 0 ;0
L 1.63528996 -2.04495 1.6849 -2.04495 0 P 0 ;0
L 1.70386998 -2.04495 1.74855 -2.04495 0 P 0 ;0
L 1.63493996 -2.04395 1.68461004 -2.04395 0 P 0 ;0
L 1.70416998 -2.04395 1.74895 -2.04395 0 P 0 ;0
L 1.63458996 -2.04295 1.68433002 -2.04295 0 P 0 ;0
L 1.70446004 -2.04295 1.74936004 -2.04295 0 P 0 ;0
L 1.63425 -2.04195 1.68405 -2.04195 0 P 0 ;0
L 1.70475 -2.04195 1.74976004 -2.04195 0 P 0 ;0
L 1.6339 -2.04095 1.68376998 -2.04095 0 P 0 ;0
L 1.70503002 -2.04095 1.75016004 -2.04095 0 P 0 ;0
L 1.63355 -2.03995 1.68348996 -2.03995 0 P 0 ;0
L 1.70531998 -2.03995 1.75056998 -2.03995 0 P 0 ;0
L 1.6332 -2.03895 1.68321004 -2.03895 0 P 0 ;0
L 1.7056 -2.03895 1.75096998 -2.03895 0 P 0 ;0
L 1.63286004 -2.03795 1.68293002 -2.03795 0 P 0 ;0
L 1.70588996 -2.03795 1.75138002 -2.03795 0 P 0 ;0
L 1.63251004 -2.03695 1.68266004 -2.03695 0 P 0 ;0
L 1.70618002 -2.03695 1.75178002 -2.03695 0 P 0 ;0
L 1.63216004 -2.03595 1.68238002 -2.03595 0 P 0 ;0
L 1.70646998 -2.03595 1.75218996 -2.03595 0 P 0 ;0
L 1.63181004 -2.03495 1.6821 -2.03495 0 P 0 ;0
L 1.70675 -2.03495 1.75258996 -2.03495 0 P 0 ;0
L 1.63146998 -2.03395 1.68183002 -2.03395 0 P 0 ;0
L 1.70703996 -2.03395 1.75298996 -2.03395 0 P 0 ;0
L 1.63111998 -2.03295 1.68155 -2.03295 0 P 0 ;0
L 1.70733002 -2.03295 1.7534 -2.03295 0 P 0 ;0
L 1.63076998 -2.03195 1.68126998 -2.03195 0 P 0 ;0
L 1.70761004 -2.03195 1.75381004 -2.03195 0 P 0 ;0
L 1.63041998 -2.03095 1.68098996 -2.03095 0 P 0 ;0
L 1.7079 -2.03095 1.75421004 -2.03095 0 P 0 ;0
L 1.63006998 -2.02995 1.68071004 -2.02995 0 P 0 ;0
L 1.70818996 -2.02995 1.75461004 -2.02995 0 P 0 ;0
L 1.62973002 -2.02895 1.68043996 -2.02895 0 P 0 ;0
L 1.70846998 -2.02895 1.75501998 -2.02895 0 P 0 ;0
L 1.62938002 -2.02795 1.68016004 -2.02795 0 P 0 ;0
L 1.70876004 -2.02795 1.75541998 -2.02795 0 P 0 ;0
L 1.62903002 -2.02695 1.67988002 -2.02695 0 P 0 ;0
L 1.70905 -2.02695 1.75583002 -2.02695 0 P 0 ;0
L 1.62868002 -2.02595 1.6796 -2.02595 0 P 0 ;0
L 1.70933996 -2.02595 1.75623002 -2.02595 0 P 0 ;0
L 1.62831004 -2.02495 1.67933002 -2.02495 0 P 0 ;0
L 1.70961998 -2.02495 1.75663996 -2.02495 0 P 0 ;0
L 1.62793996 -2.02395 1.67905 -2.02395 0 P 0 ;0
L 1.70991004 -2.02395 1.75703996 -2.02395 0 P 0 ;0
L 1.62756998 -2.02295 1.67876998 -2.02295 0 P 0 ;0
L 1.7102 -2.02295 1.75743996 -2.02295 0 P 0 ;0
L 1.6272 -2.02195 1.6785 -2.02195 0 P 0 ;0
L 1.71048002 -2.02195 1.75785 -2.02195 0 P 0 ;0
L 1.62683002 -2.02095 1.67821998 -2.02095 0 P 0 ;0
L 1.71076004 -2.02095 1.75825 -2.02095 0 P 0 ;0
L 1.62646998 -2.01995 1.67793996 -2.01995 0 P 0 ;0
L 1.71101004 -2.01995 1.75866004 -2.01995 0 P 0 ;0
L 1.6261 -2.01895 1.67766004 -2.01895 0 P 0 ;0
L 1.71126998 -2.01895 1.75906004 -2.01895 0 P 0 ;0
L 1.62573002 -2.01795 1.67738996 -2.01795 0 P 0 ;0
L 1.71151998 -2.01795 1.75946998 -2.01795 0 P 0 ;0
L 1.62536004 -2.01695 1.67711004 -2.01695 0 P 0 ;0
L 1.71176998 -2.01695 1.75986998 -2.01695 0 P 0 ;0
L 1.62498996 -2.01595 1.67683002 -2.01595 0 P 0 ;0
L 1.71203002 -2.01595 1.76026998 -2.01595 0 P 0 ;0
L 1.62461998 -2.01495 1.67656004 -2.01495 0 P 0 ;0
L 1.71228002 -2.01495 1.76068002 -2.01495 0 P 0 ;0
L 1.62425 -2.01395 1.67628002 -2.01395 0 P 0 ;0
L 1.71253996 -2.01395 1.76108002 -2.01395 0 P 0 ;0
L 1.62388002 -2.01295 1.67601998 -2.01295 0 P 0 ;0
L 1.71278996 -2.01295 1.76148996 -2.01295 0 P 0 ;0
L 1.62351004 -2.01195 1.67576998 -2.01195 0 P 0 ;0
L 1.71305 -2.01195 1.76188996 -2.01195 0 P 0 ;0
L 1.62313996 -2.01095 1.67551998 -2.01095 0 P 0 ;0
L 1.7133 -2.01095 1.76228996 -2.01095 0 P 0 ;0
L 1.62276998 -2.00995 1.67528002 -2.00995 0 P 0 ;0
L 1.71355 -2.00995 1.7627 -2.00995 0 P 0 ;0
L 1.6224 -2.00895 1.67503002 -2.00895 0 P 0 ;0
L 1.71381004 -2.00895 1.7631 -2.00895 0 P 0 ;0
L 1.62203002 -2.00795 1.67478996 -2.00795 0 P 0 ;0
L 1.71406004 -2.00795 1.76351004 -2.00795 0 P 0 ;0
L 1.62166004 -2.00695 1.67453996 -2.00695 0 P 0 ;0
L 1.71431004 -2.00695 1.76391004 -2.00695 0 P 0 ;0
L 1.62128996 -2.00595 1.67428996 -2.00595 0 P 0 ;0
L 1.71453996 -2.00595 1.76431998 -2.00595 0 P 0 ;0
L 1.62091004 -2.00495 1.67405 -2.00495 0 P 0 ;0
L 1.71476998 -2.00495 1.76471998 -2.00495 0 P 0 ;0
L 1.62051998 -2.00395 1.6738 -2.00395 0 P 0 ;0
L 1.715 -2.00395 1.76511998 -2.00395 0 P 0 ;0
L 1.62013002 -2.00295 1.67355 -2.00295 0 P 0 ;0
L 1.71523002 -2.00295 1.76553002 -2.00295 0 P 0 ;0
L 1.61973996 -2.00195 1.67331004 -2.00195 0 P 0 ;0
L 1.71546004 -2.00195 1.76593996 -2.00195 0 P 0 ;0
L 1.61935 -2.00095 1.67306004 -2.00095 0 P 0 ;0
L 1.71568996 -2.00095 1.76633996 -2.00095 0 P 0 ;0
L 1.61896004 -1.99995 1.67283996 -1.99995 0 P 0 ;0
L 1.71591998 -1.99995 1.76673996 -1.99995 0 P 0 ;0
L 1.61856998 -1.99895 1.67261998 -1.99895 0 P 0 ;0
L 1.71613996 -1.99895 1.76715 -1.99895 0 P 0 ;0
L 1.71638002 -1.99795 1.76755 -1.99795 0 P 0 ;0
L 1.7166 -1.99695 1.76796004 -1.99695 0 P 0 ;0
L 1.71683002 -1.99595 1.76836004 -1.99595 0 P 0 ;0
L 1.71866998 -1.99495 1.76876998 -1.99495 0 P 0 ;0
L 1.78213996 -2.04823996 1.84641998 -2.04823996 0 P 0 ;0
L 1.78138002 -2.04723996 1.84498996 -2.04723996 0 P 0 ;0
L 1.78071004 -2.04623996 1.84356004 -2.04623996 0 P 0 ;0
L 1.7801 -2.04523996 1.84213996 -2.04523996 0 P 0 ;0
L 1.77956004 -2.04423996 1.84071004 -2.04423996 0 P 0 ;0
L 1.77908996 -2.04323996 1.83928002 -2.04323996 0 P 0 ;0
L 1.77866004 -2.04223996 1.83786004 -2.04223996 0 P 0 ;0
L 1.77831004 -2.04123996 1.83658996 -2.04123996 0 P 0 ;0
L 1.77796004 -2.04023996 1.83536004 -2.04023996 0 P 0 ;0
L 1.77761004 -2.03923996 1.83428002 -2.03923996 0 P 0 ;0
L 1.77733996 -2.03823996 1.83321998 -2.03823996 0 P 0 ;0
L 1.77706998 -2.03723996 1.83236998 -2.03723996 0 P 0 ;0
L 1.7768 -2.03623996 1.83171004 -2.03623996 0 P 0 ;0
L 1.7766 -2.03523996 1.83121004 -2.03523996 0 P 0 ;0
L 1.77641004 -2.03423996 1.83085 -2.03423996 0 P 0 ;0
L 1.77621004 -2.03323996 1.83071004 -2.03323996 0 P 0 ;0
L 1.77608002 -2.03223996 1.83076998 -2.03223996 0 P 0 ;0
L 1.77596004 -2.03123996 1.83106004 -2.03123996 0 P 0 ;0
L 1.77583996 -2.03023996 1.83158996 -2.03023996 0 P 0 ;0
L 1.77576004 -2.02923996 1.83238002 -2.02923996 0 P 0 ;0
L 1.7757 -2.02823996 1.83356998 -2.02823996 0 P 0 ;0
L 1.7757 -2.02723996 1.83591998 -2.02723996 0 P 0 ;0
L 1.77571998 -2.02623996 1.87495 -2.02623996 0 P 0 ;0
L 1.7758 -2.02523996 1.87485 -2.02523996 0 P 0 ;0
L 1.77588996 -2.02423996 1.87475 -2.02423996 0 P 0 ;0
L 1.77605 -2.02323996 1.87465 -2.02323996 0 P 0 ;0
L 1.77621004 -2.02223996 1.87455 -2.02223996 0 P 0 ;0
L 1.7764 -2.02123996 1.87445 -2.02123996 0 P 0 ;0
L 1.77665 -2.02023996 1.87433996 -2.02023996 0 P 0 ;0
L 1.7769 -2.01923996 1.87425 -2.01923996 0 P 0 ;0
L 1.7772 -2.01823996 1.87413996 -2.01823996 0 P 0 ;0
L 1.77753002 -2.01723996 1.87405 -2.01723996 0 P 0 ;0
L 1.77786004 -2.01623996 1.87393996 -2.01623996 0 P 0 ;0
L 1.77823002 -2.01523996 1.87383996 -2.01523996 0 P 0 ;0
L 1.77863996 -2.01423996 1.87373996 -2.01423996 0 P 0 ;0
L 1.77903996 -2.01323996 1.87363996 -2.01323996 0 P 0 ;0
L 1.7795 -2.01223996 1.87353996 -2.01223996 0 P 0 ;0
L 1.77998996 -2.01123996 1.87343996 -2.01123996 0 P 0 ;0
L 1.78046998 -2.01023996 1.87333002 -2.01023996 0 P 0 ;0
L 1.78103996 -2.00923996 1.87323002 -2.00923996 0 P 0 ;0
L 1.78161004 -2.00823996 1.87311998 -2.00823996 0 P 0 ;0
L 1.78221004 -2.00723996 1.87301998 -2.00723996 0 P 0 ;0
L 1.78288002 -2.00623996 1.87291998 -2.00623996 0 P 0 ;0
L 1.64213996 -2.14795 1.70566004 -2.14795 0 P 0 ;0
L 1.64518996 -2.14695 1.7062 -2.14695 0 P 0 ;0
L 1.64728996 -2.14595 1.70673996 -2.14595 0 P 0 ;0
L 1.64906998 -2.14495 1.70728002 -2.14495 0 P 0 ;0
L 1.65058002 -2.14395 1.70783002 -2.14395 0 P 0 ;0
L 1.6519 -2.14295 1.70836998 -2.14295 0 P 0 ;0
L 1.65311998 -2.14195 1.70881998 -2.14195 0 P 0 ;0
L 1.65416998 -2.14095 1.70926998 -2.14095 0 P 0 ;0
L 1.65508996 -2.13995 1.70973002 -2.13995 0 P 0 ;0
L 1.65588002 -2.13895 1.71018002 -2.13895 0 P 0 ;0
L 1.65658002 -2.13795 1.71063002 -2.13795 0 P 0 ;0
L 1.65726998 -2.13695 1.71108996 -2.13695 0 P 0 ;0
L 1.65791998 -2.13595 1.71153996 -2.13595 0 P 0 ;0
L 1.65853002 -2.13495 1.71198996 -2.13495 0 P 0 ;0
L 1.65913002 -2.13395 1.71245 -2.13395 0 P 0 ;0
L 1.65968002 -2.13295 1.7129 -2.13295 0 P 0 ;0
L 1.66021998 -2.13195 1.71331004 -2.13195 0 P 0 ;0
L 1.66071998 -2.13095 1.71371998 -2.13095 0 P 0 ;0
L 1.66121004 -2.12995 1.71411998 -2.12995 0 P 0 ;0
L 1.66166998 -2.12895 1.71453002 -2.12895 0 P 0 ;0
L 1.66201004 -2.12795 1.71493996 -2.12795 0 P 0 ;0
L 1.66223996 -2.12695 1.71533996 -2.12695 0 P 0 ;0
L 1.66235 -2.12595 1.71575 -2.12595 0 P 0 ;0
L 1.66236004 -2.12495 1.71615 -2.12495 0 P 0 ;0
L 1.66228002 -2.12395 1.71656004 -2.12395 0 P 0 ;0
L 1.66211998 -2.12295 1.71696004 -2.12295 0 P 0 ;0
L 1.66188002 -2.12195 1.71736004 -2.12195 0 P 0 ;0
L 1.66156004 -2.12095 1.71776998 -2.12095 0 P 0 ;0
L 1.66121004 -2.11995 1.71818002 -2.11995 0 P 0 ;0
L 1.66086998 -2.11895 1.71858002 -2.11895 0 P 0 ;0
L 1.66053002 -2.11795 1.71898996 -2.11795 0 P 0 ;0
L 1.66018002 -2.11695 1.71938996 -2.11695 0 P 0 ;0
L 1.65983996 -2.11595 1.7198 -2.11595 0 P 0 ;0
L 1.65948996 -2.11495 1.7202 -2.11495 0 P 0 ;0
L 1.65913996 -2.11395 1.72061004 -2.11395 0 P 0 ;0
L 1.6588 -2.11295 1.72101004 -2.11295 0 P 0 ;0
L 1.65846004 -2.11195 1.72141998 -2.11195 0 P 0 ;0
L 1.65811004 -2.11095 1.72181998 -2.11095 0 P 0 ;0
L 1.65776998 -2.10995 1.72223002 -2.10995 0 P 0 ;0
L 1.65741998 -2.10895 1.72263002 -2.10895 0 P 0 ;0
L 1.65708002 -2.10795 1.72303996 -2.10795 0 P 0 ;0
L 1.65673002 -2.10695 1.72343996 -2.10695 0 P 0 ;0
L 1.65638996 -2.10595 1.72385 -2.10595 0 P 0 ;0
L 1.65605 -2.10495 1.72425 -2.10495 0 P 0 ;0
L 1.6557 -2.10395 1.72466004 -2.10395 0 P 0 ;0
L 1.65536004 -2.10295 1.72506998 -2.10295 0 P 0 ;0
L 1.65501004 -2.10195 1.72546998 -2.10195 0 P 0 ;0
L 1.65466998 -2.10095 1.72588002 -2.10095 0 P 0 ;0
L 1.65431998 -2.09995 1.72628002 -2.09995 0 P 0 ;0
L 1.65398002 -2.09895 1.72668996 -2.09895 0 P 0 ;0
L 1.65363002 -2.09795 1.72708996 -2.09795 0 P 0 ;0
L 1.65328996 -2.09695 1.72748996 -2.09695 0 P 0 ;0
L 1.65293996 -2.09595 1.7279 -2.09595 0 P 0 ;0
L 1.6526 -2.09495 1.72831004 -2.09495 0 P 0 ;0
L 1.65225 -2.09395 1.72871004 -2.09395 0 P 0 ;0
L 1.65191004 -2.09295 1.72911998 -2.09295 0 P 0 ;0
L 1.65156998 -2.09195 1.72951998 -2.09195 0 P 0 ;0
L 1.65121998 -2.09095 1.72993002 -2.09095 0 P 0 ;0
L 1.65088002 -2.08995 1.73033002 -2.08995 0 P 0 ;0
L 1.65053002 -2.08895 1.73073996 -2.08895 0 P 0 ;0
L 1.65018996 -2.08795 1.73113996 -2.08795 0 P 0 ;0
L 1.64983996 -2.08695 1.73155 -2.08695 0 P 0 ;0
L 1.6495 -2.08595 1.73195 -2.08595 0 P 0 ;0
L 1.64915 -2.08495 1.73236004 -2.08495 0 P 0 ;0
L 1.64881004 -2.08395 1.73276004 -2.08395 0 P 0 ;0
L 1.81726998 -1.98915 1.81196004 -1.9899 0 P 0 ;0
L 1.81196004 -1.9899 1.80668996 -1.99096998 0 P 0 ;0
L 1.80668996 -1.99096998 1.8019 -1.99226004 0 P 0 ;0
L 1.8019 -1.99226004 1.79718996 -1.99391004 0 P 0 ;0
L 1.79718996 -1.99391004 1.79316004 -1.99568002 0 P 0 ;0
L 1.79316004 -1.99568002 1.78926998 -1.99778002 0 P 0 ;0
L 1.78926998 -1.99778002 1.78771004 -1.99878002 0 P 0 ;0
L 1.78771004 -1.99878002 1.78623002 -1.99988002 0 P 0 ;0
L 1.78623002 -1.99988002 1.78481004 -2.00108002 0 P 0 ;0
L 1.78481004 -2.00108002 1.78346998 -2.00238996 0 P 0 ;0
L 1.78346998 -2.00238996 1.78228996 -2.00371998 0 P 0 ;0
L 1.78228996 -2.00371998 1.78121004 -2.00513002 0 P 0 ;0
L 1.78121004 -2.00513002 1.78023002 -2.00661004 0 P 0 ;0
L 1.78023002 -2.00661004 1.77868002 -2.00933996 0 P 0 ;0
L 1.77868002 -2.00933996 1.77731998 -2.01216998 0 P 0 ;0
L 1.77731998 -2.01216998 1.77611004 -2.01516004 0 P 0 ;0
L 1.77611004 -2.01516004 1.77508996 -2.01823002 0 P 0 ;0
L 1.77508996 -2.01823002 1.77436998 -2.02111004 0 P 0 ;0
L 1.77436998 -2.02111004 1.77388996 -2.02406004 0 P 0 ;0
L 1.77388996 -2.02406004 1.77371998 -2.02603996 0 P 0 ;0
L 1.77371998 -2.02603996 1.77368996 -2.02801998 0 P 0 ;0
L 1.77368996 -2.02801998 1.7738 -2.03001998 0 P 0 ;0
L 1.7738 -2.03001998 1.7742 -2.03338996 0 P 0 ;0
L 1.7742 -2.03338996 1.77485 -2.03671004 0 P 0 ;0
L 1.77485 -2.03671004 1.77573002 -2.03993996 0 P 0 ;0
L 1.77573002 -2.03993996 1.77683996 -2.04308002 0 P 0 ;0
L 1.77683996 -2.04308002 1.7776 -2.04481998 0 P 0 ;0
L 1.7776 -2.04481998 1.7785 -2.04648996 0 P 0 ;0
L 1.7785 -2.04648996 1.77953002 -2.04808996 0 P 0 ;0
L 1.77953002 -2.04808996 1.78061004 -2.04953996 0 P 0 ;0
L 1.78061004 -2.04953996 1.78181004 -2.05091004 0 P 0 ;0
L 1.78181004 -2.05091004 1.78311004 -2.05218996 0 P 0 ;0
L 1.78311004 -2.05218996 1.78988996 -2.05801998 0 P 0 ;0
L 1.78988996 -2.05801998 1.79883996 -2.06491004 0 P 0 ;0
L 1.79883996 -2.06491004 1.80976998 -2.07261004 0 P 0 ;0
L 1.80976998 -2.07261004 1.81753002 -2.07823002 0 P 0 ;0
L 1.81753002 -2.07823002 1.81896998 -2.07943002 0 P 0 ;0
L 1.81896998 -2.07943002 1.82033002 -2.08073002 0 P 0 ;0
L 1.82033002 -2.08073002 1.82156998 -2.08213996 0 P 0 ;0
L 1.82156998 -2.08213996 1.82186004 -2.08251004 0 P 0 ;0
L 1.82186004 -2.08251004 1.82211004 -2.0829 0 P 0 ;0
L 1.82211004 -2.0829 1.82233002 -2.08331004 0 P 0 ;0
L 1.82233002 -2.08331004 1.82253002 -2.08373996 0 P 0 ;0
L 1.82253002 -2.08373996 1.82268002 -2.08418002 0 P 0 ;0
L 1.82268002 -2.08418002 1.82281004 -2.08463002 0 P 0 ;0
L 1.82281004 -2.08463002 1.8229 -2.0851 0 P 0 ;0
L 1.8229 -2.0851 1.82293002 -2.08533996 0 P 0 ;0
L 1.82293002 -2.08533996 1.82293996 -2.08558996 0 P 0 ;0
L 1.82293996 -2.08558996 1.82291998 -2.08583996 0 P 0 ;0
L 1.82291998 -2.08583996 1.82288002 -2.08608002 0 P 0 ;0
L 1.82288002 -2.08608002 1.82283002 -2.08631998 0 P 0 ;0
L 1.82283002 -2.08631998 1.82275 -2.08656004 0 P 0 ;0
L 1.82275 -2.08656004 1.82265 -2.08678996 0 P 0 ;0
L 1.82265 -2.08678996 1.82253996 -2.087 0 P 0 ;0
L 1.82253996 -2.087 1.8224 -2.08721004 0 P 0 ;0
L 1.8224 -2.08721004 1.82225 -2.08741004 0 P 0 ;0
L 1.82225 -2.08741004 1.82208996 -2.08758996 0 P 0 ;0
L 1.82208996 -2.08758996 1.8216 -2.08803996 0 P 0 ;0
L 1.8216 -2.08803996 1.82106998 -2.08845 0 P 0 ;0
L 1.82106998 -2.08845 1.82051004 -2.08881004 0 P 0 ;0
L 1.82051004 -2.08881004 1.81991998 -2.08911998 0 P 0 ;0
L 1.81991998 -2.08911998 1.81931004 -2.08936998 0 P 0 ;0
L 1.81931004 -2.08936998 1.81868002 -2.08958002 0 P 0 ;0
L 1.81868002 -2.08958002 1.81803002 -2.08973002 0 P 0 ;0
L 1.81803002 -2.08973002 1.81736004 -2.08981998 0 P 0 ;0
L 1.81736004 -2.08981998 1.81293002 -2.09001998 0 P 0 ;0
L 1.81293002 -2.09001998 1.80846998 -2.08986004 0 P 0 ;0
L 1.80846998 -2.08986004 1.80256998 -2.08923002 0 P 0 ;0
L 1.80256998 -2.08923002 1.79668002 -2.08818996 0 P 0 ;0
L 1.79668002 -2.08818996 1.78223002 -2.08458002 0 P 0 ;0
L 1.78223002 -2.08458002 1.77788996 -2.08338002 0 P 0 ;0
L 1.77788996 -2.08338002 1.77415 -2.08246004 0 P 0 ;0
L 1.77415 -2.08246004 1.77095 -2.08175 0 P 0 ;0
L 1.77095 -2.08175 1.7709 -2.08173996 0 P 0 ;0
L 1.7709 -2.08173996 1.77076998 -2.08173996 0 P 0 ;0
L 1.77076998 -2.08173996 1.77068996 -2.08176004 0 P 0 ;0
L 1.77068996 -2.08176004 1.77053002 -2.08183996 0 P 0 ;0
L 1.77053002 -2.08183996 1.77043002 -2.08193996 0 P 0 ;0
L 1.77043002 -2.08193996 1.77036998 -2.08201998 0 P 0 ;0
L 1.77036998 -2.08201998 1.77031998 -2.08211998 0 P 0 ;0
L 1.77031998 -2.08211998 1.7703 -2.08216998 0 P 0 ;0
L 1.7703 -2.08216998 1.77028996 -2.08223002 0 P 0 ;0
L 1.77028996 -2.08223002 1.77028002 -2.08228002 0 P 0 ;0
L 1.77028002 -2.08228002 1.77028002 -2.08238996 0 P 0 ;0
L 1.77028002 -2.08238996 1.77056998 -2.08838996 0 P 0 ;0
L 1.77056998 -2.08838996 1.77096004 -2.09526004 0 P 0 ;0
L 1.77096004 -2.09526004 1.77153996 -2.1033 0 P 0 ;0
L 1.77153996 -2.1033 1.77236004 -2.11291004 0 P 0 ;0
L 1.77236004 -2.11291004 1.77311004 -2.1194 0 P 0 ;0
L 1.77311004 -2.1194 1.77383002 -2.12398002 0 P 0 ;0
L 1.77383002 -2.12398002 1.77386004 -2.12411004 0 P 0 ;0
L 1.77386004 -2.12411004 1.7739 -2.12423002 0 P 0 ;0
L 1.7739 -2.12423002 1.77395 -2.12436004 0 P 0 ;0
L 1.77395 -2.12436004 1.77401004 -2.12448002 0 P 0 ;0
L 1.77401004 -2.12448002 1.77408002 -2.12458996 0 P 0 ;0
L 1.77408002 -2.12458996 1.77416004 -2.1247 0 P 0 ;0
L 1.77416004 -2.1247 1.77425 -2.1248 0 P 0 ;0
L 1.77425 -2.1248 1.77435 -2.12488996 0 P 0 ;0
L 1.77435 -2.12488996 1.77445 -2.12496998 0 P 0 ;0
L 1.77445 -2.12496998 1.77456998 -2.12505 0 P 0 ;0
L 1.77456998 -2.12505 1.77571004 -2.12568996 0 P 0 ;0
L 1.77571004 -2.12568996 1.7769 -2.12623996 0 P 0 ;0
L 1.7769 -2.12623996 1.77813002 -2.12668996 0 P 0 ;0
L 1.77813002 -2.12668996 1.7794 -2.12703996 0 P 0 ;0
L 1.7794 -2.12703996 1.78068996 -2.12728996 0 P 0 ;0
L 1.78068996 -2.12728996 1.79791998 -2.12951004 0 P 0 ;0
L 1.79791998 -2.12951004 1.81536004 -2.13106004 0 P 0 ;0
L 1.81536004 -2.13106004 1.82125 -2.13123996 0 P 0 ;0
L 1.82125 -2.13123996 1.82716004 -2.13098996 0 P 0 ;0
L 1.82716004 -2.13098996 1.83583996 -2.12998002 0 P 0 ;0
L 1.83583996 -2.12998002 1.84445 -2.12836004 0 P 0 ;0
L 1.84445 -2.12836004 1.84911998 -2.12711004 0 P 0 ;0
L 1.84911998 -2.12711004 1.85366004 -2.12548002 0 P 0 ;0
L 1.85366004 -2.12548002 1.85806998 -2.12348002 0 P 0 ;0
L 1.85806998 -2.12348002 1.86078996 -2.12196998 0 P 0 ;0
L 1.86078996 -2.12196998 1.8634 -2.12026998 0 P 0 ;0
L 1.8634 -2.12026998 1.86586998 -2.11836998 0 P 0 ;0
L 1.86586998 -2.11836998 1.86821004 -2.11628002 0 P 0 ;0
L 1.86821004 -2.11628002 1.87026004 -2.11413002 0 P 0 ;0
L 1.87026004 -2.11413002 1.8721 -2.11181998 0 P 0 ;0
L 1.8721 -2.11181998 1.87375 -2.10936004 0 P 0 ;0
L 1.87375 -2.10936004 1.87516998 -2.10673996 0 P 0 ;0
L 1.87516998 -2.10673996 1.87605 -2.10483996 0 P 0 ;0
L 1.87605 -2.10483996 1.87683996 -2.10291004 0 P 0 ;0
L 1.87683996 -2.10291004 1.8772 -2.10188002 0 P 0 ;0
L 1.8772 -2.10188002 1.87748996 -2.10083002 0 P 0 ;0
L 1.87748996 -2.10083002 1.87771004 -2.09976998 0 P 0 ;0
L 1.87771004 -2.09976998 1.87798002 -2.09788996 0 P 0 ;0
L 1.87798002 -2.09788996 1.87811998 -2.09601004 0 P 0 ;0
L 1.87811998 -2.09601004 1.87821004 -2.08966998 0 P 0 ;0
L 1.87821004 -2.08966998 1.8781 -2.08353996 0 P 0 ;0
L 1.8781 -2.08353996 1.87798002 -2.08166004 0 P 0 ;0
L 1.87798002 -2.08166004 1.87773002 -2.07976998 0 P 0 ;0
L 1.87773002 -2.07976998 1.87753002 -2.07873996 0 P 0 ;0
L 1.87753002 -2.07873996 1.87726998 -2.07773996 0 P 0 ;0
L 1.87726998 -2.07773996 1.87695 -2.07673996 0 P 0 ;0
L 1.87695 -2.07673996 1.87628996 -2.07505 0 P 0 ;0
L 1.87628996 -2.07505 1.87553002 -2.07338002 0 P 0 ;0
L 1.87553002 -2.07338002 1.87441004 -2.07133996 0 P 0 ;0
L 1.87441004 -2.07133996 1.87313996 -2.06938002 0 P 0 ;0
L 1.87313996 -2.06938002 1.87171004 -2.06751004 0 P 0 ;0
L 1.87171004 -2.06751004 1.8688 -2.06416004 0 P 0 ;0
L 1.8688 -2.06416004 1.86566998 -2.06095 0 P 0 ;0
L 1.86566998 -2.06095 1.86181998 -2.05741998 0 P 0 ;0
L 1.86181998 -2.05741998 1.85778002 -2.05406998 0 P 0 ;0
L 1.85778002 -2.05406998 1.84833996 -2.04715 0 P 0 ;0
L 1.84833996 -2.04715 1.83913996 -2.0407 0 P 0 ;0
L 1.83913996 -2.0407 1.83686004 -2.0389 0 P 0 ;0
L 1.83686004 -2.0389 1.83471998 -2.03691998 0 P 0 ;0
L 1.83471998 -2.03691998 1.83428002 -2.03643002 0 P 0 ;0
L 1.83428002 -2.03643002 1.83386998 -2.0359 0 P 0 ;0
L 1.83386998 -2.0359 1.83351004 -2.03535 0 P 0 ;0
L 1.83351004 -2.03535 1.83318996 -2.03476004 0 P 0 ;0
L 1.83318996 -2.03476004 1.83291998 -2.03415 0 P 0 ;0
L 1.83291998 -2.03415 1.83283996 -2.03393996 0 P 0 ;0
L 1.83283996 -2.03393996 1.83278002 -2.03371004 0 P 0 ;0
L 1.83278002 -2.03371004 1.83273002 -2.03348996 0 P 0 ;0
L 1.83273002 -2.03348996 1.83271004 -2.03326004 0 P 0 ;0
L 1.83271004 -2.03326004 1.8327 -2.03303002 0 P 0 ;0
L 1.8327 -2.03303002 1.83271004 -2.0328 0 P 0 ;0
L 1.83271004 -2.0328 1.83275 -2.03258002 0 P 0 ;0
L 1.83275 -2.03258002 1.83278996 -2.03235 0 P 0 ;0
L 1.83278996 -2.03235 1.83286004 -2.03213002 0 P 0 ;0
L 1.83286004 -2.03213002 1.83293996 -2.03191998 0 P 0 ;0
L 1.83293996 -2.03191998 1.83305 -2.03171004 0 P 0 ;0
L 1.83305 -2.03171004 1.83325 -2.03135 0 P 0 ;0
L 1.83325 -2.03135 1.83348996 -2.03101998 0 P 0 ;0
L 1.83348996 -2.03101998 1.83375 -2.03071004 0 P 0 ;0
L 1.83375 -2.03071004 1.83403002 -2.03041004 0 P 0 ;0
L 1.83403002 -2.03041004 1.83433996 -2.03015 0 P 0 ;0
L 1.83433996 -2.03015 1.83466998 -2.02991004 0 P 0 ;0
L 1.83466998 -2.02991004 1.83501998 -2.02968996 0 P 0 ;0
L 1.83501998 -2.02968996 1.83538002 -2.02951004 0 P 0 ;0
L 1.83538002 -2.02951004 1.83576004 -2.02936004 0 P 0 ;0
L 1.83576004 -2.02936004 1.83615 -2.02923996 0 P 0 ;0
L 1.83615 -2.02923996 1.83655 -2.02915 0 P 0 ;0
L 1.83655 -2.02915 1.8392 -2.02873996 0 P 0 ;0
L 1.8392 -2.02873996 1.84188002 -2.0285 0 P 0 ;0
L 1.84188002 -2.0285 1.84458002 -2.02841004 0 P 0 ;0
L 1.84458002 -2.02841004 1.84993996 -2.02858002 0 P 0 ;0
L 1.84993996 -2.02858002 1.85526998 -2.02916004 0 P 0 ;0
L 1.85526998 -2.02916004 1.86155 -2.03023002 0 P 0 ;0
L 1.86155 -2.03023002 1.86778002 -2.03158002 0 P 0 ;0
L 1.86778002 -2.03158002 1.8713 -2.03238996 0 P 0 ;0
L 1.8713 -2.03238996 1.87428996 -2.03303002 0 P 0 ;0
L 1.87428996 -2.03303002 1.8769 -2.03356004 0 P 0 ;0
L 1.8769 -2.03356004 1.87691998 -2.03356998 0 P 0 ;0
L 1.87691998 -2.03356998 1.87696004 -2.03356998 0 P 0 ;0
L 1.87696004 -2.03356998 1.87696998 -2.03356004 0 P 0 ;0
L 1.87696998 -2.03356004 1.87701004 -2.03356004 0 P 0 ;0
L 1.87701004 -2.03356004 1.87703996 -2.03353996 0 P 0 ;0
L 1.87703996 -2.03353996 1.87706004 -2.03353002 0 P 0 ;0
L 1.87706004 -2.03353002 1.87706998 -2.03351998 0 P 0 ;0
L 1.87706998 -2.03351998 1.87708996 -2.03351004 0 P 0 ;0
L 1.87708996 -2.03351004 1.8771 -2.03348996 0 P 0 ;0
L 1.8771 -2.03348996 1.87711004 -2.03348002 0 P 0 ;0
L 1.87711004 -2.03348002 1.87721998 -2.0333 0 P 0 ;0
L 1.87721998 -2.0333 1.87731998 -2.0331 0 P 0 ;0
L 1.87731998 -2.0331 1.8774 -2.0329 0 P 0 ;0
L 1.8774 -2.0329 1.87746004 -2.03268996 0 P 0 ;0
L 1.87746004 -2.03268996 1.87751004 -2.03248002 0 P 0 ;0
L 1.87751004 -2.03248002 1.87753002 -2.03226998 0 P 0 ;0
L 1.87753002 -2.03226998 1.87753996 -2.03205 0 P 0 ;0
L 1.87753996 -2.03205 1.87753002 -2.03183002 0 P 0 ;0
L 1.87753002 -2.03183002 1.87565 -2.01323996 0 P 0 ;0
L 1.87565 -2.01323996 1.87371004 -1.99451998 0 P 0 ;0
L 1.87371004 -1.99451998 1.8737 -1.99438996 0 P 0 ;0
L 1.8737 -1.99438996 1.87366998 -1.99426998 0 P 0 ;0
L 1.87366998 -1.99426998 1.87363002 -1.99415 0 P 0 ;0
L 1.87363002 -1.99415 1.87358002 -1.99403002 0 P 0 ;0
L 1.87358002 -1.99403002 1.87351998 -1.99391004 0 P 0 ;0
L 1.87351998 -1.99391004 1.87346004 -1.9938 0 P 0 ;0
L 1.87346004 -1.9938 1.87338002 -1.9937 0 P 0 ;0
L 1.87338002 -1.9937 1.87328996 -1.9936 0 P 0 ;0
L 1.87328996 -1.9936 1.8732 -1.99351004 0 P 0 ;0
L 1.8732 -1.99351004 1.8731 -1.99343002 0 P 0 ;0
L 1.8731 -1.99343002 1.87298996 -1.99335 0 P 0 ;0
L 1.87298996 -1.99335 1.87248002 -1.99305 0 P 0 ;0
L 1.87248002 -1.99305 1.87193996 -1.99278002 0 P 0 ;0
L 1.87193996 -1.99278002 1.87136998 -1.99256998 0 P 0 ;0
L 1.87136998 -1.99256998 1.87078996 -1.99241004 0 P 0 ;0
L 1.87078996 -1.99241004 1.8702 -1.9923 0 P 0 ;0
L 1.8702 -1.9923 1.85876004 -1.99076004 0 P 0 ;0
L 1.85876004 -1.99076004 1.84691998 -1.98943002 0 P 0 ;0
L 1.84691998 -1.98943002 1.83693002 -1.98876004 0 P 0 ;0
L 1.83693002 -1.98876004 1.8318 -1.98863002 0 P 0 ;0
L 1.8318 -1.98863002 1.82623002 -1.98866998 0 P 0 ;0
L 1.82623002 -1.98866998 1.82106004 -1.98883996 0 P 0 ;0
L 1.82106004 -1.98883996 1.81726998 -1.98915 0 P 0 ;0
L 1.78061004 -2.12523996 1.84838002 -2.12523996 0 P 0 ;0
L 1.77733002 -2.12423996 1.85121004 -2.12423996 0 P 0 ;0
L 1.77573996 -2.12323996 1.85376998 -2.12323996 0 P 0 ;0
L 1.77558002 -2.12223996 1.85596998 -2.12223996 0 P 0 ;0
L 1.77541998 -2.12123996 1.85798996 -2.12123996 0 P 0 ;0
L 1.77526998 -2.12023996 1.85978996 -2.12023996 0 P 0 ;0
L 1.77511004 -2.11923996 1.86131998 -2.11923996 0 P 0 ;0
L 1.77498996 -2.11823996 1.86276004 -2.11823996 0 P 0 ;0
L 1.77486998 -2.11723996 1.86406998 -2.11723996 0 P 0 ;0
L 1.77475 -2.11623996 1.86526004 -2.11623996 0 P 0 ;0
L 1.77463996 -2.11523996 1.86638002 -2.11523996 0 P 0 ;0
L 1.77451998 -2.11423996 1.8674 -2.11423996 0 P 0 ;0
L 1.77441004 -2.11323996 1.86835 -2.11323996 0 P 0 ;0
L 1.77431004 -2.11223996 1.86921004 -2.11223996 0 P 0 ;0
L 1.77421998 -2.11123996 1.87001004 -2.11123996 0 P 0 ;0
L 1.77413996 -2.11023996 1.87075 -2.11023996 0 P 0 ;0
L 1.77405 -2.10923996 1.87141998 -2.10923996 0 P 0 ;0
L 1.77396998 -2.10823996 1.87208002 -2.10823996 0 P 0 ;0
L 1.77388002 -2.10723996 1.87261998 -2.10723996 0 P 0 ;0
L 1.7738 -2.10623996 1.87316998 -2.10623996 0 P 0 ;0
L 1.77371004 -2.10523996 1.87366004 -2.10523996 0 P 0 ;0
L 1.77363002 -2.10423996 1.87411998 -2.10423996 0 P 0 ;0
L 1.77353996 -2.10323996 1.87453996 -2.10323996 0 P 0 ;0
L 1.77346998 -2.10223996 1.87495 -2.10223996 0 P 0 ;0
L 1.7734 -2.10123996 1.8753 -2.10123996 0 P 0 ;0
L 1.77333002 -2.10023996 1.87556998 -2.10023996 0 P 0 ;0
L 1.77325 -2.09923996 1.87576998 -2.09923996 0 P 0 ;0
L 1.77318002 -2.09823996 1.87591998 -2.09823996 0 P 0 ;0
L 1.77311004 -2.09723996 1.87603002 -2.09723996 0 P 0 ;0
L 1.77303996 -2.09623996 1.8761 -2.09623996 0 P 0 ;0
L 1.77296998 -2.09523996 1.87613002 -2.09523996 0 P 0 ;0
L 1.77291004 -2.09423996 1.87613996 -2.09423996 0 P 0 ;0
L 1.77285 -2.09323996 1.87616004 -2.09323996 0 P 0 ;0
L 1.77278996 -2.09223996 1.87616998 -2.09223996 0 P 0 ;0
L 1.77273002 -2.09123996 1.80256998 -2.09123996 0 P 0 ;0
L 1.77268002 -2.09023996 1.7968 -2.09023996 0 P 0 ;0
L 1.77261998 -2.08923996 1.79263002 -2.08923996 0 P 0 ;0
L 1.77256004 -2.08823996 1.78861998 -2.08823996 0 P 0 ;0
L 1.77251004 -2.08723996 1.7846 -2.08723996 0 P 0 ;0
L 1.77246004 -2.08623996 1.7807 -2.08623996 0 P 0 ;0
L 1.77241998 -2.08523996 1.77705 -2.08523996 0 P 0 ;0
L 1.77236998 -2.08423996 1.77293996 -2.08423996 0 P 0 ;0
L 1.62463996 -2.18195 1.65948996 -2.18195 0 P 0 ;0
L 1.61963996 -2.18095 1.66483002 -2.18095 0 P 0 ;0
L 1.61818002 -1.99795 1.6724 -1.99795 0 P 0 ;0
L 1.61778996 -1.99695 1.67218002 -1.99695 0 P 0 ;0
L 1.6174 -1.99595 1.67196004 -1.99595 0 P 0 ;0
L 1.61701004 -1.99495 1.67173996 -1.99495 0 P 0 ;0
L 1.61391998 -2.15695 1.70026004 -2.15695 0 P 0 ;0
L 1.61386004 -2.15595 1.70088002 -2.15595 0 P 0 ;0
L 1.61381004 -2.15495 1.70151004 -2.15495 0 P 0 ;0
L 1.61375 -2.15395 1.70213996 -2.15395 0 P 0 ;0
L 1.6137 -2.15295 1.70276004 -2.15295 0 P 0 ;0
L 1.61365 -2.15195 1.70338996 -2.15195 0 P 0 ;0
L 1.6136 -2.15095 1.70401004 -2.15095 0 P 0 ;0
L 1.61355 -2.14995 1.70456998 -2.14995 0 P 0 ;0
L 1.61348996 -2.14895 1.70511998 -2.14895 0 P 0 ;0
L 1.61343996 -2.14795 1.61738002 -2.14795 0 P 0 ;0
L 1.55341004 -2.08286998 1.60538002 -2.08286998 0 P 0 ;0
L 1.55286004 -2.08186998 1.60526998 -2.08186998 0 P 0 ;0
L 1.5521 -2.08086998 1.6051 -2.08086998 0 P 0 ;0
L 1.55126998 -2.07986998 1.6049 -2.07986998 0 P 0 ;0
L 1.55033996 -2.07886998 1.60463996 -2.07886998 0 P 0 ;0
L 1.54928996 -2.07786998 1.60433002 -2.07786998 0 P 0 ;0
L 1.54806998 -2.07686998 1.60398996 -2.07686998 0 P 0 ;0
L 1.5467 -2.07586998 1.60356998 -2.07586998 0 P 0 ;0
L 1.54531004 -2.07486998 1.6031 -2.07486998 0 P 0 ;0
L 1.54391004 -2.07386998 1.60258996 -2.07386998 0 P 0 ;0
L 1.54251004 -2.07286998 1.60201004 -2.07286998 0 P 0 ;0
L 1.54111998 -2.07186998 1.60138002 -2.07186998 0 P 0 ;0
L 1.53971998 -2.07086998 1.60068002 -2.07086998 0 P 0 ;0
L 1.53833002 -2.06986998 1.59993002 -2.06986998 0 P 0 ;0
L 1.53693002 -2.06886998 1.59908002 -2.06886998 0 P 0 ;0
L 1.53556004 -2.06786998 1.59821004 -2.06786998 0 P 0 ;0
L 1.53418996 -2.06686998 1.59733996 -2.06686998 0 P 0 ;0
L 1.53281998 -2.06586998 1.59646998 -2.06586998 0 P 0 ;0
L 1.53145 -2.06486998 1.5955 -2.06486998 0 P 0 ;0
L 1.53008002 -2.06386998 1.59453002 -2.06386998 0 P 0 ;0
L 1.52871004 -2.06286998 1.59356004 -2.06286998 0 P 0 ;0
L 1.52733996 -2.06186998 1.59253002 -2.06186998 0 P 0 ;0
L 1.52596998 -2.06086998 1.59145 -2.06086998 0 P 0 ;0
L 1.5246 -2.05986998 1.59038002 -2.05986998 0 P 0 ;0
L 1.52323002 -2.05886998 1.5893 -2.05886998 0 P 0 ;0
L 1.52186004 -2.05786998 1.58813996 -2.05786998 0 P 0 ;0
L 1.52053996 -2.05686998 1.58696004 -2.05686998 0 P 0 ;0
L 1.51935 -2.05586998 1.58576998 -2.05586998 0 P 0 ;0
L 1.51816004 -2.05486998 1.58456998 -2.05486998 0 P 0 ;0
L 1.51706998 -2.05386998 1.58321004 -2.05386998 0 P 0 ;0
L 1.51603996 -2.05286998 1.58185 -2.05286998 0 P 0 ;0
L 1.51501998 -2.05186998 1.58048996 -2.05186998 0 P 0 ;0
L 1.51408996 -2.05086998 1.57913002 -2.05086998 0 P 0 ;0
L 1.5132 -2.04986998 1.57776998 -2.04986998 0 P 0 ;0
L 1.51231998 -2.04886998 1.57641998 -2.04886998 0 P 0 ;0
L 1.51151004 -2.04786998 1.57505 -2.04786998 0 P 0 ;0
L 1.51075 -2.04686998 1.57365 -2.04686998 0 P 0 ;0
L 1.51008002 -2.04586998 1.57223002 -2.04586998 0 P 0 ;0
L 1.50945 -2.04486998 1.57081004 -2.04486998 0 P 0 ;0
L 1.50888002 -2.04386998 1.56938996 -2.04386998 0 P 0 ;0
L 1.50836004 -2.04286998 1.56796998 -2.04286998 0 P 0 ;0
L 1.5079 -2.04186998 1.56655 -2.04186998 0 P 0 ;0
L 1.50748002 -2.04086998 1.56518996 -2.04086998 0 P 0 ;0
L 1.50708996 -2.03986998 1.564 -2.03986998 0 P 0 ;0
L 1.50676004 -2.03886998 1.56296998 -2.03886998 0 P 0 ;0
L 1.50641998 -2.03786998 1.56206004 -2.03786998 0 P 0 ;0
L 1.50616998 -2.03686998 1.56125 -2.03686998 0 P 0 ;0
L 1.50591004 -2.03586998 1.56066998 -2.03586998 0 P 0 ;0
L 1.5057 -2.03486998 1.56031998 -2.03486998 0 P 0 ;0
L 1.50551998 -2.03386998 1.56016004 -2.03386998 0 P 0 ;0
L 1.50533996 -2.03286998 1.56016998 -2.03286998 0 P 0 ;0
L 1.50523996 -2.03186998 1.56036004 -2.03186998 0 P 0 ;0
L 1.50513002 -2.03086998 1.56071998 -2.03086998 0 P 0 ;0
L 1.50506998 -2.02986998 1.56131004 -2.02986998 0 P 0 ;0
L 1.50503996 -2.02886998 1.5622 -2.02886998 0 P 0 ;0
L 1.50501004 -2.02786998 1.56355 -2.02786998 0 P 0 ;0
L 1.50501998 -2.02686998 1.5657 -2.02686998 0 P 0 ;0
L 1.50506998 -2.02586998 1.60378996 -2.02586998 0 P 0 ;0
L 1.50511998 -2.02486998 1.60371004 -2.02486998 0 P 0 ;0
L 1.50521004 -2.02386998 1.60363996 -2.02386998 0 P 0 ;0
L 1.50533996 -2.02286998 1.60356998 -2.02286998 0 P 0 ;0
L 1.50546998 -2.02186998 1.6035 -2.02186998 0 P 0 ;0
L 1.50563996 -2.02086998 1.60343002 -2.02086998 0 P 0 ;0
L 1.50585 -2.01986998 1.60336004 -2.01986998 0 P 0 ;0
L 1.50606004 -2.01886998 1.60328996 -2.01886998 0 P 0 ;0
L 1.50633002 -2.01786998 1.60321998 -2.01786998 0 P 0 ;0
L 1.50661998 -2.01686998 1.60315 -2.01686998 0 P 0 ;0
L 1.50691004 -2.01586998 1.60308002 -2.01586998 0 P 0 ;0
L 1.50726998 -2.01486998 1.603 -2.01486998 0 P 0 ;0
L 1.50766004 -2.01386998 1.60293002 -2.01386998 0 P 0 ;0
L 1.50808996 -2.01286998 1.60285 -2.01286998 0 P 0 ;0
L 1.50856998 -2.01186998 1.60278002 -2.01186998 0 P 0 ;0
L 1.50908996 -2.01086998 1.6027 -2.01086998 0 P 0 ;0
L 1.50966004 -2.00986998 1.60261998 -2.00986998 0 P 0 ;0
L 1.51028996 -2.00886998 1.60255 -2.00886998 0 P 0 ;0
L 1.51096998 -2.00786998 1.60246998 -2.00786998 0 P 0 ;0
L 1.51171998 -2.00686998 1.6024 -2.00686998 0 P 0 ;0
L 1.51253996 -2.00586998 1.60233002 -2.00586998 0 P 0 ;0
L 1.51343996 -2.00486998 1.60225 -2.00486998 0 P 0 ;0
L 1.5144 -2.00386998 1.60218002 -2.00386998 0 P 0 ;0
L 1.51551998 -2.00286998 1.6021 -2.00286998 0 P 0 ;0
L 1.51663996 -2.00186998 1.60203002 -2.00186998 0 P 0 ;0
L 1.51795 -2.00086998 1.60195 -2.00086998 0 P 0 ;0
L 1.51928996 -1.99986998 1.60183996 -1.99986998 0 P 0 ;0
L 1.52086998 -1.99886998 1.60173002 -1.99886998 0 P 0 ;0
L 1.52258996 -1.99786998 1.60156998 -1.99786998 0 P 0 ;0
L 1.52451004 -1.99686998 1.60138996 -1.99686998 0 P 0 ;0
L 1.52686998 -1.99586998 1.60106998 -1.99586998 0 P 0 ;0
L 1.52976004 -1.99486998 1.59943996 -1.99486998 0 P 0 ;0
L 1.53283002 -1.99386998 1.59543002 -1.99386998 0 P 0 ;0
L 1.53678996 -1.99286998 1.59003996 -1.99286998 0 P 0 ;0
L 1.54173996 -1.99186998 1.58073996 -1.99186998 0 P 0 ;0
L 1.55036998 -1.99086998 1.56493002 -1.99086998 0 P 0 ;0
L 1.6036 -2.03086998 1.60413996 -2.03086998 0 P 0 ;0
L 1.59891004 -2.02986998 1.60406998 -2.02986998 0 P 0 ;0
L 1.59435 -2.02886998 1.604 -2.02886998 0 P 0 ;0
L 1.58838996 -2.02786998 1.60393002 -2.02786998 0 P 0 ;0
L 1.57981004 -2.02686998 1.60386004 -2.02686998 0 P 0 ;0
L 1.54575 -1.98923996 1.53931998 -1.99021998 0 P 0 ;0
L 1.53931998 -1.99021998 1.53298996 -1.99171998 0 P 0 ;0
L 1.53298996 -1.99171998 1.52678996 -1.99373996 0 P 0 ;0
L 1.52678996 -1.99373996 1.52376998 -1.995 0 P 0 ;0
L 1.52376998 -1.995 1.52086998 -1.99651004 0 P 0 ;0
L 1.52086998 -1.99651004 1.5181 -1.99826004 0 P 0 ;0
L 1.5181 -1.99826004 1.51548002 -2.00023002 0 P 0 ;0
L 1.51548002 -2.00023002 1.51301004 -2.00243002 0 P 0 ;0
L 1.51301004 -2.00243002 1.51128996 -2.00423002 0 P 0 ;0
L 1.51128996 -2.00423002 1.50971998 -2.00616004 0 P 0 ;0
L 1.50971998 -2.00616004 1.50831004 -2.00821004 0 P 0 ;0
L 1.50831004 -2.00821004 1.50706998 -2.01036998 0 P 0 ;0
L 1.50706998 -2.01036998 1.50598996 -2.01261998 0 P 0 ;0
L 1.50598996 -2.01261998 1.50508996 -2.01496998 0 P 0 ;0
L 1.50508996 -2.01496998 1.5042 -2.01801004 0 P 0 ;0
L 1.5042 -2.01801004 1.50355 -2.02111004 0 P 0 ;0
L 1.50355 -2.02111004 1.50313996 -2.02426004 0 P 0 ;0
L 1.50313996 -2.02426004 1.50298996 -2.02743002 0 P 0 ;0
L 1.50298996 -2.02743002 1.50308996 -2.03063002 0 P 0 ;0
L 1.50308996 -2.03063002 1.50338002 -2.03326998 0 P 0 ;0
L 1.50338002 -2.03326998 1.50385 -2.03588002 0 P 0 ;0
L 1.50385 -2.03588002 1.50451004 -2.03845 0 P 0 ;0
L 1.50451004 -2.03845 1.50535 -2.04096998 0 P 0 ;0
L 1.50535 -2.04096998 1.50633002 -2.0433 0 P 0 ;0
L 1.50633002 -2.0433 1.5075 -2.04553002 0 P 0 ;0
L 1.5075 -2.04553002 1.50883996 -2.04766998 0 P 0 ;0
L 1.50883996 -2.04766998 1.51036998 -2.04968996 0 P 0 ;0
L 1.51036998 -2.04968996 1.51323002 -2.05291998 0 P 0 ;0
L 1.51323002 -2.05291998 1.51631998 -2.05593996 0 P 0 ;0
L 1.51631998 -2.05593996 1.51961998 -2.05871004 0 P 0 ;0
L 1.51961998 -2.05871004 1.53591004 -2.0706 0 P 0 ;0
L 1.53591004 -2.0706 1.54668002 -2.07831004 0 P 0 ;0
L 1.54668002 -2.07831004 1.54793996 -2.07933996 0 P 0 ;0
L 1.54793996 -2.07933996 1.54911998 -2.08046998 0 P 0 ;0
L 1.54911998 -2.08046998 1.55021004 -2.08168002 0 P 0 ;0
L 1.55021004 -2.08168002 1.5512 -2.08298996 0 P 0 ;0
L 1.5512 -2.08298996 1.55136004 -2.08323002 0 P 0 ;0
L 1.55136004 -2.08323002 1.5515 -2.08348002 0 P 0 ;0
L 1.5515 -2.08348002 1.55161004 -2.08373996 0 P 0 ;0
L 1.55161004 -2.08373996 1.5517 -2.08401998 0 P 0 ;0
L 1.5517 -2.08401998 1.55176998 -2.0843 0 P 0 ;0
L 1.55176998 -2.0843 1.55181004 -2.08458002 0 P 0 ;0
L 1.55181004 -2.08458002 1.55183002 -2.08486998 0 P 0 ;0
L 1.55183002 -2.08486998 1.55181998 -2.08516004 0 P 0 ;0
L 1.55181998 -2.08516004 1.55178996 -2.08545 0 P 0 ;0
L 1.55178996 -2.08545 1.55173996 -2.08573002 0 P 0 ;0
L 1.55173996 -2.08573002 1.55166004 -2.086 0 P 0 ;0
L 1.55166004 -2.086 1.55156004 -2.08628002 0 P 0 ;0
L 1.55156004 -2.08628002 1.55136998 -2.08666998 0 P 0 ;0
L 1.55136998 -2.08666998 1.55115 -2.08703996 0 P 0 ;0
L 1.55115 -2.08703996 1.5509 -2.08738996 0 P 0 ;0
L 1.5509 -2.08738996 1.55063002 -2.08771998 0 P 0 ;0
L 1.55063002 -2.08771998 1.55033002 -2.08803002 0 P 0 ;0
L 1.55033002 -2.08803002 1.55 -2.08831004 0 P 0 ;0
L 1.55 -2.08831004 1.54966004 -2.08856004 0 P 0 ;0
L 1.54966004 -2.08856004 1.54928996 -2.08878996 0 P 0 ;0
L 1.54928996 -2.08878996 1.5489 -2.08898996 0 P 0 ;0
L 1.5489 -2.08898996 1.54786004 -2.08941004 0 P 0 ;0
L 1.54786004 -2.08941004 1.54678996 -2.08973996 0 P 0 ;0
L 1.54678996 -2.08973996 1.54568002 -2.08998002 0 P 0 ;0
L 1.54568002 -2.08998002 1.54456998 -2.09011998 0 P 0 ;0
L 1.54456998 -2.09011998 1.54343996 -2.09016998 0 P 0 ;0
L 1.54343996 -2.09016998 1.53906998 -2.09003002 0 P 0 ;0
L 1.53906998 -2.09003002 1.53468002 -2.08961998 0 P 0 ;0
L 1.53468002 -2.08961998 1.52908996 -2.08878996 0 P 0 ;0
L 1.52908996 -2.08878996 1.52351004 -2.08766004 0 P 0 ;0
L 1.52351004 -2.08766004 1.51005 -2.08418996 0 P 0 ;0
L 1.51005 -2.08418996 1.50631004 -2.08318002 0 P 0 ;0
L 1.50631004 -2.08318002 1.50308002 -2.08238996 0 P 0 ;0
L 1.50308002 -2.08238996 1.50033996 -2.08183002 0 P 0 ;0
L 1.50033996 -2.08183002 1.5003 -2.08181998 0 P 0 ;0
L 1.5003 -2.08181998 1.50016004 -2.08181998 0 P 0 ;0
L 1.50016004 -2.08181998 1.50011998 -2.08183002 0 P 0 ;0
L 1.50011998 -2.08183002 1.50006998 -2.08183996 0 P 0 ;0
L 1.50006998 -2.08183996 1.50003002 -2.08186004 0 P 0 ;0
L 1.50003002 -2.08186004 1.49998996 -2.08186998 0 P 0 ;0
L 1.49998996 -2.08186998 1.49995 -2.08188996 0 P 0 ;0
L 1.49995 -2.08188996 1.49991004 -2.08191998 0 P 0 ;0
L 1.49991004 -2.08191998 1.49988002 -2.08195 0 P 0 ;0
L 1.49988002 -2.08195 1.49983996 -2.08198002 0 P 0 ;0
L 1.49983996 -2.08198002 1.4997 -2.08213996 0 P 0 ;0
L 1.4997 -2.08213996 1.49956004 -2.08231998 0 P 0 ;0
L 1.49956004 -2.08231998 1.49943996 -2.0825 0 P 0 ;0
L 1.49943996 -2.0825 1.49933996 -2.0827 0 P 0 ;0
L 1.49933996 -2.0827 1.49925 -2.0829 0 P 0 ;0
L 1.49925 -2.0829 1.49918996 -2.08311004 0 P 0 ;0
L 1.49918996 -2.08311004 1.49913996 -2.08333002 0 P 0 ;0
L 1.49913996 -2.08333002 1.49911004 -2.08355 0 P 0 ;0
L 1.49911004 -2.08355 1.4991 -2.08376998 0 P 0 ;0
L 1.4991 -2.08376998 1.49911004 -2.08398996 0 P 0 ;0
L 1.49911004 -2.08398996 1.50071004 -2.10395 0 P 0 ;0
L 1.50071004 -2.10395 1.5024 -2.12403996 0 P 0 ;0
L 1.5024 -2.12403996 1.50241998 -2.12418002 0 P 0 ;0
L 1.50241998 -2.12418002 1.50246004 -2.12431004 0 P 0 ;0
L 1.50246004 -2.12431004 1.50248996 -2.12445 0 P 0 ;0
L 1.50248996 -2.12445 1.50255 -2.12456998 0 P 0 ;0
L 1.50255 -2.12456998 1.50261004 -2.1247 0 P 0 ;0
L 1.50261004 -2.1247 1.50276998 -2.12491998 0 P 0 ;0
L 1.50276998 -2.12491998 1.50286004 -2.12501998 0 P 0 ;0
L 1.50286004 -2.12501998 1.50296998 -2.12511998 0 P 0 ;0
L 1.50296998 -2.12511998 1.50308002 -2.12521004 0 P 0 ;0
L 1.50308002 -2.12521004 1.50318996 -2.12528002 0 P 0 ;0
L 1.50318996 -2.12528002 1.50331998 -2.12535 0 P 0 ;0
L 1.50331998 -2.12535 1.50343996 -2.1254 0 P 0 ;0
L 1.50343996 -2.1254 1.50391998 -2.12556004 0 P 0 ;0
L 1.50391998 -2.12556004 1.5044 -2.12568996 0 P 0 ;0
L 1.5044 -2.12568996 1.50848002 -2.12648996 0 P 0 ;0
L 1.50848002 -2.12648996 1.51328996 -2.12738002 0 P 0 ;0
L 1.51328996 -2.12738002 1.51873996 -2.12833996 0 P 0 ;0
L 1.51873996 -2.12833996 1.52606004 -2.12945 0 P 0 ;0
L 1.52606004 -2.12945 1.53343996 -2.13023002 0 P 0 ;0
L 1.53343996 -2.13023002 1.54886998 -2.13086998 0 P 0 ;0
L 1.54886998 -2.13086998 1.56305 -2.1303 0 P 0 ;0
L 1.56305 -2.1303 1.56666004 -2.12988996 0 P 0 ;0
L 1.56666004 -2.12988996 1.57023002 -2.12926998 0 P 0 ;0
L 1.57023002 -2.12926998 1.5738 -2.12843002 0 P 0 ;0
L 1.5738 -2.12843002 1.57945 -2.12668996 0 P 0 ;0
L 1.57945 -2.12668996 1.58498002 -2.12456998 0 P 0 ;0
L 1.58498002 -2.12456998 1.58793996 -2.12318002 0 P 0 ;0
L 1.58793996 -2.12318002 1.59078996 -2.12156004 0 P 0 ;0
L 1.59078996 -2.12156004 1.59348996 -2.11971998 0 P 0 ;0
L 1.59348996 -2.11971998 1.59525 -2.11833002 0 P 0 ;0
L 1.59525 -2.11833002 1.5969 -2.11681998 0 P 0 ;0
L 1.5969 -2.11681998 1.59846004 -2.11521004 0 P 0 ;0
L 1.59846004 -2.11521004 1.59991004 -2.11348002 0 P 0 ;0
L 1.59991004 -2.11348002 1.60175 -2.11093996 0 P 0 ;0
L 1.60175 -2.11093996 1.60338002 -2.10826998 0 P 0 ;0
L 1.60338002 -2.10826998 1.60481004 -2.10548002 0 P 0 ;0
L 1.60481004 -2.10548002 1.60573002 -2.10321004 0 P 0 ;0
L 1.60573002 -2.10321004 1.60646004 -2.10088002 0 P 0 ;0
L 1.60646004 -2.10088002 1.60698002 -2.09848996 0 P 0 ;0
L 1.60698002 -2.09848996 1.60756004 -2.09421998 0 P 0 ;0
L 1.60756004 -2.09421998 1.6078 -2.08991004 0 P 0 ;0
L 1.6078 -2.08991004 1.60768996 -2.08565 0 P 0 ;0
L 1.60768996 -2.08565 1.60723002 -2.08141998 0 P 0 ;0
L 1.60723002 -2.08141998 1.60691998 -2.07968002 0 P 0 ;0
L 1.60691998 -2.07968002 1.60646998 -2.07796998 0 P 0 ;0
L 1.60646998 -2.07796998 1.60591998 -2.0763 0 P 0 ;0
L 1.60591998 -2.0763 1.60523002 -2.07466998 0 P 0 ;0
L 1.60523002 -2.07466998 1.60411998 -2.07246998 0 P 0 ;0
L 1.60411998 -2.07246998 1.60281004 -2.07038002 0 P 0 ;0
L 1.60281004 -2.07038002 1.60131998 -2.06838996 0 P 0 ;0
L 1.60131998 -2.06838996 1.59803996 -2.06461998 0 P 0 ;0
L 1.59803996 -2.06461998 1.59455 -2.06101998 0 P 0 ;0
L 1.59455 -2.06101998 1.59031998 -2.05708996 0 P 0 ;0
L 1.59031998 -2.05708996 1.58586004 -2.05333996 0 P 0 ;0
L 1.58586004 -2.05333996 1.57588002 -2.04598996 0 P 0 ;0
L 1.57588002 -2.04598996 1.56685 -2.03963996 0 P 0 ;0
L 1.56685 -2.03963996 1.56578002 -2.03878996 0 P 0 ;0
L 1.56578002 -2.03878996 1.56476998 -2.03786004 0 P 0 ;0
L 1.56476998 -2.03786004 1.56383002 -2.03686998 0 P 0 ;0
L 1.56383002 -2.03686998 1.56295 -2.0358 0 P 0 ;0
L 1.56295 -2.0358 1.56276998 -2.03555 0 P 0 ;0
L 1.56276998 -2.03555 1.56261004 -2.03528002 0 P 0 ;0
L 1.56261004 -2.03528002 1.56246998 -2.035 0 P 0 ;0
L 1.56246998 -2.035 1.56236004 -2.03471998 0 P 0 ;0
L 1.56236004 -2.03471998 1.56226998 -2.03441998 0 P 0 ;0
L 1.56226998 -2.03441998 1.5622 -2.03411998 0 P 0 ;0
L 1.5622 -2.03411998 1.56216004 -2.03381998 0 P 0 ;0
L 1.56216004 -2.03381998 1.56213996 -2.03351004 0 P 0 ;0
L 1.56213996 -2.03351004 1.56215 -2.0332 0 P 0 ;0
L 1.56215 -2.0332 1.56218002 -2.03288996 0 P 0 ;0
L 1.56218002 -2.03288996 1.56225 -2.03253996 0 P 0 ;0
L 1.56225 -2.03253996 1.56233996 -2.03221004 0 P 0 ;0
L 1.56233996 -2.03221004 1.56246004 -2.03186998 0 P 0 ;0
L 1.56246004 -2.03186998 1.56261004 -2.03156004 0 P 0 ;0
L 1.56261004 -2.03156004 1.56278996 -2.03125 0 P 0 ;0
L 1.56278996 -2.03125 1.56298002 -2.03096004 0 P 0 ;0
L 1.56298002 -2.03096004 1.56321004 -2.03068996 0 P 0 ;0
L 1.56321004 -2.03068996 1.56345 -2.03043996 0 P 0 ;0
L 1.56345 -2.03043996 1.56371004 -2.0302 0 P 0 ;0
L 1.56371004 -2.0302 1.56416004 -2.02986004 0 P 0 ;0
L 1.56416004 -2.02986004 1.56463002 -2.02955 0 P 0 ;0
L 1.56463002 -2.02955 1.56511998 -2.02928002 0 P 0 ;0
L 1.56511998 -2.02928002 1.56561998 -2.02903002 0 P 0 ;0
L 1.56561998 -2.02903002 1.56611998 -2.02883996 0 P 0 ;0
L 1.56611998 -2.02883996 1.56663996 -2.02866998 0 P 0 ;0
L 1.56663996 -2.02866998 1.56716004 -2.02855 0 P 0 ;0
L 1.56716004 -2.02855 1.5677 -2.02846998 0 P 0 ;0
L 1.5677 -2.02846998 1.56926998 -2.02835 0 P 0 ;0
L 1.56926998 -2.02835 1.57085 -2.02833996 0 P 0 ;0
L 1.57085 -2.02833996 1.57725 -2.02866998 0 P 0 ;0
L 1.57725 -2.02866998 1.58205 -2.02906004 0 P 0 ;0
L 1.58205 -2.02906004 1.58746998 -2.02975 0 P 0 ;0
L 1.58746998 -2.02975 1.59271004 -2.03056998 0 P 0 ;0
L 1.59271004 -2.03056998 1.59681004 -2.03143002 0 P 0 ;0
L 1.59681004 -2.03143002 1.60016004 -2.03221998 0 P 0 ;0
L 1.60016004 -2.03221998 1.60308002 -2.03281004 0 P 0 ;0
L 1.60308002 -2.03281004 1.60553996 -2.03323996 0 P 0 ;0
L 1.60553996 -2.03323996 1.60568996 -2.03323996 0 P 0 ;0
L 1.60568996 -2.03323996 1.60576998 -2.03321998 0 P 0 ;0
L 1.60576998 -2.03321998 1.60586004 -2.03316004 0 P 0 ;0
L 1.60586004 -2.03316004 1.6059 -2.03313996 0 P 0 ;0
L 1.6059 -2.03313996 1.60591998 -2.03311004 0 P 0 ;0
L 1.60591998 -2.03311004 1.60598996 -2.03303996 0 P 0 ;0
L 1.60598996 -2.03303996 1.60605 -2.03296998 0 P 0 ;0
L 1.60605 -2.03296998 1.6061 -2.03288996 0 P 0 ;0
L 1.6061 -2.03288996 1.60618002 -2.03273002 0 P 0 ;0
L 1.60618002 -2.03273002 1.60621004 -2.03263002 0 P 0 ;0
L 1.60621004 -2.03263002 1.60623002 -2.03253996 0 P 0 ;0
L 1.60623002 -2.03253996 1.60625 -2.03236004 0 P 0 ;0
L 1.60625 -2.03236004 1.60623996 -2.03226004 0 P 0 ;0
L 1.60623996 -2.03226004 1.60508002 -2.01578002 0 P 0 ;0
L 1.60508002 -2.01578002 1.60393996 -2.00068002 0 P 0 ;0
L 1.60393996 -2.00068002 1.60368002 -1.99833996 0 P 0 ;0
L 1.60368002 -1.99833996 1.60326998 -1.99601004 0 P 0 ;0
L 1.60326998 -1.99601004 1.60321004 -1.99576998 0 P 0 ;0
L 1.60321004 -1.99576998 1.60313996 -1.99553002 0 P 0 ;0
L 1.60313996 -1.99553002 1.60303996 -1.9953 0 P 0 ;0
L 1.60303996 -1.9953 1.60293002 -1.99508002 0 P 0 ;0
L 1.60293002 -1.99508002 1.60281004 -1.99486004 0 P 0 ;0
L 1.60281004 -1.99486004 1.60261998 -1.9946 0 P 0 ;0
L 1.60261998 -1.9946 1.60241004 -1.99435 0 P 0 ;0
L 1.60241004 -1.99435 1.60218002 -1.99411998 0 P 0 ;0
L 1.60218002 -1.99411998 1.60191998 -1.99391004 0 P 0 ;0
L 1.60191998 -1.99391004 1.60161004 -1.99368996 0 P 0 ;0
L 1.60161004 -1.99368996 1.60128996 -1.99348996 0 P 0 ;0
L 1.60128996 -1.99348996 1.60095 -1.99331998 0 P 0 ;0
L 1.60095 -1.99331998 1.6006 -1.99316004 0 P 0 ;0
L 1.6006 -1.99316004 1.59966004 -1.99283002 0 P 0 ;0
L 1.59966004 -1.99283002 1.59871004 -1.99255 0 P 0 ;0
L 1.59871004 -1.99255 1.5933 -1.99135 0 P 0 ;0
L 1.5933 -1.99135 1.5878 -1.9905 0 P 0 ;0
L 1.5878 -1.9905 1.57285 -1.98915 0 P 0 ;0
L 1.57285 -1.98915 1.55763996 -1.98861004 0 P 0 ;0
L 1.55763996 -1.98861004 1.55171004 -1.98876004 0 P 0 ;0
L 1.55171004 -1.98876004 1.54575 -1.98923996 0 P 0 ;0
L 1.53011998 -2.12786998 1.5666 -2.12786998 0 P 0 ;0
L 1.52236004 -2.12686998 1.57168002 -2.12686998 0 P 0 ;0
L 1.51621998 -2.12586998 1.5753 -2.12586998 0 P 0 ;0
L 1.51071004 -2.12486998 1.57856004 -2.12486998 0 P 0 ;0
L 1.50553002 -2.12386998 1.58121004 -2.12386998 0 P 0 ;0
L 1.50431004 -2.12286998 1.58381998 -2.12286998 0 P 0 ;0
L 1.50423002 -2.12186998 1.58601998 -2.12186998 0 P 0 ;0
L 1.50413996 -2.12086998 1.58796004 -2.12086998 0 P 0 ;0
L 1.50406004 -2.11986998 1.58971004 -2.11986998 0 P 0 ;0
L 1.50396998 -2.11886998 1.59118002 -2.11886998 0 P 0 ;0
L 1.50388996 -2.11786998 1.5926 -2.11786998 0 P 0 ;0
L 1.50381004 -2.11686998 1.59386004 -2.11686998 0 P 0 ;0
L 1.50371998 -2.11586998 1.59496998 -2.11586998 0 P 0 ;0
L 1.50363996 -2.11486998 1.59601004 -2.11486998 0 P 0 ;0
L 1.50355 -2.11386998 1.59696998 -2.11386998 0 P 0 ;0
L 1.50346998 -2.11286998 1.59781004 -2.11286998 0 P 0 ;0
L 1.50338002 -2.11186998 1.5986 -2.11186998 0 P 0 ;0
L 1.5033 -2.11086998 1.59933002 -2.11086998 0 P 0 ;0
L 1.50321004 -2.10986998 1.60005 -2.10986998 0 P 0 ;0
L 1.50313002 -2.10886998 1.60066998 -2.10886998 0 P 0 ;0
L 1.50305 -2.10786998 1.60128002 -2.10786998 0 P 0 ;0
L 1.50296004 -2.10686998 1.60185 -2.10686998 0 P 0 ;0
L 1.50288002 -2.10586998 1.60236004 -2.10586998 0 P 0 ;0
L 1.50278996 -2.10486998 1.60286998 -2.10486998 0 P 0 ;0
L 1.50271004 -2.10386998 1.6033 -2.10386998 0 P 0 ;0
L 1.50263002 -2.10286998 1.60371004 -2.10286998 0 P 0 ;0
L 1.50255 -2.10186998 1.60405 -2.10186998 0 P 0 ;0
L 1.50246998 -2.10086998 1.60436004 -2.10086998 0 P 0 ;0
L 1.50238996 -2.09986998 1.60463002 -2.09986998 0 P 0 ;0
L 1.50231004 -2.09886998 1.60485 -2.09886998 0 P 0 ;0
L 1.50223002 -2.09786998 1.60505 -2.09786998 0 P 0 ;0
L 1.50215 -2.09686998 1.60518002 -2.09686998 0 P 0 ;0
L 1.50206998 -2.09586998 1.60531998 -2.09586998 0 P 0 ;0
L 1.50198996 -2.09486998 1.60545 -2.09486998 0 P 0 ;0
L 1.50191004 -2.09386998 1.60558002 -2.09386998 0 P 0 ;0
L 1.50183002 -2.09286998 1.60563002 -2.09286998 0 P 0 ;0
L 1.50175 -2.09186998 1.53725 -2.09186998 0 P 0 ;0
L 1.54638996 -2.09186998 1.60568996 -2.09186998 0 P 0 ;0
L 1.50166998 -2.09086998 1.5295 -2.09086998 0 P 0 ;0
L 1.54956998 -2.09086998 1.60573996 -2.09086998 0 P 0 ;0
L 1.50158996 -2.08986998 1.52436004 -2.08986998 0 P 0 ;0
L 1.55125 -2.08986998 1.60578996 -2.08986998 0 P 0 ;0
L 1.50151004 -2.08886998 1.52021004 -2.08886998 0 P 0 ;0
L 1.55226998 -2.08886998 1.60576998 -2.08886998 0 P 0 ;0
L 1.50143002 -2.08786998 1.51633002 -2.08786998 0 P 0 ;0
L 1.55298002 -2.08786998 1.60573996 -2.08786998 0 P 0 ;0
L 1.50133996 -2.08686998 1.51246004 -2.08686998 0 P 0 ;0
L 1.55346998 -2.08686998 1.60571998 -2.08686998 0 P 0 ;0
L 1.50126998 -2.08586998 1.50861998 -2.08586998 0 P 0 ;0
L 1.55375 -2.08586998 1.60568996 -2.08586998 0 P 0 ;0
L 1.50118002 -2.08486998 1.50481004 -2.08486998 0 P 0 ;0
L 1.55383002 -2.08486998 1.60558996 -2.08486998 0 P 0 ;0
L 1.55371998 -2.08386998 1.60548996 -2.08386998 0 P 0 ;0
L 1.54886998 -2.12886998 1.53358996 -2.12823996 0 P 0 ;0
L 1.53358996 -2.12823996 1.52631998 -2.12746998 0 P 0 ;0
L 1.52631998 -2.12746998 1.51906004 -2.12636998 0 P 0 ;0
L 1.51906004 -2.12636998 1.51363002 -2.12541004 0 P 0 ;0
L 1.51363002 -2.12541004 1.50886998 -2.12451998 0 P 0 ;0
L 1.50886998 -2.12451998 1.50483996 -2.12373996 0 P 0 ;0
L 1.50483996 -2.12373996 1.50448996 -2.12365 0 P 0 ;0
L 1.50448996 -2.12365 1.50438002 -2.12361004 0 P 0 ;0
L 1.50438002 -2.12361004 1.5027 -2.10378002 0 P 0 ;0
L 1.5027 -2.10378002 1.50111998 -2.08403002 0 P 0 ;0
L 1.50111998 -2.08403002 1.50263996 -2.08433996 0 P 0 ;0
L 1.50263996 -2.08433996 1.50581004 -2.08511004 0 P 0 ;0
L 1.50581004 -2.08511004 1.50955 -2.08611998 0 P 0 ;0
L 1.50955 -2.08611998 1.52306004 -2.08961004 0 P 0 ;0
L 1.52306004 -2.08961004 1.52311004 -2.08961998 0 P 0 ;0
L 1.52311004 -2.08961998 1.52875 -2.09076004 0 P 0 ;0
L 1.52875 -2.09076004 1.5288 -2.09076004 0 P 0 ;0
L 1.5288 -2.09076004 1.53443996 -2.09161004 0 P 0 ;0
L 1.53443996 -2.09161004 1.53893996 -2.09203002 0 P 0 ;0
L 1.53893996 -2.09203002 1.54346004 -2.09216998 0 P 0 ;0
L 1.54346004 -2.09216998 1.54473996 -2.09211004 0 P 0 ;0
L 1.54473996 -2.09211004 1.54603002 -2.09195 0 P 0 ;0
L 1.54603002 -2.09195 1.54728996 -2.09166998 0 P 0 ;0
L 1.54728996 -2.09166998 1.54853002 -2.09128996 0 P 0 ;0
L 1.54853002 -2.09128996 1.54973002 -2.09081004 0 P 0 ;0
L 1.54973002 -2.09081004 1.55026998 -2.09053996 0 P 0 ;0
L 1.55026998 -2.09053996 1.55076998 -2.09023002 0 P 0 ;0
L 1.55076998 -2.09023002 1.55118002 -2.08991998 0 P 0 ;0
L 1.55118002 -2.08991998 1.55118002 -2.08991004 0 P 0 ;0
L 1.55118002 -2.08991004 1.5512 -2.08991004 0 P 0 ;0
L 1.5512 -2.08991004 1.55125 -2.08986998 0 P 0 ;0
L 1.55125 -2.08986998 1.55131004 -2.08981998 0 P 0 ;0
L 1.55131004 -2.08981998 1.55126998 -2.08978002 0 P 0 ;0
L 1.55126998 -2.08978002 1.55136004 -2.08978002 0 P 0 ;0
L 1.55136004 -2.08978002 1.5517 -2.08948996 0 P 0 ;0
L 1.5517 -2.08948996 1.55206004 -2.08911998 0 P 0 ;0
L 1.55206004 -2.08911998 1.55205 -2.08911004 0 P 0 ;0
L 1.55205 -2.08911004 1.55206004 -2.08911004 0 P 0 ;0
L 1.55206004 -2.08911004 1.55211998 -2.08906004 0 P 0 ;0
L 1.55211998 -2.08906004 1.55248996 -2.08861004 0 P 0 ;0
L 1.55248996 -2.08861004 1.55283996 -2.08811998 0 P 0 ;0
L 1.55283996 -2.08811998 1.55313996 -2.08761004 0 P 0 ;0
L 1.55313996 -2.08761004 1.5534 -2.08706998 0 P 0 ;0
L 1.5534 -2.08706998 1.55356004 -2.08663002 0 P 0 ;0
L 1.55356004 -2.08663002 1.55368996 -2.08618996 0 P 0 ;0
L 1.55368996 -2.08618996 1.55376998 -2.08573996 0 P 0 ;0
L 1.55376998 -2.08573996 1.55378002 -2.08565 0 P 0 ;0
L 1.55378002 -2.08565 1.55381998 -2.08528002 0 P 0 ;0
L 1.55381998 -2.08528002 1.55383002 -2.08481998 0 P 0 ;0
L 1.55383002 -2.08481998 1.5538 -2.08436998 0 P 0 ;0
L 1.5538 -2.08436998 1.55373002 -2.08391998 0 P 0 ;0
L 1.55373002 -2.08391998 1.55361998 -2.08346998 0 P 0 ;0
L 1.55361998 -2.08346998 1.55348002 -2.08303996 0 P 0 ;0
L 1.55348002 -2.08303996 1.5533 -2.08261004 0 P 0 ;0
L 1.5533 -2.08261004 1.55308996 -2.08221004 0 P 0 ;0
L 1.55308996 -2.08221004 1.55283996 -2.08183002 0 P 0 ;0
L 1.55283996 -2.08183002 1.55175 -2.0804 0 P 0 ;0
L 1.55175 -2.0804 1.55055 -2.07908002 0 P 0 ;0
L 1.55055 -2.07908002 1.54926004 -2.07783996 0 P 0 ;0
L 1.54926004 -2.07783996 1.54788996 -2.07671998 0 P 0 ;0
L 1.54788996 -2.07671998 1.53706998 -2.06898002 0 P 0 ;0
L 1.53706998 -2.06898002 1.52085 -2.05713996 0 P 0 ;0
L 1.52085 -2.05713996 1.51766004 -2.05445 0 P 0 ;0
L 1.51766004 -2.05445 1.51468002 -2.05153996 0 P 0 ;0
L 1.51468002 -2.05153996 1.51191998 -2.04841998 0 P 0 ;0
L 1.51191998 -2.04841998 1.51048996 -2.04651998 0 P 0 ;0
L 1.51048996 -2.04651998 1.50923002 -2.04453002 0 P 0 ;0
L 1.50923002 -2.04453002 1.50813996 -2.04245 0 P 0 ;0
L 1.50813996 -2.04245 1.50721998 -2.04026004 0 P 0 ;0
L 1.50721998 -2.04026004 1.50643002 -2.03788002 0 P 0 ;0
L 1.50643002 -2.03788002 1.50581004 -2.03545 0 P 0 ;0
L 1.50581004 -2.03545 1.50536004 -2.03298996 0 P 0 ;0
L 1.50536004 -2.03298996 1.50508996 -2.0305 0 P 0 ;0
L 1.50508996 -2.0305 1.50498996 -2.02745 0 P 0 ;0
L 1.50498996 -2.02745 1.50513996 -2.02443996 0 P 0 ;0
L 1.50513996 -2.02443996 1.50551998 -2.02145 0 P 0 ;0
L 1.50551998 -2.02145 1.50613996 -2.0185 0 P 0 ;0
L 1.50613996 -2.0185 1.50698996 -2.01561004 0 P 0 ;0
L 1.50698996 -2.01561004 1.50783002 -2.01341004 0 P 0 ;0
L 1.50783002 -2.01341004 1.50883002 -2.0113 0 P 0 ;0
L 1.50883002 -2.0113 1.51 -2.00928002 0 P 0 ;0
L 1.51 -2.00928002 1.51133002 -2.00736004 0 P 0 ;0
L 1.51133002 -2.00736004 1.5128 -2.00555 0 P 0 ;0
L 1.5128 -2.00555 1.5144 -2.00386004 0 P 0 ;0
L 1.5144 -2.00386004 1.51675 -2.00176998 0 P 0 ;0
L 1.51675 -2.00176998 1.51923002 -1.9999 0 P 0 ;0
L 1.51923002 -1.9999 1.52186004 -1.99823996 0 P 0 ;0
L 1.52186004 -1.99823996 1.52461998 -1.99681004 0 P 0 ;0
L 1.52461998 -1.99681004 1.52748996 -1.99561004 0 P 0 ;0
L 1.52748996 -1.99561004 1.53353002 -1.99363996 0 P 0 ;0
L 1.53353002 -1.99363996 1.5397 -1.99218002 0 P 0 ;0
L 1.5397 -1.99218002 1.54598002 -1.99123002 0 P 0 ;0
L 1.54598002 -1.99123002 1.55181004 -1.99075 0 P 0 ;0
L 1.55181004 -1.99075 1.55763002 -1.99061998 0 P 0 ;0
L 1.55763002 -1.99061998 1.57273002 -1.99113996 0 P 0 ;0
L 1.57273002 -1.99113996 1.58755 -1.99248996 0 P 0 ;0
L 1.58755 -1.99248996 1.59293002 -1.99331998 0 P 0 ;0
L 1.59293002 -1.99331998 1.59821004 -1.99448996 0 P 0 ;0
L 1.59821004 -1.99448996 1.59905 -1.99473002 0 P 0 ;0
L 1.59905 -1.99473002 1.59986004 -1.99501998 0 P 0 ;0
L 1.59986004 -1.99501998 1.60008002 -1.99511998 0 P 0 ;0
L 1.60008002 -1.99511998 1.6003 -1.99523002 0 P 0 ;0
L 1.6003 -1.99523002 1.60051004 -1.99536004 0 P 0 ;0
L 1.60051004 -1.99536004 1.60071004 -1.9955 0 P 0 ;0
L 1.60071004 -1.9955 1.60083002 -1.99561004 0 P 0 ;0
L 1.60083002 -1.99561004 1.60093996 -1.99571004 0 P 0 ;0
L 1.60093996 -1.99571004 1.60103996 -1.99583002 0 P 0 ;0
L 1.60103996 -1.99583002 1.60111998 -1.99595 0 P 0 ;0
L 1.60111998 -1.99595 1.60116998 -1.99601998 0 P 0 ;0
L 1.60116998 -1.99601998 1.60121004 -1.99611004 0 P 0 ;0
L 1.60121004 -1.99611004 1.60125 -1.99621004 0 P 0 ;0
L 1.60125 -1.99621004 1.60128002 -1.9963 0 P 0 ;0
L 1.60128002 -1.9963 1.60131004 -1.99641004 0 P 0 ;0
L 1.60131004 -1.99641004 1.6017 -1.99861998 0 P 0 ;0
L 1.6017 -1.99861998 1.60195 -2.00086998 0 P 0 ;0
L 1.60195 -2.00086998 1.60308002 -2.01593002 0 P 0 ;0
L 1.60308002 -2.01593002 1.60415 -2.03096998 0 P 0 ;0
L 1.60415 -2.03096998 1.60345 -2.03083996 0 P 0 ;0
L 1.60345 -2.03083996 1.60058996 -2.03026004 0 P 0 ;0
L 1.60058996 -2.03026004 1.59723002 -2.02948002 0 P 0 ;0
L 1.59723002 -2.02948002 1.59721998 -2.02948002 0 P 0 ;0
L 1.59721998 -2.02948002 1.59306998 -2.0286 0 P 0 ;0
L 1.59306998 -2.0286 1.58776004 -2.02776998 0 P 0 ;0
L 1.58776004 -2.02776998 1.58226004 -2.02708002 0 P 0 ;0
L 1.58226004 -2.02708002 1.57738002 -2.02666998 0 P 0 ;0
L 1.57738002 -2.02666998 1.5709 -2.02633996 0 P 0 ;0
L 1.5709 -2.02633996 1.56918996 -2.02635 0 P 0 ;0
L 1.56918996 -2.02635 1.56746998 -2.02648996 0 P 0 ;0
L 1.56746998 -2.02648996 1.56678996 -2.02658996 0 P 0 ;0
L 1.56678996 -2.02658996 1.56611998 -2.02673996 0 P 0 ;0
L 1.56611998 -2.02673996 1.56546004 -2.02695 0 P 0 ;0
L 1.56546004 -2.02695 1.56481998 -2.0272 0 P 0 ;0
L 1.56481998 -2.0272 1.56418996 -2.0275 0 P 0 ;0
L 1.56418996 -2.0275 1.56358002 -2.02785 0 P 0 ;0
L 1.56358002 -2.02785 1.563 -2.02823002 0 P 0 ;0
L 1.563 -2.02823002 1.56245 -2.02865 0 P 0 ;0
L 1.56245 -2.02865 1.56206998 -2.02898996 0 P 0 ;0
L 1.56206998 -2.02898996 1.56171004 -2.02936004 0 P 0 ;0
L 1.56171004 -2.02936004 1.56138002 -2.02976004 0 P 0 ;0
L 1.56138002 -2.02976004 1.56108996 -2.03018996 0 P 0 ;0
L 1.56108996 -2.03018996 1.56083002 -2.03063996 0 P 0 ;0
L 1.56083002 -2.03063996 1.56061998 -2.0311 0 P 0 ;0
L 1.56061998 -2.0311 1.56043996 -2.03158996 0 P 0 ;0
L 1.56043996 -2.03158996 1.5603 -2.03208002 0 P 0 ;0
L 1.5603 -2.03208002 1.5602 -2.0326 0 P 0 ;0
L 1.5602 -2.0326 1.56015 -2.03308002 0 P 0 ;0
L 1.56015 -2.03308002 1.56013996 -2.03353996 0 P 0 ;0
L 1.56013996 -2.03353996 1.56016004 -2.03391004 0 P 0 ;0
L 1.56016004 -2.03391004 1.56048002 -2.03391004 0 P 0 ;0
L 1.56048002 -2.03391004 1.56016004 -2.03393002 0 P 0 ;0
L 1.56016004 -2.03393002 1.56016998 -2.03401004 0 P 0 ;0
L 1.56016998 -2.03401004 1.56023002 -2.03448002 0 P 0 ;0
L 1.56023002 -2.03448002 1.56025 -2.03456004 0 P 0 ;0
L 1.56025 -2.03456004 1.56033002 -2.03493002 0 P 0 ;0
L 1.56033002 -2.03493002 1.56046998 -2.03538002 0 P 0 ;0
L 1.56046998 -2.03538002 1.56063996 -2.03581998 0 P 0 ;0
L 1.56063996 -2.03581998 1.56085 -2.03623996 0 P 0 ;0
L 1.56085 -2.03623996 1.56108996 -2.03663996 0 P 0 ;0
L 1.56108996 -2.03663996 1.56136004 -2.03701998 0 P 0 ;0
L 1.56136004 -2.03701998 1.56233002 -2.03818996 0 P 0 ;0
L 1.56233002 -2.03818996 1.56336998 -2.03928996 0 P 0 ;0
L 1.56336998 -2.03928996 1.56448002 -2.04031004 0 P 0 ;0
L 1.56448002 -2.04031004 1.56566004 -2.04123996 0 P 0 ;0
L 1.56566004 -2.04123996 1.57471004 -2.04761998 0 P 0 ;0
L 1.57471004 -2.04761998 1.58461998 -2.05491004 0 P 0 ;0
L 1.58461998 -2.05491004 1.58898996 -2.05858996 0 P 0 ;0
L 1.58898996 -2.05858996 1.59315 -2.06245 0 P 0 ;0
L 1.59315 -2.06245 1.59656998 -2.06596998 0 P 0 ;0
L 1.59656998 -2.06596998 1.59976004 -2.06965 0 P 0 ;0
L 1.59976004 -2.06965 1.60116004 -2.07151004 0 P 0 ;0
L 1.60116004 -2.07151004 1.60238002 -2.07346004 0 P 0 ;0
L 1.60238002 -2.07346004 1.60341998 -2.0755 0 P 0 ;0
L 1.60341998 -2.0755 1.60403996 -2.077 0 P 0 ;0
L 1.60403996 -2.077 1.60456004 -2.07853996 0 P 0 ;0
L 1.60456004 -2.07853996 1.60496004 -2.08011004 0 P 0 ;0
L 1.60496004 -2.08011004 1.60525 -2.0817 0 P 0 ;0
L 1.60525 -2.0817 1.60568996 -2.08578002 0 P 0 ;0
L 1.60568996 -2.08578002 1.60578996 -2.08988002 0 P 0 ;0
L 1.60578996 -2.08988002 1.60556998 -2.09403002 0 P 0 ;0
L 1.60556998 -2.09403002 1.60501004 -2.09813996 0 P 0 ;0
L 1.60501004 -2.09813996 1.60451998 -2.10036998 0 P 0 ;0
L 1.60451998 -2.10036998 1.60383996 -2.10253996 0 P 0 ;0
L 1.60383996 -2.10253996 1.60298996 -2.10465 0 P 0 ;0
L 1.60298996 -2.10465 1.60163996 -2.1073 0 P 0 ;0
L 1.60163996 -2.1073 1.60008002 -2.10983002 0 P 0 ;0
L 1.60008002 -2.10983002 1.59833002 -2.11225 0 P 0 ;0
L 1.59833002 -2.11225 1.59696998 -2.11386998 0 P 0 ;0
L 1.59696998 -2.11386998 1.59551004 -2.11538996 0 P 0 ;0
L 1.59551004 -2.11538996 1.59395 -2.1168 0 P 0 ;0
L 1.59395 -2.1168 1.59231004 -2.11811004 0 P 0 ;0
L 1.59231004 -2.11811004 1.58973002 -2.11986004 0 P 0 ;0
L 1.58973002 -2.11986004 1.58701998 -2.1214 0 P 0 ;0
L 1.58701998 -2.1214 1.5842 -2.12273002 0 P 0 ;0
L 1.5842 -2.12273002 1.5788 -2.1248 0 P 0 ;0
L 1.5788 -2.1248 1.57326998 -2.12648996 0 P 0 ;0
L 1.57326998 -2.12648996 1.56983002 -2.12731004 0 P 0 ;0
L 1.56983002 -2.12731004 1.56638002 -2.12791004 0 P 0 ;0
L 1.56638002 -2.12791004 1.56288996 -2.1283 0 P 0 ;0
L 1.56288996 -2.1283 1.54886998 -2.12886998 0 P 0 ;0
L 1.35851998 -2.06545 1.47866004 -2.06545 0 P 0 ;0
L 1.35936004 -2.06445 1.47871004 -2.06445 0 P 0 ;0
L 1.36041004 -2.06345 1.47875 -2.06345 0 P 0 ;0
L 1.36163996 -2.06245 1.4788 -2.06245 0 P 0 ;0
L 1.36293996 -2.06145 1.47883996 -2.06145 0 P 0 ;0
L 1.36436004 -2.06045 1.47888996 -2.06045 0 P 0 ;0
L 1.36598002 -2.05945 1.47893996 -2.05945 0 P 0 ;0
L 1.36776004 -2.05845 1.47898996 -2.05845 0 P 0 ;0
L 1.36971004 -2.05745 1.47903002 -2.05745 0 P 0 ;0
L 1.37166004 -2.05645 1.47908002 -2.05645 0 P 0 ;0
L 1.37391004 -2.05545 1.47911998 -2.05545 0 P 0 ;0
L 1.37616998 -2.05445 1.47916998 -2.05445 0 P 0 ;0
L 1.37873002 -2.05345 1.47921004 -2.05345 0 P 0 ;0
L 1.38136004 -2.05245 1.47926004 -2.05245 0 P 0 ;0
L 1.36875 -2.03345 1.37108996 -2.03345 0 P 0 ;0
L 1.36886004 -2.03245 1.37385 -2.03245 0 P 0 ;0
L 1.36896998 -2.03145 1.37678002 -2.03145 0 P 0 ;0
L 1.36908996 -2.03045 1.3797 -2.03045 0 P 0 ;0
L 1.36921004 -2.02945 1.38261998 -2.02945 0 P 0 ;0
L 1.36933002 -2.02845 1.38638996 -2.02845 0 P 0 ;0
L 1.36946004 -2.02745 1.39023996 -2.02745 0 P 0 ;0
L 1.36958002 -2.02645 1.39503002 -2.02645 0 P 0 ;0
L 1.3697 -2.02545 1.40068002 -2.02545 0 P 0 ;0
L 1.36981998 -2.02445 1.41053996 -2.02445 0 P 0 ;0
L 1.36993996 -2.02345 1.47993996 -2.02345 0 P 0 ;0
L 1.37008002 -2.02245 1.47988002 -2.02245 0 P 0 ;0
L 1.37021004 -2.02145 1.47978002 -2.02145 0 P 0 ;0
L 1.37033996 -2.02045 1.47968002 -2.02045 0 P 0 ;0
L 1.37046998 -2.01945 1.47953002 -2.01945 0 P 0 ;0
L 1.3706 -2.01845 1.47936004 -2.01845 0 P 0 ;0
L 1.37073002 -2.01745 1.47918002 -2.01745 0 P 0 ;0
L 1.37086004 -2.01645 1.47893002 -2.01645 0 P 0 ;0
L 1.37098996 -2.01545 1.47868002 -2.01545 0 P 0 ;0
L 1.37113002 -2.01445 1.4784 -2.01445 0 P 0 ;0
L 1.37126998 -2.01345 1.47806004 -2.01345 0 P 0 ;0
L 1.3714 -2.01245 1.47773002 -2.01245 0 P 0 ;0
L 1.37153996 -2.01145 1.47733002 -2.01145 0 P 0 ;0
L 1.37168002 -2.01045 1.47691004 -2.01045 0 P 0 ;0
L 1.37181004 -2.00945 1.47641004 -2.00945 0 P 0 ;0
L 1.37195 -2.00845 1.47588996 -2.00845 0 P 0 ;0
L 1.37208002 -2.00745 1.47528002 -2.00745 0 P 0 ;0
L 1.37221004 -2.00645 1.47463996 -2.00645 0 P 0 ;0
L 1.37235 -2.00545 1.47391998 -2.00545 0 P 0 ;0
L 1.37248996 -2.00445 1.47311004 -2.00445 0 P 0 ;0
L 1.37261998 -2.00345 1.47225 -2.00345 0 P 0 ;0
L 1.37276004 -2.00245 1.47126998 -2.00245 0 P 0 ;0
L 1.3729 -2.00145 1.4702 -2.00145 0 P 0 ;0
L 1.37303002 -2.00045 1.46903996 -2.00045 0 P 0 ;0
L 1.37316998 -1.99945 1.46775 -1.99945 0 P 0 ;0
L 1.3733 -1.99845 1.46625 -1.99845 0 P 0 ;0
L 1.37343996 -1.99745 1.46455 -1.99745 0 P 0 ;0
L 1.37356998 -1.99645 1.46253996 -1.99645 0 P 0 ;0
L 1.37753002 -1.99545 1.46041004 -1.99545 0 P 0 ;0
L 1.38218996 -1.99445 1.45781004 -1.99445 0 P 0 ;0
L 1.42925 -2.08345 1.47785 -2.08345 0 P 0 ;0
L 1.42931998 -2.08245 1.47788996 -2.08245 0 P 0 ;0
L 1.42938002 -2.08145 1.47793002 -2.08145 0 P 0 ;0
L 1.42945 -2.08045 1.47796998 -2.08045 0 P 0 ;0
L 1.42951004 -2.07945 1.47801004 -2.07945 0 P 0 ;0
L 1.42958002 -2.07845 1.47806004 -2.07845 0 P 0 ;0
L 1.42963996 -2.07745 1.4781 -2.07745 0 P 0 ;0
L 1.4297 -2.07645 1.47815 -2.07645 0 P 0 ;0
L 1.42976998 -2.07545 1.4782 -2.07545 0 P 0 ;0
L 1.42983002 -2.07445 1.47825 -2.07445 0 P 0 ;0
L 1.4299 -2.07345 1.47828996 -2.07345 0 P 0 ;0
L 1.42963996 -2.07245 1.47833996 -2.07245 0 P 0 ;0
L 1.42918996 -2.07145 1.47838002 -2.07145 0 P 0 ;0
L 1.38425 -2.05145 1.47931004 -2.05145 0 P 0 ;0
L 1.38731998 -2.05045 1.47933996 -2.05045 0 P 0 ;0
L 1.39088002 -2.04945 1.47938002 -2.04945 0 P 0 ;0
L 1.3947 -2.04845 1.47941004 -2.04845 0 P 0 ;0
L 1.39851004 -2.04745 1.47945 -2.04745 0 P 0 ;0
L 1.40233002 -2.04645 1.47948002 -2.04645 0 P 0 ;0
L 1.40608002 -2.04545 1.47951004 -2.04545 0 P 0 ;0
L 1.40983002 -2.04445 1.47955 -2.04445 0 P 0 ;0
L 1.41306998 -2.04345 1.47958996 -2.04345 0 P 0 ;0
L 1.41591998 -2.04245 1.47961998 -2.04245 0 P 0 ;0
L 1.41876998 -2.04145 1.47965 -2.04145 0 P 0 ;0
L 1.42133996 -2.04045 1.47968996 -2.04045 0 P 0 ;0
L 1.42361998 -2.03945 1.47971998 -2.03945 0 P 0 ;0
L 1.42591004 -2.03845 1.47975 -2.03845 0 P 0 ;0
L 1.42805 -2.03745 1.47978002 -2.03745 0 P 0 ;0
L 1.42936004 -2.03645 1.47981004 -2.03645 0 P 0 ;0
L 1.43003002 -2.03545 1.47983002 -2.03545 0 P 0 ;0
L 1.43081998 -2.03445 1.47986004 -2.03445 0 P 0 ;0
L 1.43121004 -2.03345 1.47988002 -2.03345 0 P 0 ;0
L 1.43141998 -2.03245 1.4799 -2.03245 0 P 0 ;0
L 1.43146998 -2.03145 1.47993002 -2.03145 0 P 0 ;0
L 1.43136004 -2.03045 1.47996004 -2.03045 0 P 0 ;0
L 1.43108002 -2.02945 1.47998002 -2.02945 0 P 0 ;0
L 1.4306 -2.02845 1.48001004 -2.02845 0 P 0 ;0
L 1.42986998 -2.02745 1.48001004 -2.02745 0 P 0 ;0
L 1.42875 -2.02645 1.47998996 -2.02645 0 P 0 ;0
L 1.42658996 -2.02545 1.47996998 -2.02545 0 P 0 ;0
L 1.42203996 -2.02445 1.47996004 -2.02445 0 P 0 ;0
L 1.38748002 -1.99345 1.45483002 -1.99345 0 P 0 ;0
L 1.39331998 -1.99245 1.45108996 -1.99245 0 P 0 ;0
L 1.40051004 -1.99145 1.44503002 -1.99145 0 P 0 ;0
L 1.38096998 -2.12745 1.4051 -2.12745 0 P 0 ;0
L 1.37671004 -2.12645 1.41113996 -2.12645 0 P 0 ;0
L 1.3736 -2.12545 1.41238996 -2.12545 0 P 0 ;0
L 1.37096998 -2.12445 1.41268002 -2.12445 0 P 0 ;0
L 1.36876998 -2.12345 1.41296998 -2.12345 0 P 0 ;0
L 1.36685 -2.12245 1.41326998 -2.12245 0 P 0 ;0
L 1.36516004 -2.12145 1.41356004 -2.12145 0 P 0 ;0
L 1.36366004 -2.12045 1.41385 -2.12045 0 P 0 ;0
L 1.36225 -2.11945 1.41413996 -2.11945 0 P 0 ;0
L 1.361 -2.11845 1.41443002 -2.11845 0 P 0 ;0
L 1.35983002 -2.11745 1.41471998 -2.11745 0 P 0 ;0
L 1.35876004 -2.11645 1.41501004 -2.11645 0 P 0 ;0
L 1.42661998 -2.12445 1.47693002 -2.12445 0 P 0 ;0
L 1.42665 -2.12345 1.47693002 -2.12345 0 P 0 ;0
L 1.4267 -2.12245 1.47693002 -2.12245 0 P 0 ;0
L 1.42675 -2.12145 1.47693002 -2.12145 0 P 0 ;0
L 1.42681004 -2.12045 1.47693002 -2.12045 0 P 0 ;0
L 1.42686998 -2.11945 1.47693002 -2.11945 0 P 0 ;0
L 1.42691998 -2.11845 1.47693002 -2.11845 0 P 0 ;0
L 1.42698996 -2.11745 1.47693002 -2.11745 0 P 0 ;0
L 1.42705 -2.11645 1.47693002 -2.11645 0 P 0 ;0
L 1.42711004 -2.11545 1.47693002 -2.11545 0 P 0 ;0
L 1.42716998 -2.11445 1.47693002 -2.11445 0 P 0 ;0
L 1.42723002 -2.11345 1.47693996 -2.11345 0 P 0 ;0
L 1.4273 -2.11245 1.47695 -2.11245 0 P 0 ;0
L 1.42736998 -2.11145 1.47696004 -2.11145 0 P 0 ;0
L 1.42743996 -2.11045 1.47698002 -2.11045 0 P 0 ;0
L 1.42751004 -2.10945 1.47698996 -2.10945 0 P 0 ;0
L 1.42758002 -2.10845 1.47701004 -2.10845 0 P 0 ;0
L 1.42765 -2.10745 1.47703002 -2.10745 0 P 0 ;0
L 1.42771004 -2.10645 1.47703996 -2.10645 0 P 0 ;0
L 1.42778002 -2.10545 1.47706998 -2.10545 0 P 0 ;0
L 1.42783996 -2.10445 1.4771 -2.10445 0 P 0 ;0
L 1.42791004 -2.10345 1.47713002 -2.10345 0 P 0 ;0
L 1.42798002 -2.10245 1.47716004 -2.10245 0 P 0 ;0
L 1.42805 -2.10145 1.4772 -2.10145 0 P 0 ;0
L 1.42811004 -2.10045 1.47723002 -2.10045 0 P 0 ;0
L 1.40953002 -2.09945 1.41973002 -2.09945 0 P 0 ;0
L 1.42818002 -2.09945 1.47726004 -2.09945 0 P 0 ;0
L 1.41618002 -2.09845 1.41996998 -2.09845 0 P 0 ;0
L 1.42825 -2.09845 1.47728996 -2.09845 0 P 0 ;0
L 1.42831998 -2.09745 1.47733002 -2.09745 0 P 0 ;0
L 1.42838996 -2.09645 1.47736004 -2.09645 0 P 0 ;0
L 1.42846004 -2.09545 1.47738996 -2.09545 0 P 0 ;0
L 1.42851998 -2.09445 1.47741998 -2.09445 0 P 0 ;0
L 1.42858996 -2.09345 1.47746004 -2.09345 0 P 0 ;0
L 1.42866004 -2.09245 1.4775 -2.09245 0 P 0 ;0
L 1.42873002 -2.09145 1.47753996 -2.09145 0 P 0 ;0
L 1.42878996 -2.09045 1.47758002 -2.09045 0 P 0 ;0
L 1.42886004 -2.08945 1.47761998 -2.08945 0 P 0 ;0
L 1.42893002 -2.08845 1.47766004 -2.08845 0 P 0 ;0
L 1.42898996 -2.08745 1.4777 -2.08745 0 P 0 ;0
L 1.42906004 -2.08645 1.47773002 -2.08645 0 P 0 ;0
L 1.42911998 -2.08545 1.47776998 -2.08545 0 P 0 ;0
L 1.42918996 -2.08445 1.47781004 -2.08445 0 P 0 ;0
L 1.61686004 -2.17995 1.66846004 -2.17995 0 P 0 ;0
L 1.61591004 -2.17895 1.67158996 -2.17895 0 P 0 ;0
L 1.61553996 -2.17795 1.67431998 -2.17795 0 P 0 ;0
L 1.61526998 -2.17695 1.67675 -2.17695 0 P 0 ;0
L 1.61508002 -2.17595 1.67903996 -2.17595 0 P 0 ;0
L 1.61496998 -2.17495 1.68108002 -2.17495 0 P 0 ;0
L 1.61491004 -2.17395 1.68295 -2.17395 0 P 0 ;0
L 1.61485 -2.17295 1.68458996 -2.17295 0 P 0 ;0
L 1.61478996 -2.17195 1.6861 -2.17195 0 P 0 ;0
L 1.61473002 -2.17095 1.6875 -2.17095 0 P 0 ;0
L 1.61466998 -2.16995 1.68876998 -2.16995 0 P 0 ;0
L 1.61461004 -2.16895 1.68998002 -2.16895 0 P 0 ;0
L 1.61455 -2.16795 1.69108002 -2.16795 0 P 0 ;0
L 1.61448996 -2.16695 1.69211998 -2.16695 0 P 0 ;0
L 1.61443002 -2.16595 1.69316004 -2.16595 0 P 0 ;0
L 1.61436998 -2.16495 1.69411998 -2.16495 0 P 0 ;0
L 1.61431004 -2.16395 1.69498996 -2.16395 0 P 0 ;0
L 1.61425 -2.16295 1.69586004 -2.16295 0 P 0 ;0
L 1.61418996 -2.16195 1.69673002 -2.16195 0 P 0 ;0
L 1.61413002 -2.16095 1.69746998 -2.16095 0 P 0 ;0
L 1.61406998 -2.15995 1.6982 -2.15995 0 P 0 ;0
L 1.61401998 -2.15895 1.69893996 -2.15895 0 P 0 ;0
L 1.61396998 -2.15795 1.69963002 -2.15795 0 P 0 ;0
L 1.64433002 -2.18295 1.63151004 -2.18271004 0 P 0 ;0
L 1.63151004 -2.18271004 1.62658002 -2.18226998 0 P 0 ;0
L 1.62658002 -2.18226998 1.62168996 -2.18146998 0 P 0 ;0
L 1.62168996 -2.18146998 1.6201 -2.1811 0 P 0 ;0
L 1.6201 -2.1811 1.61853996 -2.18061004 0 P 0 ;0
L 1.61853996 -2.18061004 1.61701004 -2.18001998 0 P 0 ;0
L 1.61701004 -2.18001998 1.61686004 -2.17995 0 P 0 ;0
L 1.61686004 -2.17995 1.61671004 -2.17986998 0 P 0 ;0
L 1.61671004 -2.17986998 1.61656998 -2.17976998 0 P 0 ;0
L 1.61656998 -2.17976998 1.61643996 -2.17966998 0 P 0 ;0
L 1.61643996 -2.17966998 1.61631998 -2.17955 0 P 0 ;0
L 1.61631998 -2.17955 1.61621004 -2.17943002 0 P 0 ;0
L 1.61621004 -2.17943002 1.6161 -2.1793 0 P 0 ;0
L 1.6161 -2.1793 1.61601004 -2.17915 0 P 0 ;0
L 1.61601004 -2.17915 1.61593002 -2.179 0 P 0 ;0
L 1.61593002 -2.179 1.61586004 -2.17885 0 P 0 ;0
L 1.61586004 -2.17885 1.61553002 -2.17791004 0 P 0 ;0
L 1.61553002 -2.17791004 1.61526998 -2.17696004 0 P 0 ;0
L 1.61526998 -2.17696004 1.61508996 -2.17598996 0 P 0 ;0
L 1.61508996 -2.17598996 1.61496998 -2.17496998 0 P 0 ;0
L 1.61496998 -2.17496998 1.61408002 -2.16011004 0 P 0 ;0
L 1.61408002 -2.16011004 1.61341998 -2.14758996 0 P 0 ;0
L 1.61341998 -2.14758996 1.6202 -2.14821004 0 P 0 ;0
L 1.6202 -2.14821004 1.62023002 -2.14821004 0 P 0 ;0
L 1.62023002 -2.14821004 1.63216998 -2.14893996 0 P 0 ;0
L 1.63216998 -2.14893996 1.6349 -2.14893002 0 P 0 ;0
L 1.6349 -2.14893002 1.63761998 -2.14873002 0 P 0 ;0
L 1.63761998 -2.14873002 1.64031998 -2.14835 0 P 0 ;0
L 1.64031998 -2.14835 1.64198996 -2.14798996 0 P 0 ;0
L 1.64198996 -2.14798996 1.64363002 -2.14751998 0 P 0 ;0
L 1.64363002 -2.14751998 1.64523002 -2.14693002 0 P 0 ;0
L 1.64523002 -2.14693002 1.64678996 -2.14623002 0 P 0 ;0
L 1.64678996 -2.14623002 1.64888002 -2.14506998 0 P 0 ;0
L 1.64888002 -2.14506998 1.65086998 -2.14376004 0 P 0 ;0
L 1.65086998 -2.14376004 1.65093996 -2.14371004 0 P 0 ;0
L 1.65093996 -2.14371004 1.65275 -2.14228996 0 P 0 ;0
L 1.65275 -2.14228996 1.6539 -2.14123996 0 P 0 ;0
L 1.6539 -2.14123996 1.65496004 -2.14011004 0 P 0 ;0
L 1.65496004 -2.14011004 1.65591998 -2.13891004 0 P 0 ;0
L 1.65591998 -2.13891004 1.65755 -2.13653996 0 P 0 ;0
L 1.65755 -2.13653996 1.65901998 -2.13415 0 P 0 ;0
L 1.65901998 -2.13415 1.65903002 -2.13413002 0 P 0 ;0
L 1.65903002 -2.13413002 1.66035 -2.13171998 0 P 0 ;0
L 1.66035 -2.13171998 1.66155 -2.12925 0 P 0 ;0
L 1.66155 -2.12925 1.66183996 -2.12851998 0 P 0 ;0
L 1.66183996 -2.12851998 1.66206998 -2.12776004 0 P 0 ;0
L 1.66206998 -2.12776004 1.66223996 -2.12696998 0 P 0 ;0
L 1.66223996 -2.12696998 1.66233996 -2.12618002 0 P 0 ;0
L 1.66233996 -2.12618002 1.66236998 -2.12538996 0 P 0 ;0
L 1.66236998 -2.12538996 1.66233002 -2.12436004 0 P 0 ;0
L 1.66233002 -2.12436004 1.66221004 -2.12335 0 P 0 ;0
L 1.66221004 -2.12335 1.662 -2.12235 0 P 0 ;0
L 1.662 -2.12235 1.66171004 -2.12141004 0 P 0 ;0
L 1.66171004 -2.12141004 1.64438996 -2.07113002 0 P 0 ;0
L 1.64438996 -2.07113002 1.62871998 -2.02606004 0 P 0 ;0
L 1.62871998 -2.02606004 1.62116004 -2.00558996 0 P 0 ;0
L 1.62116004 -2.00558996 1.62116004 -2.00556998 0 P 0 ;0
L 1.62116004 -2.00556998 1.61681004 -1.99443996 0 P 0 ;0
L 1.61681004 -1.99443996 1.67163002 -1.99443996 0 P 0 ;0
L 1.67163002 -1.99443996 1.67301004 -2.00076004 0 P 0 ;0
L 1.67301004 -2.00076004 1.67613002 -2.01341998 0 P 0 ;0
L 1.67613002 -2.01341998 1.68331004 -2.03931998 0 P 0 ;0
L 1.68331004 -2.03931998 1.69153002 -2.06856998 0 P 0 ;0
L 1.69153002 -2.06856998 1.6916 -2.06876004 0 P 0 ;0
L 1.6916 -2.06876004 1.69168996 -2.06896998 0 P 0 ;0
L 1.69168996 -2.06896998 1.69181004 -2.06918002 0 P 0 ;0
L 1.69181004 -2.06918002 1.69193002 -2.06936998 0 P 0 ;0
L 1.69193002 -2.06936998 1.69208002 -2.06956004 0 P 0 ;0
L 1.69208002 -2.06956004 1.69223996 -2.06973002 0 P 0 ;0
L 1.69223996 -2.06973002 1.69241998 -2.06988002 0 P 0 ;0
L 1.69241998 -2.06988002 1.6926 -2.07001998 0 P 0 ;0
L 1.6926 -2.07001998 1.6928 -2.07015 0 P 0 ;0
L 1.6928 -2.07015 1.69301004 -2.07025 0 P 0 ;0
L 1.69301004 -2.07025 1.69323002 -2.07033996 0 P 0 ;0
L 1.69323002 -2.07033996 1.69346004 -2.07041004 0 P 0 ;0
L 1.69346004 -2.07041004 1.69368002 -2.07045 0 P 0 ;0
L 1.69368002 -2.07045 1.69391998 -2.07048002 0 P 0 ;0
L 1.69391998 -2.07048002 1.69413996 -2.07048996 0 P 0 ;0
L 1.69413996 -2.07048996 1.6944 -2.07048002 0 P 0 ;0
L 1.6944 -2.07048002 1.69465 -2.07045 0 P 0 ;0
L 1.69465 -2.07045 1.69488996 -2.07038996 0 P 0 ;0
L 1.69488996 -2.07038996 1.69513996 -2.07031998 0 P 0 ;0
L 1.69513996 -2.07031998 1.69536998 -2.07021998 0 P 0 ;0
L 1.69536998 -2.07021998 1.69558996 -2.0701 0 P 0 ;0
L 1.69558996 -2.0701 1.69581004 -2.06996998 0 P 0 ;0
L 1.69581004 -2.06996998 1.69601004 -2.06981998 0 P 0 ;0
L 1.69601004 -2.06981998 1.6962 -2.06965 0 P 0 ;0
L 1.6962 -2.06965 1.69636998 -2.06946004 0 P 0 ;0
L 1.69636998 -2.06946004 1.69653002 -2.06926004 0 P 0 ;0
L 1.69653002 -2.06926004 1.69666004 -2.06905 0 P 0 ;0
L 1.69666004 -2.06905 1.69678996 -2.06883002 0 P 0 ;0
L 1.69678996 -2.06883002 1.69688002 -2.0686 0 P 0 ;0
L 1.69688002 -2.0686 1.69695 -2.0684 0 P 0 ;0
L 1.69695 -2.0684 1.70426004 -2.04365 0 P 0 ;0
L 1.70426004 -2.04365 1.70426004 -2.04363002 0 P 0 ;0
L 1.70426004 -2.04363002 1.71066998 -2.0213 0 P 0 ;0
L 1.71066998 -2.0213 1.71068002 -2.02126004 0 P 0 ;0
L 1.71068002 -2.02126004 1.71431998 -2.00693996 0 P 0 ;0
L 1.71431998 -2.00693996 1.71706004 -1.99496998 0 P 0 ;0
L 1.71706004 -1.99496998 1.74335 -1.9947 0 P 0 ;0
L 1.74335 -1.9947 1.75403002 -1.99461004 0 P 0 ;0
L 1.75403002 -1.99461004 1.76301004 -1.99465 0 P 0 ;0
L 1.76301004 -1.99465 1.76886004 -1.99471004 0 P 0 ;0
L 1.76886004 -1.99471004 1.76883996 -1.99476004 0 P 0 ;0
L 1.76883996 -1.99476004 1.74021004 -2.06556004 0 P 0 ;0
L 1.74021004 -2.06556004 1.71298002 -2.13276998 0 P 0 ;0
L 1.71298002 -2.13276998 1.70836998 -2.14293996 0 P 0 ;0
L 1.70836998 -2.14293996 1.70413996 -2.15076004 0 P 0 ;0
L 1.70413996 -2.15076004 1.69941998 -2.15828996 0 P 0 ;0
L 1.69941998 -2.15828996 1.6967 -2.16198996 0 P 0 ;0
L 1.6967 -2.16198996 1.6937 -2.16541998 0 P 0 ;0
L 1.6937 -2.16541998 1.69041998 -2.1686 0 P 0 ;0
L 1.69041998 -2.1686 1.68793996 -2.17063002 0 P 0 ;0
L 1.68793996 -2.17063002 1.68535 -2.17248002 0 P 0 ;0
L 1.68535 -2.17248002 1.68263996 -2.17413996 0 P 0 ;0
L 1.68263996 -2.17413996 1.67981004 -2.17561004 0 P 0 ;0
L 1.67981004 -2.17561004 1.67525 -2.17761004 0 P 0 ;0
L 1.67525 -2.17761004 1.6706 -2.17931998 0 P 0 ;0
L 1.6706 -2.17931998 1.66586004 -2.18073002 0 P 0 ;0
L 1.66586004 -2.18073002 1.66141998 -2.1817 0 P 0 ;0
L 1.66141998 -2.1817 1.65691998 -2.18228996 0 P 0 ;0
L 1.65691998 -2.18228996 1.64433002 -2.18295 0 P 0 ;0
L 1.61928996 -2.00628002 1.62683996 -2.02673002 0 P 0 ;0
L 1.62683996 -2.02673002 1.6425 -2.07178002 0 P 0 ;0
L 1.6425 -2.07178002 1.65981004 -2.12201998 0 P 0 ;0
L 1.65981004 -2.12201998 1.66006004 -2.12283996 0 P 0 ;0
L 1.66006004 -2.12283996 1.66023002 -2.12368002 0 P 0 ;0
L 1.66023002 -2.12368002 1.66033996 -2.12451998 0 P 0 ;0
L 1.66033996 -2.12451998 1.66036998 -2.12538002 0 P 0 ;0
L 1.66036998 -2.12538002 1.66033996 -2.12601004 0 P 0 ;0
L 1.66033996 -2.12601004 1.66026998 -2.12663996 0 P 0 ;0
L 1.66026998 -2.12663996 1.66013996 -2.12725 0 P 0 ;0
L 1.66013996 -2.12725 1.65995 -2.12786004 0 P 0 ;0
L 1.65995 -2.12786004 1.65971004 -2.12843996 0 P 0 ;0
L 1.65971004 -2.12843996 1.65856998 -2.1308 0 P 0 ;0
L 1.65856998 -2.1308 1.6573 -2.13313002 0 P 0 ;0
L 1.6573 -2.13313002 1.65586998 -2.13545 0 P 0 ;0
L 1.65586998 -2.13545 1.65431004 -2.13771998 0 P 0 ;0
L 1.65431004 -2.13771998 1.65343996 -2.1388 0 P 0 ;0
L 1.65343996 -2.1388 1.65248996 -2.13981998 0 P 0 ;0
L 1.65248996 -2.13981998 1.65146004 -2.14076004 0 P 0 ;0
L 1.65146004 -2.14076004 1.64971004 -2.14213002 0 P 0 ;0
L 1.64971004 -2.14213002 1.64785 -2.14336004 0 P 0 ;0
L 1.64785 -2.14336004 1.64588996 -2.14443996 0 P 0 ;0
L 1.64588996 -2.14443996 1.64446998 -2.14508002 0 P 0 ;0
L 1.64446998 -2.14508002 1.64301004 -2.14561998 0 P 0 ;0
L 1.64301004 -2.14561998 1.64151004 -2.14605 0 P 0 ;0
L 1.64151004 -2.14605 1.63996998 -2.14636998 0 P 0 ;0
L 1.63996998 -2.14636998 1.63741004 -2.14673996 0 P 0 ;0
L 1.63741004 -2.14673996 1.63483002 -2.14693002 0 P 0 ;0
L 1.63483002 -2.14693002 1.63223002 -2.14693996 0 P 0 ;0
L 1.63223002 -2.14693996 1.62036004 -2.14621998 0 P 0 ;0
L 1.62036004 -2.14621998 1.6113 -2.14538002 0 P 0 ;0
L 1.6113 -2.14538002 1.61208996 -2.16023002 0 P 0 ;0
L 1.61208996 -2.16023002 1.61298002 -2.17515 0 P 0 ;0
L 1.61298002 -2.17515 1.6131 -2.17628002 0 P 0 ;0
L 1.6131 -2.17628002 1.61331998 -2.17741004 0 P 0 ;0
L 1.61331998 -2.17741004 1.61361998 -2.17851004 0 P 0 ;0
L 1.61361998 -2.17851004 1.614 -2.17958996 0 P 0 ;0
L 1.614 -2.17958996 1.61413996 -2.17988996 0 P 0 ;0
L 1.61413996 -2.17988996 1.61428996 -2.18018002 0 P 0 ;0
L 1.61428996 -2.18018002 1.61446998 -2.18045 0 P 0 ;0
L 1.61446998 -2.18045 1.61466998 -2.18071004 0 P 0 ;0
L 1.61466998 -2.18071004 1.61488996 -2.18095 0 P 0 ;0
L 1.61488996 -2.18095 1.61511998 -2.18116998 0 P 0 ;0
L 1.61511998 -2.18116998 1.61538002 -2.18138002 0 P 0 ;0
L 1.61538002 -2.18138002 1.61565 -2.18156004 0 P 0 ;0
L 1.61565 -2.18156004 1.61593002 -2.18173002 0 P 0 ;0
L 1.61593002 -2.18173002 1.61623002 -2.18186004 0 P 0 ;0
L 1.61623002 -2.18186004 1.61788002 -2.1825 0 P 0 ;0
L 1.61788002 -2.1825 1.61956998 -2.18301998 0 P 0 ;0
L 1.61956998 -2.18301998 1.6213 -2.18343002 0 P 0 ;0
L 1.6213 -2.18343002 1.62633002 -2.18426004 0 P 0 ;0
L 1.62633002 -2.18426004 1.6314 -2.18471004 0 P 0 ;0
L 1.6314 -2.18471004 1.64436004 -2.18495 0 P 0 ;0
L 1.64436004 -2.18495 1.65711004 -2.18428002 0 P 0 ;0
L 1.65711004 -2.18428002 1.66176998 -2.18366998 0 P 0 ;0
L 1.66176998 -2.18366998 1.66636004 -2.18266998 0 P 0 ;0
L 1.66636004 -2.18266998 1.67123002 -2.18121004 0 P 0 ;0
L 1.67123002 -2.18121004 1.676 -2.17946998 0 P 0 ;0
L 1.676 -2.17946998 1.68068002 -2.17741998 0 P 0 ;0
L 1.68068002 -2.17741998 1.68361998 -2.17588002 0 P 0 ;0
L 1.68361998 -2.17588002 1.68646004 -2.17415 0 P 0 ;0
L 1.68646004 -2.17415 1.68916004 -2.17221998 0 P 0 ;0
L 1.68916004 -2.17221998 1.69175 -2.17008996 0 P 0 ;0
L 1.69175 -2.17008996 1.69515 -2.1668 0 P 0 ;0
L 1.69515 -2.1668 1.69826004 -2.16323996 0 P 0 ;0
L 1.69826004 -2.16323996 1.70108002 -2.15941998 0 P 0 ;0
L 1.70108002 -2.15941998 1.70586004 -2.15176998 0 P 0 ;0
L 1.70586004 -2.15176998 1.71016004 -2.14383002 0 P 0 ;0
L 1.71016004 -2.14383002 1.71481998 -2.13356004 0 P 0 ;0
L 1.71481998 -2.13356004 1.74206998 -2.06631004 0 P 0 ;0
L 1.74206998 -2.06631004 1.77071004 -1.99548002 0 P 0 ;0
L 1.77071004 -1.99548002 1.77088002 -1.99498996 0 P 0 ;0
L 1.77088002 -1.99498996 1.77101998 -1.99448996 0 P 0 ;0
L 1.77101998 -1.99448996 1.77111998 -1.99398996 0 P 0 ;0
L 1.77111998 -1.99398996 1.77118002 -1.99346998 0 P 0 ;0
L 1.77118002 -1.99346998 1.7712 -1.99295 0 P 0 ;0
L 1.7712 -1.99295 1.7712 -1.99293002 0 P 0 ;0
L 1.7712 -1.99293002 1.77118996 -1.99286998 0 P 0 ;0
L 1.77118996 -1.99286998 1.77118002 -1.99286004 0 P 0 ;0
L 1.77118002 -1.99286004 1.77118002 -1.99283996 0 P 0 ;0
L 1.77118002 -1.99283996 1.77111004 -1.99276998 0 P 0 ;0
L 1.77111004 -1.99276998 1.77106998 -1.99275 0 P 0 ;0
L 1.77106998 -1.99275 1.77106004 -1.99273996 0 P 0 ;0
L 1.77106004 -1.99273996 1.771 -1.99273002 0 P 0 ;0
L 1.771 -1.99273002 1.77098002 -1.99273002 0 P 0 ;0
L 1.77098002 -1.99273002 1.76301004 -1.99265 0 P 0 ;0
L 1.76301004 -1.99265 1.75401998 -1.99261004 0 P 0 ;0
L 1.75401998 -1.99261004 1.74333002 -1.9927 0 P 0 ;0
L 1.74333002 -1.9927 1.71546004 -1.99298996 0 P 0 ;0
L 1.71546004 -1.99298996 1.71236998 -2.00646998 0 P 0 ;0
L 1.71236998 -2.00646998 1.70873996 -2.02078002 0 P 0 ;0
L 1.70873996 -2.02078002 1.70233996 -2.04308002 0 P 0 ;0
L 1.70233996 -2.04308002 1.69505 -2.0678 0 P 0 ;0
L 1.69505 -2.0678 1.69501998 -2.06788002 0 P 0 ;0
L 1.69501998 -2.06788002 1.69498996 -2.06795 0 P 0 ;0
L 1.69498996 -2.06795 1.69495 -2.06801998 0 P 0 ;0
L 1.69495 -2.06801998 1.69485 -2.06816004 0 P 0 ;0
L 1.69485 -2.06816004 1.69478996 -2.06821998 0 P 0 ;0
L 1.69478996 -2.06821998 1.69466998 -2.06831998 0 P 0 ;0
L 1.69466998 -2.06831998 1.69453002 -2.0684 0 P 0 ;0
L 1.69453002 -2.0684 1.69445 -2.06843002 0 P 0 ;0
L 1.69445 -2.06843002 1.69438002 -2.06846004 0 P 0 ;0
L 1.69438002 -2.06846004 1.69428996 -2.06846998 0 P 0 ;0
L 1.69428996 -2.06846998 1.69421004 -2.06848996 0 P 0 ;0
L 1.69421004 -2.06848996 1.69406998 -2.06848996 0 P 0 ;0
L 1.69406998 -2.06848996 1.69395 -2.06846998 0 P 0 ;0
L 1.69395 -2.06846998 1.69383002 -2.06843002 0 P 0 ;0
L 1.69383002 -2.06843002 1.69373002 -2.06836998 0 P 0 ;0
L 1.69373002 -2.06836998 1.69363002 -2.06828996 0 P 0 ;0
L 1.69363002 -2.06828996 1.69358996 -2.06823996 0 P 0 ;0
L 1.69358996 -2.06823996 1.69355 -2.0682 0 P 0 ;0
L 1.69355 -2.0682 1.69351998 -2.06815 0 P 0 ;0
L 1.69351998 -2.06815 1.69346004 -2.06803996 0 P 0 ;0
L 1.69346004 -2.06803996 1.69343996 -2.06798002 0 P 0 ;0
L 1.69343996 -2.06798002 1.68523002 -2.03878002 0 P 0 ;0
L 1.68523002 -2.03878002 1.67806998 -2.01291998 0 P 0 ;0
L 1.67806998 -2.01291998 1.67496004 -2.00031004 0 P 0 ;0
L 1.67496004 -2.00031004 1.67323002 -1.99243996 0 P 0 ;0
L 1.67323002 -1.99243996 1.61388002 -1.99243996 0 P 0 ;0
L 1.61388002 -1.99243996 1.61928996 -2.00628002 0 P 0 ;0
L 1.35018002 -2.08345 1.39488996 -2.08345 0 P 0 ;0
L 1.35026004 -2.08245 1.39586004 -2.08245 0 P 0 ;0
L 1.35041004 -2.08145 1.39708996 -2.08145 0 P 0 ;0
L 1.35058996 -2.08045 1.39853002 -2.08045 0 P 0 ;0
L 1.35083996 -2.07945 1.40031998 -2.07945 0 P 0 ;0
L 1.35116998 -2.07845 1.40271004 -2.07845 0 P 0 ;0
L 1.35158002 -2.07745 1.40561998 -2.07745 0 P 0 ;0
L 1.35203002 -2.07645 1.4092 -2.07645 0 P 0 ;0
L 1.35248002 -2.07545 1.41288996 -2.07545 0 P 0 ;0
L 1.35293002 -2.07445 1.4164 -2.07445 0 P 0 ;0
L 1.35338996 -2.07345 1.41975 -2.07345 0 P 0 ;0
L 1.35393996 -2.07245 1.42293996 -2.07245 0 P 0 ;0
L 1.35448996 -2.07145 1.42606998 -2.07145 0 P 0 ;0
L 1.35505 -2.07045 1.47843002 -2.07045 0 P 0 ;0
L 1.3557 -2.06945 1.47846998 -2.06945 0 P 0 ;0
L 1.35635 -2.06845 1.47851998 -2.06845 0 P 0 ;0
L 1.35701998 -2.06745 1.47856998 -2.06745 0 P 0 ;0
L 1.35776998 -2.06645 1.47861004 -2.06645 0 P 0 ;0
L 1.29346998 -2.00516004 1.33388996 -2.00516004 0 P 0 ;0
L 1.29448996 -2.00416004 1.33385 -2.00416004 0 P 0 ;0
L 1.29551004 -2.00316004 1.33381004 -2.00316004 0 P 0 ;0
L 1.29653996 -2.00216004 1.33376004 -2.00216004 0 P 0 ;0
L 1.29756004 -2.00116004 1.33371004 -2.00116004 0 P 0 ;0
L 1.29861998 -2.00016004 1.33366004 -2.00016004 0 P 0 ;0
L 1.29973002 -1.99916004 1.3336 -1.99916004 0 P 0 ;0
L 1.30101004 -1.99816004 1.33355 -1.99816004 0 P 0 ;0
L 1.30238996 -1.99716004 1.3335 -1.99716004 0 P 0 ;0
L 1.30393996 -1.99616004 1.33345 -1.99616004 0 P 0 ;0
L 1.30571004 -1.99516004 1.33338996 -1.99516004 0 P 0 ;0
L 1.3077 -1.99416004 1.33333002 -1.99416004 0 P 0 ;0
L 1.31001004 -1.99316004 1.33328002 -1.99316004 0 P 0 ;0
L 1.31288002 -1.99216004 1.33321998 -1.99216004 0 P 0 ;0
L 1.31688996 -1.99116004 1.33316004 -1.99116004 0 P 0 ;0
L 1.39798996 -1.98971998 1.39326998 -1.99043002 0 P 0 ;0
L 1.39326998 -1.99043002 1.38806998 -1.9913 0 P 0 ;0
L 1.38806998 -1.9913 1.38316004 -1.9922 0 P 0 ;0
L 1.38316004 -1.9922 1.37946004 -1.99296998 0 P 0 ;0
L 1.37946004 -1.99296998 1.3718 -1.99466998 0 P 0 ;0
L 1.3718 -1.99466998 1.36896004 -2.01553996 0 P 0 ;0
L 1.36896004 -2.01553996 1.36791004 -2.02358996 0 P 0 ;0
L 1.36791004 -2.02358996 1.36708002 -2.03043002 0 P 0 ;0
L 1.36708002 -2.03043002 1.36638996 -2.03646004 0 P 0 ;0
L 1.36638996 -2.03646004 1.36638002 -2.03648996 0 P 0 ;0
L 1.36638002 -2.03648996 1.36638996 -2.03653002 0 P 0 ;0
L 1.36638996 -2.03653002 1.36638996 -2.03656998 0 P 0 ;0
L 1.36638996 -2.03656998 1.3664 -2.03663996 0 P 0 ;0
L 1.3664 -2.03663996 1.36641998 -2.03666998 0 P 0 ;0
L 1.36641998 -2.03666998 1.36643002 -2.03671004 0 P 0 ;0
L 1.36643002 -2.03671004 1.36648996 -2.0368 0 P 0 ;0
L 1.36648996 -2.0368 1.36656004 -2.03686004 0 P 0 ;0
L 1.36656004 -2.03686004 1.3666 -2.03688996 0 P 0 ;0
L 1.3666 -2.03688996 1.36663002 -2.03691004 0 P 0 ;0
L 1.36663002 -2.03691004 1.36666004 -2.03691004 0 P 0 ;0
L 1.36666004 -2.03691004 1.36671004 -2.03693002 0 P 0 ;0
L 1.36671004 -2.03693002 1.36676998 -2.03693002 0 P 0 ;0
L 1.36676998 -2.03693002 1.36685 -2.03691998 0 P 0 ;0
L 1.36685 -2.03691998 1.36895 -2.03628002 0 P 0 ;0
L 1.36895 -2.03628002 1.37143002 -2.03545 0 P 0 ;0
L 1.37143002 -2.03545 1.37428996 -2.03441004 0 P 0 ;0
L 1.37428996 -2.03441004 1.38346004 -2.03126998 0 P 0 ;0
L 1.38346004 -2.03126998 1.39251998 -2.02891998 0 P 0 ;0
L 1.39251998 -2.02891998 1.40156004 -2.02731998 0 P 0 ;0
L 1.40156004 -2.02731998 1.41068002 -2.02643996 0 P 0 ;0
L 1.41068002 -2.02643996 1.41566998 -2.02628002 0 P 0 ;0
L 1.41566998 -2.02628002 1.42066004 -2.02633996 0 P 0 ;0
L 1.42066004 -2.02633996 1.42221004 -2.02646998 0 P 0 ;0
L 1.42221004 -2.02646998 1.42375 -2.02671998 0 P 0 ;0
L 1.42375 -2.02671998 1.42525 -2.0271 0 P 0 ;0
L 1.42525 -2.0271 1.42671998 -2.02761004 0 P 0 ;0
L 1.42671998 -2.02761004 1.42706004 -2.02776004 0 P 0 ;0
L 1.42706004 -2.02776004 1.42738002 -2.02793002 0 P 0 ;0
L 1.42738002 -2.02793002 1.42768002 -2.02813996 0 P 0 ;0
L 1.42768002 -2.02813996 1.42796998 -2.02836004 0 P 0 ;0
L 1.42796998 -2.02836004 1.42823002 -2.02861004 0 P 0 ;0
L 1.42823002 -2.02861004 1.42848002 -2.02888996 0 P 0 ;0
L 1.42848002 -2.02888996 1.4287 -2.02918002 0 P 0 ;0
L 1.4287 -2.02918002 1.42888996 -2.02948996 0 P 0 ;0
L 1.42888996 -2.02948996 1.42906004 -2.02981004 0 P 0 ;0
L 1.42906004 -2.02981004 1.4292 -2.03015 0 P 0 ;0
L 1.4292 -2.03015 1.42931998 -2.0305 0 P 0 ;0
L 1.42931998 -2.0305 1.4294 -2.03086004 0 P 0 ;0
L 1.4294 -2.03086004 1.42945 -2.03121998 0 P 0 ;0
L 1.42945 -2.03121998 1.42946998 -2.03158002 0 P 0 ;0
L 1.42946998 -2.03158002 1.42946004 -2.03195 0 P 0 ;0
L 1.42946004 -2.03195 1.42941998 -2.03231004 0 P 0 ;0
L 1.42941998 -2.03231004 1.42935 -2.03266998 0 P 0 ;0
L 1.42935 -2.03266998 1.42925 -2.03301998 0 P 0 ;0
L 1.42925 -2.03301998 1.42911998 -2.03336004 0 P 0 ;0
L 1.42911998 -2.03336004 1.42896004 -2.03368996 0 P 0 ;0
L 1.42896004 -2.03368996 1.42875 -2.03405 0 P 0 ;0
L 1.42875 -2.03405 1.42851004 -2.03438996 0 P 0 ;0
L 1.42851004 -2.03438996 1.42825 -2.03471004 0 P 0 ;0
L 1.42825 -2.03471004 1.42796004 -2.03501004 0 P 0 ;0
L 1.42796004 -2.03501004 1.42765 -2.03528996 0 P 0 ;0
L 1.42765 -2.03528996 1.42731998 -2.03553996 0 P 0 ;0
L 1.42731998 -2.03553996 1.42696998 -2.03576004 0 P 0 ;0
L 1.42696998 -2.03576004 1.4266 -2.03596004 0 P 0 ;0
L 1.4266 -2.03596004 1.41951004 -2.03906004 0 P 0 ;0
L 1.41951004 -2.03906004 1.4109 -2.04208996 0 P 0 ;0
L 1.4109 -2.04208996 1.40178002 -2.04451998 0 P 0 ;0
L 1.40178002 -2.04451998 1.3878 -2.04818996 0 P 0 ;0
L 1.3878 -2.04818996 1.38176998 -2.05015 0 P 0 ;0
L 1.38176998 -2.05015 1.3758 -2.05243002 0 P 0 ;0
L 1.3758 -2.05243002 1.37086998 -2.0546 0 P 0 ;0
L 1.37086998 -2.0546 1.36603996 -2.05708002 0 P 0 ;0
L 1.36603996 -2.05708002 1.36356004 -2.05856004 0 P 0 ;0
L 1.36356004 -2.05856004 1.36118996 -2.06023002 0 P 0 ;0
L 1.36118996 -2.06023002 1.35895 -2.06206004 0 P 0 ;0
L 1.35895 -2.06206004 1.35805 -2.06291004 0 P 0 ;0
L 1.35805 -2.06291004 1.35721998 -2.06385 0 P 0 ;0
L 1.35721998 -2.06385 1.35518996 -2.06655 0 P 0 ;0
L 1.35518996 -2.06655 1.3532 -2.06961998 0 P 0 ;0
L 1.3532 -2.06961998 1.35156004 -2.07263002 0 P 0 ;0
L 1.35156004 -2.07263002 1.34951004 -2.07718002 0 P 0 ;0
L 1.34951004 -2.07718002 1.34911004 -2.07825 0 P 0 ;0
L 1.34911004 -2.07825 1.34878996 -2.07935 0 P 0 ;0
L 1.34878996 -2.07935 1.34853002 -2.08046998 0 P 0 ;0
L 1.34853002 -2.08046998 1.34825 -2.08238002 0 P 0 ;0
L 1.34825 -2.08238002 1.34811998 -2.08431004 0 P 0 ;0
L 1.34811998 -2.08431004 1.348 -2.09128996 0 P 0 ;0
L 1.348 -2.09128996 1.3481 -2.09761004 0 P 0 ;0
L 1.3481 -2.09761004 1.34823002 -2.09961004 0 P 0 ;0
L 1.34823002 -2.09961004 1.34846998 -2.10161004 0 P 0 ;0
L 1.34846998 -2.10161004 1.34876998 -2.10321998 0 P 0 ;0
L 1.34876998 -2.10321998 1.3492 -2.10478996 0 P 0 ;0
L 1.3492 -2.10478996 1.3498 -2.10648996 0 P 0 ;0
L 1.3498 -2.10648996 1.3505 -2.10815 0 P 0 ;0
L 1.3505 -2.10815 1.35178996 -2.11066004 0 P 0 ;0
L 1.35178996 -2.11066004 1.35328002 -2.11305 0 P 0 ;0
L 1.35328002 -2.11305 1.35496998 -2.1153 0 P 0 ;0
L 1.35496998 -2.1153 1.35685 -2.1174 0 P 0 ;0
L 1.35685 -2.1174 1.35891998 -2.11933996 0 P 0 ;0
L 1.35891998 -2.11933996 1.36126998 -2.12121998 0 P 0 ;0
L 1.36126998 -2.12121998 1.36373996 -2.12293002 0 P 0 ;0
L 1.36373996 -2.12293002 1.36633002 -2.12446004 0 P 0 ;0
L 1.36633002 -2.12446004 1.36901004 -2.1258 0 P 0 ;0
L 1.36901004 -2.1258 1.3718 -2.12695 0 P 0 ;0
L 1.3718 -2.12695 1.37578996 -2.12828002 0 P 0 ;0
L 1.37578996 -2.12828002 1.37986998 -2.12928996 0 P 0 ;0
L 1.37986998 -2.12928996 1.38401998 -2.12998996 0 P 0 ;0
L 1.38401998 -2.12998996 1.3882 -2.13036004 0 P 0 ;0
L 1.3882 -2.13036004 1.39443002 -2.13045 0 P 0 ;0
L 1.39443002 -2.13045 1.40066004 -2.13006998 0 P 0 ;0
L 1.40066004 -2.13006998 1.40685 -2.12923002 0 P 0 ;0
L 1.40685 -2.12923002 1.41371004 -2.12801998 0 P 0 ;0
L 1.41371004 -2.12801998 1.41583002 -2.12081004 0 P 0 ;0
L 1.41583002 -2.12081004 1.41953996 -2.10798996 0 P 0 ;0
L 1.41953996 -2.10798996 1.42135 -2.10126998 0 P 0 ;0
L 1.42135 -2.10126998 1.42236998 -2.097 0 P 0 ;0
L 1.42236998 -2.097 1.42238996 -2.09691004 0 P 0 ;0
L 1.42238996 -2.09691004 1.4224 -2.09681998 0 P 0 ;0
L 1.4224 -2.09681998 1.4224 -2.09673996 0 P 0 ;0
L 1.4224 -2.09673996 1.42238002 -2.09656004 0 P 0 ;0
L 1.42238002 -2.09656004 1.42235 -2.09648002 0 P 0 ;0
L 1.42235 -2.09648002 1.42233002 -2.09638996 0 P 0 ;0
L 1.42233002 -2.09638996 1.42225 -2.09623002 0 P 0 ;0
L 1.42225 -2.09623002 1.4222 -2.09616004 0 P 0 ;0
L 1.4222 -2.09616004 1.42213996 -2.09608996 0 P 0 ;0
L 1.42213996 -2.09608996 1.42208996 -2.09601998 0 P 0 ;0
L 1.42208996 -2.09601998 1.42203996 -2.09598996 0 P 0 ;0
L 1.42203996 -2.09598996 1.42198996 -2.09595 0 P 0 ;0
L 1.42198996 -2.09595 1.42188996 -2.09588996 0 P 0 ;0
L 1.42188996 -2.09588996 1.42183002 -2.09586004 0 P 0 ;0
L 1.42183002 -2.09586004 1.42178002 -2.09585 0 P 0 ;0
L 1.42178002 -2.09585 1.42171998 -2.09583002 0 P 0 ;0
L 1.42171998 -2.09583002 1.42166004 -2.09581998 0 P 0 ;0
L 1.42166004 -2.09581998 1.42153996 -2.09581998 0 P 0 ;0
L 1.42153996 -2.09581998 1.41978002 -2.09591004 0 P 0 ;0
L 1.41978002 -2.09591004 1.41763996 -2.09615 0 P 0 ;0
L 1.41763996 -2.09615 1.41521998 -2.09658002 0 P 0 ;0
L 1.41521998 -2.09658002 1.4107 -2.09733002 0 P 0 ;0
L 1.4107 -2.09733002 1.40613002 -2.09775 0 P 0 ;0
L 1.40613002 -2.09775 1.40481004 -2.09778002 0 P 0 ;0
L 1.40481004 -2.09778002 1.40348996 -2.09771998 0 P 0 ;0
L 1.40348996 -2.09771998 1.40216998 -2.09756004 0 P 0 ;0
L 1.40216998 -2.09756004 1.40086998 -2.0973 0 P 0 ;0
L 1.40086998 -2.0973 1.39958996 -2.09695 0 P 0 ;0
L 1.39958996 -2.09695 1.39895 -2.09671998 0 P 0 ;0
L 1.39895 -2.09671998 1.39831998 -2.09643002 0 P 0 ;0
L 1.39831998 -2.09643002 1.39773002 -2.0961 0 P 0 ;0
L 1.39773002 -2.0961 1.39716004 -2.09571004 0 P 0 ;0
L 1.39716004 -2.09571004 1.39663002 -2.09528002 0 P 0 ;0
L 1.39663002 -2.09528002 1.39613996 -2.0948 0 P 0 ;0
L 1.39613996 -2.0948 1.39568002 -2.09428002 0 P 0 ;0
L 1.39568002 -2.09428002 1.39533996 -2.09381998 0 P 0 ;0
L 1.39533996 -2.09381998 1.39505 -2.09333996 0 P 0 ;0
L 1.39505 -2.09333996 1.39478996 -2.09281998 0 P 0 ;0
L 1.39478996 -2.09281998 1.39456998 -2.09228996 0 P 0 ;0
L 1.39456998 -2.09228996 1.3944 -2.09173996 0 P 0 ;0
L 1.3944 -2.09173996 1.39428002 -2.09118996 0 P 0 ;0
L 1.39428002 -2.09118996 1.39421004 -2.09061998 0 P 0 ;0
L 1.39421004 -2.09061998 1.39418002 -2.09003996 0 P 0 ;0
L 1.39418002 -2.09003996 1.39421004 -2.08943002 0 P 0 ;0
L 1.39421004 -2.08943002 1.39428002 -2.08883002 0 P 0 ;0
L 1.39428002 -2.08883002 1.39441004 -2.08823002 0 P 0 ;0
L 1.39441004 -2.08823002 1.3946 -2.08765 0 P 0 ;0
L 1.3946 -2.08765 1.39483002 -2.08708002 0 P 0 ;0
L 1.39483002 -2.08708002 1.39511004 -2.08653996 0 P 0 ;0
L 1.39511004 -2.08653996 1.39555 -2.08583996 0 P 0 ;0
L 1.39555 -2.08583996 1.39603996 -2.08518002 0 P 0 ;0
L 1.39603996 -2.08518002 1.39658002 -2.08456004 0 P 0 ;0
L 1.39658002 -2.08456004 1.39716004 -2.08396998 0 P 0 ;0
L 1.39716004 -2.08396998 1.39778002 -2.08343002 0 P 0 ;0
L 1.39778002 -2.08343002 1.39878996 -2.08266998 0 P 0 ;0
L 1.39878996 -2.08266998 1.39985 -2.08196998 0 P 0 ;0
L 1.39985 -2.08196998 1.40096004 -2.08135 0 P 0 ;0
L 1.40096004 -2.08135 1.40211998 -2.08081004 0 P 0 ;0
L 1.40211998 -2.08081004 1.40503002 -2.07971004 0 P 0 ;0
L 1.40503002 -2.07971004 1.40801998 -2.07881998 0 P 0 ;0
L 1.40801998 -2.07881998 1.41128996 -2.07796004 0 P 0 ;0
L 1.41128996 -2.07796004 1.41506004 -2.07691998 0 P 0 ;0
L 1.41506004 -2.07691998 1.41871998 -2.07585 0 P 0 ;0
L 1.41871998 -2.07585 1.42165 -2.07495 0 P 0 ;0
L 1.42165 -2.07495 1.42791998 -2.07295 0 P 0 ;0
L 1.42791998 -2.07295 1.42731998 -2.08241004 0 P 0 ;0
L 1.42731998 -2.08241004 1.42701004 -2.08708002 0 P 0 ;0
L 1.42701004 -2.08708002 1.42658002 -2.09353996 0 P 0 ;0
L 1.42658002 -2.09353996 1.4261 -2.10055 0 P 0 ;0
L 1.4261 -2.10055 1.42566998 -2.10706004 0 P 0 ;0
L 1.42566998 -2.10706004 1.42525 -2.11306004 0 P 0 ;0
L 1.42525 -2.11306004 1.42491998 -2.11851998 0 P 0 ;0
L 1.42491998 -2.11851998 1.42466004 -2.1231 0 P 0 ;0
L 1.42466004 -2.1231 1.42461004 -2.12471004 0 P 0 ;0
L 1.42461004 -2.12471004 1.4246 -2.12716004 0 P 0 ;0
L 1.4246 -2.12716004 1.47893002 -2.12716004 0 P 0 ;0
L 1.47893002 -2.12716004 1.47893002 -2.11358002 0 P 0 ;0
L 1.47893002 -2.11358002 1.47905 -2.10616998 0 P 0 ;0
L 1.47905 -2.10616998 1.47943996 -2.09385 0 P 0 ;0
L 1.47943996 -2.09385 1.48 -2.07968996 0 P 0 ;0
L 1.48 -2.07968996 1.48066004 -2.0655 0 P 0 ;0
L 1.48066004 -2.0655 1.4813 -2.05168996 0 P 0 ;0
L 1.4813 -2.05168996 1.48175 -2.03873996 0 P 0 ;0
L 1.48175 -2.03873996 1.48201998 -2.02785 0 P 0 ;0
L 1.48201998 -2.02785 1.48191998 -2.02286004 0 P 0 ;0
L 1.48191998 -2.02286004 1.48165 -2.01995 0 P 0 ;0
L 1.48165 -2.01995 1.48115 -2.01708002 0 P 0 ;0
L 1.48115 -2.01708002 1.48043996 -2.01425 0 P 0 ;0
L 1.48043996 -2.01425 1.47951004 -2.01146998 0 P 0 ;0
L 1.47951004 -2.01146998 1.47866998 -2.00946998 0 P 0 ;0
L 1.47866998 -2.00946998 1.47768002 -2.00753996 0 P 0 ;0
L 1.47768002 -2.00753996 1.47655 -2.00568002 0 P 0 ;0
L 1.47655 -2.00568002 1.47528002 -2.00391998 0 P 0 ;0
L 1.47528002 -2.00391998 1.47388002 -2.00225 0 P 0 ;0
L 1.47388002 -2.00225 1.47228996 -2.00063002 0 P 0 ;0
L 1.47228996 -2.00063002 1.4706 -1.99911998 0 P 0 ;0
L 1.4706 -1.99911998 1.4688 -1.99773002 0 P 0 ;0
L 1.4688 -1.99773002 1.46691004 -1.99648002 0 P 0 ;0
L 1.46691004 -1.99648002 1.46491998 -1.99535 0 P 0 ;0
L 1.46491998 -1.99535 1.46098996 -1.99351004 0 P 0 ;0
L 1.46098996 -1.99351004 1.45693002 -1.99196998 0 P 0 ;0
L 1.45693002 -1.99196998 1.45276004 -1.99076004 0 P 0 ;0
L 1.45276004 -1.99076004 1.44953996 -1.99006004 0 P 0 ;0
L 1.44953996 -1.99006004 1.44628996 -1.98956004 0 P 0 ;0
L 1.44628996 -1.98956004 1.44298002 -1.98923996 0 P 0 ;0
L 1.44298002 -1.98923996 1.42695 -1.98856998 0 P 0 ;0
L 1.42695 -1.98856998 1.41038996 -1.98865 0 P 0 ;0
L 1.41038996 -1.98865 1.4042 -1.98901004 0 P 0 ;0
L 1.4042 -1.98901004 1.39798996 -1.98971998 0 P 0 ;0
L 1.35778996 -2.11545 1.4153 -2.11545 0 P 0 ;0
L 1.35688996 -2.11445 1.41558996 -2.11445 0 P 0 ;0
L 1.35608002 -2.11345 1.41588002 -2.11345 0 P 0 ;0
L 1.35533002 -2.11245 1.41616998 -2.11245 0 P 0 ;0
L 1.35463996 -2.11145 1.41646004 -2.11145 0 P 0 ;0
L 1.35401004 -2.11045 1.41675 -2.11045 0 P 0 ;0
L 1.35341004 -2.10945 1.41703996 -2.10945 0 P 0 ;0
L 1.3529 -2.10845 1.41733002 -2.10845 0 P 0 ;0
L 1.35238002 -2.10745 1.41761998 -2.10745 0 P 0 ;0
L 1.35195 -2.10645 1.41788002 -2.10645 0 P 0 ;0
L 1.35155 -2.10545 1.41816004 -2.10545 0 P 0 ;0
L 1.3512 -2.10445 1.41841998 -2.10445 0 P 0 ;0
L 1.35091004 -2.10345 1.41868996 -2.10345 0 P 0 ;0
L 1.35066004 -2.10245 1.41896004 -2.10245 0 P 0 ;0
L 1.35046998 -2.10145 1.41923002 -2.10145 0 P 0 ;0
L 1.35033996 -2.10045 1.41948996 -2.10045 0 P 0 ;0
L 1.35021998 -2.09945 1.40141004 -2.09945 0 P 0 ;0
L 1.35016004 -2.09845 1.39791004 -2.09845 0 P 0 ;0
L 1.3501 -2.09745 1.39616004 -2.09745 0 P 0 ;0
L 1.35008002 -2.09645 1.39496004 -2.09645 0 P 0 ;0
L 1.35006998 -2.09545 1.39406004 -2.09545 0 P 0 ;0
L 1.35005 -2.09445 1.39338002 -2.09445 0 P 0 ;0
L 1.35003996 -2.09345 1.39288002 -2.09345 0 P 0 ;0
L 1.35001998 -2.09245 1.39253002 -2.09245 0 P 0 ;0
L 1.35001004 -2.09145 1.3923 -2.09145 0 P 0 ;0
L 1.35001998 -2.09045 1.3922 -2.09045 0 P 0 ;0
L 1.35003002 -2.08945 1.3922 -2.08945 0 P 0 ;0
L 1.35005 -2.08845 1.39231998 -2.08845 0 P 0 ;0
L 1.35006998 -2.08745 1.39256004 -2.08745 0 P 0 ;0
L 1.35008002 -2.08645 1.39293002 -2.08645 0 P 0 ;0
L 1.3501 -2.08545 1.39343002 -2.08545 0 P 0 ;0
L 1.35011004 -2.08445 1.39408996 -2.08445 0 P 0 ;0
L 1.39438002 -2.12845 1.3883 -2.12836004 0 P 0 ;0
L 1.3883 -2.12836004 1.38426998 -2.128 0 P 0 ;0
L 1.38426998 -2.128 1.38028002 -2.12733002 0 P 0 ;0
L 1.38028002 -2.12733002 1.37635 -2.12636004 0 P 0 ;0
L 1.37635 -2.12636004 1.37248996 -2.12508002 0 P 0 ;0
L 1.37248996 -2.12508002 1.36983996 -2.12398002 0 P 0 ;0
L 1.36983996 -2.12398002 1.36728996 -2.1227 0 P 0 ;0
L 1.36728996 -2.1227 1.36481998 -2.12123996 0 P 0 ;0
L 1.36481998 -2.12123996 1.36246004 -2.11961004 0 P 0 ;0
L 1.36246004 -2.11961004 1.36023002 -2.11781998 0 P 0 ;0
L 1.36023002 -2.11781998 1.35828996 -2.116 0 P 0 ;0
L 1.35828996 -2.116 1.35651998 -2.11403002 0 P 0 ;0
L 1.35651998 -2.11403002 1.35493002 -2.11191004 0 P 0 ;0
L 1.35493002 -2.11191004 1.35353002 -2.10966998 0 P 0 ;0
L 1.35353002 -2.10966998 1.35231004 -2.10731004 0 P 0 ;0
L 1.35231004 -2.10731004 1.35166998 -2.10576998 0 P 0 ;0
L 1.35166998 -2.10576998 1.35111004 -2.1042 0 P 0 ;0
L 1.35111004 -2.1042 1.35071998 -2.10276004 0 P 0 ;0
L 1.35071998 -2.10276004 1.35045 -2.1013 0 P 0 ;0
L 1.35045 -2.1013 1.35021998 -2.09943002 0 P 0 ;0
L 1.35021998 -2.09943002 1.3501 -2.09753002 0 P 0 ;0
L 1.3501 -2.09753002 1.35001004 -2.09128002 0 P 0 ;0
L 1.35001004 -2.09128002 1.35011998 -2.0844 0 P 0 ;0
L 1.35011998 -2.0844 1.35023996 -2.08258996 0 P 0 ;0
L 1.35023996 -2.08258996 1.3505 -2.08083996 0 P 0 ;0
L 1.3505 -2.08083996 1.35071998 -2.07985 0 P 0 ;0
L 1.35071998 -2.07985 1.35101004 -2.07888002 0 P 0 ;0
L 1.35101004 -2.07888002 1.35136004 -2.07793002 0 P 0 ;0
L 1.35136004 -2.07793002 1.35335 -2.07351998 0 P 0 ;0
L 1.35335 -2.07351998 1.35491998 -2.07065 0 P 0 ;0
L 1.35491998 -2.07065 1.35683002 -2.0677 0 P 0 ;0
L 1.35683002 -2.0677 1.35876998 -2.06511004 0 P 0 ;0
L 1.35876998 -2.06511004 1.35948996 -2.0643 0 P 0 ;0
L 1.35948996 -2.0643 1.36026998 -2.06356004 0 P 0 ;0
L 1.36026998 -2.06356004 1.3624 -2.06181998 0 P 0 ;0
L 1.3624 -2.06181998 1.36465 -2.06023996 0 P 0 ;0
L 1.36465 -2.06023996 1.36701004 -2.05883002 0 P 0 ;0
L 1.36701004 -2.05883002 1.37173002 -2.05641004 0 P 0 ;0
L 1.37173002 -2.05641004 1.37656004 -2.05426998 0 P 0 ;0
L 1.37656004 -2.05426998 1.38243002 -2.05203996 0 P 0 ;0
L 1.38243002 -2.05203996 1.38836004 -2.0501 0 P 0 ;0
L 1.38836004 -2.0501 1.4023 -2.04645 0 P 0 ;0
L 1.4023 -2.04645 1.41148996 -2.044 0 P 0 ;0
L 1.41148996 -2.044 1.42016998 -2.04095 0 P 0 ;0
L 1.42016998 -2.04095 1.42016998 -2.04093996 0 P 0 ;0
L 1.42016998 -2.04093996 1.42021004 -2.04093996 0 P 0 ;0
L 1.42021004 -2.04093996 1.42023996 -2.04093002 0 P 0 ;0
L 1.42023996 -2.04093002 1.42746998 -2.03776004 0 P 0 ;0
L 1.42746998 -2.03776004 1.42753002 -2.03773002 0 P 0 ;0
L 1.42753002 -2.03773002 1.42796998 -2.03748996 0 P 0 ;0
L 1.42796998 -2.03748996 1.42846004 -2.03718996 0 P 0 ;0
L 1.42846004 -2.03718996 1.42891998 -2.03683996 0 P 0 ;0
L 1.42891998 -2.03683996 1.42935 -2.03646004 0 P 0 ;0
L 1.42935 -2.03646004 1.42975 -2.03603996 0 P 0 ;0
L 1.42975 -2.03603996 1.43011004 -2.0356 0 P 0 ;0
L 1.43011004 -2.0356 1.43016004 -2.03553002 0 P 0 ;0
L 1.43016004 -2.03553002 1.4299 -2.03535 0 P 0 ;0
L 1.4299 -2.03535 1.43028002 -2.03535 0 P 0 ;0
L 1.43028002 -2.03535 1.43043996 -2.03513002 0 P 0 ;0
L 1.43043996 -2.03513002 1.43048002 -2.03506004 0 P 0 ;0
L 1.43048002 -2.03506004 1.43041998 -2.03501998 0 P 0 ;0
L 1.43041998 -2.03501998 1.4305 -2.03501998 0 P 0 ;0
L 1.4305 -2.03501998 1.43073002 -2.03463002 0 P 0 ;0
L 1.43073002 -2.03463002 1.43096004 -2.03415 0 P 0 ;0
L 1.43096004 -2.03415 1.43115 -2.03365 0 P 0 ;0
L 1.43115 -2.03365 1.4313 -2.03313002 0 P 0 ;0
L 1.4313 -2.03313002 1.4314 -2.03261004 0 P 0 ;0
L 1.4314 -2.03261004 1.43146004 -2.03208002 0 P 0 ;0
L 1.43146004 -2.03208002 1.43146998 -2.03155 0 P 0 ;0
L 1.43146998 -2.03155 1.43143996 -2.03101004 0 P 0 ;0
L 1.43143996 -2.03101004 1.43143002 -2.03093002 0 P 0 ;0
L 1.43143002 -2.03093002 1.43136004 -2.03048996 0 P 0 ;0
L 1.43136004 -2.03048996 1.43125 -2.02996998 0 P 0 ;0
L 1.43125 -2.02996998 1.43108002 -2.02946004 0 P 0 ;0
L 1.43108002 -2.02946004 1.43086998 -2.02896004 0 P 0 ;0
L 1.43086998 -2.02896004 1.43063002 -2.02848996 0 P 0 ;0
L 1.43063002 -2.02848996 1.43033996 -2.02803996 0 P 0 ;0
L 1.43033996 -2.02803996 1.43001998 -2.02761004 0 P 0 ;0
L 1.43001998 -2.02761004 1.42966004 -2.02721004 0 P 0 ;0
L 1.42966004 -2.02721004 1.42928002 -2.02685 0 P 0 ;0
L 1.42928002 -2.02685 1.42886004 -2.02651998 0 P 0 ;0
L 1.42886004 -2.02651998 1.42841998 -2.02623002 0 P 0 ;0
L 1.42841998 -2.02623002 1.42795 -2.02596998 0 P 0 ;0
L 1.42795 -2.02596998 1.42746004 -2.02575 0 P 0 ;0
L 1.42746004 -2.02575 1.42583002 -2.02518002 0 P 0 ;0
L 1.42583002 -2.02518002 1.42416004 -2.02476004 0 P 0 ;0
L 1.42416004 -2.02476004 1.42245 -2.02448002 0 P 0 ;0
L 1.42245 -2.02448002 1.42075 -2.02435 0 P 0 ;0
L 1.42075 -2.02435 1.41565 -2.02428002 0 P 0 ;0
L 1.41565 -2.02428002 1.4156 -2.02428002 0 P 0 ;0
L 1.4156 -2.02428002 1.41055 -2.02445 0 P 0 ;0
L 1.41055 -2.02445 1.41048002 -2.02445 0 P 0 ;0
L 1.41048002 -2.02445 1.40128996 -2.02533996 0 P 0 ;0
L 1.40128996 -2.02533996 1.39208996 -2.02696998 0 P 0 ;0
L 1.39208996 -2.02696998 1.38288002 -2.02936004 0 P 0 ;0
L 1.38288002 -2.02936004 1.37363002 -2.03251998 0 P 0 ;0
L 1.37363002 -2.03251998 1.37076998 -2.03356004 0 P 0 ;0
L 1.37076998 -2.03356004 1.36865 -2.03426998 0 P 0 ;0
L 1.36865 -2.03426998 1.36906004 -2.03066998 0 P 0 ;0
L 1.36906004 -2.03066998 1.36988996 -2.02383996 0 P 0 ;0
L 1.36988996 -2.02383996 1.37095 -2.01581004 0 P 0 ;0
L 1.37095 -2.01581004 1.37358996 -1.99631998 0 P 0 ;0
L 1.37358996 -1.99631998 1.37988002 -1.99491998 0 P 0 ;0
L 1.37988002 -1.99491998 1.38353996 -1.99416998 0 P 0 ;0
L 1.38353996 -1.99416998 1.38841998 -1.99326998 0 P 0 ;0
L 1.38841998 -1.99326998 1.39358002 -1.9924 0 P 0 ;0
L 1.39358002 -1.9924 1.39825 -1.9917 0 P 0 ;0
L 1.39825 -1.9917 1.40436998 -1.991 0 P 0 ;0
L 1.40436998 -1.991 1.41045 -1.99065 0 P 0 ;0
L 1.41045 -1.99065 1.42691004 -1.99056998 0 P 0 ;0
L 1.42691004 -1.99056998 1.44283996 -1.99123996 0 P 0 ;0
L 1.44283996 -1.99123996 1.44603996 -1.99153996 0 P 0 ;0
L 1.44603996 -1.99153996 1.44918002 -1.99203002 0 P 0 ;0
L 1.44918002 -1.99203002 1.45226004 -1.9927 0 P 0 ;0
L 1.45226004 -1.9927 1.4563 -1.99386998 0 P 0 ;0
L 1.4563 -1.99386998 1.46021004 -1.99535 0 P 0 ;0
L 1.46021004 -1.99535 1.464 -1.99713002 0 P 0 ;0
L 1.464 -1.99713002 1.46586004 -1.99818996 0 P 0 ;0
L 1.46586004 -1.99818996 1.46763996 -1.99936004 0 P 0 ;0
L 1.46763996 -1.99936004 1.46931998 -2.00066004 0 P 0 ;0
L 1.46931998 -2.00066004 1.47091004 -2.00206998 0 P 0 ;0
L 1.47091004 -2.00206998 1.47238996 -2.00358996 0 P 0 ;0
L 1.47238996 -2.00358996 1.4737 -2.00515 0 P 0 ;0
L 1.4737 -2.00515 1.47488002 -2.00678996 0 P 0 ;0
L 1.47488002 -2.00678996 1.47593996 -2.00851004 0 P 0 ;0
L 1.47593996 -2.00851004 1.47686004 -2.01031004 0 P 0 ;0
L 1.47686004 -2.01031004 1.47763996 -2.01216998 0 P 0 ;0
L 1.47763996 -2.01216998 1.47851998 -2.01481004 0 P 0 ;0
L 1.47851998 -2.01481004 1.47918996 -2.01748996 0 P 0 ;0
L 1.47918996 -2.01748996 1.47966004 -2.02021998 0 P 0 ;0
L 1.47966004 -2.02021998 1.47993002 -2.02296998 0 P 0 ;0
L 1.47993002 -2.02296998 1.48001998 -2.02783996 0 P 0 ;0
L 1.48001998 -2.02783996 1.47975 -2.03868996 0 P 0 ;0
L 1.47975 -2.03868996 1.4793 -2.05161004 0 P 0 ;0
L 1.4793 -2.05161004 1.47866004 -2.06543002 0 P 0 ;0
L 1.47866004 -2.06543002 1.47801004 -2.07961004 0 P 0 ;0
L 1.47801004 -2.07961004 1.47743996 -2.09378996 0 P 0 ;0
L 1.47743996 -2.09378996 1.47705 -2.10613002 0 P 0 ;0
L 1.47705 -2.10613002 1.47693002 -2.11356004 0 P 0 ;0
L 1.47693002 -2.11356004 1.47693002 -2.12516004 0 P 0 ;0
L 1.47693002 -2.12516004 1.42661004 -2.12516004 0 P 0 ;0
L 1.42661004 -2.12516004 1.42661004 -2.12473996 0 P 0 ;0
L 1.42661004 -2.12473996 1.42666004 -2.12318002 0 P 0 ;0
L 1.42666004 -2.12318002 1.42691004 -2.11863996 0 P 0 ;0
L 1.42691004 -2.11863996 1.42725 -2.1132 0 P 0 ;0
L 1.42725 -2.1132 1.42766004 -2.1072 0 P 0 ;0
L 1.42766004 -2.1072 1.42766004 -2.10718996 0 P 0 ;0
L 1.42766004 -2.10718996 1.4281 -2.10068996 0 P 0 ;0
L 1.4281 -2.10068996 1.42858002 -2.09368002 0 P 0 ;0
L 1.42858002 -2.09368002 1.42901004 -2.08721004 0 P 0 ;0
L 1.42901004 -2.08721004 1.42901004 -2.0872 0 P 0 ;0
L 1.42901004 -2.0872 1.42931004 -2.08256004 0 P 0 ;0
L 1.42931004 -2.08256004 1.42991998 -2.07308002 0 P 0 ;0
L 1.42991998 -2.07308002 1.42916004 -2.07136998 0 P 0 ;0
L 1.42916004 -2.07136998 1.42731998 -2.07105 0 P 0 ;0
L 1.42731998 -2.07105 1.42105 -2.07303996 0 P 0 ;0
L 1.42105 -2.07303996 1.41815 -2.07393002 0 P 0 ;0
L 1.41815 -2.07393002 1.41451004 -2.075 0 P 0 ;0
L 1.41451004 -2.075 1.41076004 -2.07603002 0 P 0 ;0
L 1.41076004 -2.07603002 1.40748002 -2.0769 0 P 0 ;0
L 1.40748002 -2.0769 1.40438996 -2.07781004 0 P 0 ;0
L 1.40438996 -2.07781004 1.40431998 -2.07783996 0 P 0 ;0
L 1.40431998 -2.07783996 1.40133996 -2.07896998 0 P 0 ;0
L 1.40133996 -2.07896998 1.40005 -2.07956998 0 P 0 ;0
L 1.40005 -2.07956998 1.39881998 -2.08026004 0 P 0 ;0
L 1.39881998 -2.08026004 1.39763996 -2.08103002 0 P 0 ;0
L 1.39763996 -2.08103002 1.39651998 -2.08188002 0 P 0 ;0
L 1.39651998 -2.08188002 1.39578996 -2.08251004 0 P 0 ;0
L 1.39578996 -2.08251004 1.39573996 -2.08256004 0 P 0 ;0
L 1.39573996 -2.08256004 1.3951 -2.08318996 0 P 0 ;0
L 1.3951 -2.08318996 1.39446998 -2.08393002 0 P 0 ;0
L 1.39446998 -2.08393002 1.3939 -2.08471004 0 P 0 ;0
L 1.3939 -2.08471004 1.39336998 -2.08553996 0 P 0 ;0
L 1.39336998 -2.08553996 1.39301004 -2.08623996 0 P 0 ;0
L 1.39301004 -2.08623996 1.39271004 -2.08696998 0 P 0 ;0
L 1.39271004 -2.08696998 1.39248002 -2.08771998 0 P 0 ;0
L 1.39248002 -2.08771998 1.39231004 -2.08848996 0 P 0 ;0
L 1.39231004 -2.08848996 1.39221004 -2.08926004 0 P 0 ;0
L 1.39221004 -2.08926004 1.39218002 -2.09003996 0 P 0 ;0
L 1.39218002 -2.09003996 1.39221004 -2.0908 0 P 0 ;0
L 1.39221004 -2.0908 1.39231004 -2.09153002 0 P 0 ;0
L 1.39231004 -2.09153002 1.39246998 -2.09226004 0 P 0 ;0
L 1.39246998 -2.09226004 1.39268996 -2.09296998 0 P 0 ;0
L 1.39268996 -2.09296998 1.39296004 -2.09365 0 P 0 ;0
L 1.39296004 -2.09365 1.3933 -2.09431004 0 P 0 ;0
L 1.3933 -2.09431004 1.39368996 -2.09493996 0 P 0 ;0
L 1.39368996 -2.09493996 1.39411998 -2.09553996 0 P 0 ;0
L 1.39411998 -2.09553996 1.39468996 -2.09618002 0 P 0 ;0
L 1.39468996 -2.09618002 1.3953 -2.09678002 0 P 0 ;0
L 1.3953 -2.09678002 1.39596004 -2.09731998 0 P 0 ;0
L 1.39596004 -2.09731998 1.39666998 -2.0978 0 P 0 ;0
L 1.39666998 -2.0978 1.39673996 -2.09783996 0 P 0 ;0
L 1.39673996 -2.09783996 1.39741004 -2.09821998 0 P 0 ;0
L 1.39741004 -2.09821998 1.39748996 -2.09825 0 P 0 ;0
L 1.39748996 -2.09825 1.39818996 -2.09856998 0 P 0 ;0
L 1.39818996 -2.09856998 1.39898996 -2.09886004 0 P 0 ;0
L 1.39898996 -2.09886004 1.39906998 -2.09888002 0 P 0 ;0
L 1.39906998 -2.09888002 1.40043996 -2.09888002 0 P 0 ;0
L 1.40043996 -2.09888002 1.40033996 -2.09923002 0 P 0 ;0
L 1.40033996 -2.09923002 1.40041998 -2.09925 0 P 0 ;0
L 1.40041998 -2.09925 1.40186004 -2.09953002 0 P 0 ;0
L 1.40186004 -2.09953002 1.40331004 -2.09971004 0 P 0 ;0
L 1.40331004 -2.09971004 1.40478002 -2.09978002 0 P 0 ;0
L 1.40478002 -2.09978002 1.40625 -2.09975 0 P 0 ;0
L 1.40625 -2.09975 1.41096004 -2.09931004 0 P 0 ;0
L 1.41096004 -2.09931004 1.41556998 -2.09855 0 P 0 ;0
L 1.41556998 -2.09855 1.41791998 -2.09813002 0 P 0 ;0
L 1.41791998 -2.09813002 1.41995 -2.09791004 0 P 0 ;0
L 1.41995 -2.09791004 1.4201 -2.0979 0 P 0 ;0
L 1.4201 -2.0979 1.41941004 -2.10078002 0 P 0 ;0
L 1.41941004 -2.10078002 1.41761004 -2.10745 0 P 0 ;0
L 1.41761004 -2.10745 1.41391004 -2.12025 0 P 0 ;0
L 1.41391004 -2.12025 1.41215 -2.12626998 0 P 0 ;0
L 1.41215 -2.12626998 1.40655 -2.12725 0 P 0 ;0
L 1.40655 -2.12725 1.40046004 -2.12808002 0 P 0 ;0
L 1.40046004 -2.12808002 1.39438002 -2.12845 0 P 0 ;0
L 1.15303002 -2.08283002 1.20788996 -2.08283002 0 P 0 ;0
L 1.15398996 -2.08183002 1.20795 -2.08183002 0 P 0 ;0
L 1.15483002 -2.08083002 1.208 -2.08083002 0 P 0 ;0
L 1.15555 -2.07983002 1.20805 -2.07983002 0 P 0 ;0
L 1.15621998 -2.07883002 1.2081 -2.07883002 0 P 0 ;0
L 1.15681998 -2.07783002 1.20816004 -2.07783002 0 P 0 ;0
L 1.15733002 -2.07683002 1.20821004 -2.07683002 0 P 0 ;0
L 1.15778996 -2.07583002 1.20826004 -2.07583002 0 P 0 ;0
L 1.15818002 -2.07483002 1.20831004 -2.07483002 0 P 0 ;0
L 1.15853996 -2.07383002 1.20836998 -2.07383002 0 P 0 ;0
L 1.15881998 -2.07283002 1.20841998 -2.07283002 0 P 0 ;0
L 1.1591 -2.07183002 1.20846998 -2.07183002 0 P 0 ;0
L 1.15938002 -2.07083002 1.20853002 -2.07083002 0 P 0 ;0
L 1.1596 -2.06983002 1.20858002 -2.06983002 0 P 0 ;0
L 1.15981004 -2.06883002 1.20863996 -2.06883002 0 P 0 ;0
L 1.16001004 -2.06783002 1.20868996 -2.06783002 0 P 0 ;0
L 1.1602 -2.06683002 1.20875 -2.06683002 0 P 0 ;0
L 1.16033996 -2.06583002 1.2088 -2.06583002 0 P 0 ;0
L 1.16048996 -2.06483002 1.20886004 -2.06483002 0 P 0 ;0
L 1.16063996 -2.06383002 1.20891998 -2.06383002 0 P 0 ;0
L 1.16078002 -2.06283002 1.20896998 -2.06283002 0 P 0 ;0
L 1.16088996 -2.06183002 1.20903002 -2.06183002 0 P 0 ;0
L 1.16098996 -2.06083002 1.20908002 -2.06083002 0 P 0 ;0
L 1.16108996 -2.05983002 1.20913996 -2.05983002 0 P 0 ;0
L 1.16118002 -2.05883002 1.20918996 -2.05883002 0 P 0 ;0
L 1.16128002 -2.05783002 1.20925 -2.05783002 0 P 0 ;0
L 1.16133996 -2.05683002 1.2093 -2.05683002 0 P 0 ;0
L 1.1614 -2.05583002 1.20936004 -2.05583002 0 P 0 ;0
L 1.16146004 -2.05483002 1.20941004 -2.05483002 0 P 0 ;0
L 1.16151998 -2.05383002 1.20946998 -2.05383002 0 P 0 ;0
L 1.16158002 -2.05283002 1.20951998 -2.05283002 0 P 0 ;0
L 1.16163996 -2.05183002 1.20958002 -2.05183002 0 P 0 ;0
L 1.1617 -2.05083002 1.20963996 -2.05083002 0 P 0 ;0
L 1.16175 -2.04983002 1.2097 -2.04983002 0 P 0 ;0
L 1.16181004 -2.04883002 1.20975 -2.04883002 0 P 0 ;0
L 1.16186998 -2.04783002 1.20981004 -2.04783002 0 P 0 ;0
L 1.16193002 -2.04683002 1.20986998 -2.04683002 0 P 0 ;0
L 1.16198996 -2.04583002 1.20993002 -2.04583002 0 P 0 ;0
L 1.16205 -2.04483002 1.20998996 -2.04483002 0 P 0 ;0
L 1.16211004 -2.04383002 1.21005 -2.04383002 0 P 0 ;0
L 1.16215 -2.04283002 1.2101 -2.04283002 0 P 0 ;0
L 1.1622 -2.04183002 1.21016004 -2.04183002 0 P 0 ;0
L 1.16225 -2.04083002 1.21021998 -2.04083002 0 P 0 ;0
L 1.16228996 -2.03983002 1.21028002 -2.03983002 0 P 0 ;0
L 1.16233996 -2.03883002 1.21033996 -2.03883002 0 P 0 ;0
L 1.16238002 -2.03783002 1.2104 -2.03783002 0 P 0 ;0
L 1.16243002 -2.03683002 1.21046004 -2.03683002 0 P 0 ;0
L 1.16246998 -2.03583002 1.21051004 -2.03583002 0 P 0 ;0
L 1.16251998 -2.03483002 1.21056998 -2.03483002 0 P 0 ;0
L 1.16256998 -2.03383002 1.21063996 -2.03383002 0 P 0 ;0
L 1.16261004 -2.03283002 1.2107 -2.03283002 0 P 0 ;0
L 1.16266004 -2.03183002 1.21076004 -2.03183002 0 P 0 ;0
L 1.1627 -2.03083002 1.21083002 -2.03083002 0 P 0 ;0
L 1.16015 -1.97631004 1.17066004 -1.97631004 0 P 0 ;0
L 1.15961998 -1.97531004 1.17026004 -1.97531004 0 P 0 ;0
L 1.1591 -1.97431004 1.16986998 -1.97431004 0 P 0 ;0
L 1.15856998 -1.97331004 1.16946998 -1.97331004 0 P 0 ;0
L 1.15803996 -1.97231004 1.16903002 -1.97231004 0 P 0 ;0
L 1.15746998 -1.97131004 1.16858996 -1.97131004 0 P 0 ;0
L 1.1569 -1.97031004 1.16815 -1.97031004 0 P 0 ;0
L 1.15631998 -1.96931004 1.16771004 -1.96931004 0 P 0 ;0
L 1.15573996 -1.96831004 1.16726998 -1.96831004 0 P 0 ;0
L 1.15516004 -1.96731004 1.16681998 -1.96731004 0 P 0 ;0
L 1.15458996 -1.96631004 1.16638002 -1.96631004 0 P 0 ;0
L 1.15398002 -1.96531004 1.16593996 -1.96531004 0 P 0 ;0
L 1.1533 -1.96431004 1.16548996 -1.96431004 0 P 0 ;0
L 1.15261998 -1.96331004 1.16503002 -1.96331004 0 P 0 ;0
L 1.15193996 -1.96231004 1.16448002 -1.96231004 0 P 0 ;0
L 1.15126004 -1.96131004 1.16393002 -1.96131004 0 P 0 ;0
L 1.15058002 -1.96031004 1.16338002 -1.96031004 0 P 0 ;0
L 1.1499 -1.95931004 1.16283002 -1.95931004 0 P 0 ;0
L 1.1491 -1.95831004 1.16228996 -1.95831004 0 P 0 ;0
L 1.14831004 -1.95731004 1.16173996 -1.95731004 0 P 0 ;0
L 1.14751004 -1.95631004 1.16118996 -1.95631004 0 P 0 ;0
L 1.14671004 -1.95531004 1.16063996 -1.95531004 0 P 0 ;0
L 1.14591998 -1.95431004 1.16008996 -1.95431004 0 P 0 ;0
L 1.14511998 -1.95331004 1.15943996 -1.95331004 0 P 0 ;0
L 1.1442 -1.95231004 1.15878002 -1.95231004 0 P 0 ;0
L 1.14326998 -1.95131004 1.15811004 -1.95131004 0 P 0 ;0
L 1.14233996 -1.95031004 1.15745 -1.95031004 0 P 0 ;0
L 1.14141004 -1.94931004 1.15678002 -1.94931004 0 P 0 ;0
L 1.14048996 -1.94831004 1.15611998 -1.94831004 0 P 0 ;0
L 1.1395 -1.94731004 1.15545 -1.94731004 0 P 0 ;0
L 1.13843002 -1.94631004 1.15478996 -1.94631004 0 P 0 ;0
L 1.13736004 -1.94531004 1.15411998 -1.94531004 0 P 0 ;0
L 1.13628996 -1.94431004 1.15333002 -1.94431004 0 P 0 ;0
L 1.13521004 -1.94331004 1.15253002 -1.94331004 0 P 0 ;0
L 1.13413996 -1.94231004 1.15173996 -1.94231004 0 P 0 ;0
L 1.13306998 -1.94131004 1.15093996 -1.94131004 0 P 0 ;0
L 1.132 -1.94031004 1.15013996 -1.94031004 0 P 0 ;0
L 1.13081004 -1.93931004 1.14935 -1.93931004 0 P 0 ;0
L 1.12958002 -1.93831004 1.14855 -1.93831004 0 P 0 ;0
L 1.12833996 -1.93731004 1.14775 -1.93731004 0 P 0 ;0
L 1.1271 -1.93631004 1.14688996 -1.93631004 0 P 0 ;0
L 1.12586004 -1.93531004 1.14593996 -1.93531004 0 P 0 ;0
L 1.12461998 -1.93431004 1.14498996 -1.93431004 0 P 0 ;0
L 1.12338002 -1.93331004 1.14405 -1.93331004 0 P 0 ;0
L 1.12203002 -1.93231004 1.1431 -1.93231004 0 P 0 ;0
L 1.1206 -1.93131004 1.14216004 -1.93131004 0 P 0 ;0
L 1.11916004 -1.93031004 1.14121004 -1.93031004 0 P 0 ;0
L 1.11771998 -1.92931004 1.14026998 -1.92931004 0 P 0 ;0
L 1.11628996 -1.92831004 1.13931998 -1.92831004 0 P 0 ;0
L 1.11483996 -1.92731004 1.13838002 -1.92731004 0 P 0 ;0
L 1.11338996 -1.92631004 1.13743002 -1.92631004 0 P 0 ;0
L 1.11171998 -1.92531004 1.13648996 -1.92531004 0 P 0 ;0
L 1.11005 -1.92431004 1.13538002 -1.92431004 0 P 0 ;0
L 1.10838002 -1.92331004 1.13426998 -1.92331004 0 P 0 ;0
L 1.1067 -1.92231004 1.13315 -1.92231004 0 P 0 ;0
L 1.10503002 -1.92131004 1.13203002 -1.92131004 0 P 0 ;0
L 1.10336004 -1.92031004 1.13091998 -1.92031004 0 P 0 ;0
L 1.1015 -1.91931004 1.1298 -1.91931004 0 P 0 ;0
L 1.09955 -1.91831004 1.12868002 -1.91831004 0 P 0 ;0
L 1.16275 -2.02983002 1.21088996 -2.02983002 0 P 0 ;0
L 1.16278996 -2.02883002 1.21095 -2.02883002 0 P 0 ;0
L 1.16283996 -2.02783002 1.21101004 -2.02783002 0 P 0 ;0
L 1.16226998 -2.02683002 1.21108002 -2.02683002 0 P 0 ;0
L 1.16153996 -2.02583002 1.21113996 -2.02583002 0 P 0 ;0
L 1.15846004 -2.02483002 1.2112 -2.02483002 0 P 0 ;0
L 1.10036004 -2.00383002 1.21255 -2.00383002 0 P 0 ;0
L 1.10226004 -2.00283002 1.2126 -2.00283002 0 P 0 ;0
L 1.10433996 -2.00183002 1.21266998 -2.00183002 0 P 0 ;0
L 1.1065 -2.00083002 1.21273002 -2.00083002 0 P 0 ;0
L 1.10886998 -1.99983002 1.21278996 -1.99983002 0 P 0 ;0
L 1.11138002 -1.99883002 1.21285 -1.99883002 0 P 0 ;0
L 1.11436998 -1.99783002 1.21288002 -1.99783002 0 P 0 ;0
L 1.11748996 -1.99683002 1.21255 -1.99683002 0 P 0 ;0
L 1.12061998 -1.99583002 1.2089 -1.99583002 0 P 0 ;0
L 1.12433996 -1.99483002 1.2036 -1.99483002 0 P 0 ;0
L 1.12863996 -1.99383002 1.19728002 -1.99383002 0 P 0 ;0
L 1.13295 -1.99283002 1.19096998 -1.99283002 0 P 0 ;0
L 1.13985 -1.99183002 1.18111998 -1.99183002 0 P 0 ;0
L 1.14948002 -1.99083002 1.1651 -1.99083002 0 P 0 ;0
L 1.24218002 -2.08316004 1.29143996 -2.08316004 0 P 0 ;0
L 1.24223002 -2.08216004 1.29151004 -2.08216004 0 P 0 ;0
L 1.24228002 -2.08116004 1.29158996 -2.08116004 0 P 0 ;0
L 1.24233996 -2.08016004 1.29166004 -2.08016004 0 P 0 ;0
L 1.24238996 -2.07916004 1.29173002 -2.07916004 0 P 0 ;0
L 1.24245 -2.07816004 1.29181004 -2.07816004 0 P 0 ;0
L 1.2425 -2.07716004 1.29188002 -2.07716004 0 P 0 ;0
L 1.24256004 -2.07616004 1.29195 -2.07616004 0 P 0 ;0
L 1.24261004 -2.07516004 1.29203002 -2.07516004 0 P 0 ;0
L 1.24266998 -2.07416004 1.2921 -2.07416004 0 P 0 ;0
L 1.24271998 -2.07316004 1.29216998 -2.07316004 0 P 0 ;0
L 1.24278002 -2.07216004 1.29223996 -2.07216004 0 P 0 ;0
L 1.24283002 -2.07116004 1.29231998 -2.07116004 0 P 0 ;0
L 1.24288002 -2.07016004 1.29238996 -2.07016004 0 P 0 ;0
L 1.24293002 -2.06916004 1.29246004 -2.06916004 0 P 0 ;0
L 1.24296998 -2.06816004 1.29253002 -2.06816004 0 P 0 ;0
L 1.24301998 -2.06716004 1.29261004 -2.06716004 0 P 0 ;0
L 1.24306004 -2.06616004 1.2927 -2.06616004 0 P 0 ;0
L 1.24311004 -2.06516004 1.29281004 -2.06516004 0 P 0 ;0
L 1.24315 -2.06416004 1.29291998 -2.06416004 0 P 0 ;0
L 1.2432 -2.06316004 1.29303002 -2.06316004 0 P 0 ;0
L 1.24323996 -2.06216004 1.29315 -2.06216004 0 P 0 ;0
L 1.24328996 -2.06116004 1.29331998 -2.06116004 0 P 0 ;0
L 1.24333002 -2.06016004 1.2935 -2.06016004 0 P 0 ;0
L 1.24338002 -2.05916004 1.29366998 -2.05916004 0 P 0 ;0
L 1.24341998 -2.05816004 1.29385 -2.05816004 0 P 0 ;0
L 1.24346998 -2.05716004 1.29408996 -2.05716004 0 P 0 ;0
L 1.24351004 -2.05616004 1.29433996 -2.05616004 0 P 0 ;0
L 1.24355 -2.05516004 1.29458996 -2.05516004 0 P 0 ;0
L 1.2436 -2.05416004 1.29485 -2.05416004 0 P 0 ;0
L 1.24363996 -2.05316004 1.29516998 -2.05316004 0 P 0 ;0
L 1.24368996 -2.05216004 1.29551998 -2.05216004 0 P 0 ;0
L 1.24373002 -2.05116004 1.29586004 -2.05116004 0 P 0 ;0
L 1.24378002 -2.05016004 1.29621004 -2.05016004 0 P 0 ;0
L 1.24383002 -2.04916004 1.29663996 -2.04916004 0 P 0 ;0
L 1.24386998 -2.04816004 1.29708002 -2.04816004 0 P 0 ;0
L 1.24391004 -2.04716004 1.29753002 -2.04716004 0 P 0 ;0
L 1.24396004 -2.04616004 1.29796998 -2.04616004 0 P 0 ;0
L 1.244 -2.04516004 1.29851004 -2.04516004 0 P 0 ;0
L 1.24405 -2.04416004 1.2991 -2.04416004 0 P 0 ;0
L 1.24408996 -2.04316004 1.29975 -2.04316004 0 P 0 ;0
L 1.24413996 -2.04216004 1.3005 -2.04216004 0 P 0 ;0
L 1.24418002 -2.04116004 1.30131998 -2.04116004 0 P 0 ;0
L 1.24423002 -2.04016004 1.30223002 -2.04016004 0 P 0 ;0
L 1.24426998 -2.03916004 1.30326998 -2.03916004 0 P 0 ;0
L 1.24431998 -2.03816004 1.30446004 -2.03816004 0 P 0 ;0
L 1.24436004 -2.03716004 1.30581998 -2.03716004 0 P 0 ;0
L 1.24441004 -2.03616004 1.30738002 -2.03616004 0 P 0 ;0
L 1.24445 -2.03516004 1.30923002 -2.03516004 0 P 0 ;0
L 1.24448996 -2.03416004 1.31156004 -2.03416004 0 P 0 ;0
L 1.24453996 -2.03316004 1.31478996 -2.03316004 0 P 0 ;0
L 1.24458996 -2.03216004 1.32013002 -2.03216004 0 P 0 ;0
L 1.24461998 -2.03116004 1.33481004 -2.03116004 0 P 0 ;0
L 1.24463996 -2.03016004 1.33478002 -2.03016004 0 P 0 ;0
L 1.24466004 -2.02916004 1.33473996 -2.02916004 0 P 0 ;0
L 1.24468002 -2.02816004 1.33471004 -2.02816004 0 P 0 ;0
L 1.2447 -2.02716004 1.33468002 -2.02716004 0 P 0 ;0
L 1.24471998 -2.02616004 1.33463996 -2.02616004 0 P 0 ;0
L 1.24473996 -2.02516004 1.3346 -2.02516004 0 P 0 ;0
L 1.24476004 -2.02416004 1.33456998 -2.02416004 0 P 0 ;0
L 1.24478002 -2.02316004 1.33453002 -2.02316004 0 P 0 ;0
L 1.2448 -2.02216004 1.3345 -2.02216004 0 P 0 ;0
L 1.24481998 -2.02116004 1.33446998 -2.02116004 0 P 0 ;0
L 1.24483996 -2.02016004 1.33443002 -2.02016004 0 P 0 ;0
L 1.24486004 -2.01916004 1.3344 -2.01916004 0 P 0 ;0
L 1.24488002 -2.01816004 1.33436004 -2.01816004 0 P 0 ;0
L 1.2449 -2.01716004 1.33433002 -2.01716004 0 P 0 ;0
L 1.24491998 -2.01616004 1.33428996 -2.01616004 0 P 0 ;0
L 1.24493996 -2.01516004 1.33426004 -2.01516004 0 P 0 ;0
L 1.24496004 -2.01416004 1.33421998 -2.01416004 0 P 0 ;0
L 1.24498002 -2.01316004 1.33418996 -2.01316004 0 P 0 ;0
L 1.245 -2.01216004 1.33415 -2.01216004 0 P 0 ;0
L 1.24501998 -2.01116004 1.33411998 -2.01116004 0 P 0 ;0
L 1.24503996 -2.01016004 1.33408002 -2.01016004 0 P 0 ;0
L 1.24506004 -2.00916004 1.33403996 -2.00916004 0 P 0 ;0
L 1.24508002 -2.00816004 1.334 -2.00816004 0 P 0 ;0
L 1.2451 -2.00716004 1.33396004 -2.00716004 0 P 0 ;0
L 1.24511998 -2.00616004 1.33393002 -2.00616004 0 P 0 ;0
L 1.24513996 -2.00516004 1.29098996 -2.00516004 0 P 0 ;0
L 1.24513996 -2.00416004 1.29033002 -2.00416004 0 P 0 ;0
L 1.24513996 -2.00316004 1.29005 -2.00316004 0 P 0 ;0
L 1.24513996 -2.00216004 1.29005 -2.00216004 0 P 0 ;0
L 1.24513996 -2.00116004 1.29005 -2.00116004 0 P 0 ;0
L 1.24515 -2.00016004 1.29005 -2.00016004 0 P 0 ;0
L 1.24515 -1.99916004 1.29005 -1.99916004 0 P 0 ;0
L 1.24515 -1.99816004 1.29005 -1.99816004 0 P 0 ;0
L 1.24515 -1.99716004 1.29005 -1.99716004 0 P 0 ;0
L 1.24515 -1.99616004 1.29005 -1.99616004 0 P 0 ;0
L 1.24515 -1.99516004 1.29005 -1.99516004 0 P 0 ;0
L 1.16085 -2.02753002 1.1601 -2.04393002 0 P 0 ;0
L 1.1601 -2.04393002 1.15928996 -2.05771998 0 P 0 ;0
L 1.15928996 -2.05771998 1.15883996 -2.06228002 0 P 0 ;0
L 1.15883996 -2.06228002 1.15818002 -2.06681998 0 P 0 ;0
L 1.15818002 -2.06681998 1.15751004 -2.07006998 0 P 0 ;0
L 1.15751004 -2.07006998 1.15661004 -2.07328996 0 P 0 ;0
L 1.15661004 -2.07328996 1.15616004 -2.07453996 0 P 0 ;0
L 1.15616004 -2.07453996 1.15563002 -2.07576998 0 P 0 ;0
L 1.15563002 -2.07576998 1.15501998 -2.07696004 0 P 0 ;0
L 1.15501998 -2.07696004 1.15433002 -2.0781 0 P 0 ;0
L 1.15433002 -2.0781 1.1534 -2.07941998 0 P 0 ;0
L 1.1534 -2.07941998 1.15236004 -2.08066004 0 P 0 ;0
L 1.15236004 -2.08066004 1.15123002 -2.08181998 0 P 0 ;0
L 1.15123002 -2.08181998 1.15001004 -2.08286998 0 P 0 ;0
L 1.15001004 -2.08286998 1.14871004 -2.08383002 0 P 0 ;0
L 1.14871004 -2.08383002 1.14733002 -2.08468002 0 P 0 ;0
L 1.14733002 -2.08468002 1.14591004 -2.0854 0 P 0 ;0
L 1.14591004 -2.0854 1.14443996 -2.086 0 P 0 ;0
L 1.14443996 -2.086 1.14291004 -2.08648002 0 P 0 ;0
L 1.14291004 -2.08648002 1.14136004 -2.08683002 0 P 0 ;0
L 1.14136004 -2.08683002 1.13976998 -2.08703996 0 P 0 ;0
L 1.13976998 -2.08703996 1.13816004 -2.08713002 0 P 0 ;0
L 1.13816004 -2.08713002 1.13656998 -2.08708002 0 P 0 ;0
L 1.13656998 -2.08708002 1.13498996 -2.0869 0 P 0 ;0
L 1.13498996 -2.0869 1.13341998 -2.08658996 0 P 0 ;0
L 1.13341998 -2.08658996 1.13188996 -2.08615 0 P 0 ;0
L 1.13188996 -2.08615 1.1304 -2.08558996 0 P 0 ;0
L 1.1304 -2.08558996 1.12895 -2.08488996 0 P 0 ;0
L 1.12895 -2.08488996 1.12756998 -2.08408002 0 P 0 ;0
L 1.12756998 -2.08408002 1.12625 -2.08315 0 P 0 ;0
L 1.12625 -2.08315 1.12501004 -2.08211998 0 P 0 ;0
L 1.12501004 -2.08211998 1.12386004 -2.081 0 P 0 ;0
L 1.12386004 -2.081 1.12281004 -2.07978002 0 P 0 ;0
L 1.12281004 -2.07978002 1.12183996 -2.07846998 0 P 0 ;0
L 1.12183996 -2.07846998 1.1211 -2.07726004 0 P 0 ;0
L 1.1211 -2.07726004 1.12046998 -2.07598996 0 P 0 ;0
L 1.12046998 -2.07598996 1.11996004 -2.07466998 0 P 0 ;0
L 1.11996004 -2.07466998 1.11955 -2.07331004 0 P 0 ;0
L 1.11955 -2.07331004 1.11926998 -2.07191004 0 P 0 ;0
L 1.11926998 -2.07191004 1.11868002 -2.06693996 0 P 0 ;0
L 1.11868002 -2.06693996 1.11848002 -2.06191004 0 P 0 ;0
L 1.11848002 -2.06191004 1.11871004 -2.05668002 0 P 0 ;0
L 1.11871004 -2.05668002 1.11936004 -2.05148002 0 P 0 ;0
L 1.11936004 -2.05148002 1.11978996 -2.04936998 0 P 0 ;0
L 1.11978996 -2.04936998 1.12036998 -2.0473 0 P 0 ;0
L 1.12036998 -2.0473 1.12108996 -2.04528002 0 P 0 ;0
L 1.12108996 -2.04528002 1.12196004 -2.04331998 0 P 0 ;0
L 1.12196004 -2.04331998 1.1229 -2.04153996 0 P 0 ;0
L 1.1229 -2.04153996 1.12396998 -2.03985 0 P 0 ;0
L 1.12396998 -2.03985 1.12516998 -2.03823002 0 P 0 ;0
L 1.12516998 -2.03823002 1.12735 -2.03573996 0 P 0 ;0
L 1.12735 -2.03573996 1.12973002 -2.03345 0 P 0 ;0
L 1.12973002 -2.03345 1.13223996 -2.03141998 0 P 0 ;0
L 1.13223996 -2.03141998 1.13491998 -2.02961004 0 P 0 ;0
L 1.13491998 -2.02961004 1.13611004 -2.02893002 0 P 0 ;0
L 1.13611004 -2.02893002 1.13735 -2.02833996 0 P 0 ;0
L 1.13735 -2.02833996 1.13861998 -2.02781998 0 P 0 ;0
L 1.13861998 -2.02781998 1.13993996 -2.0274 0 P 0 ;0
L 1.13993996 -2.0274 1.14191004 -2.02693002 0 P 0 ;0
L 1.14191004 -2.02693002 1.14391004 -2.02663002 0 P 0 ;0
L 1.14391004 -2.02663002 1.14935 -2.02626004 0 P 0 ;0
L 1.14935 -2.02626004 1.15471004 -2.0263 0 P 0 ;0
L 1.15471004 -2.0263 1.15591004 -2.02638996 0 P 0 ;0
L 1.15591004 -2.02638996 1.1571 -2.02656998 0 P 0 ;0
L 1.1571 -2.02656998 1.15828002 -2.02683996 0 P 0 ;0
L 1.15828002 -2.02683996 1.16085 -2.02753002 0 P 0 ;0
L 1.13876998 -2.14783002 1.20233002 -2.14783002 0 P 0 ;0
L 1.14236998 -2.14683002 1.20266004 -2.14683002 0 P 0 ;0
L 1.14481004 -2.14583002 1.20296004 -2.14583002 0 P 0 ;0
L 1.1467 -2.14483002 1.20325 -2.14483002 0 P 0 ;0
L 1.14826004 -2.14383002 1.20353002 -2.14383002 0 P 0 ;0
L 1.1496 -2.14283002 1.20373996 -2.14283002 0 P 0 ;0
L 1.15078996 -2.14183002 1.20395 -2.14183002 0 P 0 ;0
L 1.15186004 -2.14083002 1.20415 -2.14083002 0 P 0 ;0
L 1.15278996 -2.13983002 1.20431998 -2.13983002 0 P 0 ;0
L 1.15361998 -2.13883002 1.20446004 -2.13883002 0 P 0 ;0
L 1.15436004 -2.13783002 1.20458002 -2.13783002 0 P 0 ;0
L 1.155 -2.13683002 1.20466998 -2.13683002 0 P 0 ;0
L 1.15556998 -2.13583002 1.20475 -2.13583002 0 P 0 ;0
L 1.15608996 -2.13483002 1.20481998 -2.13483002 0 P 0 ;0
L 1.15653996 -2.13383002 1.20488996 -2.13383002 0 P 0 ;0
L 1.15691004 -2.13283002 1.20496004 -2.13283002 0 P 0 ;0
L 1.15723996 -2.13183002 1.20503002 -2.13183002 0 P 0 ;0
L 1.15751998 -2.13083002 1.2051 -2.13083002 0 P 0 ;0
L 1.15773002 -2.12983002 1.20516004 -2.12983002 0 P 0 ;0
L 1.15793002 -2.12883002 1.20523002 -2.12883002 0 P 0 ;0
L 1.15806004 -2.12783002 1.2053 -2.12783002 0 P 0 ;0
L 1.15816998 -2.12683002 1.20536998 -2.12683002 0 P 0 ;0
L 1.15821004 -2.12583002 1.20543996 -2.12583002 0 P 0 ;0
L 1.11716004 -2.12483002 1.12726004 -2.12483002 0 P 0 ;0
L 1.15823996 -2.12483002 1.20551004 -2.12483002 0 P 0 ;0
L 1.10911998 -2.12383002 1.1352 -2.12383002 0 P 0 ;0
L 1.15821998 -2.12383002 1.20556998 -2.12383002 0 P 0 ;0
L 1.10468996 -2.12283002 1.14018996 -2.12283002 0 P 0 ;0
L 1.1582 -2.12283002 1.20563996 -2.12283002 0 P 0 ;0
L 1.10131004 -2.12183002 1.14366998 -2.12183002 0 P 0 ;0
L 1.15818002 -2.12183002 1.2057 -2.12183002 0 P 0 ;0
L 1.15808996 -2.12083002 1.20576004 -2.12083002 0 P 0 ;0
L 1.15781004 -2.11983002 1.20583002 -2.11983002 0 P 0 ;0
L 1.15721004 -2.11883002 1.20588002 -2.11883002 0 P 0 ;0
L 1.14146004 -2.08883002 1.20758002 -2.08883002 0 P 0 ;0
L 1.14525 -2.08783002 1.20763002 -2.08783002 0 P 0 ;0
L 1.14751004 -2.08683002 1.20768002 -2.08683002 0 P 0 ;0
L 1.14928002 -2.08583002 1.20773002 -2.08583002 0 P 0 ;0
L 1.15073002 -2.08483002 1.20778996 -2.08483002 0 P 0 ;0
L 1.15196004 -2.08383002 1.20783996 -2.08383002 0 P 0 ;0
L 1.13818996 -2.08913002 1.13826998 -2.08913002 0 P 0 ;0
L 1.13826998 -2.08913002 1.13988002 -2.08903996 0 P 0 ;0
L 1.13988002 -2.08903996 1.13996004 -2.08903996 0 P 0 ;0
L 1.13996004 -2.08903996 1.14001004 -2.08903002 0 P 0 ;0
L 1.14001004 -2.08903002 1.14005 -2.08901998 0 P 0 ;0
L 1.14005 -2.08901998 1.14163002 -2.08881004 0 P 0 ;0
L 1.14163002 -2.08881004 1.14166998 -2.0888 0 P 0 ;0
L 1.14166998 -2.0888 1.14171004 -2.0888 0 P 0 ;0
L 1.14171004 -2.0888 1.14178996 -2.08878002 0 P 0 ;0
L 1.14178996 -2.08878002 1.14335 -2.08843002 0 P 0 ;0
L 1.14335 -2.08843002 1.14351004 -2.08838996 0 P 0 ;0
L 1.14351004 -2.08838996 1.14503002 -2.08791004 0 P 0 ;0
L 1.14503002 -2.08791004 1.14511004 -2.08788996 0 P 0 ;0
L 1.14511004 -2.08788996 1.14515 -2.08786998 0 P 0 ;0
L 1.14515 -2.08786998 1.14518996 -2.08786004 0 P 0 ;0
L 1.14518996 -2.08786004 1.14666004 -2.08725 0 P 0 ;0
L 1.14666004 -2.08725 1.14673996 -2.08721998 0 P 0 ;0
L 1.14673996 -2.08721998 1.14678002 -2.0872 0 P 0 ;0
L 1.14678002 -2.0872 1.14681998 -2.08718996 0 P 0 ;0
L 1.14681998 -2.08718996 1.14823996 -2.08646998 0 P 0 ;0
L 1.14823996 -2.08646998 1.14826998 -2.08645 0 P 0 ;0
L 1.14826998 -2.08645 1.14835 -2.08641004 0 P 0 ;0
L 1.14835 -2.08641004 1.14838002 -2.08638002 0 P 0 ;0
L 1.14838002 -2.08638002 1.14976004 -2.08553002 0 P 0 ;0
L 1.14976004 -2.08553002 1.14978996 -2.08551004 0 P 0 ;0
L 1.14978996 -2.08551004 1.14983002 -2.08548996 0 P 0 ;0
L 1.14983002 -2.08548996 1.14988996 -2.08543996 0 P 0 ;0
L 1.14988996 -2.08543996 1.1512 -2.08448996 0 P 0 ;0
L 1.1512 -2.08448996 1.15126004 -2.08443996 0 P 0 ;0
L 1.15126004 -2.08443996 1.15128996 -2.08441004 0 P 0 ;0
L 1.15128996 -2.08441004 1.15131998 -2.08438996 0 P 0 ;0
L 1.15131998 -2.08438996 1.15253996 -2.08333002 0 P 0 ;0
L 1.15253996 -2.08333002 1.15256998 -2.0833 0 P 0 ;0
L 1.15256998 -2.0833 1.1526 -2.08328002 0 P 0 ;0
L 1.1526 -2.08328002 1.15263002 -2.08323996 0 P 0 ;0
L 1.15263002 -2.08323996 1.15266004 -2.08321998 0 P 0 ;0
L 1.15266004 -2.08321998 1.15378996 -2.08206004 0 P 0 ;0
L 1.15378996 -2.08206004 1.15376004 -2.08203996 0 P 0 ;0
L 1.15376004 -2.08203996 1.15381998 -2.08203996 0 P 0 ;0
L 1.15381998 -2.08203996 1.15383996 -2.082 0 P 0 ;0
L 1.15383996 -2.082 1.15386998 -2.08196998 0 P 0 ;0
L 1.15386998 -2.08196998 1.1539 -2.08195 0 P 0 ;0
L 1.1539 -2.08195 1.15493002 -2.08071004 0 P 0 ;0
L 1.15493002 -2.08071004 1.15493002 -2.0807 0 P 0 ;0
L 1.15493002 -2.0807 1.15496004 -2.08066998 0 P 0 ;0
L 1.15496004 -2.08066998 1.15498002 -2.08063996 0 P 0 ;0
L 1.15498002 -2.08063996 1.15501004 -2.08061004 0 P 0 ;0
L 1.15501004 -2.08061004 1.15503002 -2.08058002 0 P 0 ;0
L 1.15503002 -2.08058002 1.15596004 -2.07926004 0 P 0 ;0
L 1.15596004 -2.07926004 1.15603996 -2.07913996 0 P 0 ;0
L 1.15603996 -2.07913996 1.15673002 -2.07798996 0 P 0 ;0
L 1.15673002 -2.07798996 1.15676998 -2.07793002 0 P 0 ;0
L 1.15676998 -2.07793002 1.15678996 -2.07786998 0 P 0 ;0
L 1.15678996 -2.07786998 1.15741004 -2.07668996 0 P 0 ;0
L 1.15741004 -2.07668996 1.15743996 -2.07663002 0 P 0 ;0
L 1.15743996 -2.07663002 1.15746004 -2.07656998 0 P 0 ;0
L 1.15746004 -2.07656998 1.15746998 -2.07656998 0 P 0 ;0
L 1.15746998 -2.07656998 1.158 -2.07533996 0 P 0 ;0
L 1.158 -2.07533996 1.15801004 -2.07531004 0 P 0 ;0
L 1.15801004 -2.07531004 1.15803002 -2.07528002 0 P 0 ;0
L 1.15803002 -2.07528002 1.15805 -2.07521998 0 P 0 ;0
L 1.15805 -2.07521998 1.15848996 -2.07396004 0 P 0 ;0
L 1.15848996 -2.07396004 1.15841004 -2.07393002 0 P 0 ;0
L 1.15841004 -2.07393002 1.15851004 -2.07393002 0 P 0 ;0
L 1.15851004 -2.07393002 1.15851998 -2.0739 0 P 0 ;0
L 1.15851998 -2.0739 1.15853002 -2.07386004 0 P 0 ;0
L 1.15853002 -2.07386004 1.15853996 -2.07383002 0 P 0 ;0
L 1.15853996 -2.07383002 1.15943996 -2.07061004 0 P 0 ;0
L 1.15943996 -2.07061004 1.15945 -2.07058002 0 P 0 ;0
L 1.15945 -2.07058002 1.15946004 -2.07053996 0 P 0 ;0
L 1.15946004 -2.07053996 1.15946998 -2.07051004 0 P 0 ;0
L 1.15946998 -2.07051004 1.15946998 -2.07046998 0 P 0 ;0
L 1.15946998 -2.07046998 1.16013996 -2.06723002 0 P 0 ;0
L 1.16013996 -2.06723002 1.16013996 -2.0672 0 P 0 ;0
L 1.16013996 -2.0672 1.16016004 -2.06713996 0 P 0 ;0
L 1.16016004 -2.06713996 1.16016004 -2.06711004 0 P 0 ;0
L 1.16016004 -2.06711004 1.16081998 -2.06256004 0 P 0 ;0
L 1.16081998 -2.06256004 1.16081998 -2.06253996 0 P 0 ;0
L 1.16081998 -2.06253996 1.16083002 -2.0625 0 P 0 ;0
L 1.16083002 -2.0625 1.16083002 -2.06246998 0 P 0 ;0
L 1.16083002 -2.06246998 1.16126998 -2.05791004 0 P 0 ;0
L 1.16126998 -2.05791004 1.16128002 -2.0579 0 P 0 ;0
L 1.16128002 -2.0579 1.16128002 -2.05783996 0 P 0 ;0
L 1.16128002 -2.05783996 1.1621 -2.04405 0 P 0 ;0
L 1.1621 -2.04405 1.1621 -2.04401998 0 P 0 ;0
L 1.1621 -2.04401998 1.16285 -2.02761998 0 P 0 ;0
L 1.16285 -2.02761998 1.16136998 -2.0256 0 P 0 ;0
L 1.16136998 -2.0256 1.15878996 -2.02491004 0 P 0 ;0
L 1.15878996 -2.02491004 1.15878002 -2.0249 0 P 0 ;0
L 1.15878002 -2.0249 1.15871998 -2.02488996 0 P 0 ;0
L 1.15871998 -2.02488996 1.15755 -2.02461998 0 P 0 ;0
L 1.15755 -2.02461998 1.15746998 -2.0246 0 P 0 ;0
L 1.15746998 -2.0246 1.1574 -2.0246 0 P 0 ;0
L 1.1574 -2.0246 1.15621004 -2.02441004 0 P 0 ;0
L 1.15621004 -2.02441004 1.15616998 -2.02441004 0 P 0 ;0
L 1.15616998 -2.02441004 1.1561 -2.0244 0 P 0 ;0
L 1.1561 -2.0244 1.15606004 -2.02438996 0 P 0 ;0
L 1.15606004 -2.02438996 1.15486004 -2.0243 0 P 0 ;0
L 1.15486004 -2.0243 1.15471998 -2.0243 0 P 0 ;0
L 1.15471998 -2.0243 1.14936004 -2.02426004 0 P 0 ;0
L 1.14936004 -2.02426004 1.14928996 -2.02426004 0 P 0 ;0
L 1.14928996 -2.02426004 1.14925 -2.02426998 0 P 0 ;0
L 1.14925 -2.02426998 1.14921004 -2.02426998 0 P 0 ;0
L 1.14921004 -2.02426998 1.14376998 -2.02463996 0 P 0 ;0
L 1.14376998 -2.02463996 1.1437 -2.02463996 0 P 0 ;0
L 1.1437 -2.02463996 1.14365 -2.02465 0 P 0 ;0
L 1.14365 -2.02465 1.14361004 -2.02465 0 P 0 ;0
L 1.14361004 -2.02465 1.14161998 -2.02495 0 P 0 ;0
L 1.14161998 -2.02495 1.14161004 -2.02495 0 P 0 ;0
L 1.14161004 -2.02495 1.14153002 -2.02496998 0 P 0 ;0
L 1.14153002 -2.02496998 1.14148996 -2.02496998 0 P 0 ;0
L 1.14148996 -2.02496998 1.14143996 -2.02498996 0 P 0 ;0
L 1.14143996 -2.02498996 1.13946998 -2.02545 0 P 0 ;0
L 1.13946998 -2.02545 1.13943996 -2.02546998 0 P 0 ;0
L 1.13943996 -2.02546998 1.1394 -2.02546998 0 P 0 ;0
L 1.1394 -2.02546998 1.13933002 -2.0255 0 P 0 ;0
L 1.13933002 -2.0255 1.13801004 -2.02591998 0 P 0 ;0
L 1.13801004 -2.02591998 1.13798002 -2.02593002 0 P 0 ;0
L 1.13798002 -2.02593002 1.13793996 -2.02593996 0 P 0 ;0
L 1.13793996 -2.02593996 1.13788002 -2.02596998 0 P 0 ;0
L 1.13788002 -2.02596998 1.1366 -2.02648002 0 P 0 ;0
L 1.1366 -2.02648002 1.13653996 -2.0265 0 P 0 ;0
L 1.13653996 -2.0265 1.13648002 -2.02653002 0 P 0 ;0
L 1.13648002 -2.02653002 1.13523996 -2.02713002 0 P 0 ;0
L 1.13523996 -2.02713002 1.13518002 -2.02716004 0 P 0 ;0
L 1.13518002 -2.02716004 1.13515 -2.02716998 0 P 0 ;0
L 1.13515 -2.02716998 1.13511998 -2.02718996 0 P 0 ;0
L 1.13511998 -2.02718996 1.13393002 -2.02786998 0 P 0 ;0
L 1.13393002 -2.02786998 1.13388996 -2.02788996 0 P 0 ;0
L 1.13388996 -2.02788996 1.1338 -2.02795 0 P 0 ;0
L 1.1338 -2.02795 1.13111998 -2.02976004 0 P 0 ;0
L 1.13111998 -2.02976004 1.13105 -2.02981004 0 P 0 ;0
L 1.13105 -2.02981004 1.13101004 -2.02983996 0 P 0 ;0
L 1.13101004 -2.02983996 1.13098002 -2.02986004 0 P 0 ;0
L 1.13098002 -2.02986004 1.12846998 -2.03188996 0 P 0 ;0
L 1.12846998 -2.03188996 1.12838002 -2.03198002 0 P 0 ;0
L 1.12838002 -2.03198002 1.12833996 -2.03201004 0 P 0 ;0
L 1.12833996 -2.03201004 1.12596004 -2.0343 0 P 0 ;0
L 1.12596004 -2.0343 1.12593996 -2.03433002 0 P 0 ;0
L 1.12593996 -2.03433002 1.1259 -2.03436004 0 P 0 ;0
L 1.1259 -2.03436004 1.12588002 -2.03438996 0 P 0 ;0
L 1.12588002 -2.03438996 1.12585 -2.03443002 0 P 0 ;0
L 1.12585 -2.03443002 1.12366998 -2.03691004 0 P 0 ;0
L 1.12366998 -2.03691004 1.12363996 -2.03695 0 P 0 ;0
L 1.12363996 -2.03695 1.12361998 -2.03698002 0 P 0 ;0
L 1.12361998 -2.03698002 1.12358996 -2.03701004 0 P 0 ;0
L 1.12358996 -2.03701004 1.12356998 -2.03703996 0 P 0 ;0
L 1.12356998 -2.03703996 1.12236998 -2.03865 0 P 0 ;0
L 1.12236998 -2.03865 1.12233996 -2.03868996 0 P 0 ;0
L 1.12233996 -2.03868996 1.12233002 -2.03871004 0 P 0 ;0
L 1.12233002 -2.03871004 1.12228996 -2.03878002 0 P 0 ;0
L 1.12228996 -2.03878002 1.12121004 -2.04046998 0 P 0 ;0
L 1.12121004 -2.04046998 1.12118996 -2.0405 0 P 0 ;0
L 1.12118996 -2.0405 1.12116998 -2.04053996 0 P 0 ;0
L 1.12116998 -2.04053996 1.12115 -2.04056998 0 P 0 ;0
L 1.12115 -2.04056998 1.12113996 -2.04061004 0 P 0 ;0
L 1.12113996 -2.04061004 1.12018996 -2.04238002 0 P 0 ;0
L 1.12018996 -2.04238002 1.12016004 -2.04245 0 P 0 ;0
L 1.12016004 -2.04245 1.12013996 -2.04248002 0 P 0 ;0
L 1.12013996 -2.04248002 1.12013002 -2.04251004 0 P 0 ;0
L 1.12013002 -2.04251004 1.11926004 -2.04446998 0 P 0 ;0
L 1.11926004 -2.04446998 1.11925 -2.0445 0 P 0 ;0
L 1.11925 -2.0445 1.11923002 -2.04453996 0 P 0 ;0
L 1.11923002 -2.04453996 1.11921998 -2.04458002 0 P 0 ;0
L 1.11921998 -2.04458002 1.11921004 -2.04461004 0 P 0 ;0
L 1.11921004 -2.04461004 1.11848002 -2.04663002 0 P 0 ;0
L 1.11848002 -2.04663002 1.11846998 -2.04666004 0 P 0 ;0
L 1.11846998 -2.04666004 1.11846004 -2.0467 0 P 0 ;0
L 1.11846004 -2.0467 1.11843996 -2.04676998 0 P 0 ;0
L 1.11843996 -2.04676998 1.11786004 -2.04883996 0 P 0 ;0
L 1.11786004 -2.04883996 1.11785 -2.04886998 0 P 0 ;0
L 1.11785 -2.04886998 1.11783996 -2.04891004 0 P 0 ;0
L 1.11783996 -2.04891004 1.11783996 -2.04893996 0 P 0 ;0
L 1.11783996 -2.04893996 1.11783002 -2.04896998 0 P 0 ;0
L 1.11783002 -2.04896998 1.11783002 -2.04898002 0 P 0 ;0
L 1.11783002 -2.04898002 1.1174 -2.05108002 0 P 0 ;0
L 1.1174 -2.05108002 1.1174 -2.05111998 0 P 0 ;0
L 1.1174 -2.05111998 1.11738996 -2.05116004 0 P 0 ;0
L 1.11738996 -2.05116004 1.11738002 -2.05118996 0 P 0 ;0
L 1.11738002 -2.05118996 1.11738002 -2.05123002 0 P 0 ;0
L 1.11738002 -2.05123002 1.11673002 -2.05643002 0 P 0 ;0
L 1.11673002 -2.05643002 1.11671998 -2.05646998 0 P 0 ;0
L 1.11671998 -2.05646998 1.11671998 -2.05655 0 P 0 ;0
L 1.11671998 -2.05655 1.11671004 -2.05658996 0 P 0 ;0
L 1.11671004 -2.05658996 1.11648996 -2.06181998 0 P 0 ;0
L 1.11648996 -2.06181998 1.11648002 -2.06186998 0 P 0 ;0
L 1.11648002 -2.06186998 1.11648002 -2.06195 0 P 0 ;0
L 1.11648002 -2.06195 1.11648996 -2.06198996 0 P 0 ;0
L 1.11648996 -2.06198996 1.11668002 -2.06696998 0 P 0 ;0
L 1.11668002 -2.06696998 1.11768002 -2.06696998 0 P 0 ;0
L 1.11768002 -2.06696998 1.11668002 -2.06701004 0 P 0 ;0
L 1.11668002 -2.06701004 1.11668002 -2.06713002 0 P 0 ;0
L 1.11668002 -2.06713002 1.11668996 -2.06716998 0 P 0 ;0
L 1.11668996 -2.06716998 1.11728002 -2.07215 0 P 0 ;0
L 1.11728002 -2.07215 1.11728996 -2.07218996 0 P 0 ;0
L 1.11728996 -2.07218996 1.11728996 -2.07223002 0 P 0 ;0
L 1.11728996 -2.07223002 1.11731004 -2.07231004 0 P 0 ;0
L 1.11731004 -2.07231004 1.11758996 -2.07371004 0 P 0 ;0
L 1.11758996 -2.07371004 1.1176 -2.07375 0 P 0 ;0
L 1.1176 -2.07375 1.11761004 -2.0738 0 P 0 ;0
L 1.11761004 -2.0738 1.11761998 -2.07383996 0 P 0 ;0
L 1.11761998 -2.07383996 1.11763996 -2.07388002 0 P 0 ;0
L 1.11763996 -2.07388002 1.11803996 -2.07523996 0 P 0 ;0
L 1.11803996 -2.07523996 1.11806004 -2.07531998 0 P 0 ;0
L 1.11806004 -2.07531998 1.11808002 -2.07536004 0 P 0 ;0
L 1.11808002 -2.07536004 1.11808996 -2.07541004 0 P 0 ;0
L 1.11808996 -2.07541004 1.11861004 -2.07673002 0 P 0 ;0
L 1.11861004 -2.07673002 1.11863996 -2.07681004 0 P 0 ;0
L 1.11863996 -2.07681004 1.11866004 -2.07683996 0 P 0 ;0
L 1.11866004 -2.07683996 1.11868002 -2.07688002 0 P 0 ;0
L 1.11868002 -2.07688002 1.11931004 -2.07815 0 P 0 ;0
L 1.11931004 -2.07815 1.11935 -2.07823002 0 P 0 ;0
L 1.11935 -2.07823002 1.1194 -2.0783 0 P 0 ;0
L 1.1194 -2.0783 1.12013996 -2.07951998 0 P 0 ;0
L 1.12013996 -2.07951998 1.12021004 -2.07961998 0 P 0 ;0
L 1.12021004 -2.07961998 1.12023002 -2.07965 0 P 0 ;0
L 1.12023002 -2.07965 1.12023002 -2.07966004 0 P 0 ;0
L 1.12023002 -2.07966004 1.1212 -2.08096998 0 P 0 ;0
L 1.1212 -2.08096998 1.12123996 -2.08103002 0 P 0 ;0
L 1.12123996 -2.08103002 1.12126998 -2.08106004 0 P 0 ;0
L 1.12126998 -2.08106004 1.12128996 -2.08108996 0 P 0 ;0
L 1.12128996 -2.08108996 1.12235 -2.08231004 0 P 0 ;0
L 1.12235 -2.08231004 1.12238002 -2.08233996 0 P 0 ;0
L 1.12238002 -2.08233996 1.1224 -2.08236998 0 P 0 ;0
L 1.1224 -2.08236998 1.12246004 -2.08243002 0 P 0 ;0
L 1.12246004 -2.08243002 1.12361004 -2.08355 0 P 0 ;0
L 1.12361004 -2.08355 1.12366998 -2.08361004 0 P 0 ;0
L 1.12366998 -2.08361004 1.1237 -2.08363002 0 P 0 ;0
L 1.1237 -2.08363002 1.12373002 -2.08366004 0 P 0 ;0
L 1.12373002 -2.08366004 1.12496998 -2.08468996 0 P 0 ;0
L 1.12496998 -2.08468996 1.125 -2.08471004 0 P 0 ;0
L 1.125 -2.08471004 1.12503002 -2.08473996 0 P 0 ;0
L 1.12503002 -2.08473996 1.12506998 -2.08476004 0 P 0 ;0
L 1.12506998 -2.08476004 1.1251 -2.08478996 0 P 0 ;0
L 1.1251 -2.08478996 1.12641998 -2.08571004 0 P 0 ;0
L 1.12641998 -2.08571004 1.12645 -2.08573002 0 P 0 ;0
L 1.12645 -2.08573002 1.12648002 -2.08576004 0 P 0 ;0
L 1.12648002 -2.08576004 1.12651004 -2.08578002 0 P 0 ;0
L 1.12651004 -2.08578002 1.12655 -2.0858 0 P 0 ;0
L 1.12655 -2.0858 1.12793996 -2.08661004 0 P 0 ;0
L 1.12793996 -2.08661004 1.12801004 -2.08665 0 P 0 ;0
L 1.12801004 -2.08665 1.12805 -2.08666998 0 P 0 ;0
L 1.12805 -2.08666998 1.12808002 -2.08668996 0 P 0 ;0
L 1.12808002 -2.08668996 1.12808996 -2.08668996 0 P 0 ;0
L 1.12808996 -2.08668996 1.12953996 -2.08738996 0 P 0 ;0
L 1.12953996 -2.08738996 1.12961998 -2.08743002 0 P 0 ;0
L 1.12961998 -2.08743002 1.12965 -2.08743996 0 P 0 ;0
L 1.12965 -2.08743996 1.1297 -2.08746004 0 P 0 ;0
L 1.1297 -2.08746004 1.13118002 -2.08801998 0 P 0 ;0
L 1.13118002 -2.08801998 1.13133996 -2.08808002 0 P 0 ;0
L 1.13133996 -2.08808002 1.13286998 -2.08851004 0 P 0 ;0
L 1.13286998 -2.08851004 1.13295 -2.08853996 0 P 0 ;0
L 1.13295 -2.08853996 1.13303996 -2.08855 0 P 0 ;0
L 1.13303996 -2.08855 1.1346 -2.08886004 0 P 0 ;0
L 1.1346 -2.08886004 1.13471998 -2.08888996 0 P 0 ;0
L 1.13471998 -2.08888996 1.13476004 -2.08888996 0 P 0 ;0
L 1.13476004 -2.08888996 1.13633996 -2.08906998 0 P 0 ;0
L 1.13633996 -2.08906998 1.13638996 -2.08908002 0 P 0 ;0
L 1.13638996 -2.08908002 1.13651004 -2.08908002 0 P 0 ;0
L 1.13651004 -2.08908002 1.1381 -2.08913002 0 P 0 ;0
L 1.1381 -2.08913002 1.13818996 -2.08913002 0 P 0 ;0
L 1.31623996 -1.98923996 1.3135 -1.98988002 0 P 0 ;0
L 1.3135 -1.98988002 1.31078996 -1.99071004 0 P 0 ;0
L 1.31078996 -1.99071004 1.30813002 -1.99175 0 P 0 ;0
L 1.30813002 -1.99175 1.30553996 -1.99296998 0 P 0 ;0
L 1.30553996 -1.99296998 1.30308996 -1.99431998 0 P 0 ;0
L 1.30308996 -1.99431998 1.30073996 -1.99585 0 P 0 ;0
L 1.30073996 -1.99585 1.29863996 -1.99746004 0 P 0 ;0
L 1.29863996 -1.99746004 1.29666004 -1.99923996 0 P 0 ;0
L 1.29666004 -1.99923996 1.29205 -2.00375 0 P 0 ;0
L 1.29205 -2.00375 1.29205 -1.99243996 0 P 0 ;0
L 1.29205 -1.99243996 1.24316004 -1.99243996 0 P 0 ;0
L 1.24316004 -1.99243996 1.24313996 -2.00521004 0 P 0 ;0
L 1.24313996 -2.00521004 1.24261004 -2.03151004 0 P 0 ;0
L 1.24261004 -2.03151004 1.24086998 -2.07046004 0 P 0 ;0
L 1.24086998 -2.07046004 1.23873996 -2.10921004 0 P 0 ;0
L 1.23873996 -2.10921004 1.23811998 -2.11641998 0 P 0 ;0
L 1.23811998 -2.11641998 1.23711998 -2.12361998 0 P 0 ;0
L 1.23711998 -2.12361998 1.23655 -2.12716004 0 P 0 ;0
L 1.23655 -2.12716004 1.29205 -2.12716004 0 P 0 ;0
L 1.29205 -2.12716004 1.29206998 -2.11766004 0 P 0 ;0
L 1.29206998 -2.11766004 1.29238996 -2.10283996 0 P 0 ;0
L 1.29238996 -2.10283996 1.29336004 -2.08431004 0 P 0 ;0
L 1.29336004 -2.08431004 1.29463996 -2.06673002 0 P 0 ;0
L 1.29463996 -2.06673002 1.29511004 -2.06253002 0 P 0 ;0
L 1.29511004 -2.06253002 1.29583996 -2.05836004 0 P 0 ;0
L 1.29583996 -2.05836004 1.29683002 -2.05446998 0 P 0 ;0
L 1.29683002 -2.05446998 1.29813996 -2.05068996 0 P 0 ;0
L 1.29813996 -2.05068996 1.29978002 -2.04701998 0 P 0 ;0
L 1.29978002 -2.04701998 1.30056998 -2.04556998 0 P 0 ;0
L 1.30056998 -2.04556998 1.30146998 -2.04418996 0 P 0 ;0
L 1.30146998 -2.04418996 1.30246998 -2.04288002 0 P 0 ;0
L 1.30246998 -2.04288002 1.30356998 -2.04165 0 P 0 ;0
L 1.30356998 -2.04165 1.30475 -2.0405 0 P 0 ;0
L 1.30475 -2.0405 1.30603996 -2.03945 0 P 0 ;0
L 1.30603996 -2.03945 1.30773996 -2.03826004 0 P 0 ;0
L 1.30773996 -2.03826004 1.30953002 -2.03723002 0 P 0 ;0
L 1.30953002 -2.03723002 1.31141004 -2.03635 0 P 0 ;0
L 1.31141004 -2.03635 1.31335 -2.03563002 0 P 0 ;0
L 1.31335 -2.03563002 1.31535 -2.03508002 0 P 0 ;0
L 1.31535 -2.03508002 1.31973996 -2.03423002 0 P 0 ;0
L 1.31973996 -2.03423002 1.32416004 -2.03366998 0 P 0 ;0
L 1.32416004 -2.03366998 1.32863002 -2.0334 0 P 0 ;0
L 1.32863002 -2.0334 1.33688002 -2.03318002 0 P 0 ;0
L 1.33688002 -2.03318002 1.33613002 -2.01151004 0 P 0 ;0
L 1.33613002 -2.01151004 1.33581004 -2.00315 0 P 0 ;0
L 1.33581004 -2.00315 1.33543996 -1.99596004 0 P 0 ;0
L 1.33543996 -1.99596004 1.33508002 -1.98971004 0 P 0 ;0
L 1.33508002 -1.98971004 1.33503996 -1.98945 0 P 0 ;0
L 1.33503996 -1.98945 1.335 -1.98931998 0 P 0 ;0
L 1.335 -1.98931998 1.33496004 -1.9892 0 P 0 ;0
L 1.33496004 -1.9892 1.3349 -1.98908002 0 P 0 ;0
L 1.3349 -1.98908002 1.33483996 -1.98896998 0 P 0 ;0
L 1.33483996 -1.98896998 1.33476998 -1.98886004 0 P 0 ;0
L 1.33476998 -1.98886004 1.33468996 -1.98876004 0 P 0 ;0
L 1.33468996 -1.98876004 1.3346 -1.98866998 0 P 0 ;0
L 1.3346 -1.98866998 1.33451004 -1.98858996 0 P 0 ;0
L 1.33451004 -1.98858996 1.3344 -1.98851998 0 P 0 ;0
L 1.3344 -1.98851998 1.3343 -1.98845 0 P 0 ;0
L 1.3343 -1.98845 1.33418002 -1.98838996 0 P 0 ;0
L 1.33418002 -1.98838996 1.33406998 -1.98833996 0 P 0 ;0
L 1.33406998 -1.98833996 1.33395 -1.9883 0 P 0 ;0
L 1.33395 -1.9883 1.33383002 -1.98828002 0 P 0 ;0
L 1.33383002 -1.98828002 1.3337 -1.98826004 0 P 0 ;0
L 1.3337 -1.98826004 1.33356998 -1.98825 0 P 0 ;0
L 1.33356998 -1.98825 1.32756998 -1.98823002 0 P 0 ;0
L 1.32756998 -1.98823002 1.32135 -1.98853996 0 P 0 ;0
L 1.32135 -1.98853996 1.31878996 -1.98881998 0 P 0 ;0
L 1.31878996 -1.98881998 1.31623996 -1.98923996 0 P 0 ;0
L 1.2389 -2.12516004 1.29006004 -2.12516004 0 P 0 ;0
L 1.23906998 -2.12416004 1.29006004 -2.12416004 0 P 0 ;0
L 1.23921004 -2.12316004 1.29006004 -2.12316004 0 P 0 ;0
L 1.23933996 -2.12216004 1.29006004 -2.12216004 0 P 0 ;0
L 1.23948996 -2.12116004 1.29006004 -2.12116004 0 P 0 ;0
L 1.23961998 -2.12016004 1.29006998 -2.12016004 0 P 0 ;0
L 1.23976004 -2.11916004 1.29006998 -2.11916004 0 P 0 ;0
L 1.2399 -2.11816004 1.29006998 -2.11816004 0 P 0 ;0
L 1.24003996 -2.11716004 1.29008002 -2.11716004 0 P 0 ;0
L 1.24015 -2.11616004 1.2901 -2.11616004 0 P 0 ;0
L 1.24023996 -2.11516004 1.29011998 -2.11516004 0 P 0 ;0
L 1.24033002 -2.11416004 1.29013996 -2.11416004 0 P 0 ;0
L 1.24041004 -2.11316004 1.29016004 -2.11316004 0 P 0 ;0
L 1.24048996 -2.11216004 1.29018996 -2.11216004 0 P 0 ;0
L 1.24058002 -2.11116004 1.29021004 -2.11116004 0 P 0 ;0
L 1.24066998 -2.11016004 1.29023002 -2.11016004 0 P 0 ;0
L 1.24075 -2.10916004 1.29025 -2.10916004 0 P 0 ;0
L 1.2408 -2.10816004 1.29026998 -2.10816004 0 P 0 ;0
L 1.24086004 -2.10716004 1.29028996 -2.10716004 0 P 0 ;0
L 1.24091004 -2.10616004 1.29031998 -2.10616004 0 P 0 ;0
L 1.24096998 -2.10516004 1.29033996 -2.10516004 0 P 0 ;0
L 1.24101998 -2.10416004 1.29036004 -2.10416004 0 P 0 ;0
L 1.24108002 -2.10316004 1.29038002 -2.10316004 0 P 0 ;0
L 1.24113002 -2.10216004 1.29041998 -2.10216004 0 P 0 ;0
L 1.24118002 -2.10116004 1.29046998 -2.10116004 0 P 0 ;0
L 1.24123996 -2.10016004 1.29053002 -2.10016004 0 P 0 ;0
L 1.24128996 -2.09916004 1.29058002 -2.09916004 0 P 0 ;0
L 1.24135 -2.09816004 1.29063002 -2.09816004 0 P 0 ;0
L 1.2414 -2.09716004 1.29068002 -2.09716004 0 P 0 ;0
L 1.24146004 -2.09616004 1.29073996 -2.09616004 0 P 0 ;0
L 1.24151004 -2.09516004 1.29078996 -2.09516004 0 P 0 ;0
L 1.24156998 -2.09416004 1.29083996 -2.09416004 0 P 0 ;0
L 1.24161998 -2.09316004 1.2909 -2.09316004 0 P 0 ;0
L 1.24168002 -2.09216004 1.29095 -2.09216004 0 P 0 ;0
L 1.24173002 -2.09116004 1.291 -2.09116004 0 P 0 ;0
L 1.24178996 -2.09016004 1.29105 -2.09016004 0 P 0 ;0
L 1.24183996 -2.08916004 1.2911 -2.08916004 0 P 0 ;0
L 1.2419 -2.08816004 1.29116004 -2.08816004 0 P 0 ;0
L 1.24196004 -2.08716004 1.29121004 -2.08716004 0 P 0 ;0
L 1.24201004 -2.08616004 1.29126998 -2.08616004 0 P 0 ;0
L 1.24206998 -2.08516004 1.29131998 -2.08516004 0 P 0 ;0
L 1.24211998 -2.08416004 1.29136998 -2.08416004 0 P 0 ;0
L 1.2389 -2.12516004 1.2391 -2.12393002 0 P 0 ;0
L 1.2391 -2.12393002 1.2391 -2.1239 0 P 0 ;0
L 1.2391 -2.1239 1.24011004 -2.11665 0 P 0 ;0
L 1.24011004 -2.11665 1.24073002 -2.10935 0 P 0 ;0
L 1.24073002 -2.10935 1.24073996 -2.10931998 0 P 0 ;0
L 1.24073996 -2.10931998 1.24286004 -2.07056004 0 P 0 ;0
L 1.24286004 -2.07056004 1.24461004 -2.03158002 0 P 0 ;0
L 1.24461004 -2.03158002 1.24513996 -2.00523002 0 P 0 ;0
L 1.24513996 -2.00523002 1.24515 -1.99443996 0 P 0 ;0
L 1.24515 -1.99443996 1.29005 -1.99443996 0 P 0 ;0
L 1.29005 -1.99443996 1.29005 -2.00375 0 P 0 ;0
L 1.29005 -2.00375 1.29128002 -2.0056 0 P 0 ;0
L 1.29128002 -2.0056 1.29345 -2.00518002 0 P 0 ;0
L 1.29345 -2.00518002 1.29803002 -2.0007 0 P 0 ;0
L 1.29803002 -2.0007 1.29991998 -1.999 0 P 0 ;0
L 1.29991998 -1.999 1.30188996 -1.99748996 0 P 0 ;0
L 1.30188996 -1.99748996 1.30411998 -1.99603996 0 P 0 ;0
L 1.30411998 -1.99603996 1.30645 -1.99475 0 P 0 ;0
L 1.30645 -1.99475 1.30891998 -1.99358996 0 P 0 ;0
L 1.30891998 -1.99358996 1.31145 -1.9926 0 P 0 ;0
L 1.31145 -1.9926 1.31401998 -1.99181004 0 P 0 ;0
L 1.31401998 -1.99181004 1.31663996 -1.9912 0 P 0 ;0
L 1.31663996 -1.9912 1.31906004 -1.9908 0 P 0 ;0
L 1.31906004 -1.9908 1.32151004 -1.99053002 0 P 0 ;0
L 1.32151004 -1.99053002 1.32761998 -1.99023002 0 P 0 ;0
L 1.32761998 -1.99023002 1.3331 -1.99025 0 P 0 ;0
L 1.3331 -1.99025 1.33345 -1.99608002 0 P 0 ;0
L 1.33345 -1.99608002 1.33381004 -2.00323002 0 P 0 ;0
L 1.33381004 -2.00323002 1.33413002 -2.01158996 0 P 0 ;0
L 1.33413002 -2.01158996 1.33413002 -2.0116 0 P 0 ;0
L 1.33413002 -2.0116 1.33481998 -2.03123002 0 P 0 ;0
L 1.33481998 -2.03123002 1.32853996 -2.0314 0 P 0 ;0
L 1.32853996 -2.0314 1.32398002 -2.03166998 0 P 0 ;0
L 1.32398002 -2.03166998 1.31941998 -2.03225 0 P 0 ;0
L 1.31941998 -2.03225 1.31488996 -2.03313002 0 P 0 ;0
L 1.31488996 -2.03313002 1.31273996 -2.03373002 0 P 0 ;0
L 1.31273996 -2.03373002 1.31063996 -2.0345 0 P 0 ;0
L 1.31063996 -2.0345 1.3086 -2.03545 0 P 0 ;0
L 1.3086 -2.03545 1.30666004 -2.03656998 0 P 0 ;0
L 1.30666004 -2.03656998 1.30658996 -2.03661998 0 P 0 ;0
L 1.30658996 -2.03661998 1.30483002 -2.03786004 0 P 0 ;0
L 1.30483002 -2.03786004 1.30341998 -2.03901004 0 P 0 ;0
L 1.30341998 -2.03901004 1.30336998 -2.03906004 0 P 0 ;0
L 1.30336998 -2.03906004 1.30211998 -2.04026004 0 P 0 ;0
L 1.30211998 -2.04026004 1.30093002 -2.0416 0 P 0 ;0
L 1.30093002 -2.0416 1.29983002 -2.04303996 0 P 0 ;0
L 1.29983002 -2.04303996 1.29978996 -2.0431 0 P 0 ;0
L 1.29978996 -2.0431 1.29885 -2.04453996 0 P 0 ;0
L 1.29885 -2.04453996 1.29798996 -2.04613002 0 P 0 ;0
L 1.29798996 -2.04613002 1.29631998 -2.04986998 0 P 0 ;0
L 1.29631998 -2.04986998 1.29628002 -2.04995 0 P 0 ;0
L 1.29628002 -2.04995 1.29625 -2.05003002 0 P 0 ;0
L 1.29625 -2.05003002 1.29491998 -2.0539 0 P 0 ;0
L 1.29491998 -2.0539 1.29388996 -2.05793996 0 P 0 ;0
L 1.29388996 -2.05793996 1.29386998 -2.05801998 0 P 0 ;0
L 1.29386998 -2.05801998 1.29313996 -2.06221004 0 P 0 ;0
L 1.29313996 -2.06221004 1.29313002 -2.06223996 0 P 0 ;0
L 1.29313002 -2.06223996 1.29311998 -2.0623 0 P 0 ;0
L 1.29311998 -2.0623 1.29265 -2.06655 0 P 0 ;0
L 1.29265 -2.06655 1.29136998 -2.08418996 0 P 0 ;0
L 1.29136998 -2.08418996 1.29038996 -2.10276998 0 P 0 ;0
L 1.29038996 -2.10276998 1.29006998 -2.11763002 0 P 0 ;0
L 1.29006998 -2.11763002 1.29006004 -2.12516004 0 P 0 ;0
L 1.29006004 -2.12516004 1.2389 -2.12516004 0 P 0 ;0
L 1.09846998 -2.00483002 1.21248002 -2.00483002 0 P 0 ;0
L 1.09838002 -2.12083002 1.14708002 -2.12083002 0 P 0 ;0
L 1.11933002 -2.18283002 1.15161998 -2.18283002 0 P 0 ;0
L 1.11001998 -2.18183002 1.15838002 -2.18183002 0 P 0 ;0
L 1.10246998 -2.18083002 1.16333996 -2.18083002 0 P 0 ;0
L 1.04061004 -1.89731004 1.09978002 -1.89731004 0 P 0 ;0
L 1.03565 -1.89631004 1.09821004 -1.89631004 0 P 0 ;0
L 1.03068996 -1.89531004 1.09661004 -1.89531004 0 P 0 ;0
L 1.02573002 -1.89431004 1.09475 -1.89431004 0 P 0 ;0
L 1.019 -1.89331004 1.09288002 -1.89331004 0 P 0 ;0
L 1.01163996 -1.89231004 1.09101998 -1.89231004 0 P 0 ;0
L 0.99518996 -1.89131004 1.08916004 -1.89131004 0 P 0 ;0
L 0.87011998 -1.88331004 1.07278996 -1.88331004 0 P 0 ;0
L 0.86963996 -1.88231004 1.07053002 -1.88231004 0 P 0 ;0
L 0.86916004 -1.88131004 1.06828002 -1.88131004 0 P 0 ;0
L 0.86863002 -1.88031004 1.06603002 -1.88031004 0 P 0 ;0
L 0.86806998 -1.87931004 1.06351004 -1.87931004 0 P 0 ;0
L 0.8675 -1.87831004 1.06076998 -1.87831004 0 P 0 ;0
L 0.86693002 -1.87731004 1.05803996 -1.87731004 0 P 0 ;0
L 0.86631004 -1.87631004 1.05531004 -1.87631004 0 P 0 ;0
L 0.86563996 -1.87531004 1.05256998 -1.87531004 0 P 0 ;0
L 0.86498002 -1.87431004 1.04983996 -1.87431004 0 P 0 ;0
L 0.86431998 -1.87331004 1.0471 -1.87331004 0 P 0 ;0
L 0.86356004 -1.87231004 1.04376004 -1.87231004 0 P 0 ;0
L 0.86278996 -1.87131004 1.04041998 -1.87131004 0 P 0 ;0
L 0.86203002 -1.87031004 1.03708002 -1.87031004 0 P 0 ;0
L 0.86118996 -1.86931004 1.03373996 -1.86931004 0 P 0 ;0
L 0.8603 -1.86831004 1.0304 -1.86831004 0 P 0 ;0
L 0.85941004 -1.86731004 1.02656998 -1.86731004 0 P 0 ;0
L 0.8585 -1.86631004 1.02231998 -1.86631004 0 P 0 ;0
L 0.85756998 -1.86531004 1.01806998 -1.86531004 0 P 0 ;0
L 0.85663002 -1.86431004 1.01381998 -1.86431004 0 P 0 ;0
L 0.85568996 -1.86331004 1.00931998 -1.86331004 0 P 0 ;0
L 0.85481004 -1.86231004 1.00335 -1.86231004 0 P 0 ;0
L 0.85916998 -1.86131004 0.99738002 -1.86131004 0 P 0 ;0
L 0.86716998 -1.86031004 0.99141998 -1.86031004 0 P 0 ;0
L 0.87476998 -1.89731004 0.89943002 -1.89731004 0 P 0 ;0
L 0.87453996 -1.89631004 0.90426004 -1.89631004 0 P 0 ;0
L 0.87431004 -1.89531004 0.9097 -1.89531004 0 P 0 ;0
L 0.87406998 -1.89431004 0.91608002 -1.89431004 0 P 0 ;0
L 0.87383002 -1.89331004 0.92246004 -1.89331004 0 P 0 ;0
L 0.87355 -1.89231004 0.93086004 -1.89231004 0 P 0 ;0
L 0.87323002 -1.89131004 0.95553002 -1.89131004 0 P 0 ;0
L 0.87291004 -1.89031004 1.08728996 -1.89031004 0 P 0 ;0
L 0.87258996 -1.88931004 1.08543002 -1.88931004 0 P 0 ;0
L 0.87223002 -1.88831004 1.08356998 -1.88831004 0 P 0 ;0
L 0.87183002 -1.88731004 1.0817 -1.88731004 0 P 0 ;0
L 0.87143002 -1.88631004 1.07955 -1.88631004 0 P 0 ;0
L 0.87103002 -1.88531004 1.07728996 -1.88531004 0 P 0 ;0
L 0.8706 -1.88431004 1.07503996 -1.88431004 0 P 0 ;0
L 0.87525 -1.85931004 0.98545 -1.85931004 0 P 0 ;0
L 0.88421004 -1.85831004 0.97621004 -1.85831004 0 P 0 ;0
L 0.89393002 -1.85731004 0.96606998 -1.85731004 0 P 0 ;0
L 0.9106 -1.85631004 0.95203002 -1.85631004 0 P 0 ;0
L 1.08716004 -1.91231004 1.12151004 -1.91231004 0 P 0 ;0
L 1.08486004 -1.91131004 1.12018996 -1.91131004 0 P 0 ;0
L 1.08256004 -1.91031004 1.11886004 -1.91031004 0 P 0 ;0
L 1.08023002 -1.90931004 1.11753996 -1.90931004 0 P 0 ;0
L 1.07738002 -1.90831004 1.11621004 -1.90831004 0 P 0 ;0
L 1.07453002 -1.90731004 1.11488996 -1.90731004 0 P 0 ;0
L 1.07168996 -1.90631004 1.11356998 -1.90631004 0 P 0 ;0
L 1.06883996 -1.90531004 1.11223996 -1.90531004 0 P 0 ;0
L 1.066 -1.90431004 1.11076998 -1.90431004 0 P 0 ;0
L 1.06315 -1.90331004 1.1092 -1.90331004 0 P 0 ;0
L 1.0599 -1.90231004 1.10763002 -1.90231004 0 P 0 ;0
L 1.05611998 -1.90131004 1.10606004 -1.90131004 0 P 0 ;0
L 1.05235 -1.90031004 1.10448996 -1.90031004 0 P 0 ;0
L 1.04856998 -1.89931004 1.10291998 -1.89931004 0 P 0 ;0
L 1.04478996 -1.89831004 1.10135 -1.89831004 0 P 0 ;0
L 0.98815 -2.08316004 1.03726998 -2.08316004 0 P 0 ;0
L 0.98818002 -2.08216004 1.03731004 -2.08216004 0 P 0 ;0
L 0.98821998 -2.08116004 1.03735 -2.08116004 0 P 0 ;0
L 0.98825 -2.08016004 1.03738996 -2.08016004 0 P 0 ;0
L 0.98828002 -2.07916004 1.03743002 -2.07916004 0 P 0 ;0
L 0.98831998 -2.07816004 1.03746998 -2.07816004 0 P 0 ;0
L 0.98835 -2.07716004 1.03751004 -2.07716004 0 P 0 ;0
L 0.98838002 -2.07616004 1.03755 -2.07616004 0 P 0 ;0
L 0.98841998 -2.07516004 1.03758002 -2.07516004 0 P 0 ;0
L 0.98845 -2.07416004 1.03761004 -2.07416004 0 P 0 ;0
L 0.98848002 -2.07316004 1.03763996 -2.07316004 0 P 0 ;0
L 0.98851004 -2.07216004 1.03768002 -2.07216004 0 P 0 ;0
L 0.98855 -2.07116004 1.03771004 -2.07116004 0 P 0 ;0
L 0.98858002 -2.07016004 1.03773996 -2.07016004 0 P 0 ;0
L 0.98858996 -2.06916004 1.03776998 -2.06916004 0 P 0 ;0
L 0.98858996 -2.06816004 1.0378 -2.06816004 0 P 0 ;0
L 0.98858996 -2.06716004 1.03783002 -2.06716004 0 P 0 ;0
L 0.98858002 -2.06616004 1.03786004 -2.06616004 0 P 0 ;0
L 0.98856998 -2.06516004 1.0379 -2.06516004 0 P 0 ;0
L 0.98856998 -2.06416004 1.03793002 -2.06416004 0 P 0 ;0
L 0.98856998 -2.06316004 1.03796004 -2.06316004 0 P 0 ;0
L 0.98856004 -2.06216004 1.03798996 -2.06216004 0 P 0 ;0
L 0.98855 -2.06116004 1.03801998 -2.06116004 0 P 0 ;0
L 0.98855 -2.06016004 1.03805 -2.06016004 0 P 0 ;0
L 0.98853996 -2.05916004 1.03808002 -2.05916004 0 P 0 ;0
L 0.98853996 -2.05816004 1.0381 -2.05816004 0 P 0 ;0
L 0.98853002 -2.05716004 1.03811998 -2.05716004 0 P 0 ;0
L 0.98848002 -2.05616004 1.03815 -2.05616004 0 P 0 ;0
L 0.98841004 -2.05516004 1.03818002 -2.05516004 0 P 0 ;0
L 0.98835 -2.05416004 1.0382 -2.05416004 0 P 0 ;0
L 0.98828002 -2.05316004 1.03821998 -2.05316004 0 P 0 ;0
L 0.98821004 -2.05216004 1.03825 -2.05216004 0 P 0 ;0
L 0.98815 -2.05116004 1.03826998 -2.05116004 0 P 0 ;0
L 0.98808996 -2.05016004 1.03828996 -2.05016004 0 P 0 ;0
L 0.98801998 -2.04916004 1.03831998 -2.04916004 0 P 0 ;0
L 0.98796004 -2.04816004 1.03833996 -2.04816004 0 P 0 ;0
L 0.98788996 -2.04716004 1.03836004 -2.04716004 0 P 0 ;0
L 0.98783002 -2.04616004 1.03838996 -2.04616004 0 P 0 ;0
L 0.98768996 -2.04516004 1.0384 -2.04516004 0 P 0 ;0
L 0.98756004 -2.04416004 1.03841004 -2.04416004 0 P 0 ;0
L 0.98738002 -2.04316004 1.03841998 -2.04316004 0 P 0 ;0
L 0.98716004 -2.04216004 1.03843002 -2.04216004 0 P 0 ;0
L 0.98691998 -2.04116004 1.03843996 -2.04116004 0 P 0 ;0
L 0.98661998 -2.04016004 1.03845 -2.04016004 0 P 0 ;0
L 0.98631998 -2.03916004 1.03846004 -2.03916004 0 P 0 ;0
L 0.98593996 -2.03816004 1.03846998 -2.03816004 0 P 0 ;0
L 0.98546998 -2.03716004 1.03848002 -2.03716004 0 P 0 ;0
L 0.98491004 -2.03616004 1.03846998 -2.03616004 0 P 0 ;0
L 0.98425 -2.03516004 1.03846004 -2.03516004 0 P 0 ;0
L 0.98346004 -2.03416004 1.03846004 -2.03416004 0 P 0 ;0
L 0.98251998 -2.03316004 1.03843996 -2.03316004 0 P 0 ;0
L 0.98138002 -2.03216004 1.03843002 -2.03216004 0 P 0 ;0
L 0.97998996 -2.03116004 1.03841998 -2.03116004 0 P 0 ;0
L 0.97813996 -2.03016004 1.03841004 -2.03016004 0 P 0 ;0
L 0.97491004 -2.02916004 1.0384 -2.02916004 0 P 0 ;0
L 0.94763996 -2.00716004 1.03293996 -2.00716004 0 P 0 ;0
L 0.94978996 -2.00616004 1.03231998 -2.00616004 0 P 0 ;0
L 0.95081004 -2.00516004 1.0317 -2.00516004 0 P 0 ;0
L 0.95183002 -2.00416004 1.03098002 -2.00416004 0 P 0 ;0
L 0.95285 -2.00316004 1.03023002 -2.00316004 0 P 0 ;0
L 0.95388996 -2.00216004 1.02936004 -2.00216004 0 P 0 ;0
L 0.95498002 -2.00116004 1.02841998 -2.00116004 0 P 0 ;0
L 0.95621998 -2.00016004 1.02738996 -2.00016004 0 P 0 ;0
L 0.95761998 -1.99916004 1.0262 -1.99916004 0 P 0 ;0
L 0.9592 -1.99816004 1.02486004 -1.99816004 0 P 0 ;0
L 0.96083996 -1.99716004 1.02335 -1.99716004 0 P 0 ;0
L 0.9627 -1.99616004 1.02161004 -1.99616004 0 P 0 ;0
L 0.96468996 -1.99516004 1.01951998 -1.99516004 0 P 0 ;0
L 0.96685 -1.99416004 1.01683002 -1.99416004 0 P 0 ;0
L 0.96936998 -1.99316004 1.01378002 -1.99316004 0 P 0 ;0
L 0.97236998 -1.99216004 1.00981004 -1.99216004 0 P 0 ;0
L 0.97676004 -1.99116004 1.00456998 -1.99116004 0 P 0 ;0
L 1.06713996 -2.08283002 1.12288002 -2.08283002 0 P 0 ;0
L 1.06698996 -2.08183002 1.12193996 -2.08183002 0 P 0 ;0
L 1.06686004 -2.08083002 1.12108996 -2.08083002 0 P 0 ;0
L 1.06673996 -2.07983002 1.12036004 -2.07983002 0 P 0 ;0
L 1.06661998 -2.07883002 1.11971998 -2.07883002 0 P 0 ;0
L 1.06653002 -2.07783002 1.11916004 -2.07783002 0 P 0 ;0
L 1.06648002 -2.07683002 1.11866004 -2.07683002 0 P 0 ;0
L 1.06641998 -2.07583002 1.11826004 -2.07583002 0 P 0 ;0
L 1.06636998 -2.07483002 1.11791998 -2.07483002 0 P 0 ;0
L 1.06631998 -2.07383002 1.11761998 -2.07383002 0 P 0 ;0
L 1.06626004 -2.07283002 1.11741998 -2.07283002 0 P 0 ;0
L 1.06621004 -2.07183002 1.11723996 -2.07183002 0 P 0 ;0
L 1.06616004 -2.07083002 1.11711998 -2.07083002 0 P 0 ;0
L 1.06616004 -2.06983002 1.11701004 -2.06983002 0 P 0 ;0
L 1.06616004 -2.06883002 1.11688996 -2.06883002 0 P 0 ;0
L 1.06616998 -2.06783002 1.11676998 -2.06783002 0 P 0 ;0
L 1.06618002 -2.06683002 1.11666998 -2.06683002 0 P 0 ;0
L 1.06618996 -2.06583002 1.11663002 -2.06583002 0 P 0 ;0
L 1.0662 -2.06483002 1.11658996 -2.06483002 0 P 0 ;0
L 1.06621004 -2.06383002 1.11656004 -2.06383002 0 P 0 ;0
L 1.06623002 -2.06283002 1.11651998 -2.06283002 0 P 0 ;0
L 1.06631004 -2.06183002 1.11648996 -2.06183002 0 P 0 ;0
L 1.06638002 -2.06083002 1.11653002 -2.06083002 0 P 0 ;0
L 1.06645 -2.05983002 1.11656998 -2.05983002 0 P 0 ;0
L 1.06651998 -2.05883002 1.11661998 -2.05883002 0 P 0 ;0
L 1.06658996 -2.05783002 1.11666004 -2.05783002 0 P 0 ;0
L 1.06666998 -2.05683002 1.11671004 -2.05683002 0 P 0 ;0
L 1.06673996 -2.05583002 1.11681004 -2.05583002 0 P 0 ;0
L 1.06686004 -2.05483002 1.11693002 -2.05483002 0 P 0 ;0
L 1.067 -2.05383002 1.11705 -2.05383002 0 P 0 ;0
L 1.06713996 -2.05283002 1.11718002 -2.05283002 0 P 0 ;0
L 1.06728002 -2.05183002 1.11731004 -2.05183002 0 P 0 ;0
L 1.06741998 -2.05083002 1.11746004 -2.05083002 0 P 0 ;0
L 1.06756004 -2.04983002 1.11766004 -2.04983002 0 P 0 ;0
L 1.0677 -2.04883002 1.11786004 -2.04883002 0 P 0 ;0
L 1.06786004 -2.04783002 1.11813996 -2.04783002 0 P 0 ;0
L 1.06806998 -2.04683002 1.11841998 -2.04683002 0 P 0 ;0
L 1.06828002 -2.04583002 1.11876998 -2.04583002 0 P 0 ;0
L 1.06848996 -2.04483002 1.11913002 -2.04483002 0 P 0 ;0
L 1.06871004 -2.04383002 1.11955 -2.04383002 0 P 0 ;0
L 1.06898996 -2.04283002 1.11998996 -2.04283002 0 P 0 ;0
L 1.06928002 -2.04183002 1.12048002 -2.04183002 0 P 0 ;0
L 1.06956004 -2.04083002 1.12101004 -2.04083002 0 P 0 ;0
L 1.06985 -2.03983002 1.12161998 -2.03983002 0 P 0 ;0
L 1.07021004 -2.03883002 1.12225 -2.03883002 0 P 0 ;0
L 1.07056998 -2.03783002 1.12298002 -2.03783002 0 P 0 ;0
L 1.07093002 -2.03683002 1.12373996 -2.03683002 0 P 0 ;0
L 1.07128996 -2.03583002 1.12461998 -2.03583002 0 P 0 ;0
L 1.07173002 -2.03483002 1.12548996 -2.03483002 0 P 0 ;0
L 1.07216998 -2.03383002 1.12646004 -2.03383002 0 P 0 ;0
L 1.07261998 -2.03283002 1.12748996 -2.03283002 0 P 0 ;0
L 1.07308002 -2.03183002 1.12855 -2.03183002 0 P 0 ;0
L 1.07361998 -2.03083002 1.12978996 -2.03083002 0 P 0 ;0
L 1.09761004 -1.91731004 1.12756998 -1.91731004 0 P 0 ;0
L 1.09566004 -1.91631004 1.12645 -1.91631004 0 P 0 ;0
L 1.09371004 -1.91531004 1.12533002 -1.91531004 0 P 0 ;0
L 1.09176004 -1.91431004 1.12416004 -1.91431004 0 P 0 ;0
L 1.08946004 -1.91331004 1.12283996 -1.91331004 0 P 0 ;0
L 1.07415 -2.02983002 1.13101998 -2.02983002 0 P 0 ;0
L 1.07468996 -2.02883002 1.13248996 -2.02883002 0 P 0 ;0
L 1.07528996 -2.02783002 1.134 -2.02783002 0 P 0 ;0
L 1.07591998 -2.02683002 1.13586004 -2.02683002 0 P 0 ;0
L 1.07656004 -2.02583002 1.13828996 -2.02583002 0 P 0 ;0
L 1.07721004 -2.02483002 1.14243002 -2.02483002 0 P 0 ;0
L 1.07795 -2.02383002 1.21126998 -2.02383002 0 P 0 ;0
L 1.07868002 -2.02283002 1.21133002 -2.02283002 0 P 0 ;0
L 1.07941998 -2.02183002 1.2114 -2.02183002 0 P 0 ;0
L 1.08021004 -2.02083002 1.21146004 -2.02083002 0 P 0 ;0
L 1.08103996 -2.01983002 1.21153002 -2.01983002 0 P 0 ;0
L 1.08186998 -2.01883002 1.2116 -2.01883002 0 P 0 ;0
L 1.08273002 -2.01783002 1.21166004 -2.01783002 0 P 0 ;0
L 1.08366998 -2.01683002 1.21173002 -2.01683002 0 P 0 ;0
L 1.0846 -2.01583002 1.2118 -2.01583002 0 P 0 ;0
L 1.08555 -2.01483002 1.21186004 -2.01483002 0 P 0 ;0
L 1.08661004 -2.01383002 1.21193002 -2.01383002 0 P 0 ;0
L 1.08766998 -2.01283002 1.21198996 -2.01283002 0 P 0 ;0
L 1.08873002 -2.01183002 1.21205 -2.01183002 0 P 0 ;0
L 1.0898 -2.01083002 1.21211998 -2.01083002 0 P 0 ;0
L 1.09098996 -2.00983002 1.21218002 -2.00983002 0 P 0 ;0
L 1.09225 -2.00883002 1.21223996 -2.00883002 0 P 0 ;0
L 1.09358996 -2.00783002 1.2123 -2.00783002 0 P 0 ;0
L 1.09506998 -2.00683002 1.21236004 -2.00683002 0 P 0 ;0
L 1.09668996 -2.00583002 1.21241998 -2.00583002 0 P 0 ;0
L 0.98546998 -2.12516004 1.03548996 -2.12516004 0 P 0 ;0
L 0.98558996 -2.12416004 1.03553996 -2.12416004 0 P 0 ;0
L 0.9857 -2.12316004 1.03558002 -2.12316004 0 P 0 ;0
L 0.98581004 -2.12216004 1.03561998 -2.12216004 0 P 0 ;0
L 0.98591004 -2.12116004 1.03566998 -2.12116004 0 P 0 ;0
L 0.98598996 -2.12016004 1.03571004 -2.12016004 0 P 0 ;0
L 0.98608002 -2.11916004 1.03575 -2.11916004 0 P 0 ;0
L 0.98616998 -2.11816004 1.0358 -2.11816004 0 P 0 ;0
L 0.98625 -2.11716004 1.03583996 -2.11716004 0 P 0 ;0
L 0.98633996 -2.11616004 1.03588002 -2.11616004 0 P 0 ;0
L 0.98641998 -2.11516004 1.03593002 -2.11516004 0 P 0 ;0
L 0.98651004 -2.11416004 1.03596998 -2.11416004 0 P 0 ;0
L 0.9866 -2.11316004 1.03601004 -2.11316004 0 P 0 ;0
L 0.98668002 -2.11216004 1.03605 -2.11216004 0 P 0 ;0
L 0.98676998 -2.11116004 1.0361 -2.11116004 0 P 0 ;0
L 0.98685 -2.11016004 1.03613996 -2.11016004 0 P 0 ;0
L 0.98693996 -2.10916004 1.03618002 -2.10916004 0 P 0 ;0
L 0.987 -2.10816004 1.03623002 -2.10816004 0 P 0 ;0
L 0.98705 -2.10716004 1.03626998 -2.10716004 0 P 0 ;0
L 0.9871 -2.10616004 1.03631004 -2.10616004 0 P 0 ;0
L 0.98716004 -2.10516004 1.03636004 -2.10516004 0 P 0 ;0
L 0.9872 -2.10416004 1.0364 -2.10416004 0 P 0 ;0
L 0.98725 -2.10316004 1.03643996 -2.10316004 0 P 0 ;0
L 0.98731004 -2.10216004 1.03648002 -2.10216004 0 P 0 ;0
L 0.98735 -2.10116004 1.03653002 -2.10116004 0 P 0 ;0
L 0.9874 -2.10016004 1.03656998 -2.10016004 0 P 0 ;0
L 0.98746004 -2.09916004 1.03661004 -2.09916004 0 P 0 ;0
L 0.98751004 -2.09816004 1.03666004 -2.09816004 0 P 0 ;0
L 0.98755 -2.09716004 1.0367 -2.09716004 0 P 0 ;0
L 0.9876 -2.09616004 1.03673996 -2.09616004 0 P 0 ;0
L 0.98766004 -2.09516004 1.03678996 -2.09516004 0 P 0 ;0
L 0.9877 -2.09416004 1.03683002 -2.09416004 0 P 0 ;0
L 0.98775 -2.09316004 1.03686998 -2.09316004 0 P 0 ;0
L 0.98781004 -2.09216004 1.03691998 -2.09216004 0 P 0 ;0
L 0.98785 -2.09116004 1.03696004 -2.09116004 0 P 0 ;0
L 0.9879 -2.09016004 1.037 -2.09016004 0 P 0 ;0
L 0.98796004 -2.08916004 1.03703996 -2.08916004 0 P 0 ;0
L 0.98798996 -2.08816004 1.03706998 -2.08816004 0 P 0 ;0
L 0.98801998 -2.08716004 1.03711004 -2.08716004 0 P 0 ;0
L 0.98805 -2.08616004 1.03715 -2.08616004 0 P 0 ;0
L 0.98808996 -2.08516004 1.03718996 -2.08516004 0 P 0 ;0
L 0.98811998 -2.08416004 1.03723002 -2.08416004 0 P 0 ;0
L 1.08216998 -2.15683002 1.19803996 -2.15683002 0 P 0 ;0
L 1.0821 -2.15583002 1.19861004 -2.15583002 0 P 0 ;0
L 1.08201998 -2.15483002 1.19918002 -2.15483002 0 P 0 ;0
L 1.08195 -2.15383002 1.1997 -2.15383002 0 P 0 ;0
L 1.08188996 -2.15283002 1.20018002 -2.15283002 0 P 0 ;0
L 1.08183002 -2.15183002 1.20066004 -2.15183002 0 P 0 ;0
L 1.08176998 -2.15083002 1.20113996 -2.15083002 0 P 0 ;0
L 1.08171998 -2.14983002 1.20153996 -2.14983002 0 P 0 ;0
L 1.08166004 -2.14883002 1.20193002 -2.14883002 0 P 0 ;0
L 1.0816 -2.14783002 1.11538996 -2.14783002 0 P 0 ;0
L 1.08155 -2.14683002 1.10903002 -2.14683002 0 P 0 ;0
L 1.0815 -2.14583002 1.10415 -2.14583002 0 P 0 ;0
L 1.08146004 -2.14483002 1.09953002 -2.14483002 0 P 0 ;0
L 1.08141004 -2.14383002 1.09563996 -2.14383002 0 P 0 ;0
L 1.08136004 -2.14283002 1.09183996 -2.14283002 0 P 0 ;0
L 1.08131004 -2.14183002 1.08821004 -2.14183002 0 P 0 ;0
L 1.08133002 -2.14083002 1.08471998 -2.14083002 0 P 0 ;0
L 1.09586998 -2.11983002 1.14965 -2.11983002 0 P 0 ;0
L 1.09361998 -2.11883002 1.15221998 -2.11883002 0 P 0 ;0
L 1.09158996 -2.11783002 1.20595 -2.11783002 0 P 0 ;0
L 1.08988002 -2.11683002 1.20601004 -2.11683002 0 P 0 ;0
L 1.08823996 -2.11583002 1.20606998 -2.11583002 0 P 0 ;0
L 1.08678996 -2.11483002 1.20613002 -2.11483002 0 P 0 ;0
L 1.08541004 -2.11383002 1.20618996 -2.11383002 0 P 0 ;0
L 1.08416998 -2.11283002 1.20625 -2.11283002 0 P 0 ;0
L 1.08295 -2.11183002 1.20631004 -2.11183002 0 P 0 ;0
L 1.08188002 -2.11083002 1.20638002 -2.11083002 0 P 0 ;0
L 1.08081998 -2.10983002 1.20643996 -2.10983002 0 P 0 ;0
L 1.07986004 -2.10883002 1.2065 -2.10883002 0 P 0 ;0
L 1.07895 -2.10783002 1.20656004 -2.10783002 0 P 0 ;0
L 1.07803002 -2.10683002 1.20661998 -2.10683002 0 P 0 ;0
L 1.07723996 -2.10583002 1.20666998 -2.10583002 0 P 0 ;0
L 1.07646004 -2.10483002 1.20671998 -2.10483002 0 P 0 ;0
L 1.07568002 -2.10383002 1.20678002 -2.10383002 0 P 0 ;0
L 1.075 -2.10283002 1.20683002 -2.10283002 0 P 0 ;0
L 1.07433002 -2.10183002 1.20688002 -2.10183002 0 P 0 ;0
L 1.07366998 -2.10083002 1.20693996 -2.10083002 0 P 0 ;0
L 1.07308996 -2.09983002 1.20698996 -2.09983002 0 P 0 ;0
L 1.07253002 -2.09883002 1.20705 -2.09883002 0 P 0 ;0
L 1.07198002 -2.09783002 1.2071 -2.09783002 0 P 0 ;0
L 1.07146998 -2.09683002 1.20715 -2.09683002 0 P 0 ;0
L 1.07101998 -2.09583002 1.2072 -2.09583002 0 P 0 ;0
L 1.07056998 -2.09483002 1.20726004 -2.09483002 0 P 0 ;0
L 1.07013002 -2.09383002 1.20731004 -2.09383002 0 P 0 ;0
L 1.06976998 -2.09283002 1.20736004 -2.09283002 0 P 0 ;0
L 1.06941998 -2.09183002 1.20741998 -2.09183002 0 P 0 ;0
L 1.06906004 -2.09083002 1.20746998 -2.09083002 0 P 0 ;0
L 1.06876004 -2.08983002 1.20753002 -2.08983002 0 P 0 ;0
L 1.06848996 -2.08883002 1.13443002 -2.08883002 0 P 0 ;0
L 1.06821998 -2.08783002 1.13068002 -2.08783002 0 P 0 ;0
L 1.06795 -2.08683002 1.12836998 -2.08683002 0 P 0 ;0
L 1.06771998 -2.08583002 1.1266 -2.08583002 0 P 0 ;0
L 1.06753002 -2.08483002 1.12516004 -2.08483002 0 P 0 ;0
L 1.06733002 -2.08383002 1.12393996 -2.08383002 0 P 0 ;0
L 0.90273996 -1.85456998 0.89068996 -1.85558002 0 P 0 ;0
L 0.89068996 -1.85558002 0.87421004 -1.85741998 0 P 0 ;0
L 0.87421004 -1.85741998 0.85783002 -1.85946998 0 P 0 ;0
L 0.85783002 -1.85946998 0.85526998 -1.8599 0 P 0 ;0
L 0.85526998 -1.8599 0.85276004 -1.86055 0 P 0 ;0
L 0.85276004 -1.86055 0.85255 -1.86063996 0 P 0 ;0
L 0.85255 -1.86063996 0.85248996 -1.86068996 0 P 0 ;0
L 0.85248996 -1.86068996 0.85243002 -1.86073002 0 P 0 ;0
L 0.85243002 -1.86073002 0.85238002 -1.86078002 0 P 0 ;0
L 0.85238002 -1.86078002 0.85233002 -1.86083996 0 P 0 ;0
L 0.85233002 -1.86083996 0.85225 -1.86096004 0 P 0 ;0
L 0.85225 -1.86096004 0.85218002 -1.8611 0 P 0 ;0
L 0.85218002 -1.8611 0.85216004 -1.86116998 0 P 0 ;0
L 0.85216004 -1.86116998 0.85215 -1.86123996 0 P 0 ;0
L 0.85215 -1.86123996 0.85213996 -1.86136998 0 P 0 ;0
L 0.85213996 -1.86136998 0.85213002 -1.86148996 0 P 0 ;0
L 0.85213002 -1.86148996 0.85213996 -1.86161998 0 P 0 ;0
L 0.85213996 -1.86161998 0.85215 -1.86173996 0 P 0 ;0
L 0.85215 -1.86173996 0.85218002 -1.86186998 0 P 0 ;0
L 0.85218002 -1.86186998 0.85221004 -1.86198996 0 P 0 ;0
L 0.85221004 -1.86198996 0.85225 -1.8621 0 P 0 ;0
L 0.85225 -1.8621 0.85231004 -1.86221998 0 P 0 ;0
L 0.85231004 -1.86221998 0.85236998 -1.86233002 0 P 0 ;0
L 0.85236998 -1.86233002 0.85281998 -1.863 0 P 0 ;0
L 0.85281998 -1.863 0.8533 -1.86363996 0 P 0 ;0
L 0.8533 -1.86363996 0.85383002 -1.86425 0 P 0 ;0
L 0.85383002 -1.86425 0.85736004 -1.86801998 0 P 0 ;0
L 0.85736004 -1.86801998 0.86013002 -1.87113002 0 P 0 ;0
L 0.86013002 -1.87113002 0.86266004 -1.87443002 0 P 0 ;0
L 0.86266004 -1.87443002 0.86501004 -1.87798996 0 P 0 ;0
L 0.86501004 -1.87798996 0.86711998 -1.88171004 0 P 0 ;0
L 0.86711998 -1.88171004 0.86896998 -1.88553996 0 P 0 ;0
L 0.86896998 -1.88553996 0.87055 -1.8895 0 P 0 ;0
L 0.87055 -1.8895 0.8718 -1.89343002 0 P 0 ;0
L 0.8718 -1.89343002 0.87276004 -1.89745 0 P 0 ;0
L 0.87276004 -1.89745 0.87371004 -1.90195 0 P 0 ;0
L 0.87371004 -1.90195 0.87383002 -1.90236004 0 P 0 ;0
L 0.87383002 -1.90236004 0.87396998 -1.90276004 0 P 0 ;0
L 0.87396998 -1.90276004 0.87416004 -1.90313996 0 P 0 ;0
L 0.87416004 -1.90313996 0.87436998 -1.90351004 0 P 0 ;0
L 0.87436998 -1.90351004 0.87443002 -1.9036 0 P 0 ;0
L 0.87443002 -1.9036 0.87456998 -1.90376004 0 P 0 ;0
L 0.87456998 -1.90376004 0.87465 -1.90381998 0 P 0 ;0
L 0.87465 -1.90381998 0.87473002 -1.90388996 0 P 0 ;0
L 0.87473002 -1.90388996 0.87481998 -1.90393996 0 P 0 ;0
L 0.87481998 -1.90393996 0.87491998 -1.90398996 0 P 0 ;0
L 0.87491998 -1.90398996 0.87501004 -1.90403002 0 P 0 ;0
L 0.87501004 -1.90403002 0.87521004 -1.90408996 0 P 0 ;0
L 0.87521004 -1.90408996 0.87531998 -1.9041 0 P 0 ;0
L 0.87531998 -1.9041 0.87573002 -1.90413002 0 P 0 ;0
L 0.87573002 -1.90413002 0.87613996 -1.90411998 0 P 0 ;0
L 0.87613996 -1.90411998 0.87653996 -1.90408002 0 P 0 ;0
L 0.87653996 -1.90408002 0.87695 -1.90401004 0 P 0 ;0
L 0.87695 -1.90401004 0.90756004 -1.89766998 0 P 0 ;0
L 0.90756004 -1.89766998 0.92603996 -1.89478002 0 P 0 ;0
L 0.92603996 -1.89478002 0.93486004 -1.89393996 0 P 0 ;0
L 0.93486004 -1.89393996 0.94371004 -1.8935 0 P 0 ;0
L 0.94371004 -1.8935 0.97045 -1.89308002 0 P 0 ;0
L 0.97045 -1.89308002 0.99468996 -1.89328996 0 P 0 ;0
L 0.99468996 -1.89328996 1.01021004 -1.89413996 0 P 0 ;0
L 1.01021004 -1.89413996 1.0241 -1.89601998 0 P 0 ;0
L 1.0241 -1.89601998 1.04188002 -1.89961004 0 P 0 ;0
L 1.04188002 -1.89961004 1.06095 -1.90466004 0 P 0 ;0
L 1.06095 -1.90466004 1.07963996 -1.91123002 0 P 0 ;0
L 1.07963996 -1.91123002 1.09093996 -1.91613002 0 P 0 ;0
L 1.09093996 -1.91613002 1.10186998 -1.92175 0 P 0 ;0
L 1.10186998 -1.92175 1.11243996 -1.92806998 0 P 0 ;0
L 1.11243996 -1.92806998 1.12163002 -1.93446998 0 P 0 ;0
L 1.12163002 -1.93446998 1.13033002 -1.94148996 0 P 0 ;0
L 1.13033002 -1.94148996 1.1385 -1.94911004 0 P 0 ;0
L 1.1385 -1.94911004 1.14358996 -1.9546 0 P 0 ;0
L 1.14358996 -1.9546 1.14825 -1.96045 0 P 0 ;0
L 1.14825 -1.96045 1.15246998 -1.96663002 0 P 0 ;0
L 1.15246998 -1.96663002 1.15623002 -1.97316004 0 P 0 ;0
L 1.15623002 -1.97316004 1.15895 -1.97831004 0 P 0 ;0
L 1.15895 -1.97831004 1.17358996 -1.97831004 0 P 0 ;0
L 1.17358996 -1.97831004 1.17135 -1.9726 0 P 0 ;0
L 1.17135 -1.9726 1.16696004 -1.96266998 0 P 0 ;0
L 1.16696004 -1.96266998 1.16171998 -1.95313002 0 P 0 ;0
L 1.16171998 -1.95313002 1.1557 -1.94406998 0 P 0 ;0
L 1.1557 -1.94406998 1.14885 -1.93548002 0 P 0 ;0
L 1.14885 -1.93548002 1.13778996 -1.92378002 0 P 0 ;0
L 1.13778996 -1.92378002 1.12576998 -1.91301998 0 P 0 ;0
L 1.12576998 -1.91301998 1.11283996 -1.90326004 0 P 0 ;0
L 1.11283996 -1.90326004 1.09783002 -1.89368996 0 P 0 ;0
L 1.09783002 -1.89368996 1.08213002 -1.88526998 0 P 0 ;0
L 1.08213002 -1.88526998 1.06576998 -1.87801004 0 P 0 ;0
L 1.06576998 -1.87801004 1.04776004 -1.87141998 0 P 0 ;0
L 1.04776004 -1.87141998 1.02938002 -1.86591998 0 P 0 ;0
L 1.02938002 -1.86591998 1.01058002 -1.8615 0 P 0 ;0
L 1.01058002 -1.8615 0.98441998 -1.85711004 0 P 0 ;0
L 0.98441998 -1.85711004 0.95781004 -1.85448996 0 P 0 ;0
L 0.95781004 -1.85448996 0.93061004 -1.85366004 0 P 0 ;0
L 0.93061004 -1.85366004 0.90273996 -1.85456998 0 P 0 ;0
L 1.16015 -1.97631004 1.15798002 -1.97218996 0 P 0 ;0
L 1.15798002 -1.97218996 1.15796004 -1.97216004 0 P 0 ;0
L 1.15796004 -1.97216004 1.15416004 -1.96556998 0 P 0 ;0
L 1.15416004 -1.96556998 1.15411998 -1.96551004 0 P 0 ;0
L 1.15411998 -1.96551004 1.14986004 -1.95926004 0 P 0 ;0
L 1.14986004 -1.95926004 1.14981998 -1.95921004 0 P 0 ;0
L 1.14981998 -1.95921004 1.14511004 -1.9533 0 P 0 ;0
L 1.14511004 -1.9533 1.13991998 -1.9477 0 P 0 ;0
L 1.13991998 -1.9477 1.13986004 -1.94765 0 P 0 ;0
L 1.13986004 -1.94765 1.13163996 -1.93998002 0 P 0 ;0
L 1.13163996 -1.93998002 1.12283002 -1.93286004 0 P 0 ;0
L 1.12283002 -1.93286004 1.11351998 -1.92638996 0 P 0 ;0
L 1.11351998 -1.92638996 1.10283996 -1.92 0 P 0 ;0
L 1.10283996 -1.92 1.0918 -1.91433002 0 P 0 ;0
L 1.0918 -1.91433002 1.08036998 -1.90936004 0 P 0 ;0
L 1.08036998 -1.90936004 1.06153002 -1.90273996 0 P 0 ;0
L 1.06153002 -1.90273996 1.06146004 -1.90273002 0 P 0 ;0
L 1.06146004 -1.90273002 1.04233002 -1.89766004 0 P 0 ;0
L 1.04233002 -1.89766004 1.02443002 -1.89405 0 P 0 ;0
L 1.02443002 -1.89405 1.0104 -1.89213996 0 P 0 ;0
L 1.0104 -1.89213996 0.99475 -1.89128996 0 P 0 ;0
L 0.99475 -1.89128996 0.97045 -1.89108002 0 P 0 ;0
L 0.97045 -1.89108002 0.94365 -1.8915 0 P 0 ;0
L 0.94365 -1.8915 0.94361998 -1.8915 0 P 0 ;0
L 0.94361998 -1.8915 0.93471998 -1.89195 0 P 0 ;0
L 0.93471998 -1.89195 0.92578996 -1.89278996 0 P 0 ;0
L 0.92578996 -1.89278996 0.9072 -1.89571004 0 P 0 ;0
L 0.9072 -1.89571004 0.87656998 -1.90203996 0 P 0 ;0
L 0.87656998 -1.90203996 0.87626998 -1.9021 0 P 0 ;0
L 0.87626998 -1.9021 0.87601998 -1.90211998 0 P 0 ;0
L 0.87601998 -1.90211998 0.87588996 -1.90213002 0 P 0 ;0
L 0.87588996 -1.90213002 0.87583002 -1.90198996 0 P 0 ;0
L 0.87583002 -1.90198996 0.87573002 -1.90175 0 P 0 ;0
L 0.87573002 -1.90175 0.87566004 -1.90146998 0 P 0 ;0
L 0.87566004 -1.90146998 0.87471004 -1.89701004 0 P 0 ;0
L 0.87471004 -1.89701004 0.8747 -1.89698996 0 P 0 ;0
L 0.8747 -1.89698996 0.87373002 -1.89288996 0 P 0 ;0
L 0.87373002 -1.89288996 0.87243002 -1.88881998 0 P 0 ;0
L 0.87243002 -1.88881998 0.8724 -1.88876004 0 P 0 ;0
L 0.8724 -1.88876004 0.8708 -1.88473996 0 P 0 ;0
L 0.8708 -1.88473996 0.8689 -1.88078002 0 P 0 ;0
L 0.8689 -1.88078002 0.86671998 -1.87693996 0 P 0 ;0
L 0.86671998 -1.87693996 0.86428996 -1.87326004 0 P 0 ;0
L 0.86428996 -1.87326004 0.86166998 -1.86985 0 P 0 ;0
L 0.86166998 -1.86985 0.85883996 -1.86668002 0 P 0 ;0
L 0.85883996 -1.86668002 0.85883002 -1.86666004 0 P 0 ;0
L 0.85883002 -1.86666004 0.85531998 -1.86291004 0 P 0 ;0
L 0.85531998 -1.86291004 0.85486004 -1.86238002 0 P 0 ;0
L 0.85486004 -1.86238002 0.85466004 -1.86211998 0 P 0 ;0
L 0.85466004 -1.86211998 0.8557 -1.86186004 0 P 0 ;0
L 0.8557 -1.86186004 0.85811998 -1.86145 0 P 0 ;0
L 0.85811998 -1.86145 0.87443996 -1.85941004 0 P 0 ;0
L 0.87443996 -1.85941004 0.89088996 -1.85756998 0 P 0 ;0
L 0.89088996 -1.85756998 0.90286004 -1.85656998 0 P 0 ;0
L 0.90286004 -1.85656998 0.93061004 -1.85566004 0 P 0 ;0
L 0.93061004 -1.85566004 0.95768002 -1.85648996 0 P 0 ;0
L 0.95768002 -1.85648996 0.98416004 -1.8591 0 P 0 ;0
L 0.98416004 -1.8591 1.01018996 -1.86346004 0 P 0 ;0
L 1.01018996 -1.86346004 1.02886004 -1.86785 0 P 0 ;0
L 1.02886004 -1.86785 1.04711998 -1.87331998 0 P 0 ;0
L 1.04711998 -1.87331998 1.06501004 -1.87986004 0 P 0 ;0
L 1.06501004 -1.87986004 1.08125 -1.88706998 0 P 0 ;0
L 1.08125 -1.88706998 1.09681004 -1.89541998 0 P 0 ;0
L 1.09681004 -1.89541998 1.1117 -1.9049 0 P 0 ;0
L 1.1117 -1.9049 1.1245 -1.91456998 0 P 0 ;0
L 1.1245 -1.91456998 1.13638996 -1.92521004 0 P 0 ;0
L 1.13638996 -1.92521004 1.14733996 -1.93678996 0 P 0 ;0
L 1.14733996 -1.93678996 1.15408002 -1.94525 0 P 0 ;0
L 1.15408002 -1.94525 1.16001004 -1.95416998 0 P 0 ;0
L 1.16001004 -1.95416998 1.16516004 -1.96355 0 P 0 ;0
L 1.16516004 -1.96355 1.1695 -1.97336998 0 P 0 ;0
L 1.1695 -1.97336998 1.17066004 -1.97631004 0 P 0 ;0
L 1.17066004 -1.97631004 1.16015 -1.97631004 0 P 0 ;0
L 0.87563002 -1.90131004 0.8801 -1.90131004 0 P 0 ;0
L 0.87541004 -1.90031004 0.88493996 -1.90031004 0 P 0 ;0
L 0.8752 -1.89931004 0.88976998 -1.89931004 0 P 0 ;0
L 0.87498996 -1.89831004 0.8946 -1.89831004 0 P 0 ;0
L 0.89423002 -2.08316004 0.94355 -2.08316004 0 P 0 ;0
L 0.89428996 -2.08216004 0.9436 -2.08216004 0 P 0 ;0
L 0.89435 -2.08116004 0.94365 -2.08116004 0 P 0 ;0
L 0.89441004 -2.08016004 0.9437 -2.08016004 0 P 0 ;0
L 0.89446004 -2.07916004 0.94375 -2.07916004 0 P 0 ;0
L 0.89451998 -2.07816004 0.94378996 -2.07816004 0 P 0 ;0
L 0.89458002 -2.07716004 0.94383996 -2.07716004 0 P 0 ;0
L 0.89463996 -2.07616004 0.94388996 -2.07616004 0 P 0 ;0
L 0.8947 -2.07516004 0.94393996 -2.07516004 0 P 0 ;0
L 0.89475 -2.07416004 0.94398002 -2.07416004 0 P 0 ;0
L 0.89481004 -2.07316004 0.94403002 -2.07316004 0 P 0 ;0
L 0.89486998 -2.07216004 0.94408002 -2.07216004 0 P 0 ;0
L 0.89493002 -2.07116004 0.94415 -2.07116004 0 P 0 ;0
L 0.89498996 -2.07016004 0.94426004 -2.07016004 0 P 0 ;0
L 0.89505 -2.06916004 0.94436998 -2.06916004 0 P 0 ;0
L 0.8951 -2.06816004 0.94448002 -2.06816004 0 P 0 ;0
L 0.89516004 -2.06716004 0.94458996 -2.06716004 0 P 0 ;0
L 0.89521998 -2.06616004 0.9447 -2.06616004 0 P 0 ;0
L 0.89526998 -2.06516004 0.94481004 -2.06516004 0 P 0 ;0
L 0.89531004 -2.06416004 0.94491998 -2.06416004 0 P 0 ;0
L 0.89535 -2.06316004 0.94503002 -2.06316004 0 P 0 ;0
L 0.8954 -2.06216004 0.94513996 -2.06216004 0 P 0 ;0
L 0.89543996 -2.06116004 0.94531998 -2.06116004 0 P 0 ;0
L 0.89548996 -2.06016004 0.94551004 -2.06016004 0 P 0 ;0
L 0.89553002 -2.05916004 0.9457 -2.05916004 0 P 0 ;0
L 0.89558002 -2.05816004 0.94588996 -2.05816004 0 P 0 ;0
L 0.89561998 -2.05716004 0.94608002 -2.05716004 0 P 0 ;0
L 0.89566998 -2.05616004 0.94626998 -2.05616004 0 P 0 ;0
L 0.89571004 -2.05516004 0.94646998 -2.05516004 0 P 0 ;0
L 0.89575 -2.05416004 0.94666004 -2.05416004 0 P 0 ;0
L 0.8958 -2.05316004 0.94685 -2.05316004 0 P 0 ;0
L 0.89583996 -2.05216004 0.94708002 -2.05216004 0 P 0 ;0
L 0.89588996 -2.05116004 0.94735 -2.05116004 0 P 0 ;0
L 0.89593996 -2.05016004 0.94761998 -2.05016004 0 P 0 ;0
L 0.89598002 -2.04916004 0.9479 -2.04916004 0 P 0 ;0
L 0.89601998 -2.04816004 0.94825 -2.04816004 0 P 0 ;0
L 0.89606998 -2.04716004 0.94858996 -2.04716004 0 P 0 ;0
L 0.89611004 -2.04616004 0.94893002 -2.04616004 0 P 0 ;0
L 0.89616004 -2.04516004 0.94935 -2.04516004 0 P 0 ;0
L 0.8962 -2.04416004 0.94976998 -2.04416004 0 P 0 ;0
L 0.89625 -2.04316004 0.9502 -2.04316004 0 P 0 ;0
L 0.89628002 -2.04216004 0.95068996 -2.04216004 0 P 0 ;0
L 0.89631004 -2.04116004 0.95118996 -2.04116004 0 P 0 ;0
L 0.89633996 -2.04016004 0.95168996 -2.04016004 0 P 0 ;0
L 0.89638002 -2.03916004 0.95228002 -2.03916004 0 P 0 ;0
L 0.89641004 -2.03816004 0.95291004 -2.03816004 0 P 0 ;0
L 0.89643996 -2.03716004 0.95363002 -2.03716004 0 P 0 ;0
L 0.89646998 -2.03616004 0.95445 -2.03616004 0 P 0 ;0
L 0.89651004 -2.03516004 0.95535 -2.03516004 0 P 0 ;0
L 0.89653996 -2.03416004 0.95636998 -2.03416004 0 P 0 ;0
L 0.89656998 -2.03316004 0.95756998 -2.03316004 0 P 0 ;0
L 0.8966 -2.03216004 0.95893996 -2.03216004 0 P 0 ;0
L 0.89663996 -2.03116004 0.96055 -2.03116004 0 P 0 ;0
L 0.89666998 -2.03016004 0.96278002 -2.03016004 0 P 0 ;0
L 0.8967 -2.02916004 0.96676004 -2.02916004 0 P 0 ;0
L 0.89673996 -2.02816004 1.03838996 -2.02816004 0 P 0 ;0
L 0.89676998 -2.02716004 1.03838002 -2.02716004 0 P 0 ;0
L 0.8968 -2.02616004 1.03833996 -2.02616004 0 P 0 ;0
L 0.89683996 -2.02516004 1.03828996 -2.02516004 0 P 0 ;0
L 0.89686998 -2.02416004 1.03823002 -2.02416004 0 P 0 ;0
L 0.8969 -2.02316004 1.03816004 -2.02316004 0 P 0 ;0
L 0.89693996 -2.02216004 1.0381 -2.02216004 0 P 0 ;0
L 0.89696998 -2.02116004 1.03803996 -2.02116004 0 P 0 ;0
L 0.897 -2.02016004 1.0379 -2.02016004 0 P 0 ;0
L 0.89703002 -2.01916004 1.03773996 -2.01916004 0 P 0 ;0
L 0.89706004 -2.01816004 1.03751998 -2.01816004 0 P 0 ;0
L 0.89708996 -2.01716004 1.03728002 -2.01716004 0 P 0 ;0
L 0.89711998 -2.01616004 1.03698996 -2.01616004 0 P 0 ;0
L 0.89713996 -2.01516004 1.03668002 -2.01516004 0 P 0 ;0
L 0.89716998 -2.01416004 1.03631004 -2.01416004 0 P 0 ;0
L 0.8972 -2.01316004 1.03591998 -2.01316004 0 P 0 ;0
L 0.89721998 -2.01216004 1.03548996 -2.01216004 0 P 0 ;0
L 0.89725 -2.01116004 1.03505 -2.01116004 0 P 0 ;0
L 0.89726998 -2.01016004 1.03458002 -2.01016004 0 P 0 ;0
L 0.8973 -2.00916004 1.03405 -2.00916004 0 P 0 ;0
L 0.89733002 -2.00816004 1.03351998 -2.00816004 0 P 0 ;0
L 0.89736004 -2.00716004 0.94676004 -2.00716004 0 P 0 ;0
L 0.89738002 -2.00616004 0.9461 -2.00616004 0 P 0 ;0
L 0.89741004 -2.00516004 0.94563996 -2.00516004 0 P 0 ;0
L 0.89743996 -2.00416004 0.94563996 -2.00416004 0 P 0 ;0
L 0.89746004 -2.00316004 0.94563996 -2.00316004 0 P 0 ;0
L 0.89748996 -2.00216004 0.94563996 -2.00216004 0 P 0 ;0
L 0.89751004 -2.00116004 0.94563996 -2.00116004 0 P 0 ;0
L 0.89753996 -2.00016004 0.94563996 -2.00016004 0 P 0 ;0
L 0.89756998 -1.99916004 0.94563996 -1.99916004 0 P 0 ;0
L 0.8976 -1.99816004 0.94563996 -1.99816004 0 P 0 ;0
L 0.89761998 -1.99716004 0.94563996 -1.99716004 0 P 0 ;0
L 0.89765 -1.99616004 0.94563996 -1.99616004 0 P 0 ;0
L 0.89768002 -1.99516004 0.94563996 -1.99516004 0 P 0 ;0
L 0.97546998 -1.98933996 0.97236998 -1.99006004 0 P 0 ;0
L 0.97236998 -1.99006004 0.96931998 -1.99103002 0 P 0 ;0
L 0.96931998 -1.99103002 0.96603002 -1.99233002 0 P 0 ;0
L 0.96603002 -1.99233002 0.96281004 -1.99383002 0 P 0 ;0
L 0.96281004 -1.99383002 0.95976004 -1.99546998 0 P 0 ;0
L 0.95976004 -1.99546998 0.95681004 -1.99728996 0 P 0 ;0
L 0.95681004 -1.99728996 0.95521004 -1.99841004 0 P 0 ;0
L 0.95521004 -1.99841004 0.95368996 -1.99963002 0 P 0 ;0
L 0.95368996 -1.99963002 0.95223996 -2.00095 0 P 0 ;0
L 0.95223996 -2.00095 0.94763996 -2.00546998 0 P 0 ;0
L 0.94763996 -2.00546998 0.94763996 -1.99243996 0 P 0 ;0
L 0.94763996 -1.99243996 0.89575 -1.99243996 0 P 0 ;0
L 0.89575 -1.99243996 0.89505 -2.01878002 0 P 0 ;0
L 0.89505 -2.01878002 0.89423996 -2.04316004 0 P 0 ;0
L 0.89423996 -2.04316004 0.89321998 -2.0661 0 P 0 ;0
L 0.89321998 -2.0661 0.89198996 -2.08728996 0 P 0 ;0
L 0.89198996 -2.08728996 0.89055 -2.1063 0 P 0 ;0
L 0.89055 -2.1063 0.88993996 -2.11358002 0 P 0 ;0
L 0.88993996 -2.11358002 0.88943002 -2.11988002 0 P 0 ;0
L 0.88943002 -2.11988002 0.88898996 -2.12533996 0 P 0 ;0
L 0.88898996 -2.12533996 0.88896004 -2.12613002 0 P 0 ;0
L 0.88896004 -2.12613002 0.88896998 -2.12621004 0 P 0 ;0
L 0.88896998 -2.12621004 0.88898002 -2.12625 0 P 0 ;0
L 0.88898002 -2.12625 0.88898996 -2.12628002 0 P 0 ;0
L 0.88898996 -2.12628002 0.88901998 -2.12636004 0 P 0 ;0
L 0.88901998 -2.12636004 0.88903996 -2.12638996 0 P 0 ;0
L 0.88903996 -2.12638996 0.88906998 -2.12641998 0 P 0 ;0
L 0.88906998 -2.12641998 0.88908996 -2.12645 0 P 0 ;0
L 0.88908996 -2.12645 0.88911998 -2.12646998 0 P 0 ;0
L 0.88911998 -2.12646998 0.88915 -2.1265 0 P 0 ;0
L 0.88915 -2.1265 0.88921004 -2.12653996 0 P 0 ;0
L 0.88921004 -2.12653996 0.88925 -2.12655 0 P 0 ;0
L 0.88925 -2.12655 0.88928002 -2.12656004 0 P 0 ;0
L 0.88928002 -2.12656004 0.88931998 -2.12658002 0 P 0 ;0
L 0.88931998 -2.12658002 0.8894 -2.12658002 0 P 0 ;0
L 0.8894 -2.12658002 0.89648002 -2.12686998 0 P 0 ;0
L 0.89648002 -2.12686998 0.90518996 -2.1271 0 P 0 ;0
L 0.90518996 -2.1271 0.9165 -2.12716004 0 P 0 ;0
L 0.9165 -2.12716004 0.94403996 -2.12716004 0 P 0 ;0
L 0.94403996 -2.12716004 0.94468996 -2.10135 0 P 0 ;0
L 0.94468996 -2.10135 0.9461 -2.07171998 0 P 0 ;0
L 0.9461 -2.07171998 0.94713002 -2.06233002 0 P 0 ;0
L 0.94713002 -2.06233002 0.9489 -2.05308002 0 P 0 ;0
L 0.9489 -2.05308002 0.94975 -2.04995 0 P 0 ;0
L 0.94975 -2.04995 0.9508 -2.04688996 0 P 0 ;0
L 0.9508 -2.04688996 0.95205 -2.0439 0 P 0 ;0
L 0.95205 -2.0439 0.95351004 -2.041 0 P 0 ;0
L 0.95351004 -2.041 0.9544 -2.03951004 0 P 0 ;0
L 0.9544 -2.03951004 0.95541998 -2.03811004 0 P 0 ;0
L 0.95541998 -2.03811004 0.95655 -2.03678996 0 P 0 ;0
L 0.95655 -2.03678996 0.95778996 -2.03556998 0 P 0 ;0
L 0.95778996 -2.03556998 0.95911998 -2.03446998 0 P 0 ;0
L 0.95911998 -2.03446998 0.96056998 -2.03346998 0 P 0 ;0
L 0.96056998 -2.03346998 0.96151004 -2.03291004 0 P 0 ;0
L 0.96151004 -2.03291004 0.96248996 -2.03243002 0 P 0 ;0
L 0.96248996 -2.03243002 0.96351004 -2.03201998 0 P 0 ;0
L 0.96351004 -2.03201998 0.96455 -2.03168996 0 P 0 ;0
L 0.96455 -2.03168996 0.96613002 -2.0313 0 P 0 ;0
L 0.96613002 -2.0313 0.96773002 -2.03101998 0 P 0 ;0
L 0.96773002 -2.03101998 0.96935 -2.03086004 0 P 0 ;0
L 0.96935 -2.03086004 0.97095 -2.03081004 0 P 0 ;0
L 0.97095 -2.03081004 0.97255 -2.03086998 0 P 0 ;0
L 0.97255 -2.03086998 0.97413002 -2.03105 0 P 0 ;0
L 0.97413002 -2.03105 0.97513002 -2.03123996 0 P 0 ;0
L 0.97513002 -2.03123996 0.9761 -2.03151004 0 P 0 ;0
L 0.9761 -2.03151004 0.97706004 -2.03186004 0 P 0 ;0
L 0.97706004 -2.03186004 0.97796998 -2.0323 0 P 0 ;0
L 0.97796998 -2.0323 0.97885 -2.0328 0 P 0 ;0
L 0.97885 -2.0328 0.97968002 -2.03336998 0 P 0 ;0
L 0.97968002 -2.03336998 0.98046998 -2.03398996 0 P 0 ;0
L 0.98046998 -2.03398996 0.98121998 -2.03468002 0 P 0 ;0
L 0.98121998 -2.03468002 0.98191004 -2.03541998 0 P 0 ;0
L 0.98191004 -2.03541998 0.98253996 -2.0362 0 P 0 ;0
L 0.98253996 -2.0362 0.9831 -2.03703002 0 P 0 ;0
L 0.9831 -2.03703002 0.9836 -2.03788996 0 P 0 ;0
L 0.9836 -2.03788996 0.98403996 -2.0388 0 P 0 ;0
L 0.98403996 -2.0388 0.9844 -2.03973996 0 P 0 ;0
L 0.9844 -2.03973996 0.98505 -2.04188996 0 P 0 ;0
L 0.98505 -2.04188996 0.98553002 -2.04408002 0 P 0 ;0
L 0.98553002 -2.04408002 0.98583002 -2.0463 0 P 0 ;0
L 0.98583002 -2.0463 0.98653002 -2.05705 0 P 0 ;0
L 0.98653002 -2.05705 0.9866 -2.06961004 0 P 0 ;0
L 0.9866 -2.06961004 0.98596004 -2.08908002 0 P 0 ;0
L 0.98596004 -2.08908002 0.98498002 -2.10858002 0 P 0 ;0
L 0.98498002 -2.10858002 0.98388002 -2.12146998 0 P 0 ;0
L 0.98388002 -2.12146998 0.98323002 -2.12716004 0 P 0 ;0
L 0.98323002 -2.12716004 1.03741004 -2.12716004 0 P 0 ;0
L 1.03741004 -2.12716004 1.03896004 -2.09103002 0 P 0 ;0
L 1.03896004 -2.09103002 1.03956004 -2.0759 0 P 0 ;0
L 1.03956004 -2.0759 1.04005 -2.06025 0 P 0 ;0
L 1.04005 -2.06025 1.04038996 -2.04626004 0 P 0 ;0
L 1.04038996 -2.04626004 1.04048002 -2.03698996 0 P 0 ;0
L 1.04048002 -2.03698996 1.04036998 -2.02651998 0 P 0 ;0
L 1.04036998 -2.02651998 1.04003996 -2.02096998 0 P 0 ;0
L 1.04003996 -2.02096998 1.03975 -2.01895 0 P 0 ;0
L 1.03975 -2.01895 1.0393 -2.01693996 0 P 0 ;0
L 1.0393 -2.01693996 1.03868996 -2.01483996 0 P 0 ;0
L 1.03868996 -2.01483996 1.03793996 -2.01278002 0 P 0 ;0
L 1.03793996 -2.01278002 1.03658996 -2.00968002 0 P 0 ;0
L 1.03658996 -2.00968002 1.03501004 -2.00668996 0 P 0 ;0
L 1.03501004 -2.00668996 1.0332 -2.0038 0 P 0 ;0
L 1.0332 -2.0038 1.03186998 -2.002 0 P 0 ;0
L 1.03186998 -2.002 1.0304 -2.0003 0 P 0 ;0
L 1.0304 -2.0003 1.0288 -1.99873002 0 P 0 ;0
L 1.0288 -1.99873002 1.02708002 -1.99728996 0 P 0 ;0
L 1.02708002 -1.99728996 1.02518002 -1.99593002 0 P 0 ;0
L 1.02518002 -1.99593002 1.02318002 -1.99471998 0 P 0 ;0
L 1.02318002 -1.99471998 1.0211 -1.99365 0 P 0 ;0
L 1.0211 -1.99365 1.01893002 -1.99273996 0 P 0 ;0
L 1.01893002 -1.99273996 1.01358996 -1.99098996 0 P 0 ;0
L 1.01358996 -1.99098996 1.0081 -1.98971004 0 P 0 ;0
L 1.0081 -1.98971004 1.00428996 -1.98908996 0 P 0 ;0
L 1.00428996 -1.98908996 1.00043996 -1.98868002 0 P 0 ;0
L 1.00043996 -1.98868002 0.99138002 -1.98826004 0 P 0 ;0
L 0.99138002 -1.98826004 0.98251998 -1.98846998 0 P 0 ;0
L 0.98251998 -1.98846998 0.97898996 -1.98878996 0 P 0 ;0
L 0.97898996 -1.98878996 0.97546998 -1.98933996 0 P 0 ;0
L 0.91651004 -2.12516004 0.94208996 -2.12516004 0 P 0 ;0
L 0.8911 -2.12416004 0.94211004 -2.12416004 0 P 0 ;0
L 0.89118002 -2.12316004 0.94213996 -2.12316004 0 P 0 ;0
L 0.89125 -2.12216004 0.94216004 -2.12216004 0 P 0 ;0
L 0.89133002 -2.12116004 0.94218996 -2.12116004 0 P 0 ;0
L 0.89141004 -2.12016004 0.94221004 -2.12016004 0 P 0 ;0
L 0.89148996 -2.11916004 0.94223996 -2.11916004 0 P 0 ;0
L 0.89156998 -2.11816004 0.94226998 -2.11816004 0 P 0 ;0
L 0.89166004 -2.11716004 0.94228996 -2.11716004 0 P 0 ;0
L 0.89173996 -2.11616004 0.94231004 -2.11616004 0 P 0 ;0
L 0.89181998 -2.11516004 0.94233996 -2.11516004 0 P 0 ;0
L 0.8919 -2.11416004 0.94236004 -2.11416004 0 P 0 ;0
L 0.89198002 -2.11316004 0.94238996 -2.11316004 0 P 0 ;0
L 0.89206998 -2.11216004 0.94241998 -2.11216004 0 P 0 ;0
L 0.89215 -2.11116004 0.94243996 -2.11116004 0 P 0 ;0
L 0.89223002 -2.11016004 0.94246998 -2.11016004 0 P 0 ;0
L 0.89231998 -2.10916004 0.94248996 -2.10916004 0 P 0 ;0
L 0.8924 -2.10816004 0.94251998 -2.10816004 0 P 0 ;0
L 0.89248002 -2.10716004 0.94255 -2.10716004 0 P 0 ;0
L 0.89256998 -2.10616004 0.94256998 -2.10616004 0 P 0 ;0
L 0.89263996 -2.10516004 0.94258996 -2.10516004 0 P 0 ;0
L 0.89271004 -2.10416004 0.94261998 -2.10416004 0 P 0 ;0
L 0.89278996 -2.10316004 0.94263996 -2.10316004 0 P 0 ;0
L 0.89286998 -2.10216004 0.94266998 -2.10216004 0 P 0 ;0
L 0.89293996 -2.10116004 0.9427 -2.10116004 0 P 0 ;0
L 0.89301998 -2.10016004 0.94275 -2.10016004 0 P 0 ;0
L 0.89308996 -2.09916004 0.94278996 -2.09916004 0 P 0 ;0
L 0.89316998 -2.09816004 0.94283996 -2.09816004 0 P 0 ;0
L 0.89325 -2.09716004 0.94288996 -2.09716004 0 P 0 ;0
L 0.89331998 -2.09616004 0.94293996 -2.09616004 0 P 0 ;0
L 0.8934 -2.09516004 0.94298002 -2.09516004 0 P 0 ;0
L 0.89346998 -2.09416004 0.94303002 -2.09416004 0 P 0 ;0
L 0.89355 -2.09316004 0.94308002 -2.09316004 0 P 0 ;0
L 0.89361998 -2.09216004 0.94313002 -2.09216004 0 P 0 ;0
L 0.8937 -2.09116004 0.94318002 -2.09116004 0 P 0 ;0
L 0.89378002 -2.09016004 0.94321998 -2.09016004 0 P 0 ;0
L 0.89385 -2.08916004 0.94326998 -2.08916004 0 P 0 ;0
L 0.89393002 -2.08816004 0.94331998 -2.08816004 0 P 0 ;0
L 0.894 -2.08716004 0.94336004 -2.08716004 0 P 0 ;0
L 0.89406004 -2.08616004 0.94341004 -2.08616004 0 P 0 ;0
L 0.89411998 -2.08516004 0.94346004 -2.08516004 0 P 0 ;0
L 0.89418002 -2.08416004 0.94351004 -2.08416004 0 P 0 ;0
L 0.91651004 -2.12516004 0.90521998 -2.1251 0 P 0 ;0
L 0.90521998 -2.1251 0.89655 -2.12486998 0 P 0 ;0
L 0.89655 -2.12486998 0.89106004 -2.12465 0 P 0 ;0
L 0.89106004 -2.12465 0.89141998 -2.12003996 0 P 0 ;0
L 0.89141998 -2.12003996 0.89193996 -2.11373996 0 P 0 ;0
L 0.89193996 -2.11373996 0.89253996 -2.10645 0 P 0 ;0
L 0.89253996 -2.10645 0.89398002 -2.08741998 0 P 0 ;0
L 0.89398002 -2.08741998 0.89521998 -2.06621998 0 P 0 ;0
L 0.89521998 -2.06621998 0.89521998 -2.06618996 0 P 0 ;0
L 0.89521998 -2.06618996 0.89623996 -2.04323002 0 P 0 ;0
L 0.89623996 -2.04323002 0.89703996 -2.01883002 0 P 0 ;0
L 0.89703996 -2.01883002 0.8977 -1.99443996 0 P 0 ;0
L 0.8977 -1.99443996 0.94563996 -1.99443996 0 P 0 ;0
L 0.94563996 -1.99443996 0.94563996 -2.00546998 0 P 0 ;0
L 0.94563996 -2.00546998 0.94686004 -2.00731004 0 P 0 ;0
L 0.94686004 -2.00731004 0.94903002 -2.00688996 0 P 0 ;0
L 0.94903002 -2.00688996 0.95361998 -2.00241004 0 P 0 ;0
L 0.95361998 -2.00241004 0.95498996 -2.00115 0 P 0 ;0
L 0.95498996 -2.00115 0.95641998 -2.00001004 0 P 0 ;0
L 0.95641998 -2.00001004 0.9579 -1.99896004 0 P 0 ;0
L 0.9579 -1.99896004 0.96076004 -1.9972 0 P 0 ;0
L 0.96076004 -1.9972 0.9637 -1.99561998 0 P 0 ;0
L 0.9637 -1.99561998 0.96683002 -1.99416998 0 P 0 ;0
L 0.96683002 -1.99416998 0.96998996 -1.99291998 0 P 0 ;0
L 0.96998996 -1.99291998 0.9729 -1.99198996 0 P 0 ;0
L 0.9729 -1.99198996 0.97586004 -1.9913 0 P 0 ;0
L 0.97586004 -1.9913 0.97923002 -1.99076998 0 P 0 ;0
L 0.97923002 -1.99076998 0.98263002 -1.99046998 0 P 0 ;0
L 0.98263002 -1.99046998 0.99136004 -1.99026004 0 P 0 ;0
L 0.99136004 -1.99026004 1.00028996 -1.99066998 0 P 0 ;0
L 1.00028996 -1.99066998 1.00403002 -1.99108002 0 P 0 ;0
L 1.00403002 -1.99108002 1.00771004 -1.99166998 0 P 0 ;0
L 1.00771004 -1.99166998 1.01305 -1.99291998 0 P 0 ;0
L 1.01305 -1.99291998 1.01823002 -1.99461998 0 P 0 ;0
L 1.01823002 -1.99461998 1.02026004 -1.99546998 0 P 0 ;0
L 1.02026004 -1.99546998 1.02221004 -1.99646998 0 P 0 ;0
L 1.02221004 -1.99646998 1.02408002 -1.9976 0 P 0 ;0
L 1.02408002 -1.9976 1.02585 -1.99886998 0 P 0 ;0
L 1.02585 -1.99886998 1.02746004 -2.00021004 0 P 0 ;0
L 1.02746004 -2.00021004 1.02893996 -2.00166998 0 P 0 ;0
L 1.02893996 -2.00166998 1.03031004 -2.00325 0 P 0 ;0
L 1.03031004 -2.00325 1.03155 -2.00493002 0 P 0 ;0
L 1.03155 -2.00493002 1.03326998 -2.00768002 0 P 0 ;0
L 1.03326998 -2.00768002 1.03478002 -2.01055 0 P 0 ;0
L 1.03478002 -2.01055 1.03608002 -2.01351998 0 P 0 ;0
L 1.03608002 -2.01351998 1.03678996 -2.01546998 0 P 0 ;0
L 1.03678996 -2.01546998 1.03736004 -2.01743002 0 P 0 ;0
L 1.03736004 -2.01743002 1.03778002 -2.0193 0 P 0 ;0
L 1.03778002 -2.0193 1.03805 -2.02116998 0 P 0 ;0
L 1.03805 -2.02116998 1.03836998 -2.02658996 0 P 0 ;0
L 1.03836998 -2.02658996 1.03848002 -2.03698996 0 P 0 ;0
L 1.03848002 -2.03698996 1.03838996 -2.04623002 0 P 0 ;0
L 1.03838996 -2.04623002 1.03805 -2.06018996 0 P 0 ;0
L 1.03805 -2.06018996 1.03756004 -2.07583002 0 P 0 ;0
L 1.03756004 -2.07583002 1.03696998 -2.09095 0 P 0 ;0
L 1.03696998 -2.09095 1.03548996 -2.12516004 0 P 0 ;0
L 1.03548996 -2.12516004 0.98546998 -2.12516004 0 P 0 ;0
L 0.98546998 -2.12516004 0.98586998 -2.12166004 0 P 0 ;0
L 0.98586998 -2.12166004 0.98696998 -2.10871998 0 P 0 ;0
L 0.98696998 -2.10871998 0.98796004 -2.08916004 0 P 0 ;0
L 0.98796004 -2.08916004 0.9886 -2.06963002 0 P 0 ;0
L 0.9886 -2.06963002 0.98853002 -2.05698002 0 P 0 ;0
L 0.98853002 -2.05698002 0.98781998 -2.0461 0 P 0 ;0
L 0.98781998 -2.0461 0.9875 -2.04373002 0 P 0 ;0
L 0.9875 -2.04373002 0.98748002 -2.04365 0 P 0 ;0
L 0.98748002 -2.04365 0.98698996 -2.04138996 0 P 0 ;0
L 0.98698996 -2.04138996 0.9863 -2.03908002 0 P 0 ;0
L 0.9863 -2.03908002 0.98588002 -2.038 0 P 0 ;0
L 0.98588002 -2.038 0.98538002 -2.03696004 0 P 0 ;0
L 0.98538002 -2.03696004 0.9848 -2.03596004 0 P 0 ;0
L 0.9848 -2.03596004 0.98413996 -2.03501004 0 P 0 ;0
L 0.98413996 -2.03501004 0.98341998 -2.03411004 0 P 0 ;0
L 0.98341998 -2.03411004 0.98336998 -2.03405 0 P 0 ;0
L 0.98336998 -2.03405 0.98263002 -2.03326004 0 P 0 ;0
L 0.98263002 -2.03326004 0.98176998 -2.03246998 0 P 0 ;0
L 0.98176998 -2.03246998 0.98086998 -2.03175 0 P 0 ;0
L 0.98086998 -2.03175 0.97991004 -2.0311 0 P 0 ;0
L 0.97991004 -2.0311 0.9789 -2.03051998 0 P 0 ;0
L 0.9789 -2.03051998 0.97783002 -2.03001998 0 P 0 ;0
L 0.97783002 -2.03001998 0.97673002 -2.02961004 0 P 0 ;0
L 0.97673002 -2.02961004 0.97663996 -2.02958002 0 P 0 ;0
L 0.97663996 -2.02958002 0.97558996 -2.02928996 0 P 0 ;0
L 0.97558996 -2.02928996 0.97443002 -2.02906998 0 P 0 ;0
L 0.97443002 -2.02906998 0.9727 -2.02888002 0 P 0 ;0
L 0.9727 -2.02888002 0.97261998 -2.02886998 0 P 0 ;0
L 0.97261998 -2.02886998 0.97096004 -2.02881004 0 P 0 ;0
L 0.97096004 -2.02881004 0.96921004 -2.02886004 0 P 0 ;0
L 0.96921004 -2.02886004 0.96745 -2.02903996 0 P 0 ;0
L 0.96745 -2.02903996 0.96571004 -2.02933996 0 P 0 ;0
L 0.96571004 -2.02933996 0.964 -2.02976004 0 P 0 ;0
L 0.964 -2.02976004 0.96283002 -2.03013996 0 P 0 ;0
L 0.96283002 -2.03013996 0.96168002 -2.0306 0 P 0 ;0
L 0.96168002 -2.0306 0.96056998 -2.03115 0 P 0 ;0
L 0.96056998 -2.03115 0.95948996 -2.03178002 0 P 0 ;0
L 0.95948996 -2.03178002 0.95791004 -2.03286998 0 P 0 ;0
L 0.95791004 -2.03286998 0.95645 -2.03408996 0 P 0 ;0
L 0.95645 -2.03408996 0.95508996 -2.03541998 0 P 0 ;0
L 0.95508996 -2.03541998 0.95383996 -2.03686998 0 P 0 ;0
L 0.95383996 -2.03686998 0.9538 -2.03693002 0 P 0 ;0
L 0.9538 -2.03693002 0.95273002 -2.03841004 0 P 0 ;0
L 0.95273002 -2.03841004 0.95175 -2.04003996 0 P 0 ;0
L 0.95175 -2.04003996 0.95023002 -2.04306004 0 P 0 ;0
L 0.95023002 -2.04306004 0.94896004 -2.04611004 0 P 0 ;0
L 0.94896004 -2.04611004 0.94893002 -2.04616998 0 P 0 ;0
L 0.94893002 -2.04616998 0.94783002 -2.04936004 0 P 0 ;0
L 0.94783002 -2.04936004 0.94695 -2.05263002 0 P 0 ;0
L 0.94695 -2.05263002 0.94515 -2.06203002 0 P 0 ;0
L 0.94515 -2.06203002 0.9441 -2.07156004 0 P 0 ;0
L 0.9441 -2.07156004 0.9427 -2.10128002 0 P 0 ;0
L 0.9427 -2.10128002 0.94208996 -2.12516004 0 P 0 ;0
L 0.94208996 -2.12516004 0.91651004 -2.12516004 0 P 0 ;0
L 0.93143002 -2.21261998 1.00578996 -2.21261998 0 P 0 ;0
L 0.94051004 -2.21161998 1.00803002 -2.21161998 0 P 0 ;0
L 0.94941998 -2.21061998 1.01026004 -2.21061998 0 P 0 ;0
L 0.9555 -2.20961998 1.0125 -2.20961998 0 P 0 ;0
L 0.96158002 -2.20861998 1.01473996 -2.20861998 0 P 0 ;0
L 0.96766004 -2.20761998 1.01696998 -2.20761998 0 P 0 ;0
L 0.97373002 -2.20661998 1.01921004 -2.20661998 0 P 0 ;0
L 0.97981004 -2.20561998 1.02145 -2.20561998 0 P 0 ;0
L 0.98498996 -2.20461998 1.02368996 -2.20461998 0 P 0 ;0
L 0.98973996 -2.20361998 1.02591998 -2.20361998 0 P 0 ;0
L 0.99448996 -2.20261998 1.02816004 -2.20261998 0 P 0 ;0
L 0.99923996 -2.20161998 1.0304 -2.20161998 0 P 0 ;0
L 1.00398996 -2.20061998 1.03243996 -2.20061998 0 P 0 ;0
L 1.00875 -2.19961998 1.0344 -2.19961998 0 P 0 ;0
L 1.01348996 -2.19861998 1.03636998 -2.19861998 0 P 0 ;0
L 1.0178 -2.19761998 1.03833996 -2.19761998 0 P 0 ;0
L 1.02168996 -2.19661998 1.04031004 -2.19661998 0 P 0 ;0
L 1.02558002 -2.19561998 1.04228002 -2.19561998 0 P 0 ;0
L 1.02946998 -2.19461998 1.04415 -2.19461998 0 P 0 ;0
L 1.03336004 -2.19361998 1.04596998 -2.19361998 0 P 0 ;0
L 1.03725 -2.19261998 1.04778996 -2.19261998 0 P 0 ;0
L 1.04113996 -2.19161998 1.0496 -2.19161998 0 P 0 ;0
L 1.14356998 -1.98926998 1.13261004 -1.99086004 0 P 0 ;0
L 1.13261004 -1.99086004 1.12165 -1.9934 0 P 0 ;0
L 1.12165 -1.9934 1.11125 -1.99673002 0 P 0 ;0
L 1.11125 -1.99673002 1.10658002 -1.99858996 0 P 0 ;0
L 1.10658002 -1.99858996 1.10198996 -2.00071004 0 P 0 ;0
L 1.10198996 -2.00071004 1.09653002 -2.00358996 0 P 0 ;0
L 1.09653002 -2.00358996 1.09436998 -2.00488996 0 P 0 ;0
L 1.09436998 -2.00488996 1.09226004 -2.00631004 0 P 0 ;0
L 1.09226004 -2.00631004 1.09028002 -2.00781004 0 P 0 ;0
L 1.09028002 -2.00781004 1.08836998 -2.00941998 0 P 0 ;0
L 1.08836998 -2.00941998 1.08405 -2.0135 0 P 0 ;0
L 1.08405 -2.0135 1.08096998 -2.01678996 0 P 0 ;0
L 1.08096998 -2.01678996 1.07808002 -2.02026998 0 P 0 ;0
L 1.07808002 -2.02026998 1.0754 -2.02393002 0 P 0 ;0
L 1.0754 -2.02393002 1.07313996 -2.02748002 0 P 0 ;0
L 1.07313996 -2.02748002 1.07116004 -2.03118996 0 P 0 ;0
L 1.07116004 -2.03118996 1.06943996 -2.03505 0 P 0 ;0
L 1.06943996 -2.03505 1.06795 -2.03918996 0 P 0 ;0
L 1.06795 -2.03918996 1.06673996 -2.04343996 0 P 0 ;0
L 1.06673996 -2.04343996 1.06583002 -2.04778002 0 P 0 ;0
L 1.06583002 -2.04778002 1.06476998 -2.05538996 0 P 0 ;0
L 1.06476998 -2.05538996 1.06421004 -2.06306004 0 P 0 ;0
L 1.06421004 -2.06306004 1.06415 -2.07076004 0 P 0 ;0
L 1.06415 -2.07076004 1.06456998 -2.0785 0 P 0 ;0
L 1.06456998 -2.0785 1.06508996 -2.08276004 0 P 0 ;0
L 1.06508996 -2.08276004 1.06591004 -2.08696004 0 P 0 ;0
L 1.06591004 -2.08696004 1.06703002 -2.09108002 0 P 0 ;0
L 1.06703002 -2.09108002 1.06833002 -2.09473002 0 P 0 ;0
L 1.06833002 -2.09473002 1.06991998 -2.09823996 0 P 0 ;0
L 1.06991998 -2.09823996 1.0718 -2.10161998 0 P 0 ;0
L 1.0718 -2.10161998 1.07398002 -2.10491998 0 P 0 ;0
L 1.07398002 -2.10491998 1.07641998 -2.10803002 0 P 0 ;0
L 1.07641998 -2.10803002 1.07908996 -2.11095 0 P 0 ;0
L 1.07908996 -2.11095 1.08175 -2.11345 0 P 0 ;0
L 1.08175 -2.11345 1.08458996 -2.11573996 0 P 0 ;0
L 1.08458996 -2.11573996 1.08758996 -2.1178 0 P 0 ;0
L 1.08758996 -2.1178 1.09073002 -2.11963996 0 P 0 ;0
L 1.09073002 -2.11963996 1.094 -2.12123996 0 P 0 ;0
L 1.094 -2.12123996 1.0986 -2.12306998 0 P 0 ;0
L 1.0986 -2.12306998 1.10331004 -2.12456004 0 P 0 ;0
L 1.10331004 -2.12456004 1.10811004 -2.12568996 0 P 0 ;0
L 1.10811004 -2.12568996 1.11298002 -2.12646998 0 P 0 ;0
L 1.11298002 -2.12646998 1.1182 -2.12693002 0 P 0 ;0
L 1.1182 -2.12693002 1.12343996 -2.12703002 0 P 0 ;0
L 1.12343996 -2.12703002 1.12866998 -2.12676004 0 P 0 ;0
L 1.12866998 -2.12676004 1.13388002 -2.12613002 0 P 0 ;0
L 1.13388002 -2.12613002 1.14086004 -2.12473996 0 P 0 ;0
L 1.14086004 -2.12473996 1.1477 -2.12273996 0 P 0 ;0
L 1.1477 -2.12273996 1.15433996 -2.12015 0 P 0 ;0
L 1.15433996 -2.12015 1.1545 -2.12008996 0 P 0 ;0
L 1.1545 -2.12008996 1.15466004 -2.12003996 0 P 0 ;0
L 1.15466004 -2.12003996 1.15483002 -2.12001004 0 P 0 ;0
L 1.15483002 -2.12001004 1.15498996 -2.11998996 0 P 0 ;0
L 1.15498996 -2.11998996 1.15533002 -2.11998996 0 P 0 ;0
L 1.15533002 -2.11998996 1.15538996 -2.12 0 P 0 ;0
L 1.15538996 -2.12 1.15545 -2.12001998 0 P 0 ;0
L 1.15545 -2.12001998 1.15551004 -2.12003002 0 P 0 ;0
L 1.15551004 -2.12003002 1.15556004 -2.12006004 0 P 0 ;0
L 1.15556004 -2.12006004 1.15561004 -2.12008002 0 P 0 ;0
L 1.15561004 -2.12008002 1.15566004 -2.12011004 0 P 0 ;0
L 1.15566004 -2.12011004 1.15571004 -2.12015 0 P 0 ;0
L 1.15571004 -2.12015 1.15575 -2.12018996 0 P 0 ;0
L 1.15575 -2.12018996 1.15578996 -2.12023996 0 P 0 ;0
L 1.15578996 -2.12023996 1.15583002 -2.12028002 0 P 0 ;0
L 1.15583002 -2.12028002 1.15586004 -2.12033996 0 P 0 ;0
L 1.15586004 -2.12033996 1.15588002 -2.12038996 0 P 0 ;0
L 1.15588002 -2.12038996 1.15591004 -2.12043996 0 P 0 ;0
L 1.15591004 -2.12043996 1.15601998 -2.12076004 0 P 0 ;0
L 1.15601998 -2.12076004 1.1561 -2.12108002 0 P 0 ;0
L 1.1561 -2.12108002 1.15616004 -2.12141998 0 P 0 ;0
L 1.15616004 -2.12141998 1.15618002 -2.12175 0 P 0 ;0
L 1.15618002 -2.12175 1.15623996 -2.12505 0 P 0 ;0
L 1.15623996 -2.12505 1.15616004 -2.12688002 0 P 0 ;0
L 1.15616004 -2.12688002 1.15593002 -2.12871004 0 P 0 ;0
L 1.15593002 -2.12871004 1.15553996 -2.13051998 0 P 0 ;0
L 1.15553996 -2.13051998 1.15516004 -2.1318 0 P 0 ;0
L 1.15516004 -2.1318 1.1547 -2.13305 0 P 0 ;0
L 1.1547 -2.13305 1.15415 -2.13426004 0 P 0 ;0
L 1.15415 -2.13426004 1.15351004 -2.13545 0 P 0 ;0
L 1.15351004 -2.13545 1.15278996 -2.1366 0 P 0 ;0
L 1.15278996 -2.1366 1.15198002 -2.13768996 0 P 0 ;0
L 1.15198002 -2.13768996 1.15111004 -2.13873002 0 P 0 ;0
L 1.15111004 -2.13873002 1.15016004 -2.13971004 0 P 0 ;0
L 1.15016004 -2.13971004 1.14876004 -2.14096004 0 P 0 ;0
L 1.14876004 -2.14096004 1.14726004 -2.1421 0 P 0 ;0
L 1.14726004 -2.1421 1.14566998 -2.14311004 0 P 0 ;0
L 1.14566998 -2.14311004 1.144 -2.144 0 P 0 ;0
L 1.144 -2.144 1.14226004 -2.14476004 0 P 0 ;0
L 1.14226004 -2.14476004 1.14046004 -2.14536998 0 P 0 ;0
L 1.14046004 -2.14536998 1.13863002 -2.14583002 0 P 0 ;0
L 1.13863002 -2.14583002 1.13676004 -2.14613996 0 P 0 ;0
L 1.13676004 -2.14613996 1.13041998 -2.14663996 0 P 0 ;0
L 1.13041998 -2.14663996 1.12403996 -2.1466 0 P 0 ;0
L 1.12403996 -2.1466 1.11621998 -2.14593996 0 P 0 ;0
L 1.11621998 -2.14593996 1.10843996 -2.14471004 0 P 0 ;0
L 1.10843996 -2.14471004 1.09946998 -2.14276998 0 P 0 ;0
L 1.09946998 -2.14276998 1.0905 -2.14041004 0 P 0 ;0
L 1.0905 -2.14041004 1.07963996 -2.13728996 0 P 0 ;0
L 1.07963996 -2.13728996 1.07936004 -2.1401 0 P 0 ;0
L 1.07936004 -2.1401 1.07931004 -2.14103996 0 P 0 ;0
L 1.07931004 -2.14103996 1.07931998 -2.14198002 0 P 0 ;0
L 1.07931998 -2.14198002 1.07956998 -2.14735 0 P 0 ;0
L 1.07956998 -2.14735 1.07993996 -2.15375 0 P 0 ;0
L 1.07993996 -2.15375 1.08045 -2.16081998 0 P 0 ;0
L 1.08045 -2.16081998 1.08181004 -2.17873002 0 P 0 ;0
L 1.08181004 -2.17873002 1.08996004 -2.18061004 0 P 0 ;0
L 1.08996004 -2.18061004 1.09951004 -2.18246004 0 P 0 ;0
L 1.09951004 -2.18246004 1.11243996 -2.18416998 0 P 0 ;0
L 1.11243996 -2.18416998 1.1254 -2.18543002 0 P 0 ;0
L 1.1254 -2.18543002 1.13508002 -2.18583002 0 P 0 ;0
L 1.13508002 -2.18583002 1.14765 -2.18528996 0 P 0 ;0
L 1.14765 -2.18528996 1.15368002 -2.18461004 0 P 0 ;0
L 1.15368002 -2.18461004 1.15971004 -2.18363996 0 P 0 ;0
L 1.15971004 -2.18363996 1.16521004 -2.18248002 0 P 0 ;0
L 1.16521004 -2.18248002 1.17063996 -2.18103002 0 P 0 ;0
L 1.17063996 -2.18103002 1.17528996 -2.17946998 0 P 0 ;0
L 1.17528996 -2.17946998 1.17978002 -2.17753996 0 P 0 ;0
L 1.17978002 -2.17753996 1.18216998 -2.1763 0 P 0 ;0
L 1.18216998 -2.1763 1.18446004 -2.17488996 0 P 0 ;0
L 1.18446004 -2.17488996 1.18663996 -2.17331004 0 P 0 ;0
L 1.18663996 -2.17331004 1.18871004 -2.17156004 0 P 0 ;0
L 1.18871004 -2.17156004 1.19161004 -2.16871998 0 P 0 ;0
L 1.19161004 -2.16871998 1.19431004 -2.16568996 0 P 0 ;0
L 1.19431004 -2.16568996 1.19678996 -2.16246998 0 P 0 ;0
L 1.19678996 -2.16246998 1.19908996 -2.15901998 0 P 0 ;0
L 1.19908996 -2.15901998 1.20113996 -2.15543996 0 P 0 ;0
L 1.20113996 -2.15543996 1.20295 -2.15171004 0 P 0 ;0
L 1.20295 -2.15171004 1.20435 -2.14815 0 P 0 ;0
L 1.20435 -2.14815 1.20543996 -2.14448996 0 P 0 ;0
L 1.20543996 -2.14448996 1.20621004 -2.14073996 0 P 0 ;0
L 1.20621004 -2.14073996 1.20651998 -2.13855 0 P 0 ;0
L 1.20651998 -2.13855 1.20671998 -2.13633996 0 P 0 ;0
L 1.20671998 -2.13633996 1.20761998 -2.12321004 0 P 0 ;0
L 1.20761998 -2.12321004 1.20858002 -2.10753996 0 P 0 ;0
L 1.20858002 -2.10753996 1.20951004 -2.09021998 0 P 0 ;0
L 1.20951004 -2.09021998 1.21048002 -2.07166004 0 P 0 ;0
L 1.21048002 -2.07166004 1.21156004 -2.05228002 0 P 0 ;0
L 1.21156004 -2.05228002 1.21258002 -2.03478996 0 P 0 ;0
L 1.21258002 -2.03478996 1.21333002 -2.02286004 0 P 0 ;0
L 1.21333002 -2.02286004 1.21393996 -2.01373996 0 P 0 ;0
L 1.21393996 -2.01373996 1.21443996 -2.00568996 0 P 0 ;0
L 1.21443996 -2.00568996 1.21485 -1.99883996 0 P 0 ;0
L 1.21485 -1.99883996 1.2149 -1.99721004 0 P 0 ;0
L 1.2149 -1.99721004 1.21488996 -1.99703996 0 P 0 ;0
L 1.21488996 -1.99703996 1.21486998 -1.99686004 0 P 0 ;0
L 1.21486998 -1.99686004 1.21483996 -1.99668996 0 P 0 ;0
L 1.21483996 -1.99668996 1.21478996 -1.99653002 0 P 0 ;0
L 1.21478996 -1.99653002 1.21473002 -1.99636998 0 P 0 ;0
L 1.21473002 -1.99636998 1.21466004 -1.99621004 0 P 0 ;0
L 1.21466004 -1.99621004 1.21458002 -1.99606004 0 P 0 ;0
L 1.21458002 -1.99606004 1.21448002 -1.99591004 0 P 0 ;0
L 1.21448002 -1.99591004 1.21433002 -1.99571998 0 P 0 ;0
L 1.21433002 -1.99571998 1.21416998 -1.99553996 0 P 0 ;0
L 1.21416998 -1.99553996 1.21398996 -1.99538002 0 P 0 ;0
L 1.21398996 -1.99538002 1.21378996 -1.99523996 0 P 0 ;0
L 1.21378996 -1.99523996 1.21358002 -1.99511004 0 P 0 ;0
L 1.21358002 -1.99511004 1.21336004 -1.995 0 P 0 ;0
L 1.21336004 -1.995 1.21261004 -1.99468996 0 P 0 ;0
L 1.21261004 -1.99468996 1.21183996 -1.99443996 0 P 0 ;0
L 1.21183996 -1.99443996 1.21105 -1.99423002 0 P 0 ;0
L 1.21105 -1.99423002 1.20593996 -1.99318002 0 P 0 ;0
L 1.20593996 -1.99318002 1.18996998 -1.99065 0 P 0 ;0
L 1.18996998 -1.99065 1.17318996 -1.98908002 0 P 0 ;0
L 1.17318996 -1.98908002 1.15718996 -1.98858002 0 P 0 ;0
L 1.15718996 -1.98858002 1.1504 -1.98876004 0 P 0 ;0
L 1.1504 -1.98876004 1.14356998 -1.98926998 0 P 0 ;0
L 1.04503996 -2.19061998 1.05141998 -2.19061998 0 P 0 ;0
L 1.04893002 -2.18961998 1.05323002 -2.18961998 0 P 0 ;0
L 1.05263002 -2.18861998 1.05503996 -2.18861998 0 P 0 ;0
L 1.05628996 -2.18761998 1.05676004 -2.18761998 0 P 0 ;0
L 1.09645 -2.17983002 1.16738002 -2.17983002 0 P 0 ;0
L 1.09126004 -2.17883002 1.17091004 -2.17883002 0 P 0 ;0
L 1.0868 -2.17783002 1.17386998 -2.17783002 0 P 0 ;0
L 1.08368002 -2.17683002 1.17636004 -2.17683002 0 P 0 ;0
L 1.0836 -2.17583002 1.1787 -2.17583002 0 P 0 ;0
L 1.08351998 -2.17483002 1.18066998 -2.17483002 0 P 0 ;0
L 1.08345 -2.17383002 1.18236998 -2.17383002 0 P 0 ;0
L 1.08336998 -2.17283002 1.1839 -2.17283002 0 P 0 ;0
L 1.08328996 -2.17183002 1.18526998 -2.17183002 0 P 0 ;0
L 1.08321998 -2.17083002 1.18646998 -2.17083002 0 P 0 ;0
L 1.08313996 -2.16983002 1.18761998 -2.16983002 0 P 0 ;0
L 1.08306998 -2.16883002 1.18863996 -2.16883002 0 P 0 ;0
L 1.08298996 -2.16783002 1.18966004 -2.16783002 0 P 0 ;0
L 1.08291998 -2.16683002 1.19061004 -2.16683002 0 P 0 ;0
L 1.08283996 -2.16583002 1.1915 -2.16583002 0 P 0 ;0
L 1.08276004 -2.16483002 1.19238996 -2.16483002 0 P 0 ;0
L 1.08268996 -2.16383002 1.19321004 -2.16383002 0 P 0 ;0
L 1.08261004 -2.16283002 1.19398002 -2.16283002 0 P 0 ;0
L 1.08253002 -2.16183002 1.19476004 -2.16183002 0 P 0 ;0
L 1.08246004 -2.16083002 1.19548002 -2.16083002 0 P 0 ;0
L 1.08238002 -2.15983002 1.19613996 -2.15983002 0 P 0 ;0
L 1.08231004 -2.15883002 1.19681004 -2.15883002 0 P 0 ;0
L 1.08223996 -2.15783002 1.19746004 -2.15783002 0 P 0 ;0
L 1.13506998 -2.18383002 1.12553002 -2.18343996 0 P 0 ;0
L 1.12553002 -2.18343996 1.11266004 -2.18218002 0 P 0 ;0
L 1.11266004 -2.18218002 1.09983002 -2.18048002 0 P 0 ;0
L 1.09983002 -2.18048002 1.09036998 -2.17866004 0 P 0 ;0
L 1.09036998 -2.17866004 1.0837 -2.17711004 0 P 0 ;0
L 1.0837 -2.17711004 1.08245 -2.16066998 0 P 0 ;0
L 1.08245 -2.16066998 1.08193996 -2.15361998 0 P 0 ;0
L 1.08193996 -2.15361998 1.08156998 -2.14726004 0 P 0 ;0
L 1.08156998 -2.14726004 1.08131998 -2.14191004 0 P 0 ;0
L 1.08131998 -2.14191004 1.08131004 -2.14108996 0 P 0 ;0
L 1.08131004 -2.14108996 1.08136004 -2.14026004 0 P 0 ;0
L 1.08136004 -2.14026004 1.0814 -2.13986998 0 P 0 ;0
L 1.0814 -2.13986998 1.08996004 -2.14233002 0 P 0 ;0
L 1.08996004 -2.14233002 1.08996998 -2.14233996 0 P 0 ;0
L 1.08996998 -2.14233996 1.08998996 -2.14233996 0 P 0 ;0
L 1.08998996 -2.14233996 1.099 -2.14471998 0 P 0 ;0
L 1.099 -2.14471998 1.10806998 -2.14668002 0 P 0 ;0
L 1.10806998 -2.14668002 1.11598002 -2.14791998 0 P 0 ;0
L 1.11598002 -2.14791998 1.12395 -2.1486 0 P 0 ;0
L 1.12395 -2.1486 1.13048996 -2.14863996 0 P 0 ;0
L 1.13048996 -2.14863996 1.137 -2.14811998 0 P 0 ;0
L 1.137 -2.14811998 1.13903002 -2.14778996 0 P 0 ;0
L 1.13903002 -2.14778996 1.14103002 -2.14728996 0 P 0 ;0
L 1.14103002 -2.14728996 1.14298002 -2.14661998 0 P 0 ;0
L 1.14298002 -2.14661998 1.14486998 -2.14581004 0 P 0 ;0
L 1.14486998 -2.14581004 1.14668002 -2.14483996 0 P 0 ;0
L 1.14668002 -2.14483996 1.1484 -2.14373996 0 P 0 ;0
L 1.1484 -2.14373996 1.15003002 -2.1425 0 P 0 ;0
L 1.15003002 -2.1425 1.15155 -2.14115 0 P 0 ;0
L 1.15155 -2.14115 1.1526 -2.14006998 0 P 0 ;0
L 1.1526 -2.14006998 1.15263996 -2.14001998 0 P 0 ;0
L 1.15263996 -2.14001998 1.15356004 -2.13893002 0 P 0 ;0
L 1.15356004 -2.13893002 1.15443996 -2.13771998 0 P 0 ;0
L 1.15443996 -2.13771998 1.15523002 -2.13646004 0 P 0 ;0
L 1.15523002 -2.13646004 1.15593996 -2.13515 0 P 0 ;0
L 1.15593996 -2.13515 1.15655 -2.13381004 0 P 0 ;0
L 1.15655 -2.13381004 1.15706004 -2.13243002 0 P 0 ;0
L 1.15706004 -2.13243002 1.15748002 -2.13101004 0 P 0 ;0
L 1.15748002 -2.13101004 1.1579 -2.12905 0 P 0 ;0
L 1.1579 -2.12905 1.15816004 -2.12706004 0 P 0 ;0
L 1.15816004 -2.12706004 1.15825 -2.12506998 0 P 0 ;0
L 1.15825 -2.12506998 1.15818002 -2.12165 0 P 0 ;0
L 1.15818002 -2.12165 1.15813996 -2.12118002 0 P 0 ;0
L 1.15813996 -2.12118002 1.15813002 -2.1211 0 P 0 ;0
L 1.15813002 -2.1211 1.15806004 -2.12068002 0 P 0 ;0
L 1.15806004 -2.12068002 1.15793996 -2.12018996 0 P 0 ;0
L 1.15793996 -2.12018996 1.15778002 -2.11973002 0 P 0 ;0
L 1.15778002 -2.11973002 1.1577 -2.11953002 0 P 0 ;0
L 1.1577 -2.11953002 1.15758996 -2.11933002 0 P 0 ;0
L 1.15758996 -2.11933002 1.15746998 -2.11913996 0 P 0 ;0
L 1.15746998 -2.11913996 1.15733002 -2.11895 0 P 0 ;0
L 1.15733002 -2.11895 1.15716998 -2.11878002 0 P 0 ;0
L 1.15716998 -2.11878002 1.157 -2.11863002 0 P 0 ;0
L 1.157 -2.11863002 1.15681998 -2.11848996 0 P 0 ;0
L 1.15681998 -2.11848996 1.15663002 -2.11836004 0 P 0 ;0
L 1.15663002 -2.11836004 1.15641998 -2.11825 0 P 0 ;0
L 1.15641998 -2.11825 1.15621004 -2.11816004 0 P 0 ;0
L 1.15621004 -2.11816004 1.15598996 -2.11808996 0 P 0 ;0
L 1.15598996 -2.11808996 1.15576998 -2.11803996 0 P 0 ;0
L 1.15576998 -2.11803996 1.15553002 -2.118 0 P 0 ;0
L 1.15553002 -2.118 1.15518002 -2.11798002 0 P 0 ;0
L 1.15518002 -2.11798002 1.15483996 -2.11798996 0 P 0 ;0
L 1.15483996 -2.11798996 1.15451004 -2.11803002 0 P 0 ;0
L 1.15451004 -2.11803002 1.15418002 -2.1181 0 P 0 ;0
L 1.15418002 -2.1181 1.15386004 -2.1182 0 P 0 ;0
L 1.15386004 -2.1182 1.15361004 -2.11828996 0 P 0 ;0
L 1.15361004 -2.11828996 1.14705 -2.12083996 0 P 0 ;0
L 1.14705 -2.12083996 1.14038996 -2.12278996 0 P 0 ;0
L 1.14038996 -2.12278996 1.13356004 -2.12416004 0 P 0 ;0
L 1.13356004 -2.12416004 1.1285 -2.12476998 0 P 0 ;0
L 1.1285 -2.12476998 1.12341004 -2.12501998 0 P 0 ;0
L 1.12341004 -2.12501998 1.11831004 -2.12493002 0 P 0 ;0
L 1.11831004 -2.12493002 1.11323002 -2.12448996 0 P 0 ;0
L 1.11323002 -2.12448996 1.10848996 -2.12373002 0 P 0 ;0
L 1.10848996 -2.12373002 1.10383996 -2.12263002 0 P 0 ;0
L 1.10383996 -2.12263002 1.09926998 -2.12118996 0 P 0 ;0
L 1.09926998 -2.12118996 1.09481004 -2.11941004 0 P 0 ;0
L 1.09481004 -2.11941004 1.09168002 -2.11788002 0 P 0 ;0
L 1.09168002 -2.11788002 1.08866004 -2.11611998 0 P 0 ;0
L 1.08866004 -2.11611998 1.08578002 -2.11413002 0 P 0 ;0
L 1.08578002 -2.11413002 1.08306998 -2.11193996 0 P 0 ;0
L 1.08306998 -2.11193996 1.08051998 -2.10955 0 P 0 ;0
L 1.08051998 -2.10955 1.07793996 -2.10673002 0 P 0 ;0
L 1.07793996 -2.10673002 1.07561004 -2.10373996 0 P 0 ;0
L 1.07561004 -2.10373996 1.07351004 -2.10058002 0 P 0 ;0
L 1.07351004 -2.10058002 1.07171004 -2.09733996 0 P 0 ;0
L 1.07171004 -2.09733996 1.07018002 -2.09396998 0 P 0 ;0
L 1.07018002 -2.09396998 1.06893996 -2.09048002 0 P 0 ;0
L 1.06893996 -2.09048002 1.06786004 -2.0865 0 P 0 ;0
L 1.06786004 -2.0865 1.06706004 -2.08243996 0 P 0 ;0
L 1.06706004 -2.08243996 1.06656004 -2.07833002 0 P 0 ;0
L 1.06656004 -2.07833002 1.06615 -2.07071004 0 P 0 ;0
L 1.06615 -2.07071004 1.06621004 -2.06313996 0 P 0 ;0
L 1.06621004 -2.06313996 1.06675 -2.0556 0 P 0 ;0
L 1.06675 -2.0556 1.0678 -2.04813002 0 P 0 ;0
L 1.0678 -2.04813002 1.06868996 -2.04391998 0 P 0 ;0
L 1.06868996 -2.04391998 1.06985 -2.03981004 0 P 0 ;0
L 1.06985 -2.03981004 1.0713 -2.03578996 0 P 0 ;0
L 1.0713 -2.03578996 1.07296004 -2.03206998 0 P 0 ;0
L 1.07296004 -2.03206998 1.07486998 -2.02848996 0 P 0 ;0
L 1.07486998 -2.02848996 1.07705 -2.02506004 0 P 0 ;0
L 1.07705 -2.02506004 1.07966004 -2.0215 0 P 0 ;0
L 1.07966004 -2.0215 1.08246998 -2.01811004 0 P 0 ;0
L 1.08246998 -2.01811004 1.08546998 -2.01491004 0 P 0 ;0
L 1.08546998 -2.01491004 1.0897 -2.01091004 0 P 0 ;0
L 1.0897 -2.01091004 1.09153002 -2.00936998 0 P 0 ;0
L 1.09153002 -2.00936998 1.09341998 -2.00793996 0 P 0 ;0
L 1.09341998 -2.00793996 1.09545 -2.00658002 0 P 0 ;0
L 1.09545 -2.00658002 1.09751004 -2.00533996 0 P 0 ;0
L 1.09751004 -2.00533996 1.10288002 -2.0025 0 P 0 ;0
L 1.10288002 -2.0025 1.10736998 -2.00043002 0 P 0 ;0
L 1.10736998 -2.00043002 1.11193002 -1.99861004 0 P 0 ;0
L 1.11193002 -1.99861004 1.12218002 -1.99533002 0 P 0 ;0
L 1.12218002 -1.99533002 1.13298002 -1.99281998 0 P 0 ;0
L 1.13298002 -1.99281998 1.14378996 -1.99126004 0 P 0 ;0
L 1.14378996 -1.99126004 1.1505 -1.99075 0 P 0 ;0
L 1.1505 -1.99075 1.15718002 -1.99058996 0 P 0 ;0
L 1.15718002 -1.99058996 1.17306998 -1.99108002 0 P 0 ;0
L 1.17306998 -1.99108002 1.18971998 -1.99263002 0 P 0 ;0
L 1.18971998 -1.99263002 1.20558002 -1.99515 0 P 0 ;0
L 1.20558002 -1.99515 1.21058996 -1.99618002 0 P 0 ;0
L 1.21058996 -1.99618002 1.21126998 -1.99636004 0 P 0 ;0
L 1.21126998 -1.99636004 1.21191998 -1.99656998 0 P 0 ;0
L 1.21191998 -1.99656998 1.21253002 -1.99681998 0 P 0 ;0
L 1.21253002 -1.99681998 1.21261004 -1.99686004 0 P 0 ;0
L 1.21261004 -1.99686004 1.21266004 -1.99688996 0 P 0 ;0
L 1.21266004 -1.99688996 1.21271998 -1.99693002 0 P 0 ;0
L 1.21271998 -1.99693002 1.21281998 -1.99703002 0 P 0 ;0
L 1.21281998 -1.99703002 1.21286004 -1.99708996 0 P 0 ;0
L 1.21286004 -1.99708996 1.21288002 -1.99711004 0 P 0 ;0
L 1.21288002 -1.99711004 1.21288002 -1.99711998 0 P 0 ;0
L 1.21288002 -1.99711998 1.21288996 -1.99715 0 P 0 ;0
L 1.21288996 -1.99715 1.2129 -1.99716998 0 P 0 ;0
L 1.2129 -1.99716998 1.2129 -1.99721998 0 P 0 ;0
L 1.2129 -1.99721998 1.21285 -1.99875 0 P 0 ;0
L 1.21285 -1.99875 1.21243996 -2.00556998 0 P 0 ;0
L 1.21243996 -2.00556998 1.21193996 -2.01361004 0 P 0 ;0
L 1.21193996 -2.01361004 1.21133996 -2.02273002 0 P 0 ;0
L 1.21133996 -2.02273002 1.21133996 -2.02273996 0 P 0 ;0
L 1.21133996 -2.02273996 1.21058996 -2.03468002 0 P 0 ;0
L 1.21058996 -2.03468002 1.20956004 -2.05216998 0 P 0 ;0
L 1.20956004 -2.05216998 1.20848996 -2.07156004 0 P 0 ;0
L 1.20848996 -2.07156004 1.20848996 -2.07156998 0 P 0 ;0
L 1.20848996 -2.07156998 1.20751004 -2.09011004 0 P 0 ;0
L 1.20751004 -2.09011004 1.20658996 -2.10743996 0 P 0 ;0
L 1.20658996 -2.10743996 1.20561998 -2.12308996 0 P 0 ;0
L 1.20561998 -2.12308996 1.20473002 -2.13618996 0 P 0 ;0
L 1.20473002 -2.13618996 1.20453002 -2.13831998 0 P 0 ;0
L 1.20453002 -2.13831998 1.20423996 -2.14041004 0 P 0 ;0
L 1.20423996 -2.14041004 1.2035 -2.144 0 P 0 ;0
L 1.2035 -2.144 1.20246004 -2.1475 0 P 0 ;0
L 1.20246004 -2.1475 1.20111998 -2.1509 0 P 0 ;0
L 1.20111998 -2.1509 1.19936998 -2.1545 0 P 0 ;0
L 1.19936998 -2.1545 1.19738002 -2.15796998 0 P 0 ;0
L 1.19738002 -2.15796998 1.19516004 -2.1613 0 P 0 ;0
L 1.19516004 -2.1613 1.19276998 -2.16441004 0 P 0 ;0
L 1.19276998 -2.16441004 1.19016004 -2.16733996 0 P 0 ;0
L 1.19016004 -2.16733996 1.18736004 -2.17008002 0 P 0 ;0
L 1.18736004 -2.17008002 1.1854 -2.17173996 0 P 0 ;0
L 1.1854 -2.17173996 1.18335 -2.17323002 0 P 0 ;0
L 1.18335 -2.17323002 1.18118002 -2.17456004 0 P 0 ;0
L 1.18118002 -2.17456004 1.17893002 -2.17573002 0 P 0 ;0
L 1.17893002 -2.17573002 1.17456998 -2.1776 0 P 0 ;0
L 1.17456998 -2.1776 1.17006998 -2.17911998 0 P 0 ;0
L 1.17006998 -2.17911998 1.16473996 -2.18053002 0 P 0 ;0
L 1.16473996 -2.18053002 1.15935 -2.18166998 0 P 0 ;0
L 1.15935 -2.18166998 1.15341998 -2.18263002 0 P 0 ;0
L 1.15341998 -2.18263002 1.1475 -2.18328996 0 P 0 ;0
L 1.1475 -2.18328996 1.13506998 -2.18383002 0 P 0 ;0
L 0.90491998 -2.21461998 1.00131004 -2.21461998 0 P 0 ;0
L 0.92235 -2.21361998 1.00355 -2.21361998 0 P 0 ;0
L 0.76925 -1.8965 0.85586998 -1.8965 0 P 0 ;0
L 0.76958996 -1.8955 0.85556004 -1.8955 0 P 0 ;0
L 0.76995 -1.8945 0.85521004 -1.8945 0 P 0 ;0
L 0.77031004 -1.8935 0.85486004 -1.8935 0 P 0 ;0
L 0.77071004 -1.8925 0.85443996 -1.8925 0 P 0 ;0
L 0.77115 -1.8915 0.85401004 -1.8915 0 P 0 ;0
L 0.7716 -1.8905 0.85355 -1.8905 0 P 0 ;0
L 0.77206004 -1.8895 0.85303002 -1.8895 0 P 0 ;0
L 0.7726 -1.8885 0.85251004 -1.8885 0 P 0 ;0
L 0.77313996 -1.8875 0.85198996 -1.8875 0 P 0 ;0
L 0.77368996 -1.8865 0.85138002 -1.8865 0 P 0 ;0
L 0.77433002 -1.8855 0.85073996 -1.8855 0 P 0 ;0
L 0.77496004 -1.8845 0.85011004 -1.8845 0 P 0 ;0
L 0.77561998 -1.8835 0.84943002 -1.8835 0 P 0 ;0
L 0.77636004 -1.8825 0.84866998 -1.8825 0 P 0 ;0
L 0.77711004 -1.8815 0.84791004 -1.8815 0 P 0 ;0
L 0.7779 -1.8805 0.84713002 -1.8805 0 P 0 ;0
L 0.77876998 -1.8795 0.84623002 -1.8795 0 P 0 ;0
L 0.77963996 -1.8785 0.84533002 -1.8785 0 P 0 ;0
L 0.7806 -1.8775 0.8444 -1.8775 0 P 0 ;0
L 0.78161004 -1.8765 0.84335 -1.8765 0 P 0 ;0
L 0.78265 -1.8755 0.84228996 -1.8755 0 P 0 ;0
L 0.78381998 -1.8745 0.84108996 -1.8745 0 P 0 ;0
L 0.78498996 -1.8735 0.83986998 -1.8735 0 P 0 ;0
L 0.78635 -1.8725 0.83848002 -1.8725 0 P 0 ;0
L 0.78773002 -1.8715 0.83706004 -1.8715 0 P 0 ;0
L 0.78933002 -1.8705 0.83541998 -1.8705 0 P 0 ;0
L 0.791 -1.8695 0.83366004 -1.8695 0 P 0 ;0
L 0.793 -1.8685 0.83171998 -1.8685 0 P 0 ;0
L 0.79525 -1.8675 0.82941998 -1.8675 0 P 0 ;0
L 0.79791998 -1.8665 0.82671004 -1.8665 0 P 0 ;0
L 0.80143996 -1.8655 0.82328996 -1.8655 0 P 0 ;0
L 0.80705 -1.8645 0.81776004 -1.8645 0 P 0 ;0
L 0.74543002 -1.89661998 0.75033002 -1.89661998 0 P 0 ;0
L 0.74751004 -1.89561998 0.75058996 -1.89561998 0 P 0 ;0
L 0.74958996 -1.89461998 0.75086004 -1.89461998 0 P 0 ;0
L 0.76733996 -1.9125 0.85751998 -1.9125 0 P 0 ;0
L 0.76728996 -1.9115 0.85756004 -1.9115 0 P 0 ;0
L 0.76723996 -1.9105 0.85758996 -1.9105 0 P 0 ;0
L 0.76721998 -1.9095 0.85763002 -1.9095 0 P 0 ;0
L 0.76725 -1.9085 0.85761004 -1.9085 0 P 0 ;0
L 0.76728002 -1.9075 0.85756998 -1.9075 0 P 0 ;0
L 0.76731004 -1.9065 0.85753002 -1.9065 0 P 0 ;0
L 0.76741998 -1.9055 0.85748996 -1.9055 0 P 0 ;0
L 0.76753996 -1.9045 0.85738002 -1.9045 0 P 0 ;0
L 0.76766004 -1.9035 0.85726004 -1.9035 0 P 0 ;0
L 0.76781998 -1.9025 0.85713996 -1.9025 0 P 0 ;0
L 0.76801998 -1.9015 0.85701004 -1.9015 0 P 0 ;0
L 0.76821004 -1.9005 0.85683002 -1.9005 0 P 0 ;0
L 0.76841998 -1.8995 0.85661998 -1.8995 0 P 0 ;0
L 0.7687 -1.8985 0.85641004 -1.8985 0 P 0 ;0
L 0.76896998 -1.8975 0.85613996 -1.8975 0 P 0 ;0
L 0.76751004 -2.08325 0.8416 -2.08325 0 P 0 ;0
L 0.76761998 -2.08225 0.84161998 -2.08225 0 P 0 ;0
L 0.76773996 -2.08125 0.84166998 -2.08125 0 P 0 ;0
L 0.76786004 -2.08025 0.84171998 -2.08025 0 P 0 ;0
L 0.76796998 -2.07925 0.84176998 -2.07925 0 P 0 ;0
L 0.76808002 -2.07825 0.84181004 -2.07825 0 P 0 ;0
L 0.76818002 -2.07725 0.84186004 -2.07725 0 P 0 ;0
L 0.76828996 -2.07625 0.8419 -2.07625 0 P 0 ;0
L 0.76838996 -2.07525 0.84195 -2.07525 0 P 0 ;0
L 0.76848996 -2.07425 0.842 -2.07425 0 P 0 ;0
L 0.7686 -2.07325 0.84205 -2.07325 0 P 0 ;0
L 0.7687 -2.07225 0.84208996 -2.07225 0 P 0 ;0
L 0.7688 -2.07125 0.84213996 -2.07125 0 P 0 ;0
L 0.7689 -2.07025 0.84218002 -2.07025 0 P 0 ;0
L 0.76901004 -2.06925 0.84223002 -2.06925 0 P 0 ;0
L 0.76911004 -2.06825 0.84228002 -2.06825 0 P 0 ;0
L 0.76921004 -2.06725 0.84233002 -2.06725 0 P 0 ;0
L 0.76931998 -2.06625 0.84236998 -2.06625 0 P 0 ;0
L 0.76941998 -2.06525 0.84241998 -2.06525 0 P 0 ;0
L 0.76948996 -2.06425 0.84246004 -2.06425 0 P 0 ;0
L 0.76956004 -2.06325 0.84251004 -2.06325 0 P 0 ;0
L 0.76963002 -2.06225 0.84256004 -2.06225 0 P 0 ;0
L 0.7697 -2.06125 0.8426 -2.06125 0 P 0 ;0
L 0.76976998 -2.06025 0.84265 -2.06025 0 P 0 ;0
L 0.76983996 -2.05925 0.8427 -2.05925 0 P 0 ;0
L 0.76991004 -2.05825 0.84273996 -2.05825 0 P 0 ;0
L 0.76996998 -2.05725 0.84278996 -2.05725 0 P 0 ;0
L 0.77001004 -2.05625 0.84283996 -2.05625 0 P 0 ;0
L 0.77003996 -2.05525 0.84288002 -2.05525 0 P 0 ;0
L 0.77008002 -2.05425 0.84295 -2.05425 0 P 0 ;0
L 0.77011998 -2.05325 0.84303996 -2.05325 0 P 0 ;0
L 0.77016004 -2.05225 0.84311998 -2.05225 0 P 0 ;0
L 0.77018996 -2.05125 0.84321004 -2.05125 0 P 0 ;0
L 0.77023002 -2.05025 0.8433 -2.05025 0 P 0 ;0
L 0.77026998 -2.04925 0.84338002 -2.04925 0 P 0 ;0
L 0.77031004 -2.04825 0.84346998 -2.04825 0 P 0 ;0
L 0.77033996 -2.04725 0.84356004 -2.04725 0 P 0 ;0
L 0.77038002 -2.04625 0.84363996 -2.04625 0 P 0 ;0
L 0.77041004 -2.04525 0.84373002 -2.04525 0 P 0 ;0
L 0.77043996 -2.04425 0.84381004 -2.04425 0 P 0 ;0
L 0.77046004 -2.04325 0.8439 -2.04325 0 P 0 ;0
L 0.77048002 -2.04225 0.84398996 -2.04225 0 P 0 ;0
L 0.77051004 -2.04125 0.84406998 -2.04125 0 P 0 ;0
L 0.77053002 -2.04025 0.84416004 -2.04025 0 P 0 ;0
L 0.77055 -2.03925 0.84425 -2.03925 0 P 0 ;0
L 0.77058002 -2.03825 0.84433002 -2.03825 0 P 0 ;0
L 0.7706 -2.03725 0.84441998 -2.03725 0 P 0 ;0
L 0.77061998 -2.03625 0.84451004 -2.03625 0 P 0 ;0
L 0.77065 -2.03525 0.84458996 -2.03525 0 P 0 ;0
L 0.77066998 -2.03425 0.84468002 -2.03425 0 P 0 ;0
L 0.7707 -2.03325 0.84476998 -2.03325 0 P 0 ;0
L 0.77071998 -2.03225 0.84485 -2.03225 0 P 0 ;0
L 0.77073002 -2.03125 0.84493996 -2.03125 0 P 0 ;0
L 0.77073996 -2.03025 0.84503002 -2.03025 0 P 0 ;0
L 0.79986004 -1.8638 0.79643996 -1.86486998 0 P 0 ;0
L 0.79643996 -1.86486998 0.79311998 -1.86621004 0 P 0 ;0
L 0.79311998 -1.86621004 0.78991004 -1.86781004 0 P 0 ;0
L 0.78991004 -1.86781004 0.78683996 -1.86966998 0 P 0 ;0
L 0.78683996 -1.86966998 0.78391998 -1.87178002 0 P 0 ;0
L 0.78391998 -1.87178002 0.78111998 -1.87416998 0 P 0 ;0
L 0.78111998 -1.87416998 0.7785 -1.87676004 0 P 0 ;0
L 0.7785 -1.87676004 0.77608002 -1.87953996 0 P 0 ;0
L 0.77608002 -1.87953996 0.77386998 -1.8825 0 P 0 ;0
L 0.77386998 -1.8825 0.77188002 -1.88561998 0 P 0 ;0
L 0.77188002 -1.88561998 0.77013996 -1.88886004 0 P 0 ;0
L 0.77013996 -1.88886004 0.76863996 -1.89221004 0 P 0 ;0
L 0.76863996 -1.89221004 0.7674 -1.89566998 0 P 0 ;0
L 0.7674 -1.89566998 0.76643002 -1.89921004 0 P 0 ;0
L 0.76643002 -1.89921004 0.76571004 -1.90283996 0 P 0 ;0
L 0.76571004 -1.90283996 0.76531004 -1.90636004 0 P 0 ;0
L 0.76531004 -1.90636004 0.7652 -1.90991004 0 P 0 ;0
L 0.7652 -1.90991004 0.76538996 -1.91345 0 P 0 ;0
L 0.76538996 -1.91345 0.76586998 -1.91696998 0 P 0 ;0
L 0.76586998 -1.91696998 0.76663996 -1.92046004 0 P 0 ;0
L 0.76663996 -1.92046004 0.76803002 -1.92493996 0 P 0 ;0
L 0.76803002 -1.92493996 0.76978002 -1.9293 0 P 0 ;0
L 0.76978002 -1.9293 0.77106998 -1.93193996 0 P 0 ;0
L 0.77106998 -1.93193996 0.77253002 -1.93448002 0 P 0 ;0
L 0.77253002 -1.93448002 0.77416004 -1.93693996 0 P 0 ;0
L 0.77416004 -1.93693996 0.77593002 -1.93923002 0 P 0 ;0
L 0.77593002 -1.93923002 0.77783996 -1.94141004 0 P 0 ;0
L 0.77783996 -1.94141004 0.77988996 -1.94345 0 P 0 ;0
L 0.77988996 -1.94345 0.78216004 -1.94545 0 P 0 ;0
L 0.78216004 -1.94545 0.78453996 -1.9473 0 P 0 ;0
L 0.78453996 -1.9473 0.78703002 -1.94901998 0 P 0 ;0
L 0.78703002 -1.94901998 0.79016998 -1.95088002 0 P 0 ;0
L 0.79016998 -1.95088002 0.79343996 -1.95248996 0 P 0 ;0
L 0.79343996 -1.95248996 0.79683002 -1.95383996 0 P 0 ;0
L 0.79683002 -1.95383996 0.80031998 -1.95491998 0 P 0 ;0
L 0.80031998 -1.95491998 0.80391004 -1.95573996 0 P 0 ;0
L 0.80391004 -1.95573996 0.80751998 -1.95626004 0 P 0 ;0
L 0.80751998 -1.95626004 0.81116004 -1.9565 0 P 0 ;0
L 0.81116004 -1.9565 0.81481004 -1.95646004 0 P 0 ;0
L 0.81481004 -1.95646004 0.81843996 -1.95613002 0 P 0 ;0
L 0.81843996 -1.95613002 0.82205 -1.95551004 0 P 0 ;0
L 0.82205 -1.95551004 0.82561998 -1.95461004 0 P 0 ;0
L 0.82561998 -1.95461004 0.82911004 -1.95345 0 P 0 ;0
L 0.82911004 -1.95345 0.83248996 -1.95201004 0 P 0 ;0
L 0.83248996 -1.95201004 0.83576004 -1.95031998 0 P 0 ;0
L 0.83576004 -1.95031998 0.83891998 -1.94836004 0 P 0 ;0
L 0.83891998 -1.94836004 0.84191998 -1.94616998 0 P 0 ;0
L 0.84191998 -1.94616998 0.84475 -1.94375 0 P 0 ;0
L 0.84475 -1.94375 0.84738996 -1.94113996 0 P 0 ;0
L 0.84738996 -1.94113996 0.84983002 -1.93833996 0 P 0 ;0
L 0.84983002 -1.93833996 0.85206998 -1.93533996 0 P 0 ;0
L 0.85206998 -1.93533996 0.8536 -1.93291998 0 P 0 ;0
L 0.8536 -1.93291998 0.85496004 -1.93041004 0 P 0 ;0
L 0.85496004 -1.93041004 0.85613996 -1.9278 0 P 0 ;0
L 0.85613996 -1.9278 0.85711998 -1.92511004 0 P 0 ;0
L 0.85711998 -1.92511004 0.85823002 -1.92123002 0 P 0 ;0
L 0.85823002 -1.92123002 0.85901998 -1.91726998 0 P 0 ;0
L 0.85901998 -1.91726998 0.85948996 -1.91323996 0 P 0 ;0
L 0.85948996 -1.91323996 0.85963996 -1.90918002 0 P 0 ;0
L 0.85963996 -1.90918002 0.85946998 -1.90513002 0 P 0 ;0
L 0.85946998 -1.90513002 0.85898002 -1.9011 0 P 0 ;0
L 0.85898002 -1.9011 0.85841998 -1.89826004 0 P 0 ;0
L 0.85841998 -1.89826004 0.85766004 -1.89546004 0 P 0 ;0
L 0.85766004 -1.89546004 0.85671004 -1.89273002 0 P 0 ;0
L 0.85671004 -1.89273002 0.85556998 -1.89006004 0 P 0 ;0
L 0.85556998 -1.89006004 0.85361998 -1.88631004 0 P 0 ;0
L 0.85361998 -1.88631004 0.85136004 -1.88273996 0 P 0 ;0
L 0.85136004 -1.88273996 0.84881004 -1.87938002 0 P 0 ;0
L 0.84881004 -1.87938002 0.84596998 -1.87623002 0 P 0 ;0
L 0.84596998 -1.87623002 0.84355 -1.87393996 0 P 0 ;0
L 0.84355 -1.87393996 0.84096998 -1.87181998 0 P 0 ;0
L 0.84096998 -1.87181998 0.83826004 -1.86988996 0 P 0 ;0
L 0.83826004 -1.86988996 0.83541004 -1.86815 0 P 0 ;0
L 0.83541004 -1.86815 0.83243996 -1.86661004 0 P 0 ;0
L 0.83243996 -1.86661004 0.82938996 -1.86531004 0 P 0 ;0
L 0.82938996 -1.86531004 0.82625 -1.86423002 0 P 0 ;0
L 0.82625 -1.86423002 0.82303996 -1.86336004 0 P 0 ;0
L 0.82303996 -1.86336004 0.81978002 -1.86273002 0 P 0 ;0
L 0.81978002 -1.86273002 0.81646998 -1.86233002 0 P 0 ;0
L 0.81646998 -1.86233002 0.81228996 -1.86215 0 P 0 ;0
L 0.81228996 -1.86215 0.80811004 -1.86233996 0 P 0 ;0
L 0.80811004 -1.86233996 0.80396004 -1.86288996 0 P 0 ;0
L 0.80396004 -1.86288996 0.79986004 -1.8638 0 P 0 ;0
L 0.80308996 -1.9535 0.82186004 -1.9535 0 P 0 ;0
L 0.79926004 -1.9525 0.82563996 -1.9525 0 P 0 ;0
L 0.79636004 -1.9515 0.82856998 -1.9515 0 P 0 ;0
L 0.79393002 -1.9505 0.83093996 -1.9505 0 P 0 ;0
L 0.7919 -1.9495 0.83298996 -1.9495 0 P 0 ;0
L 0.79008002 -1.9485 0.8349 -1.9485 0 P 0 ;0
L 0.78838996 -1.9475 0.83651004 -1.9475 0 P 0 ;0
L 0.7869 -1.9465 0.83806998 -1.9465 0 P 0 ;0
L 0.78548002 -1.9455 0.83943996 -1.9455 0 P 0 ;0
L 0.7842 -1.9445 0.84078996 -1.9445 0 P 0 ;0
L 0.78298002 -1.9435 0.84196998 -1.9435 0 P 0 ;0
L 0.78183996 -1.9425 0.84313996 -1.9425 0 P 0 ;0
L 0.78076998 -1.9415 0.84418996 -1.9415 0 P 0 ;0
L 0.77976004 -1.9405 0.8452 -1.9405 0 P 0 ;0
L 0.77883002 -1.9395 0.84616998 -1.9395 0 P 0 ;0
L 0.77793996 -1.9385 0.84703996 -1.9385 0 P 0 ;0
L 0.77711998 -1.9375 0.84791004 -1.9375 0 P 0 ;0
L 0.77635 -1.9365 0.84871004 -1.9365 0 P 0 ;0
L 0.77561004 -1.9355 0.84945 -1.9355 0 P 0 ;0
L 0.77493996 -1.9345 0.8502 -1.9345 0 P 0 ;0
L 0.77428002 -1.9335 0.85086998 -1.9335 0 P 0 ;0
L 0.7737 -1.9325 0.8515 -1.9325 0 P 0 ;0
L 0.77311998 -1.9315 0.8521 -1.9315 0 P 0 ;0
L 0.77258996 -1.9305 0.85263996 -1.9305 0 P 0 ;0
L 0.7721 -1.9295 0.85318002 -1.9295 0 P 0 ;0
L 0.77161004 -1.9285 0.85363002 -1.9285 0 P 0 ;0
L 0.77121004 -1.9275 0.85408002 -1.9275 0 P 0 ;0
L 0.77081004 -1.9265 0.85448002 -1.9265 0 P 0 ;0
L 0.77041004 -1.9255 0.85485 -1.9255 0 P 0 ;0
L 0.77001004 -1.9245 0.85521998 -1.9245 0 P 0 ;0
L 0.76968002 -1.9235 0.8555 -1.9235 0 P 0 ;0
L 0.76936998 -1.9225 0.85578996 -1.9225 0 P 0 ;0
L 0.76906004 -1.9215 0.85606998 -1.9215 0 P 0 ;0
L 0.76875 -1.9205 0.85633002 -1.9205 0 P 0 ;0
L 0.76848002 -1.9195 0.85653002 -1.9195 0 P 0 ;0
L 0.76826004 -1.9185 0.85673002 -1.9185 0 P 0 ;0
L 0.76803002 -1.9175 0.85693002 -1.9175 0 P 0 ;0
L 0.76783002 -1.9165 0.85708996 -1.9165 0 P 0 ;0
L 0.76768996 -1.9155 0.85721004 -1.9155 0 P 0 ;0
L 0.76755 -1.9145 0.85733002 -1.9145 0 P 0 ;0
L 0.76741998 -1.9135 0.85745 -1.9135 0 P 0 ;0
L 0.81121004 -1.9545 0.80773002 -1.95426998 0 P 0 ;0
L 0.80773002 -1.95426998 0.80426998 -1.95376998 0 P 0 ;0
L 0.80426998 -1.95376998 0.80083996 -1.95298996 0 P 0 ;0
L 0.80083996 -1.95298996 0.7975 -1.95195 0 P 0 ;0
L 0.7975 -1.95195 0.79426004 -1.95066004 0 P 0 ;0
L 0.79426004 -1.95066004 0.79111998 -1.94911998 0 P 0 ;0
L 0.79111998 -1.94911998 0.78811004 -1.94733002 0 P 0 ;0
L 0.78811004 -1.94733002 0.78573002 -1.94568996 0 P 0 ;0
L 0.78573002 -1.94568996 0.78343996 -1.9439 0 P 0 ;0
L 0.78343996 -1.9439 0.78126004 -1.94198996 0 P 0 ;0
L 0.78126004 -1.94198996 0.7793 -1.94003996 0 P 0 ;0
L 0.7793 -1.94003996 0.77746998 -1.93796004 0 P 0 ;0
L 0.77746998 -1.93796004 0.77578996 -1.93576998 0 P 0 ;0
L 0.77578996 -1.93576998 0.77423002 -1.93343002 0 P 0 ;0
L 0.77423002 -1.93343002 0.77283996 -1.931 0 P 0 ;0
L 0.77283996 -1.931 0.77161004 -1.92848996 0 P 0 ;0
L 0.77161004 -1.92848996 0.76991998 -1.92426998 0 P 0 ;0
L 0.76991998 -1.92426998 0.76858002 -1.91993996 0 P 0 ;0
L 0.76858002 -1.91993996 0.76783996 -1.91661998 0 P 0 ;0
L 0.76783996 -1.91661998 0.76738002 -1.91326998 0 P 0 ;0
L 0.76738002 -1.91326998 0.76721004 -1.90988996 0 P 0 ;0
L 0.76721004 -1.90988996 0.76731004 -1.90651004 0 P 0 ;0
L 0.76731004 -1.90651004 0.7677 -1.90315 0 P 0 ;0
L 0.7677 -1.90315 0.76838002 -1.89966998 0 P 0 ;0
L 0.76838002 -1.89966998 0.76931004 -1.89626998 0 P 0 ;0
L 0.76931004 -1.89626998 0.7705 -1.89296004 0 P 0 ;0
L 0.7705 -1.89296004 0.77193996 -1.88973996 0 P 0 ;0
L 0.77193996 -1.88973996 0.7736 -1.88663996 0 P 0 ;0
L 0.7736 -1.88663996 0.77551004 -1.88363996 0 P 0 ;0
L 0.77551004 -1.88363996 0.77763002 -1.8808 0 P 0 ;0
L 0.77763002 -1.8808 0.77996004 -1.87813002 0 P 0 ;0
L 0.77996004 -1.87813002 0.78246998 -1.87565 0 P 0 ;0
L 0.78246998 -1.87565 0.78516004 -1.87336004 0 P 0 ;0
L 0.78516004 -1.87336004 0.78795 -1.87133996 0 P 0 ;0
L 0.78795 -1.87133996 0.79088002 -1.86956004 0 P 0 ;0
L 0.79088002 -1.86956004 0.79393996 -1.86803002 0 P 0 ;0
L 0.79393996 -1.86803002 0.79711004 -1.86675 0 P 0 ;0
L 0.79711004 -1.86675 0.80038002 -1.86573002 0 P 0 ;0
L 0.80038002 -1.86573002 0.80431004 -1.86486004 0 P 0 ;0
L 0.80431004 -1.86486004 0.80828996 -1.86433996 0 P 0 ;0
L 0.80828996 -1.86433996 0.8123 -1.86416004 0 P 0 ;0
L 0.8123 -1.86416004 0.81631004 -1.86431998 0 P 0 ;0
L 0.81631004 -1.86431998 0.81946998 -1.86471004 0 P 0 ;0
L 0.81946998 -1.86471004 0.82258996 -1.86531004 0 P 0 ;0
L 0.82258996 -1.86531004 0.82566004 -1.86613996 0 P 0 ;0
L 0.82566004 -1.86613996 0.82866998 -1.86718002 0 P 0 ;0
L 0.82866998 -1.86718002 0.83158996 -1.86843002 0 P 0 ;0
L 0.83158996 -1.86843002 0.83443002 -1.86988996 0 P 0 ;0
L 0.83443002 -1.86988996 0.83716004 -1.87156004 0 P 0 ;0
L 0.83716004 -1.87156004 0.83976004 -1.87341004 0 P 0 ;0
L 0.83976004 -1.87341004 0.84223002 -1.87543996 0 P 0 ;0
L 0.84223002 -1.87543996 0.84453996 -1.87763002 0 P 0 ;0
L 0.84453996 -1.87763002 0.84726998 -1.88065 0 P 0 ;0
L 0.84726998 -1.88065 0.84971998 -1.88388002 0 P 0 ;0
L 0.84971998 -1.88388002 0.85188996 -1.88731004 0 P 0 ;0
L 0.85188996 -1.88731004 0.85376004 -1.89091004 0 P 0 ;0
L 0.85376004 -1.89091004 0.85483996 -1.89345 0 P 0 ;0
L 0.85483996 -1.89345 0.85575 -1.89605 0 P 0 ;0
L 0.85575 -1.89605 0.85646998 -1.89871004 0 P 0 ;0
L 0.85646998 -1.89871004 0.857 -1.90141004 0 P 0 ;0
L 0.857 -1.90141004 0.85748002 -1.9053 0 P 0 ;0
L 0.85748002 -1.9053 0.85763996 -1.90918996 0 P 0 ;0
L 0.85763996 -1.90918996 0.8575 -1.91308002 0 P 0 ;0
L 0.8575 -1.91308002 0.85703996 -1.91696004 0 P 0 ;0
L 0.85703996 -1.91696004 0.85628002 -1.92076004 0 P 0 ;0
L 0.85628002 -1.92076004 0.85521998 -1.92448996 0 P 0 ;0
L 0.85521998 -1.92448996 0.85428002 -1.92705 0 P 0 ;0
L 0.85428002 -1.92705 0.85316998 -1.92951998 0 P 0 ;0
L 0.85316998 -1.92951998 0.85188002 -1.93191004 0 P 0 ;0
L 0.85188002 -1.93191004 0.85041998 -1.9342 0 P 0 ;0
L 0.85041998 -1.9342 0.84826998 -1.93708002 0 P 0 ;0
L 0.84826998 -1.93708002 0.84593002 -1.93976998 0 P 0 ;0
L 0.84593002 -1.93976998 0.8434 -1.94228002 0 P 0 ;0
L 0.8434 -1.94228002 0.84068002 -1.9446 0 P 0 ;0
L 0.84068002 -1.9446 0.8378 -1.9467 0 P 0 ;0
L 0.8378 -1.9467 0.83476998 -1.94858002 0 P 0 ;0
L 0.83476998 -1.94858002 0.83163996 -1.9502 0 P 0 ;0
L 0.83163996 -1.9502 0.8284 -1.95158002 0 P 0 ;0
L 0.8284 -1.95158002 0.82506004 -1.95268996 0 P 0 ;0
L 0.82506004 -1.95268996 0.82163996 -1.95356004 0 P 0 ;0
L 0.82163996 -1.95356004 0.81818002 -1.95413996 0 P 0 ;0
L 0.81818002 -1.95413996 0.8147 -1.95446004 0 P 0 ;0
L 0.8147 -1.95446004 0.81121004 -1.9545 0 P 0 ;0
L 0.77075 -2.02925 0.84511004 -2.02925 0 P 0 ;0
L 0.77076004 -2.02825 0.8452 -2.02825 0 P 0 ;0
L 0.77076998 -2.02725 0.84528996 -2.02725 0 P 0 ;0
L 0.77078002 -2.02625 0.84536998 -2.02625 0 P 0 ;0
L 0.77078996 -2.02525 0.84548996 -2.02525 0 P 0 ;0
L 0.7708 -2.02425 0.84561998 -2.02425 0 P 0 ;0
L 0.77081004 -2.02325 0.84575 -2.02325 0 P 0 ;0
L 0.77081998 -2.02225 0.84588002 -2.02225 0 P 0 ;0
L 0.77083002 -2.02125 0.84601004 -2.02125 0 P 0 ;0
L 0.77083996 -2.02025 0.84613996 -2.02025 0 P 0 ;0
L 0.77085 -2.01925 0.84626004 -2.01925 0 P 0 ;0
L 0.77085 -2.01825 0.84638996 -2.01825 0 P 0 ;0
L 0.77085 -2.01725 0.84651998 -2.01725 0 P 0 ;0
L 0.77086004 -2.01625 0.84663996 -2.01625 0 P 0 ;0
L 0.77086004 -2.01525 0.84676998 -2.01525 0 P 0 ;0
L 0.77086004 -2.01425 0.8469 -2.01425 0 P 0 ;0
L 0.77086004 -2.01325 0.84703002 -2.01325 0 P 0 ;0
L 0.77086004 -2.01225 0.84716004 -2.01225 0 P 0 ;0
L 0.77086004 -2.01125 0.84728996 -2.01125 0 P 0 ;0
L 0.77086004 -2.01025 0.84741004 -2.01025 0 P 0 ;0
L 0.77086998 -2.00925 0.84753996 -2.00925 0 P 0 ;0
L 0.77086998 -2.00825 0.84766998 -2.00825 0 P 0 ;0
L 0.77086998 -2.00725 0.84778996 -2.00725 0 P 0 ;0
L 0.77086998 -2.00625 0.84791998 -2.00625 0 P 0 ;0
L 0.77086998 -2.00525 0.84805 -2.00525 0 P 0 ;0
L 0.77086998 -2.00425 0.84818002 -2.00425 0 P 0 ;0
L 0.77088002 -2.00325 0.84831004 -2.00325 0 P 0 ;0
L 0.77088002 -2.00225 0.84843996 -2.00225 0 P 0 ;0
L 0.77088002 -2.00125 0.84856004 -2.00125 0 P 0 ;0
L 0.77088002 -2.00025 0.84868996 -2.00025 0 P 0 ;0
L 0.77088002 -1.99925 0.84881998 -1.99925 0 P 0 ;0
L 0.77088002 -1.99825 0.84896004 -1.99825 0 P 0 ;0
L 0.77088002 -1.99725 0.84911004 -1.99725 0 P 0 ;0
L 0.77088996 -1.99625 0.84926998 -1.99625 0 P 0 ;0
L 0.77088996 -1.99525 0.84941998 -1.99525 0 P 0 ;0
L 0.77088996 -1.99425 0.84956998 -1.99425 0 P 0 ;0
L 0.77088996 -1.99325 0.84971998 -1.99325 0 P 0 ;0
L 0.77088996 -1.99225 0.84986998 -1.99225 0 P 0 ;0
L 0.77088996 -1.99125 0.85003002 -1.99125 0 P 0 ;0
L 0.7709 -1.99025 0.85018002 -1.99025 0 P 0 ;0
L 0.7709 -1.98925 0.85033002 -1.98925 0 P 0 ;0
L 0.76885 -2.01878002 0.76871998 -2.03201998 0 P 0 ;0
L 0.76871998 -2.03201998 0.7684 -2.04553996 0 P 0 ;0
L 0.7684 -2.04553996 0.76796004 -2.05751004 0 P 0 ;0
L 0.76796004 -2.05751004 0.76741004 -2.06523002 0 P 0 ;0
L 0.76741004 -2.06523002 0.76596004 -2.07933996 0 P 0 ;0
L 0.76596004 -2.07933996 0.7636 -2.09918002 0 P 0 ;0
L 0.7636 -2.09918002 0.76116004 -2.119 0 P 0 ;0
L 0.76116004 -2.119 0.76011998 -2.12526004 0 P 0 ;0
L 0.76011998 -2.12526004 0.75948996 -2.12825 0 P 0 ;0
L 0.75948996 -2.12825 0.84418002 -2.12825 0 P 0 ;0
L 0.84418002 -2.12825 0.84361998 -2.10788002 0 P 0 ;0
L 0.84361998 -2.10788002 0.8436 -2.08276004 0 P 0 ;0
L 0.8436 -2.08276004 0.8449 -2.05491998 0 P 0 ;0
L 0.8449 -2.05491998 0.84736004 -2.02641004 0 P 0 ;0
L 0.84736004 -2.02641004 0.85083996 -1.99923002 0 P 0 ;0
L 0.85083996 -1.99923002 0.85268996 -1.987 0 P 0 ;0
L 0.85268996 -1.987 0.7689 -1.987 0 P 0 ;0
L 0.7689 -1.987 0.76885 -2.01878002 0 P 0 ;0
L 0.76195 -2.12625 0.84211998 -2.12625 0 P 0 ;0
L 0.76213996 -2.12525 0.8421 -2.12525 0 P 0 ;0
L 0.76231004 -2.12425 0.84206998 -2.12425 0 P 0 ;0
L 0.76248002 -2.12325 0.84203996 -2.12325 0 P 0 ;0
L 0.76263996 -2.12225 0.84201004 -2.12225 0 P 0 ;0
L 0.76281004 -2.12125 0.84198996 -2.12125 0 P 0 ;0
L 0.76296998 -2.12025 0.84196004 -2.12025 0 P 0 ;0
L 0.76313996 -2.11925 0.84193002 -2.11925 0 P 0 ;0
L 0.76326998 -2.11825 0.8419 -2.11825 0 P 0 ;0
L 0.76338996 -2.11725 0.84188002 -2.11725 0 P 0 ;0
L 0.76351004 -2.11625 0.84185 -2.11625 0 P 0 ;0
L 0.76363996 -2.11525 0.84181998 -2.11525 0 P 0 ;0
L 0.76376004 -2.11425 0.84178996 -2.11425 0 P 0 ;0
L 0.76388002 -2.11325 0.84176998 -2.11325 0 P 0 ;0
L 0.76401004 -2.11225 0.84173996 -2.11225 0 P 0 ;0
L 0.76413002 -2.11125 0.84171004 -2.11125 0 P 0 ;0
L 0.76425 -2.11025 0.84168002 -2.11025 0 P 0 ;0
L 0.76438002 -2.10925 0.84166004 -2.10925 0 P 0 ;0
L 0.7645 -2.10825 0.84163002 -2.10825 0 P 0 ;0
L 0.76461998 -2.10725 0.84161998 -2.10725 0 P 0 ;0
L 0.76475 -2.10625 0.84161998 -2.10625 0 P 0 ;0
L 0.76486998 -2.10525 0.84161998 -2.10525 0 P 0 ;0
L 0.76498996 -2.10425 0.84161998 -2.10425 0 P 0 ;0
L 0.76511998 -2.10325 0.84161998 -2.10325 0 P 0 ;0
L 0.76523996 -2.10225 0.84161998 -2.10225 0 P 0 ;0
L 0.76536004 -2.10125 0.84161998 -2.10125 0 P 0 ;0
L 0.76548996 -2.10025 0.84161998 -2.10025 0 P 0 ;0
L 0.76561004 -2.09925 0.84161998 -2.09925 0 P 0 ;0
L 0.76573002 -2.09825 0.84161004 -2.09825 0 P 0 ;0
L 0.76583996 -2.09725 0.84161004 -2.09725 0 P 0 ;0
L 0.76596998 -2.09625 0.84161004 -2.09625 0 P 0 ;0
L 0.76608996 -2.09525 0.84161004 -2.09525 0 P 0 ;0
L 0.7662 -2.09425 0.84161004 -2.09425 0 P 0 ;0
L 0.76631998 -2.09325 0.84161004 -2.09325 0 P 0 ;0
L 0.76643996 -2.09225 0.84161004 -2.09225 0 P 0 ;0
L 0.76656004 -2.09125 0.84161004 -2.09125 0 P 0 ;0
L 0.76668002 -2.09025 0.84161004 -2.09025 0 P 0 ;0
L 0.76678996 -2.08925 0.84161004 -2.08925 0 P 0 ;0
L 0.76691998 -2.08825 0.84161004 -2.08825 0 P 0 ;0
L 0.76703002 -2.08725 0.84161004 -2.08725 0 P 0 ;0
L 0.76715 -2.08625 0.8416 -2.08625 0 P 0 ;0
L 0.76726998 -2.08525 0.8416 -2.08525 0 P 0 ;0
L 0.76738996 -2.08425 0.8416 -2.08425 0 P 0 ;0
L 0.76195 -2.12625 0.76208002 -2.12561998 0 P 0 ;0
L 0.76208002 -2.12561998 0.76313996 -2.11928996 0 P 0 ;0
L 0.76313996 -2.11928996 0.76558996 -2.09941998 0 P 0 ;0
L 0.76558996 -2.09941998 0.76558996 -2.09941004 0 P 0 ;0
L 0.76558996 -2.09941004 0.76793996 -2.07956004 0 P 0 ;0
L 0.76793996 -2.07956004 0.7694 -2.0654 0 P 0 ;0
L 0.7694 -2.0654 0.76941004 -2.06536004 0 P 0 ;0
L 0.76941004 -2.06536004 0.76996004 -2.05761998 0 P 0 ;0
L 0.76996004 -2.05761998 0.76996004 -2.05758996 0 P 0 ;0
L 0.76996004 -2.05758996 0.7704 -2.0456 0 P 0 ;0
L 0.7704 -2.0456 0.77071998 -2.03206004 0 P 0 ;0
L 0.77071998 -2.03206004 0.77085 -2.01878002 0 P 0 ;0
L 0.77085 -2.01878002 0.7709 -1.989 0 P 0 ;0
L 0.7709 -1.989 0.85036004 -1.989 0 P 0 ;0
L 0.85036004 -1.989 0.84886004 -1.99895 0 P 0 ;0
L 0.84886004 -1.99895 0.84538002 -2.02618996 0 P 0 ;0
L 0.84538002 -2.02618996 0.8429 -2.05478996 0 P 0 ;0
L 0.8429 -2.05478996 0.8416 -2.08271004 0 P 0 ;0
L 0.8416 -2.08271004 0.84161998 -2.10791004 0 P 0 ;0
L 0.84161998 -2.10791004 0.84211998 -2.12625 0 P 0 ;0
L 0.84211998 -2.12625 0.76195 -2.12625 0 P 0 ;0
L 0.71628996 -1.91261998 0.74938002 -1.91261998 0 P 0 ;0
L 0.71783002 -1.91161998 0.74933002 -1.91161998 0 P 0 ;0
L 0.71953002 -1.91061998 0.74931004 -1.91061998 0 P 0 ;0
L 0.72133002 -1.90961998 0.74928996 -1.90961998 0 P 0 ;0
L 0.72313996 -1.90861998 0.74926998 -1.90861998 0 P 0 ;0
L 0.72493996 -1.90761998 0.74928996 -1.90761998 0 P 0 ;0
L 0.72673996 -1.90661998 0.74931998 -1.90661998 0 P 0 ;0
L 0.72855 -1.90561998 0.74935 -1.90561998 0 P 0 ;0
L 0.73035 -1.90461998 0.74938996 -1.90461998 0 P 0 ;0
L 0.73215 -1.90361998 0.74946998 -1.90361998 0 P 0 ;0
L 0.73396004 -1.90261998 0.74953996 -1.90261998 0 P 0 ;0
L 0.73576004 -1.90161998 0.74961998 -1.90161998 0 P 0 ;0
L 0.73756998 -1.90061998 0.74973996 -1.90061998 0 P 0 ;0
L 0.73943002 -1.89961998 0.74986004 -1.89961998 0 P 0 ;0
L 0.74141998 -1.89861998 0.74998996 -1.89861998 0 P 0 ;0
L 0.74341004 -1.89761998 0.75015 -1.89761998 0 P 0 ;0
L 0.59843002 -2.08361998 0.6754 -2.08361998 0 P 0 ;0
L 0.59846004 -2.08261998 0.67538996 -2.08261998 0 P 0 ;0
L 0.59848002 -2.08161998 0.67538002 -2.08161998 0 P 0 ;0
L 0.59851004 -2.08061998 0.67538002 -2.08061998 0 P 0 ;0
L 0.59853002 -2.07961998 0.67546004 -2.07961998 0 P 0 ;0
L 0.59856004 -2.07861998 0.67553996 -2.07861998 0 P 0 ;0
L 0.59861998 -2.07761998 0.67561004 -2.07761998 0 P 0 ;0
L 0.5987 -2.07661998 0.67568996 -2.07661998 0 P 0 ;0
L 0.59878002 -2.07561998 0.67576004 -2.07561998 0 P 0 ;0
L 0.59885 -2.07461998 0.67583996 -2.07461998 0 P 0 ;0
L 0.59893002 -2.07361998 0.67591998 -2.07361998 0 P 0 ;0
L 0.59901004 -2.07261998 0.67598996 -2.07261998 0 P 0 ;0
L 0.59908002 -2.07161998 0.67606998 -2.07161998 0 P 0 ;0
L 0.59916004 -2.07061998 0.67613996 -2.07061998 0 P 0 ;0
L 0.59923002 -2.06961998 0.67621004 -2.06961998 0 P 0 ;0
L 0.59936004 -2.06861998 0.6763 -2.06861998 0 P 0 ;0
L 0.59948996 -2.06761998 0.67645 -2.06761998 0 P 0 ;0
L 0.59963002 -2.06661998 0.6766 -2.06661998 0 P 0 ;0
L 0.59976998 -2.06561998 0.67676004 -2.06561998 0 P 0 ;0
L 0.5999 -2.06461998 0.67691998 -2.06461998 0 P 0 ;0
L 0.60003002 -2.06361998 0.67706998 -2.06361998 0 P 0 ;0
L 0.60016998 -2.06261998 0.6773 -2.06261998 0 P 0 ;0
L 0.60031004 -2.06161998 0.67753002 -2.06161998 0 P 0 ;0
L 0.60051004 -2.06061998 0.67776004 -2.06061998 0 P 0 ;0
L 0.60071004 -2.05961998 0.67798996 -2.05961998 0 P 0 ;0
L 0.60091998 -2.05861998 0.67823002 -2.05861998 0 P 0 ;0
L 0.60111998 -2.05761998 0.67853002 -2.05761998 0 P 0 ;0
L 0.60133002 -2.05661998 0.67883996 -2.05661998 0 P 0 ;0
L 0.60153996 -2.05561998 0.67913996 -2.05561998 0 P 0 ;0
L 0.60173996 -2.05461998 0.67945 -2.05461998 0 P 0 ;0
L 0.60195 -2.05361998 0.67975 -2.05361998 0 P 0 ;0
L 0.60223002 -2.05261998 0.68006004 -2.05261998 0 P 0 ;0
L 0.60251004 -2.05161998 0.68036004 -2.05161998 0 P 0 ;0
L 0.60278996 -2.05061998 0.68066998 -2.05061998 0 P 0 ;0
L 0.60306004 -2.04961998 0.68096998 -2.04961998 0 P 0 ;0
L 0.60333996 -2.04861998 0.68135 -2.04861998 0 P 0 ;0
L 0.60361998 -2.04761998 0.68173002 -2.04761998 0 P 0 ;0
L 0.6039 -2.04661998 0.68211004 -2.04661998 0 P 0 ;0
L 0.60418002 -2.04561998 0.68248996 -2.04561998 0 P 0 ;0
L 0.60453002 -2.04461998 0.68288002 -2.04461998 0 P 0 ;0
L 0.60488002 -2.04361998 0.68326004 -2.04361998 0 P 0 ;0
L 0.60523002 -2.04261998 0.68363996 -2.04261998 0 P 0 ;0
L 0.60556998 -2.04161998 0.68401998 -2.04161998 0 P 0 ;0
L 0.60591998 -2.04061998 0.6844 -2.04061998 0 P 0 ;0
L 0.60626998 -2.03961998 0.68486004 -2.03961998 0 P 0 ;0
L 0.60661998 -2.03861998 0.68531998 -2.03861998 0 P 0 ;0
L 0.60698996 -2.03761998 0.68578002 -2.03761998 0 P 0 ;0
L 0.60743002 -2.03661998 0.68623996 -2.03661998 0 P 0 ;0
L 0.60786004 -2.03561998 0.6867 -2.03561998 0 P 0 ;0
L 0.60828996 -2.03461998 0.68716004 -2.03461998 0 P 0 ;0
L 0.60873002 -2.03361998 0.68761998 -2.03361998 0 P 0 ;0
L 0.60916004 -2.03261998 0.68808996 -2.03261998 0 P 0 ;0
L 0.60958996 -2.03161998 0.68856998 -2.03161998 0 P 0 ;0
L 0.61003002 -2.03061998 0.68911004 -2.03061998 0 P 0 ;0
L 0.61046004 -2.02961998 0.68965 -2.02961998 0 P 0 ;0
L 0.61088996 -2.02861998 0.69018996 -2.02861998 0 P 0 ;0
L 0.61133002 -2.02761998 0.69073002 -2.02761998 0 P 0 ;0
L 0.61176004 -2.02661998 0.69126998 -2.02661998 0 P 0 ;0
L 0.6122 -2.02561998 0.69181004 -2.02561998 0 P 0 ;0
L 0.61263002 -2.02461998 0.69235 -2.02461998 0 P 0 ;0
L 0.61306004 -2.02361998 0.69288002 -2.02361998 0 P 0 ;0
L 0.61348996 -2.02261998 0.69346998 -2.02261998 0 P 0 ;0
L 0.61393002 -2.02161998 0.69408996 -2.02161998 0 P 0 ;0
L 0.61436004 -2.02061998 0.6947 -2.02061998 0 P 0 ;0
L 0.61478996 -2.01961998 0.69531998 -2.01961998 0 P 0 ;0
L 0.61531004 -2.01861998 0.69593996 -2.01861998 0 P 0 ;0
L 0.61583996 -2.01761998 0.69656004 -2.01761998 0 P 0 ;0
L 0.61636004 -2.01661998 0.69718002 -2.01661998 0 P 0 ;0
L 0.61688002 -2.01561998 0.69778996 -2.01561998 0 P 0 ;0
L 0.6174 -2.01461998 0.69841998 -2.01461998 0 P 0 ;0
L 0.61791998 -2.01361998 0.69911998 -2.01361998 0 P 0 ;0
L 0.61843996 -2.01261998 0.69981998 -2.01261998 0 P 0 ;0
L 0.61896004 -2.01161998 0.70051998 -2.01161998 0 P 0 ;0
L 0.61948002 -2.01061998 0.70123002 -2.01061998 0 P 0 ;0
L 0.62 -2.00961998 0.70193002 -2.00961998 0 P 0 ;0
L 0.62051998 -2.00861998 0.70263002 -2.00861998 0 P 0 ;0
L 0.62103996 -2.00761998 0.70333002 -2.00761998 0 P 0 ;0
L 0.62163996 -2.00661998 0.70403996 -2.00661998 0 P 0 ;0
L 0.62225 -2.00561998 0.70483002 -2.00561998 0 P 0 ;0
L 0.62285 -2.00461998 0.70565 -2.00461998 0 P 0 ;0
L 0.62346004 -2.00361998 0.70646004 -2.00361998 0 P 0 ;0
L 0.62406004 -2.00261998 0.70726998 -2.00261998 0 P 0 ;0
L 0.62466004 -2.00161998 0.70808996 -2.00161998 0 P 0 ;0
L 0.62526998 -2.00061998 0.7089 -2.00061998 0 P 0 ;0
L 0.62586998 -1.99961998 0.70971004 -1.99961998 0 P 0 ;0
L 0.62648002 -1.99861998 0.71053002 -1.99861998 0 P 0 ;0
L 0.62708002 -1.99761998 0.71133996 -1.99761998 0 P 0 ;0
L 0.62768996 -1.99661998 0.71216004 -1.99661998 0 P 0 ;0
L 0.62831998 -1.99561998 0.71296998 -1.99561998 0 P 0 ;0
L 0.62901004 -1.99461998 0.71378996 -1.99461998 0 P 0 ;0
L 0.62971004 -1.99361998 0.71466004 -1.99361998 0 P 0 ;0
L 0.6304 -1.99261998 0.71561004 -1.99261998 0 P 0 ;0
L 0.6311 -1.99161998 0.71656998 -1.99161998 0 P 0 ;0
L 0.63178996 -1.99061998 0.71753002 -1.99061998 0 P 0 ;0
L 0.63248996 -1.98961998 0.71848996 -1.98961998 0 P 0 ;0
L 0.63318002 -1.98861998 0.71945 -1.98861998 0 P 0 ;0
L 0.63388002 -1.98761998 0.72041004 -1.98761998 0 P 0 ;0
L 0.63456998 -1.98661998 0.72136998 -1.98661998 0 P 0 ;0
L 0.63526998 -1.98561998 0.72233002 -1.98561998 0 P 0 ;0
L 0.63598002 -1.98461998 0.72328996 -1.98461998 0 P 0 ;0
L 0.63678996 -1.98361998 0.72425 -1.98361998 0 P 0 ;0
L 0.6376 -1.98261998 0.72521004 -1.98261998 0 P 0 ;0
L 0.63841004 -1.98161998 0.72628002 -1.98161998 0 P 0 ;0
L 0.63921998 -1.98061998 0.72738996 -1.98061998 0 P 0 ;0
L 0.64003002 -1.97961998 0.7285 -1.97961998 0 P 0 ;0
L 0.64083996 -1.97861998 0.72961004 -1.97861998 0 P 0 ;0
L 0.64165 -1.97761998 0.73071004 -1.97761998 0 P 0 ;0
L 0.64246004 -1.97661998 0.73181998 -1.97661998 0 P 0 ;0
L 0.64326998 -1.97561998 0.73293002 -1.97561998 0 P 0 ;0
L 0.64406998 -1.97461998 0.73403996 -1.97461998 0 P 0 ;0
L 0.64488002 -1.97361998 0.73515 -1.97361998 0 P 0 ;0
L 0.64568996 -1.97261998 0.73625 -1.97261998 0 P 0 ;0
L 0.6465 -1.97161998 0.73736004 -1.97161998 0 P 0 ;0
L 0.64731004 -1.97061998 0.73848002 -1.97061998 0 P 0 ;0
L 0.64811998 -1.96961998 0.73973002 -1.96961998 0 P 0 ;0
L 0.64893002 -1.96861998 0.74098996 -1.96861998 0 P 0 ;0
L 0.64981004 -1.96761998 0.74225 -1.96761998 0 P 0 ;0
L 0.65076004 -1.96661998 0.74351004 -1.96661998 0 P 0 ;0
L 0.65171004 -1.96561998 0.74476998 -1.96561998 0 P 0 ;0
L 0.65266998 -1.96461998 0.74603002 -1.96461998 0 P 0 ;0
L 0.65361998 -1.96361998 0.74728996 -1.96361998 0 P 0 ;0
L 0.65458002 -1.96261998 0.74855 -1.96261998 0 P 0 ;0
L 0.65553002 -1.96161998 0.74981004 -1.96161998 0 P 0 ;0
L 0.65648996 -1.96061998 0.75106004 -1.96061998 0 P 0 ;0
L 0.65743996 -1.95961998 0.75233996 -1.95961998 0 P 0 ;0
L 0.6584 -1.95861998 0.7537 -1.95861998 0 P 0 ;0
L 0.65935 -1.95761998 0.75506004 -1.95761998 0 P 0 ;0
L 0.66031004 -1.95661998 0.75641998 -1.95661998 0 P 0 ;0
L 0.66126004 -1.95561998 0.75778996 -1.95561998 0 P 0 ;0
L 0.66221004 -1.95461998 0.75916004 -1.95461998 0 P 0 ;0
L 0.66316998 -1.95361998 0.76053996 -1.95361998 0 P 0 ;0
L 0.66411998 -1.95261998 0.76193996 -1.95261998 0 P 0 ;0
L 0.66523002 -1.95161998 0.76333996 -1.95161998 0 P 0 ;0
L 0.66636004 -1.95061998 0.76406998 -1.95061998 0 P 0 ;0
L 0.66746998 -1.94961998 0.76355 -1.94961998 0 P 0 ;0
L 0.6686 -1.94861998 0.76291998 -1.94861998 0 P 0 ;0
L 0.66971004 -1.94761998 0.76226998 -1.94761998 0 P 0 ;0
L 0.67083996 -1.94661998 0.76161998 -1.94661998 0 P 0 ;0
L 0.67196004 -1.94561998 0.76096998 -1.94561998 0 P 0 ;0
L 0.67306998 -1.94461998 0.76033002 -1.94461998 0 P 0 ;0
L 0.6742 -1.94361998 0.75968996 -1.94361998 0 P 0 ;0
L 0.67531004 -1.94261998 0.75905 -1.94261998 0 P 0 ;0
L 0.67643996 -1.94161998 0.75846004 -1.94161998 0 P 0 ;0
L 0.67755 -1.94061998 0.75788996 -1.94061998 0 P 0 ;0
L 0.67868002 -1.93961998 0.75731998 -1.93961998 0 P 0 ;0
L 0.67978996 -1.93861998 0.75676998 -1.93861998 0 P 0 ;0
L 0.68091998 -1.93761998 0.75626998 -1.93761998 0 P 0 ;0
L 0.68221004 -1.93661998 0.75576998 -1.93661998 0 P 0 ;0
L 0.68353002 -1.93561998 0.75528002 -1.93561998 0 P 0 ;0
L 0.68483996 -1.93461998 0.75483996 -1.93461998 0 P 0 ;0
L 0.68616004 -1.93361998 0.75441004 -1.93361998 0 P 0 ;0
L 0.68746998 -1.93261998 0.75398002 -1.93261998 0 P 0 ;0
L 0.68878002 -1.93161998 0.7536 -1.93161998 0 P 0 ;0
L 0.6901 -1.93061998 0.75323996 -1.93061998 0 P 0 ;0
L 0.69141004 -1.92961998 0.75286998 -1.92961998 0 P 0 ;0
L 0.69271998 -1.92861998 0.75253996 -1.92861998 0 P 0 ;0
L 0.69403002 -1.92761998 0.75223002 -1.92761998 0 P 0 ;0
L 0.69535 -1.92661998 0.75193002 -1.92661998 0 P 0 ;0
L 0.69666004 -1.92561998 0.75163002 -1.92561998 0 P 0 ;0
L 0.69796998 -1.92461998 0.75138002 -1.92461998 0 P 0 ;0
L 0.69936998 -1.92361998 0.75113996 -1.92361998 0 P 0 ;0
L 0.70091004 -1.92261998 0.75088996 -1.92261998 0 P 0 ;0
L 0.70243996 -1.92161998 0.75066004 -1.92161998 0 P 0 ;0
L 0.70398002 -1.92061998 0.75046004 -1.92061998 0 P 0 ;0
L 0.70551998 -1.91961998 0.75026004 -1.91961998 0 P 0 ;0
L 0.70706004 -1.91861998 0.75006998 -1.91861998 0 P 0 ;0
L 0.7086 -1.91761998 0.7499 -1.91761998 0 P 0 ;0
L 0.71013996 -1.91661998 0.74976998 -1.91661998 0 P 0 ;0
L 0.71166998 -1.91561998 0.74961998 -1.91561998 0 P 0 ;0
L 0.71321004 -1.91461998 0.74951998 -1.91461998 0 P 0 ;0
L 0.71475 -1.91361998 0.74945 -1.91361998 0 P 0 ;0
L 0.61556998 -2.15661998 0.70655 -2.15661998 0 P 0 ;0
L 0.61503002 -2.15561998 0.7056 -2.15561998 0 P 0 ;0
L 0.61448996 -2.15461998 0.70465 -2.15461998 0 P 0 ;0
L 0.61395 -2.15361998 0.7037 -2.15361998 0 P 0 ;0
L 0.61341004 -2.15261998 0.70273996 -2.15261998 0 P 0 ;0
L 0.61286998 -2.15161998 0.70178996 -2.15161998 0 P 0 ;0
L 0.61233002 -2.15061998 0.70095 -2.15061998 0 P 0 ;0
L 0.61188002 -2.14961998 0.70015 -2.14961998 0 P 0 ;0
L 0.61143002 -2.14861998 0.69935 -2.14861998 0 P 0 ;0
L 0.61098002 -2.14761998 0.69855 -2.14761998 0 P 0 ;0
L 0.61053002 -2.14661998 0.69775 -2.14661998 0 P 0 ;0
L 0.61008002 -2.14561998 0.69695 -2.14561998 0 P 0 ;0
L 0.60963002 -2.14461998 0.69615 -2.14461998 0 P 0 ;0
L 0.60918002 -2.14361998 0.69535 -2.14361998 0 P 0 ;0
L 0.60873002 -2.14261998 0.69455 -2.14261998 0 P 0 ;0
L 0.60831004 -2.14161998 0.69381998 -2.14161998 0 P 0 ;0
L 0.60793996 -2.14061998 0.69315 -2.14061998 0 P 0 ;0
L 0.60756998 -2.13961998 0.69248002 -2.13961998 0 P 0 ;0
L 0.60721004 -2.13861998 0.69181004 -2.13861998 0 P 0 ;0
L 0.60683996 -2.13761998 0.69115 -2.13761998 0 P 0 ;0
L 0.60646998 -2.13661998 0.69048002 -2.13661998 0 P 0 ;0
L 0.60611004 -2.13561998 0.68981004 -2.13561998 0 P 0 ;0
L 0.60573996 -2.13461998 0.68918002 -2.13461998 0 P 0 ;0
L 0.60538002 -2.13361998 0.68863002 -2.13361998 0 P 0 ;0
L 0.60503996 -2.13261998 0.68808002 -2.13261998 0 P 0 ;0
L 0.60476004 -2.13161998 0.68753002 -2.13161998 0 P 0 ;0
L 0.60446998 -2.13061998 0.68698002 -2.13061998 0 P 0 ;0
L 0.60418002 -2.12961998 0.68643002 -2.12961998 0 P 0 ;0
L 0.6039 -2.12861998 0.68588002 -2.12861998 0 P 0 ;0
L 0.60361004 -2.12761998 0.68533002 -2.12761998 0 P 0 ;0
L 0.60331998 -2.12661998 0.68486004 -2.12661998 0 P 0 ;0
L 0.60303002 -2.12561998 0.68441998 -2.12561998 0 P 0 ;0
L 0.60275 -2.12461998 0.68396998 -2.12461998 0 P 0 ;0
L 0.60246004 -2.12361998 0.68353002 -2.12361998 0 P 0 ;0
L 0.60218002 -2.12261998 0.68308996 -2.12261998 0 P 0 ;0
L 0.60188996 -2.12161998 0.68263996 -2.12161998 0 P 0 ;0
L 0.60166998 -2.12061998 0.6822 -2.12061998 0 P 0 ;0
L 0.60145 -2.11961998 0.68176004 -2.11961998 0 P 0 ;0
L 0.60123002 -2.11861998 0.68138996 -2.11861998 0 P 0 ;0
L 0.60101004 -2.11761998 0.68105 -2.11761998 0 P 0 ;0
L 0.60078002 -2.11661998 0.68071004 -2.11661998 0 P 0 ;0
L 0.6006 -2.11561998 0.68036004 -2.11561998 0 P 0 ;0
L 0.60043002 -2.11461998 0.68001998 -2.11461998 0 P 0 ;0
L 0.60025 -2.11361998 0.67968002 -2.11361998 0 P 0 ;0
L 0.60008002 -2.11261998 0.67933002 -2.11261998 0 P 0 ;0
L 0.59991004 -2.11161998 0.67898996 -2.11161998 0 P 0 ;0
L 0.59976004 -2.11061998 0.6787 -2.11061998 0 P 0 ;0
L 0.59963996 -2.10961998 0.67845 -2.10961998 0 P 0 ;0
L 0.59951004 -2.10861998 0.6782 -2.10861998 0 P 0 ;0
L 0.59938002 -2.10761998 0.67795 -2.10761998 0 P 0 ;0
L 0.59925 -2.10661998 0.6777 -2.10661998 0 P 0 ;0
L 0.59913002 -2.10561998 0.67746004 -2.10561998 0 P 0 ;0
L 0.59905 -2.10461998 0.67721004 -2.10461998 0 P 0 ;0
L 0.59896998 -2.10361998 0.67696004 -2.10361998 0 P 0 ;0
L 0.59888002 -2.10261998 0.67671004 -2.10261998 0 P 0 ;0
L 0.5988 -2.10161998 0.67653996 -2.10161998 0 P 0 ;0
L 0.59871998 -2.10061998 0.67638002 -2.10061998 0 P 0 ;0
L 0.59866998 -2.09961998 0.67621004 -2.09961998 0 P 0 ;0
L 0.59863996 -2.09861998 0.67605 -2.09861998 0 P 0 ;0
L 0.59861004 -2.09761998 0.67588996 -2.09761998 0 P 0 ;0
L 0.59858996 -2.09661998 0.6758 -2.09661998 0 P 0 ;0
L 0.59856004 -2.09561998 0.67571004 -2.09561998 0 P 0 ;0
L 0.59853002 -2.09461998 0.67563002 -2.09461998 0 P 0 ;0
L 0.5985 -2.09361998 0.67553996 -2.09361998 0 P 0 ;0
L 0.59846998 -2.09261998 0.67546004 -2.09261998 0 P 0 ;0
L 0.59843996 -2.09161998 0.67546004 -2.09161998 0 P 0 ;0
L 0.59841998 -2.09061998 0.67545 -2.09061998 0 P 0 ;0
L 0.59838002 -2.08961998 0.67543996 -2.08961998 0 P 0 ;0
L 0.59836004 -2.08861998 0.67543002 -2.08861998 0 P 0 ;0
L 0.59833002 -2.08761998 0.67543002 -2.08761998 0 P 0 ;0
L 0.59835 -2.08661998 0.67541998 -2.08661998 0 P 0 ;0
L 0.59836998 -2.08561998 0.67541004 -2.08561998 0 P 0 ;0
L 0.5984 -2.08461998 0.67541004 -2.08461998 0 P 0 ;0
L 0.80005 -2.25161998 0.85543996 -2.25161998 0 P 0 ;0
L 0.78651998 -2.25061998 0.86596004 -2.25061998 0 P 0 ;0
L 0.77878996 -2.24961998 0.87636004 -2.24961998 0 P 0 ;0
L 0.77106004 -2.24861998 0.88285 -2.24861998 0 P 0 ;0
L 0.76398996 -2.24761998 0.88933996 -2.24761998 0 P 0 ;0
L 0.75891998 -2.24661998 0.89583996 -2.24661998 0 P 0 ;0
L 0.73781004 -1.8982 0.71738996 -1.90951998 0 P 0 ;0
L 0.71738996 -1.90951998 0.69766998 -1.92233996 0 P 0 ;0
L 0.69766998 -1.92233996 0.67971004 -1.93601998 0 P 0 ;0
L 0.67971004 -1.93601998 0.66278996 -1.95113002 0 P 0 ;0
L 0.66278996 -1.95113002 0.64786998 -1.96675 0 P 0 ;0
L 0.64786998 -1.96675 0.63423996 -1.98358996 0 P 0 ;0
L 0.63423996 -1.98358996 0.62643996 -1.99483002 0 P 0 ;0
L 0.62643996 -1.99483002 0.61933996 -2.00655 0 P 0 ;0
L 0.61933996 -2.00655 0.61298996 -2.01873996 0 P 0 ;0
L 0.61298996 -2.01873996 0.60503002 -2.03713002 0 P 0 ;0
L 0.60503002 -2.03713002 0.60225 -2.04506004 0 P 0 ;0
L 0.60225 -2.04506004 0.59998996 -2.05323002 0 P 0 ;0
L 0.59998996 -2.05323002 0.59833996 -2.0612 0 P 0 ;0
L 0.59833996 -2.0612 0.59725 -2.06928996 0 P 0 ;0
L 0.59725 -2.06928996 0.59656998 -2.07833996 0 P 0 ;0
L 0.59656998 -2.07833996 0.59633002 -2.0875 0 P 0 ;0
L 0.59633002 -2.0875 0.59668996 -2.10036998 0 P 0 ;0
L 0.59668996 -2.10036998 0.59715 -2.10596004 0 P 0 ;0
L 0.59715 -2.10596004 0.59786004 -2.11151004 0 P 0 ;0
L 0.59786004 -2.11151004 0.59878996 -2.11686998 0 P 0 ;0
L 0.59878996 -2.11686998 0.59996998 -2.1222 0 P 0 ;0
L 0.59996998 -2.1222 0.60326998 -2.13368996 0 P 0 ;0
L 0.60326998 -2.13368996 0.60656998 -2.1427 0 P 0 ;0
L 0.60656998 -2.1427 0.6105 -2.15143996 0 P 0 ;0
L 0.6105 -2.15143996 0.61505 -2.15988002 0 P 0 ;0
L 0.61505 -2.15988002 0.62023996 -2.16803996 0 P 0 ;0
L 0.62023996 -2.16803996 0.62828996 -2.17873002 0 P 0 ;0
L 0.62828996 -2.17873002 0.63718996 -2.18871004 0 P 0 ;0
L 0.63718996 -2.18871004 0.64693002 -2.19795 0 P 0 ;0
L 0.64693002 -2.19795 0.6582 -2.20701998 0 P 0 ;0
L 0.6582 -2.20701998 0.67011004 -2.21518996 0 P 0 ;0
L 0.67011004 -2.21518996 0.68261004 -2.22243002 0 P 0 ;0
L 0.68261004 -2.22243002 0.69673996 -2.22936004 0 P 0 ;0
L 0.69673996 -2.22936004 0.71123002 -2.23543996 0 P 0 ;0
L 0.71123002 -2.23543996 0.72611998 -2.24066998 0 P 0 ;0
L 0.72611998 -2.24066998 0.74536004 -2.24598996 0 P 0 ;0
L 0.74536004 -2.24598996 0.76493002 -2.24985 0 P 0 ;0
L 0.76493002 -2.24985 0.78671998 -2.25266998 0 P 0 ;0
L 0.78671998 -2.25266998 0.80863002 -2.25425 0 P 0 ;0
L 0.80863002 -2.25425 0.83146004 -2.25463002 0 P 0 ;0
L 0.83146004 -2.25463002 0.85418002 -2.25375 0 P 0 ;0
L 0.85418002 -2.25375 0.87641004 -2.25163996 0 P 0 ;0
L 0.87641004 -2.25163996 0.89853002 -2.24823002 0 P 0 ;0
L 0.89853002 -2.24823002 0.93045 -2.24101998 0 P 0 ;0
L 0.93045 -2.24101998 0.96466004 -2.23063002 0 P 0 ;0
L 0.96466004 -2.23063002 0.99911004 -2.2178 0 P 0 ;0
L 0.99911004 -2.2178 1.03183002 -2.20318002 0 P 0 ;0
L 1.03183002 -2.20318002 1.04391998 -2.19703002 0 P 0 ;0
L 1.04391998 -2.19703002 1.05581004 -2.19048996 0 P 0 ;0
L 1.05581004 -2.19048996 1.06676004 -2.18411998 0 P 0 ;0
L 1.06676004 -2.18411998 1.06681004 -2.18408996 0 P 0 ;0
L 1.06681004 -2.18408996 1.06685 -2.18405 0 P 0 ;0
L 1.06685 -2.18405 1.0669 -2.18401004 0 P 0 ;0
L 1.0669 -2.18401004 1.06693996 -2.18396998 0 P 0 ;0
L 1.06693996 -2.18396998 1.06696998 -2.18391998 0 P 0 ;0
L 1.06696998 -2.18391998 1.06701004 -2.18386998 0 P 0 ;0
L 1.06701004 -2.18386998 1.06703002 -2.18381998 0 P 0 ;0
L 1.06703002 -2.18381998 1.06706004 -2.18376004 0 P 0 ;0
L 1.06706004 -2.18376004 1.06706998 -2.18371004 0 P 0 ;0
L 1.06706998 -2.18371004 1.06708996 -2.18365 0 P 0 ;0
L 1.06708996 -2.18365 1.06708996 -2.18358996 0 P 0 ;0
L 1.06708996 -2.18358996 1.0671 -2.18353002 0 P 0 ;0
L 1.0671 -2.18353002 1.0671 -2.18346998 0 P 0 ;0
L 1.0671 -2.18346998 1.06708996 -2.18341004 0 P 0 ;0
L 1.06708996 -2.18341004 1.06706998 -2.18336004 0 P 0 ;0
L 1.06706998 -2.18336004 1.06706004 -2.1833 0 P 0 ;0
L 1.06706004 -2.1833 1.06703002 -2.18323996 0 P 0 ;0
L 1.06703002 -2.18323996 1.06701004 -2.18318996 0 P 0 ;0
L 1.06701004 -2.18318996 1.06696998 -2.18313996 0 P 0 ;0
L 1.06696998 -2.18313996 1.06693996 -2.18308996 0 P 0 ;0
L 1.06693996 -2.18308996 1.06688002 -2.18303002 0 P 0 ;0
L 1.06688002 -2.18303002 1.06678996 -2.18296998 0 P 0 ;0
L 1.06678996 -2.18296998 1.06673002 -2.18295 0 P 0 ;0
L 1.06673002 -2.18295 1.0667 -2.18295 0 P 0 ;0
L 1.0667 -2.18295 1.06666004 -2.18293996 0 P 0 ;0
L 1.06666004 -2.18293996 1.0666 -2.18293996 0 P 0 ;0
L 1.0666 -2.18293996 1.06656998 -2.18295 0 P 0 ;0
L 1.06656998 -2.18295 1.06653002 -2.18295 0 P 0 ;0
L 1.06653002 -2.18295 1.06153002 -2.1842 0 P 0 ;0
L 1.06153002 -2.1842 1.05583996 -2.18566998 0 P 0 ;0
L 1.05583996 -2.18566998 1.04916998 -2.1875 0 P 0 ;0
L 1.04916998 -2.1875 1.0153 -2.1962 0 P 0 ;0
L 1.0153 -2.1962 0.9814 -2.20333996 0 P 0 ;0
L 0.9814 -2.20333996 0.94881998 -2.2087 0 P 0 ;0
L 0.94881998 -2.2087 0.9189 -2.21198996 0 P 0 ;0
L 0.9189 -2.21198996 0.90113996 -2.21278996 0 P 0 ;0
L 0.90113996 -2.21278996 0.87738002 -2.21265 0 P 0 ;0
L 0.87738002 -2.21265 0.854 -2.21183002 0 P 0 ;0
L 0.854 -2.21183002 0.83788996 -2.21033996 0 P 0 ;0
L 0.83788996 -2.21033996 0.8174 -2.20693002 0 P 0 ;0
L 0.8174 -2.20693002 0.79708996 -2.2023 0 P 0 ;0
L 0.79708996 -2.2023 0.7769 -2.19641004 0 P 0 ;0
L 0.7769 -2.19641004 0.76433002 -2.19183996 0 P 0 ;0
L 0.76433002 -2.19183996 0.75208996 -2.18638002 0 P 0 ;0
L 0.75208996 -2.18638002 0.74026998 -2.18006998 0 P 0 ;0
L 0.74026998 -2.18006998 0.72886998 -2.17291004 0 P 0 ;0
L 0.72886998 -2.17291004 0.71961998 -2.16603002 0 P 0 ;0
L 0.71961998 -2.16603002 0.71098996 -2.15838996 0 P 0 ;0
L 0.71098996 -2.15838996 0.70303002 -2.15003002 0 P 0 ;0
L 0.70303002 -2.15003002 0.6958 -2.14098996 0 P 0 ;0
L 0.6958 -2.14098996 0.69106998 -2.1339 0 P 0 ;0
L 0.69106998 -2.1339 0.68696004 -2.12643002 0 P 0 ;0
L 0.68696004 -2.12643002 0.68351004 -2.11863002 0 P 0 ;0
L 0.68351004 -2.11863002 0.68073996 -2.11056004 0 P 0 ;0
L 0.68073996 -2.11056004 0.67866004 -2.10218996 0 P 0 ;0
L 0.67866004 -2.10218996 0.67788002 -2.09741998 0 P 0 ;0
L 0.67788002 -2.09741998 0.67746004 -2.0926 0 P 0 ;0
L 0.67746004 -2.0926 0.67738002 -2.08076004 0 P 0 ;0
L 0.67738002 -2.08076004 0.67828002 -2.06891004 0 P 0 ;0
L 0.67828002 -2.06891004 0.67903002 -2.06403996 0 P 0 ;0
L 0.67903002 -2.06403996 0.68013002 -2.05923996 0 P 0 ;0
L 0.68013002 -2.05923996 0.68288002 -2.05021998 0 P 0 ;0
L 0.68288002 -2.05021998 0.68623996 -2.04141004 0 P 0 ;0
L 0.68623996 -2.04141004 0.69018002 -2.03286004 0 P 0 ;0
L 0.69018002 -2.03286004 0.69486004 -2.02418002 0 P 0 ;0
L 0.69486004 -2.02418002 0.70003996 -2.0158 0 P 0 ;0
L 0.70003996 -2.0158 0.70573002 -2.00768996 0 P 0 ;0
L 0.70573002 -2.00768996 0.7158 -1.99531998 0 P 0 ;0
L 0.7158 -1.99531998 0.72681004 -1.98385 0 P 0 ;0
L 0.72681004 -1.98385 0.73971004 -1.9722 0 P 0 ;0
L 0.73971004 -1.9722 0.7533 -1.9614 0 P 0 ;0
L 0.7533 -1.9614 0.75753996 -1.95828002 0 P 0 ;0
L 0.75753996 -1.95828002 0.76138002 -1.95548002 0 P 0 ;0
L 0.76138002 -1.95548002 0.76463002 -1.95316004 0 P 0 ;0
L 0.76463002 -1.95316004 0.76516004 -1.95281004 0 P 0 ;0
L 0.76516004 -1.95281004 0.7657 -1.95248996 0 P 0 ;0
L 0.7657 -1.95248996 0.76578002 -1.95243996 0 P 0 ;0
L 0.76578002 -1.95243996 0.76586004 -1.95238002 0 P 0 ;0
L 0.76586004 -1.95238002 0.76593002 -1.95231998 0 P 0 ;0
L 0.76593002 -1.95231998 0.766 -1.95223996 0 P 0 ;0
L 0.766 -1.95223996 0.76606004 -1.95216998 0 P 0 ;0
L 0.76606004 -1.95216998 0.76616004 -1.95201004 0 P 0 ;0
L 0.76616004 -1.95201004 0.7662 -1.95191998 0 P 0 ;0
L 0.7662 -1.95191998 0.76626004 -1.95173996 0 P 0 ;0
L 0.76626004 -1.95173996 0.76628002 -1.95163996 0 P 0 ;0
L 0.76628002 -1.95163996 0.7663 -1.95143002 0 P 0 ;0
L 0.7663 -1.95143002 0.7663 -1.95121004 0 P 0 ;0
L 0.7663 -1.95121004 0.76628996 -1.951 0 P 0 ;0
L 0.76628996 -1.951 0.76625 -1.95078996 0 P 0 ;0
L 0.76625 -1.95078996 0.7662 -1.95058002 0 P 0 ;0
L 0.7662 -1.95058002 0.76613002 -1.95036998 0 P 0 ;0
L 0.76613002 -1.95036998 0.76583002 -1.94966998 0 P 0 ;0
L 0.76583002 -1.94966998 0.76548996 -1.94896998 0 P 0 ;0
L 0.76548996 -1.94896998 0.76508996 -1.9483 0 P 0 ;0
L 0.76508996 -1.9483 0.76253002 -1.94436004 0 P 0 ;0
L 0.76253002 -1.94436004 0.76056998 -1.94126998 0 P 0 ;0
L 0.76056998 -1.94126998 0.75871998 -1.93806004 0 P 0 ;0
L 0.75871998 -1.93806004 0.75716998 -1.93496998 0 P 0 ;0
L 0.75716998 -1.93496998 0.7558 -1.93178002 0 P 0 ;0
L 0.7558 -1.93178002 0.7546 -1.92853996 0 P 0 ;0
L 0.7546 -1.92853996 0.75358996 -1.92521004 0 P 0 ;0
L 0.75358996 -1.92521004 0.7527 -1.92161998 0 P 0 ;0
L 0.7527 -1.92161998 0.75196998 -1.91796004 0 P 0 ;0
L 0.75196998 -1.91796004 0.75155 -1.91496004 0 P 0 ;0
L 0.75155 -1.91496004 0.75133002 -1.91193002 0 P 0 ;0
L 0.75133002 -1.91193002 0.75126998 -1.9085 0 P 0 ;0
L 0.75126998 -1.9085 0.75136004 -1.90506004 0 P 0 ;0
L 0.75136004 -1.90506004 0.75161004 -1.90181998 0 P 0 ;0
L 0.75161004 -1.90181998 0.752 -1.8986 0 P 0 ;0
L 0.752 -1.8986 0.75228996 -1.89701998 0 P 0 ;0
L 0.75228996 -1.89701998 0.75268996 -1.89546998 0 P 0 ;0
L 0.75268996 -1.89546998 0.7532 -1.89395 0 P 0 ;0
L 0.7532 -1.89395 0.75358996 -1.89281998 0 P 0 ;0
L 0.75358996 -1.89281998 0.75373002 -1.89231998 0 P 0 ;0
L 0.75373002 -1.89231998 0.75383996 -1.8918 0 P 0 ;0
L 0.75383996 -1.8918 0.75391998 -1.89138996 0 P 0 ;0
L 0.75391998 -1.89138996 0.75396998 -1.89098996 0 P 0 ;0
L 0.75396998 -1.89098996 0.75396998 -1.89086004 0 P 0 ;0
L 0.75396998 -1.89086004 0.75393996 -1.89076998 0 P 0 ;0
L 0.75393996 -1.89076998 0.7539 -1.89071004 0 P 0 ;0
L 0.7539 -1.89071004 0.75386004 -1.89066998 0 P 0 ;0
L 0.75386004 -1.89066998 0.75381004 -1.89063002 0 P 0 ;0
L 0.75381004 -1.89063002 0.75378996 -1.89061004 0 P 0 ;0
L 0.75378996 -1.89061004 0.75373002 -1.89058996 0 P 0 ;0
L 0.75373002 -1.89058996 0.75368002 -1.89056998 0 P 0 ;0
L 0.75368002 -1.89056998 0.75356004 -1.89056998 0 P 0 ;0
L 0.75356004 -1.89056998 0.75346998 -1.8906 0 P 0 ;0
L 0.75346998 -1.8906 0.74898002 -1.8927 0 P 0 ;0
L 0.74898002 -1.8927 0.74383002 -1.89518002 0 P 0 ;0
L 0.74383002 -1.89518002 0.73781004 -1.8982 0 P 0 ;0
L 0.69776998 -2.22761998 0.96701004 -2.22761998 0 P 0 ;0
L 0.6957 -2.22661998 0.96968996 -2.22661998 0 P 0 ;0
L 0.69366998 -2.22561998 0.97238002 -2.22561998 0 P 0 ;0
L 0.69163002 -2.22461998 0.97506004 -2.22461998 0 P 0 ;0
L 0.68958996 -2.22361998 0.97775 -2.22361998 0 P 0 ;0
L 0.68756004 -2.22261998 0.98043002 -2.22261998 0 P 0 ;0
L 0.68551998 -2.22161998 0.98311004 -2.22161998 0 P 0 ;0
L 0.68348996 -2.22061998 0.9858 -2.22061998 0 P 0 ;0
L 0.68176998 -2.21961998 0.98848002 -2.21961998 0 P 0 ;0
L 0.68003996 -2.21861998 0.99116998 -2.21861998 0 P 0 ;0
L 0.67831004 -2.21761998 0.99385 -2.21761998 0 P 0 ;0
L 0.67658002 -2.21661998 0.99653996 -2.21661998 0 P 0 ;0
L 0.67485 -2.21561998 0.99908002 -2.21561998 0 P 0 ;0
L 0.67311998 -2.21461998 0.87665 -2.21461998 0 P 0 ;0
L 0.6714 -2.21361998 0.85166004 -2.21361998 0 P 0 ;0
L 0.6699 -2.21261998 0.84083002 -2.21261998 0 P 0 ;0
L 0.66845 -2.21161998 0.8334 -2.21161998 0 P 0 ;0
L 0.66698996 -2.21061998 0.8274 -2.21061998 0 P 0 ;0
L 0.66553002 -2.20961998 0.82138996 -2.20961998 0 P 0 ;0
L 0.66406998 -2.20861998 0.81583002 -2.20861998 0 P 0 ;0
L 0.66261998 -2.20761998 0.81143996 -2.20761998 0 P 0 ;0
L 0.66116004 -2.20661998 0.80706004 -2.20661998 0 P 0 ;0
L 0.6597 -2.20561998 0.80266998 -2.20561998 0 P 0 ;0
L 0.65841004 -2.20461998 0.79828996 -2.20461998 0 P 0 ;0
L 0.65716998 -2.20361998 0.79448996 -2.20361998 0 P 0 ;0
L 0.65593002 -2.20261998 0.79106004 -2.20261998 0 P 0 ;0
L 0.65468996 -2.20161998 0.78763996 -2.20161998 0 P 0 ;0
L 0.83143002 -2.25261998 0.80871998 -2.25225 0 P 0 ;0
L 0.80871998 -2.25225 0.78691998 -2.25066998 0 P 0 ;0
L 0.78691998 -2.25066998 0.76525 -2.24786998 0 P 0 ;0
L 0.76525 -2.24786998 0.74581998 -2.24403996 0 P 0 ;0
L 0.74581998 -2.24403996 0.72671004 -2.23876004 0 P 0 ;0
L 0.72671004 -2.23876004 0.71196004 -2.23356998 0 P 0 ;0
L 0.71196004 -2.23356998 0.69756998 -2.22753996 0 P 0 ;0
L 0.69756998 -2.22753996 0.68355 -2.22066004 0 P 0 ;0
L 0.68355 -2.22066004 0.67118002 -2.2135 0 P 0 ;0
L 0.67118002 -2.2135 0.65938996 -2.20541004 0 P 0 ;0
L 0.65938996 -2.20541004 0.64825 -2.19643996 0 P 0 ;0
L 0.64825 -2.19643996 0.63861998 -2.18731998 0 P 0 ;0
L 0.63861998 -2.18731998 0.62983002 -2.17746998 0 P 0 ;0
L 0.62983002 -2.17746998 0.62188996 -2.1669 0 P 0 ;0
L 0.62188996 -2.1669 0.61678002 -2.15886998 0 P 0 ;0
L 0.61678002 -2.15886998 0.6123 -2.15056004 0 P 0 ;0
L 0.6123 -2.15056004 0.60841998 -2.14193996 0 P 0 ;0
L 0.60841998 -2.14193996 0.60516998 -2.13306998 0 P 0 ;0
L 0.60516998 -2.13306998 0.60191004 -2.12171004 0 P 0 ;0
L 0.60191004 -2.12171004 0.60075 -2.11648002 0 P 0 ;0
L 0.60075 -2.11648002 0.59983996 -2.11121004 0 P 0 ;0
L 0.59983996 -2.11121004 0.59913996 -2.10576004 0 P 0 ;0
L 0.59913996 -2.10576004 0.59868996 -2.10026004 0 P 0 ;0
L 0.59868996 -2.10026004 0.59833002 -2.0875 0 P 0 ;0
L 0.59833002 -2.0875 0.59856998 -2.07843996 0 P 0 ;0
L 0.59856998 -2.07843996 0.59923996 -2.0695 0 P 0 ;0
L 0.59923996 -2.0695 0.60031998 -2.06153996 0 P 0 ;0
L 0.60031998 -2.06153996 0.60193002 -2.05368996 0 P 0 ;0
L 0.60193002 -2.05368996 0.60416004 -2.04566004 0 P 0 ;0
L 0.60416004 -2.04566004 0.60688996 -2.03786004 0 P 0 ;0
L 0.60688996 -2.03786004 0.6148 -2.01961004 0 P 0 ;0
L 0.6148 -2.01961004 0.62108996 -2.00753002 0 P 0 ;0
L 0.62108996 -2.00753002 0.62811998 -1.99591998 0 P 0 ;0
L 0.62811998 -1.99591998 0.63583996 -1.98478996 0 P 0 ;0
L 0.63583996 -1.98478996 0.64936998 -1.96808002 0 P 0 ;0
L 0.64936998 -1.96808002 0.66418002 -1.95256998 0 P 0 ;0
L 0.66418002 -1.95256998 0.68098002 -1.93756004 0 P 0 ;0
L 0.68098002 -1.93756004 0.69881998 -1.92398002 0 P 0 ;0
L 0.69881998 -1.92398002 0.71841998 -1.91123996 0 P 0 ;0
L 0.71841998 -1.91123996 0.73875 -1.89996998 0 P 0 ;0
L 0.73875 -1.89996998 0.74471004 -1.89696998 0 P 0 ;0
L 0.74471004 -1.89696998 0.74983002 -1.89451004 0 P 0 ;0
L 0.74983002 -1.89451004 0.7511 -1.89391004 0 P 0 ;0
L 0.7511 -1.89391004 0.75076998 -1.89488996 0 P 0 ;0
L 0.75076998 -1.89488996 0.75033996 -1.89658996 0 P 0 ;0
L 0.75033996 -1.89658996 0.75003002 -1.8983 0 P 0 ;0
L 0.75003002 -1.8983 0.74961998 -1.90161998 0 P 0 ;0
L 0.74961998 -1.90161998 0.74936004 -1.90496004 0 P 0 ;0
L 0.74936004 -1.90496004 0.74926998 -1.9085 0 P 0 ;0
L 0.74926998 -1.9085 0.74933002 -1.91201998 0 P 0 ;0
L 0.74933002 -1.91201998 0.74956004 -1.91516998 0 P 0 ;0
L 0.74956004 -1.91516998 0.75 -1.91828996 0 P 0 ;0
L 0.75 -1.91828996 0.75075 -1.92205 0 P 0 ;0
L 0.75075 -1.92205 0.75166004 -1.92573996 0 P 0 ;0
L 0.75166004 -1.92573996 0.7527 -1.92916998 0 P 0 ;0
L 0.7527 -1.92916998 0.75393996 -1.93253002 0 P 0 ;0
L 0.75393996 -1.93253002 0.75536004 -1.93581998 0 P 0 ;0
L 0.75536004 -1.93581998 0.75696004 -1.939 0 P 0 ;0
L 0.75696004 -1.939 0.75885 -1.94231004 0 P 0 ;0
L 0.75885 -1.94231004 0.76083996 -1.94543996 0 P 0 ;0
L 0.76083996 -1.94543996 0.76338996 -1.94933996 0 P 0 ;0
L 0.76338996 -1.94933996 0.76371998 -1.94991998 0 P 0 ;0
L 0.76371998 -1.94991998 0.76401004 -1.9505 0 P 0 ;0
L 0.76401004 -1.9505 0.76423996 -1.95103002 0 P 0 ;0
L 0.76423996 -1.95103002 0.76408996 -1.95111004 0 P 0 ;0
L 0.76408996 -1.95111004 0.76348996 -1.95151004 0 P 0 ;0
L 0.76348996 -1.95151004 0.76021004 -1.95386004 0 P 0 ;0
L 0.76021004 -1.95386004 0.7602 -1.95386998 0 P 0 ;0
L 0.7602 -1.95386998 0.75636998 -1.95666004 0 P 0 ;0
L 0.75636998 -1.95666004 0.75636004 -1.95666998 0 P 0 ;0
L 0.75636004 -1.95666998 0.75635 -1.95666998 0 P 0 ;0
L 0.75635 -1.95666998 0.75208996 -1.95981004 0 P 0 ;0
L 0.75208996 -1.95981004 0.73841004 -1.97066998 0 P 0 ;0
L 0.73841004 -1.97066998 0.72541004 -1.98241004 0 P 0 ;0
L 0.72541004 -1.98241004 0.7143 -1.994 0 P 0 ;0
L 0.7143 -1.994 0.71425 -1.99406004 0 P 0 ;0
L 0.71425 -1.99406004 0.70413996 -2.00648002 0 P 0 ;0
L 0.70413996 -2.00648002 0.69836998 -2.01468996 0 P 0 ;0
L 0.69836998 -2.01468996 0.69313002 -2.02318002 0 P 0 ;0
L 0.69313002 -2.02318002 0.68838996 -2.03196004 0 P 0 ;0
L 0.68838996 -2.03196004 0.68438996 -2.04063996 0 P 0 ;0
L 0.68438996 -2.04063996 0.68098996 -2.04958002 0 P 0 ;0
L 0.68098996 -2.04958002 0.6782 -2.05873002 0 P 0 ;0
L 0.6782 -2.05873002 0.67706004 -2.06366004 0 P 0 ;0
L 0.67706004 -2.06366004 0.67628996 -2.06866998 0 P 0 ;0
L 0.67628996 -2.06866998 0.67538002 -2.08068996 0 P 0 ;0
L 0.67538002 -2.08068996 0.67546004 -2.09268996 0 P 0 ;0
L 0.67546004 -2.09268996 0.67588996 -2.09766998 0 P 0 ;0
L 0.67588996 -2.09766998 0.6767 -2.10258996 0 P 0 ;0
L 0.6767 -2.10258996 0.67881998 -2.11111998 0 P 0 ;0
L 0.67881998 -2.11111998 0.68163996 -2.11936004 0 P 0 ;0
L 0.68163996 -2.11936004 0.68516004 -2.12731998 0 P 0 ;0
L 0.68516004 -2.12731998 0.68935 -2.13493996 0 P 0 ;0
L 0.68935 -2.13493996 0.69418002 -2.14216998 0 P 0 ;0
L 0.69418002 -2.14216998 0.70153002 -2.15135 0 P 0 ;0
L 0.70153002 -2.15135 0.7096 -2.15983002 0 P 0 ;0
L 0.7096 -2.15983002 0.71836004 -2.16758996 0 P 0 ;0
L 0.71836004 -2.16758996 0.71843002 -2.16763996 0 P 0 ;0
L 0.71843002 -2.16763996 0.72773996 -2.17456004 0 P 0 ;0
L 0.72773996 -2.17456004 0.73926998 -2.1818 0 P 0 ;0
L 0.73926998 -2.1818 0.75121004 -2.18818002 0 P 0 ;0
L 0.75121004 -2.18818002 0.75128002 -2.18821004 0 P 0 ;0
L 0.75128002 -2.18821004 0.76358002 -2.19368996 0 P 0 ;0
L 0.76358002 -2.19368996 0.77628002 -2.19831004 0 P 0 ;0
L 0.77628002 -2.19831004 0.79658996 -2.20423996 0 P 0 ;0
L 0.79658996 -2.20423996 0.81701004 -2.20888996 0 P 0 ;0
L 0.81701004 -2.20888996 0.83763996 -2.21233002 0 P 0 ;0
L 0.83763996 -2.21233002 0.85388002 -2.21383002 0 P 0 ;0
L 0.85388002 -2.21383002 0.87733996 -2.21465 0 P 0 ;0
L 0.87733996 -2.21465 0.90118002 -2.21478996 0 P 0 ;0
L 0.90118002 -2.21478996 0.91906004 -2.21398996 0 P 0 ;0
L 0.91906004 -2.21398996 0.94908996 -2.21068002 0 P 0 ;0
L 0.94908996 -2.21068002 0.98176998 -2.2053 0 P 0 ;0
L 0.98176998 -2.2053 1.01575 -2.19815 0 P 0 ;0
L 1.01575 -2.19815 1.04968002 -2.18943002 0 P 0 ;0
L 1.04968002 -2.18943002 1.05633996 -2.18761004 0 P 0 ;0
L 1.05633996 -2.18761004 1.05713996 -2.1874 0 P 0 ;0
L 1.05713996 -2.1874 1.05483002 -2.18875 0 P 0 ;0
L 1.05483002 -2.18875 1.04298996 -2.19526004 0 P 0 ;0
L 1.04298996 -2.19526004 1.03096998 -2.20136998 0 P 0 ;0
L 1.03096998 -2.20136998 0.99835 -2.21595 0 P 0 ;0
L 0.99835 -2.21595 0.96401998 -2.22873996 0 P 0 ;0
L 0.96401998 -2.22873996 0.92993996 -2.23908002 0 P 0 ;0
L 0.92993996 -2.23908002 0.89816004 -2.24626004 0 P 0 ;0
L 0.89816004 -2.24626004 0.87616004 -2.24965 0 P 0 ;0
L 0.87616004 -2.24965 0.85405 -2.25176004 0 P 0 ;0
L 0.85405 -2.25176004 0.83143002 -2.25261998 0 P 0 ;0
L 0.65345 -2.20061998 0.78421004 -2.20061998 0 P 0 ;0
L 0.65221004 -2.19961998 0.78078002 -2.19961998 0 P 0 ;0
L 0.65096004 -2.19861998 0.77735 -2.19861998 0 P 0 ;0
L 0.64971998 -2.19761998 0.77438996 -2.19761998 0 P 0 ;0
L 0.64848002 -2.19661998 0.77163996 -2.19661998 0 P 0 ;0
L 0.64738996 -2.19561998 0.76888996 -2.19561998 0 P 0 ;0
L 0.64633996 -2.19461998 0.76613996 -2.19461998 0 P 0 ;0
L 0.64528002 -2.19361998 0.76343002 -2.19361998 0 P 0 ;0
L 0.64421998 -2.19261998 0.76118996 -2.19261998 0 P 0 ;0
L 0.64316998 -2.19161998 0.75893996 -2.19161998 0 P 0 ;0
L 0.64211004 -2.19061998 0.7567 -2.19061998 0 P 0 ;0
L 0.64106004 -2.18961998 0.75446004 -2.18961998 0 P 0 ;0
L 0.64 -2.18861998 0.75221004 -2.18861998 0 P 0 ;0
L 0.63895 -2.18761998 0.75018002 -2.18761998 0 P 0 ;0
L 0.63801004 -2.18661998 0.74831004 -2.18661998 0 P 0 ;0
L 0.63711004 -2.18561998 0.74643002 -2.18561998 0 P 0 ;0
L 0.63621998 -2.18461998 0.74456004 -2.18461998 0 P 0 ;0
L 0.63533002 -2.18361998 0.74268002 -2.18361998 0 P 0 ;0
L 0.63443996 -2.18261998 0.74081004 -2.18261998 0 P 0 ;0
L 0.63353996 -2.18161998 0.73898996 -2.18161998 0 P 0 ;0
L 0.63265 -2.18061998 0.73738996 -2.18061998 0 P 0 ;0
L 0.63176004 -2.17961998 0.7358 -2.17961998 0 P 0 ;0
L 0.63086998 -2.17861998 0.73421004 -2.17861998 0 P 0 ;0
L 0.62996998 -2.17761998 0.73261998 -2.17761998 0 P 0 ;0
L 0.6292 -2.17661998 0.73103002 -2.17661998 0 P 0 ;0
L 0.62845 -2.17561998 0.72943996 -2.17561998 0 P 0 ;0
L 0.6277 -2.17461998 0.72783996 -2.17461998 0 P 0 ;0
L 0.62693996 -2.17361998 0.72648002 -2.17361998 0 P 0 ;0
L 0.62618996 -2.17261998 0.72513996 -2.17261998 0 P 0 ;0
L 0.62543996 -2.17161998 0.72378996 -2.17161998 0 P 0 ;0
L 0.62468996 -2.17061998 0.72245 -2.17061998 0 P 0 ;0
L 0.62393996 -2.16961998 0.7211 -2.16961998 0 P 0 ;0
L 0.62318002 -2.16861998 0.71976004 -2.16861998 0 P 0 ;0
L 0.62243996 -2.16761998 0.71841004 -2.16761998 0 P 0 ;0
L 0.62171004 -2.16661998 0.71726998 -2.16661998 0 P 0 ;0
L 0.62108002 -2.16561998 0.71613996 -2.16561998 0 P 0 ;0
L 0.62043996 -2.16461998 0.71501004 -2.16461998 0 P 0 ;0
L 0.61981004 -2.16361998 0.71388002 -2.16361998 0 P 0 ;0
L 0.61916998 -2.16261998 0.71276004 -2.16261998 0 P 0 ;0
L 0.61853002 -2.16161998 0.71163002 -2.16161998 0 P 0 ;0
L 0.6179 -2.16061998 0.7105 -2.16061998 0 P 0 ;0
L 0.61726004 -2.15961998 0.7094 -2.15961998 0 P 0 ;0
L 0.61665 -2.15861998 0.70845 -2.15861998 0 P 0 ;0
L 0.61611004 -2.15761998 0.7075 -2.15761998 0 P 0 ;0
L 0.75383996 -2.24561998 0.901 -2.24561998 0 P 0 ;0
L 0.74876998 -2.24461998 0.90541998 -2.24461998 0 P 0 ;0
L 0.74431004 -2.24361998 0.90985 -2.24361998 0 P 0 ;0
L 0.7407 -2.24261998 0.91426998 -2.24261998 0 P 0 ;0
L 0.73708002 -2.24161998 0.9187 -2.24161998 0 P 0 ;0
L 0.73346998 -2.24061998 0.92311998 -2.24061998 0 P 0 ;0
L 0.72986004 -2.23961998 0.92753996 -2.23961998 0 P 0 ;0
L 0.72633996 -2.23861998 0.93145 -2.23861998 0 P 0 ;0
L 0.72348996 -2.23761998 0.93473996 -2.23761998 0 P 0 ;0
L 0.72063996 -2.23661998 0.93803996 -2.23661998 0 P 0 ;0
L 0.7178 -2.23561998 0.94133002 -2.23561998 0 P 0 ;0
L 0.71495 -2.23461998 0.94461998 -2.23461998 0 P 0 ;0
L 0.7121 -2.23361998 0.94791998 -2.23361998 0 P 0 ;0
L 0.70968996 -2.23261998 0.95121004 -2.23261998 0 P 0 ;0
L 0.70731004 -2.23161998 0.95451004 -2.23161998 0 P 0 ;0
L 0.70491998 -2.23061998 0.9578 -2.23061998 0 P 0 ;0
L 0.70253996 -2.22961998 0.9611 -2.22961998 0 P 0 ;0
L 0.70015 -2.22861998 0.96431998 -2.22861998 0 P 0 ;0
L 0.0349 -2.3038 0.0349 -1.0038 4 P 0 ;0
L 0.0349 -1.0038 4.5349 -1.0038 4 P 0 ;0
L 4.5349 -1.0038 4.5349 -2.3038 4 P 0 ;0
L 4.5349 -2.3038 0.0349 -2.3038 4 P 0 ;0
L 0.0349 -1.6038 4.5349 -1.6038 4 P 0 ;0
L 0.0349 -1.8038 4.5349 -1.8038 4 P 0 ;0
L 2.4349 -2.1038 4.0349 -2.1038 4 P 0 ;0
L 2.4349 -2.3038 2.4349 -1.8038 4 P 0 ;0
L 3.2349 -2.1038 3.2349 -1.8038 4 P 0 ;0
L 4.0349 -2.3038 4.0349 -1.8038 4 P 0 ;0
L 0.0723999 -1.6844687 0.07906663 -1.69030079 3 P 0 ;0,4=7,6=0.000000
L 0.07906663 -1.69030079 0.08656654 -1.6938 3 P 0 ;0,4=7,6=0.000000
L 0.08656654 -1.6938 0.09323337 -1.6938 3 P 0 ;0,4=7,6=0.000000
L 0.09323337 -1.6938 0.0999001 -1.69030079 3 P 0 ;0,4=7,6=0.000000
L 0.0999001 -1.69030079 0.10490059 -1.6844687 3 P 0 ;0,4=7,6=0.000000
L 0.10490059 -1.6844687 0.1074 -1.67629951 3 P 0 ;0,4=7,6=0.000000
L 0.1074 -1.67629951 0.10573376 -1.66813455 3 P 0 ;0,4=7,6=0.000000
L 0.10573376 -1.66813455 0.10156644 -1.66113396 3 P 0 ;0,4=7,6=0.000000
L 0.10156644 -1.66113396 0.09406654 -1.65646614 3 P 0 ;0,4=7,6=0.000000
L 0.09406654 -1.65646614 0.08406713 -1.65413327 3 P 0 ;0,4=7,6=0.000000
L 0.08406713 -1.65413327 0.07823346 -1.64946762 3 P 0 ;0,4=7,6=0.000000
L 0.07823346 -1.64946762 0.07573248 -1.64130059 3 P 0 ;0,4=7,6=0.000000
L 0.07573248 -1.64130059 0.0774003 -1.63313356 3 P 0 ;0,4=7,6=0.000000
L 0.0774003 -1.63313356 0.08156614 -1.62730148 3 P 0 ;0,4=7,6=0.000000
L 0.08156614 -1.62730148 0.0873997 -1.6238 3 P 0 ;0,4=7,6=0.000000
L 0.0873997 -1.6238 0.09323337 -1.6238 3 P 0 ;0,4=7,6=0.000000
L 0.09323337 -1.6238 0.09906693 -1.62613287 3 P 0 ;0,4=7,6=0.000000
L 0.09906693 -1.62613287 0.10406742 -1.63196713 3 P 0 ;0,4=7,6=0.000000
L 0.1383999 -1.6938 0.1383999 -1.6238 3 P 0 ;0,4=7,6=0.000000
L 0.1734 -1.6238 0.1734 -1.6938 3 P 0 ;0,4=7,6=0.000000
L 0.1734 -1.65880108 0.1383999 -1.65880108 3 P 0 ;0,4=7,6=0.000000
L 0.23856683 -1.6938 0.20523307 -1.6938 3 P 0 ;0,4=7,6=0.000000
L 0.20523307 -1.6938 0.20523307 -1.6238 3 P 0 ;0,4=7,6=0.000000
L 0.20523307 -1.6238 0.23856683 -1.6238 3 P 0 ;0,4=7,6=0.000000
L 0.22523337 -1.65763258 0.20523307 -1.65763258 3 P 0 ;0,4=7,6=0.000000
L 0.30456683 -1.6938 0.27123307 -1.6938 3 P 0 ;0,4=7,6=0.000000
L 0.27123307 -1.6938 0.27123307 -1.6238 3 P 0 ;0,4=7,6=0.000000
L 0.27123307 -1.6238 0.30456683 -1.6238 3 P 0 ;0,4=7,6=0.000000
L 0.29123337 -1.65763258 0.27123307 -1.65763258 3 P 0 ;0,4=7,6=0.000000
L 0.35389921 -1.6238 0.35389921 -1.6938 3 P 0 ;0,4=7,6=0.000000
L 0.33473356 -1.6238 0.37306634 -1.6238 3 P 0 ;0,4=7,6=0.000000
L 0.09489921 -1.7188 0.09489921 -1.7888 3 P 0 ;0,4=8,6=0.000000
L 0.07573356 -1.7188 0.11406634 -1.7188 3 P 0 ;0,4=8,6=0.000000
L 0.1508998 -1.7188 0.17089862 -1.7188 3 P 0 ;0,4=8,6=0.000000
L 0.16089921 -1.7188 0.16089921 -1.7888 3 P 0 ;0,4=8,6=0.000000
L 0.1508998 -1.7888 0.17089862 -1.7888 3 P 0 ;0,4=8,6=0.000000
L 0.22689921 -1.7188 0.22689921 -1.7888 3 P 0 ;0,4=8,6=0.000000
L 0.20773356 -1.7188 0.24606634 -1.7188 3 P 0 ;0,4=8,6=0.000000
L 0.27623307 -1.7188 0.27623307 -1.7888 3 P 0 ;0,4=8,6=0.000000
L 0.27623307 -1.7888 0.30956683 -1.7888 3 P 0 ;0,4=8,6=0.000000
L 0.37556683 -1.7888 0.34223307 -1.7888 3 P 0 ;0,4=8,6=0.000000
L 0.34223307 -1.7888 0.34223307 -1.7188 3 P 0 ;0,4=8,6=0.000000
L 0.34223307 -1.7188 0.37556683 -1.7188 3 P 0 ;0,4=8,6=0.000000
L 0.36223337 -1.75263258 0.34223307 -1.75263258 3 P 0 ;0,4=8,6=0.000000
L 2.5438999 -1.96813563 2.5519 -1.97480089 3 P 0 ;0,4=9,6=0.000000
L 2.5519 -1.97480089 2.5608999 -1.9788 3 P 0 ;0,4=9,6=0.000000
L 2.5608999 -1.9788 2.5689 -1.9788 3 P 0 ;0,4=9,6=0.000000
L 2.5689 -1.9788 2.5769001 -1.97480089 3 P 0 ;0,4=9,6=0.000000
L 2.5769001 -1.97480089 2.58290069 -1.96813563 3 P 0 ;0,4=9,6=0.000000
L 2.58290069 -1.96813563 2.5859 -1.95879941 3 P 0 ;0,4=9,6=0.000000
L 2.5859 -1.95879941 2.58390049 -1.94946811 3 P 0 ;0,4=9,6=0.000000
L 2.58390049 -1.94946811 2.5788997 -1.94146732 3 P 0 ;0,4=9,6=0.000000
L 2.5788997 -1.94146732 2.5698998 -1.93613278 3 P 0 ;0,4=9,6=0.000000
L 2.5698998 -1.93613278 2.55790049 -1.93346663 3 P 0 ;0,4=9,6=0.000000
L 2.55790049 -1.93346663 2.5509002 -1.92813445 3 P 0 ;0,4=9,6=0.000000
L 2.5509002 -1.92813445 2.54789902 -1.91880069 3 P 0 ;0,4=9,6=0.000000
L 2.54789902 -1.91880069 2.54990039 -1.90946683 3 P 0 ;0,4=9,6=0.000000
L 2.54990039 -1.90946683 2.55489931 -1.90280167 3 P 0 ;0,4=9,6=0.000000
L 2.55489931 -1.90280167 2.5618997 -1.8988 3 P 0 ;0,4=9,6=0.000000
L 2.5618997 -1.8988 2.5689 -1.8988 3 P 0 ;0,4=9,6=0.000000
L 2.5689 -1.8988 2.57590039 -1.90146614 3 P 0 ;0,4=9,6=0.000000
L 2.57590039 -1.90146614 2.58190089 -1.90813386 3 P 0 ;0,4=9,6=0.000000
L 2.6648998 -1.90546772 2.65889931 -1.90146614 3 P 0 ;0,4=9,6=0.000000
L 2.65889931 -1.90146614 2.65190079 -1.8988 3 P 0 ;0,4=9,6=0.000000
L 2.65190079 -1.8988 2.64390069 -1.8988 3 P 0 ;0,4=9,6=0.000000
L 2.64390069 -1.8988 2.63489892 -1.90280167 3 P 0 ;0,4=9,6=0.000000
L 2.63489892 -1.90280167 2.62790039 -1.90946683 3 P 0 ;0,4=9,6=0.000000
L 2.62790039 -1.90946683 2.62289961 -1.91746762 3 P 0 ;0,4=9,6=0.000000
L 2.62289961 -1.91746762 2.61889862 -1.93080049 3 P 0 ;0,4=9,6=0.000000
L 2.61889862 -1.93080049 2.61789892 -1.94280039 3 P 0 ;0,4=9,6=0.000000
L 2.61789892 -1.94280039 2.6199003 -1.9548003 3 P 0 ;0,4=9,6=0.000000
L 2.6199003 -1.9548003 2.62289961 -1.96280098 3 P 0 ;0,4=9,6=0.000000
L 2.62289961 -1.96280098 2.6289002 -1.97080177 3 P 0 ;0,4=9,6=0.000000
L 2.6289002 -1.97080177 2.63590049 -1.97613396 3 P 0 ;0,4=9,6=0.000000
L 2.63590049 -1.97613396 2.64289902 -1.9788 3 P 0 ;0,4=9,6=0.000000
L 2.64289902 -1.9788 2.64989941 -1.9788 3 P 0 ;0,4=9,6=0.000000
L 2.64989941 -1.9788 2.6568997 -1.97613396 3 P 0 ;0,4=9,6=0.000000
L 2.6568997 -1.97613396 2.6629003 -1.97213484 3 P 0 ;0,4=9,6=0.000000
L 2.6629003 -1.97213484 2.66790098 -1.96680266 3 P 0 ;0,4=9,6=0.000000
L 2.69589892 -1.9788 2.72089902 -1.8988 3 P 0 ;0,4=9,6=0.000000
L 2.72089902 -1.8988 2.74590098 -1.9788 3 P 0 ;0,4=9,6=0.000000
L 2.73689931 -1.95080118 2.70489882 -1.95080118 3 P 0 ;0,4=9,6=0.000000
L 2.77889961 -1.8988 2.77889961 -1.9788 3 P 0 ;0,4=9,6=0.000000
L 2.77889961 -1.9788 2.8189003 -1.9788 3 P 0 ;0,4=9,6=0.000000
L 2.8969003 -1.9788 2.85689961 -1.9788 3 P 0 ;0,4=9,6=0.000000
L 2.85689961 -1.9788 2.85689961 -1.8988 3 P 0 ;0,4=9,6=0.000000
L 2.85689961 -1.8988 2.8969003 -1.8988 3 P 0 ;0,4=9,6=0.000000
L 2.8809 -1.93746575 2.85689961 -1.93746575 3 P 0 ;0,4=9,6=0.000000
L 3.03289902 -1.9788 3.03289902 -1.8988 3 P 0 ;0,4=9,6=0.000000
L 3.03289902 -1.8988 3.0208998 -1.91479911 3 P 0 ;0,4=9,6=0.000000
L 3.0208998 -1.9788 3.04489833 -1.9788 3 P 0 ;0,4=9,6=0.000000
L 3.11089902 -1.98146604 3.10889951 -1.98013297 3 P 0 ;0,4=9,6=0.000000
L 3.10889951 -1.98013297 3.10889951 -1.97746703 3 P 0 ;0,4=9,6=0.000000
L 3.10889951 -1.97746703 3.11089902 -1.97613396 3 P 0 ;0,4=9,6=0.000000
L 3.11089902 -1.97613396 3.11290039 -1.97746703 3 P 0 ;0,4=9,6=0.000000
L 3.11290039 -1.97746703 3.11290039 -1.98013297 3 P 0 ;0,4=9,6=0.000000
L 3.11290039 -1.98013297 3.11089902 -1.98146604 3 P 0 ;0,4=9,6=0.000000
L 3.11089902 -1.945469 3.10889951 -1.94413346 3 P 0 ;0,4=9,6=0.000000
L 3.10889951 -1.94413346 3.10889951 -1.94146732 3 P 0 ;0,4=9,6=0.000000
L 3.10889951 -1.94146732 3.11089902 -1.94013435 3 P 0 ;0,4=9,6=0.000000
L 3.11089902 -1.94013435 3.11290039 -1.94146732 3 P 0 ;0,4=9,6=0.000000
L 3.11290039 -1.94146732 3.11290039 -1.94413346 3 P 0 ;0,4=9,6=0.000000
L 3.11290039 -1.94413346 3.11089902 -1.945469 3 P 0 ;0,4=9,6=0.000000
L 3.18889902 -1.9788 3.18889902 -1.8988 3 P 0 ;0,4=9,6=0.000000
L 3.18889902 -1.8988 3.1768998 -1.91479911 3 P 0 ;0,4=9,6=0.000000
L 3.1768998 -1.9788 3.20089833 -1.9788 3 P 0 ;0,4=9,6=0.000000
L 2.5138999 -2.23313563 2.5219 -2.23980089 3 P 0 ;0,4=7,6=0.000000
L 2.5219 -2.23980089 2.5308999 -2.2438 3 P 0 ;0,4=7,6=0.000000
L 2.5308999 -2.2438 2.5389 -2.2438 3 P 0 ;0,4=7,6=0.000000
L 2.5389 -2.2438 2.5469001 -2.23980089 3 P 0 ;0,4=7,6=0.000000
L 2.5469001 -2.23980089 2.55290069 -2.23313563 3 P 0 ;0,4=7,6=0.000000
L 2.55290069 -2.23313563 2.5559 -2.22379941 3 P 0 ;0,4=7,6=0.000000
L 2.5559 -2.22379941 2.55390049 -2.21446811 3 P 0 ;0,4=7,6=0.000000
L 2.55390049 -2.21446811 2.5488997 -2.20646732 3 P 0 ;0,4=7,6=0.000000
L 2.5488997 -2.20646732 2.5398998 -2.20113278 3 P 0 ;0,4=7,6=0.000000
L 2.5398998 -2.20113278 2.52790049 -2.19846663 3 P 0 ;0,4=7,6=0.000000
L 2.52790049 -2.19846663 2.5209002 -2.19313445 3 P 0 ;0,4=7,6=0.000000
L 2.5209002 -2.19313445 2.51789902 -2.18380069 3 P 0 ;0,4=7,6=0.000000
L 2.51789902 -2.18380069 2.51990039 -2.17446683 3 P 0 ;0,4=7,6=0.000000
L 2.51990039 -2.17446683 2.52489931 -2.16780167 3 P 0 ;0,4=7,6=0.000000
L 2.52489931 -2.16780167 2.5318997 -2.1638 3 P 0 ;0,4=7,6=0.000000
L 2.5318997 -2.1638 2.5389 -2.1638 3 P 0 ;0,4=7,6=0.000000
L 2.5389 -2.1638 2.54590039 -2.16646614 3 P 0 ;0,4=7,6=0.000000
L 2.54590039 -2.16646614 2.55190089 -2.17313386 3 P 0 ;0,4=7,6=0.000000
L 2.5918999 -2.2438 2.5918999 -2.1638 3 P 0 ;0,4=7,6=0.000000
L 2.6339 -2.1638 2.6339 -2.2438 3 P 0 ;0,4=7,6=0.000000
L 2.6339 -2.20380128 2.5918999 -2.20380128 3 P 0 ;0,4=7,6=0.000000
L 2.7109003 -2.2438 2.67089961 -2.2438 3 P 0 ;0,4=7,6=0.000000
L 2.67089961 -2.2438 2.67089961 -2.1638 3 P 0 ;0,4=7,6=0.000000
L 2.67089961 -2.1638 2.7109003 -2.1638 3 P 0 ;0,4=7,6=0.000000
L 2.6949 -2.20246575 2.67089961 -2.20246575 3 P 0 ;0,4=7,6=0.000000
L 2.7889003 -2.2438 2.74889961 -2.2438 3 P 0 ;0,4=7,6=0.000000
L 2.74889961 -2.2438 2.74889961 -2.1638 3 P 0 ;0,4=7,6=0.000000
L 2.74889961 -2.1638 2.7889003 -2.1638 3 P 0 ;0,4=7,6=0.000000
L 2.7729 -2.20246575 2.74889961 -2.20246575 3 P 0 ;0,4=7,6=0.000000
L 2.84689902 -2.1638 2.84689902 -2.2438 3 P 0 ;0,4=7,6=0.000000
L 2.8239003 -2.1638 2.86989961 -2.1638 3 P 0 ;0,4=7,6=0.000000
L 3.29489961 -1.9238 3.29489961 -2.0038 3 P 0 ;0,4=10,6=0.000000
L 3.29489961 -2.0038 3.3349003 -2.0038 3 P 0 ;0,4=10,6=0.000000
L 3.36789892 -2.0038 3.39289902 -1.9238 3 P 0 ;0,4=10,6=0.000000
L 3.39289902 -1.9238 3.41790098 -2.0038 3 P 0 ;0,4=10,6=0.000000
L 3.40889931 -1.97580118 3.37689882 -1.97580118 3 P 0 ;0,4=10,6=0.000000
L 3.47089902 -2.0038 3.47089902 -1.96780039 3 P 0 ;0,4=10,6=0.000000
L 3.47089902 -1.96780039 3.45089961 -1.9238 3 P 0 ;0,4=10,6=0.000000
L 3.4909003 -1.9238 3.47089902 -1.96780039 3 P 0 ;0,4=10,6=0.000000
L 3.5689003 -2.0038 3.52889961 -2.0038 3 P 0 ;0,4=10,6=0.000000
L 3.52889961 -2.0038 3.52889961 -1.9238 3 P 0 ;0,4=10,6=0.000000
L 3.52889961 -1.9238 3.5689003 -1.9238 3 P 0 ;0,4=10,6=0.000000
L 3.5529 -1.96246575 3.52889961 -1.96246575 3 P 0 ;0,4=10,6=0.000000
L 3.60689961 -2.0038 3.60689961 -1.9238 3 P 0 ;0,4=10,6=0.000000
L 3.60689961 -1.9238 3.6318998 -1.9238 3 P 0 ;0,4=10,6=0.000000
L 3.6318998 -1.9238 3.6398999 -1.92780167 3 P 0 ;0,4=10,6=0.000000
L 3.6398999 -1.92780167 3.64490069 -1.93313386 3 P 0 ;0,4=10,6=0.000000
L 3.64490069 -1.93313386 3.6469003 -1.94380069 3 P 0 ;0,4=10,6=0.000000
L 3.6469003 -1.94380069 3.64490069 -1.95446752 3 P 0 ;0,4=10,6=0.000000
L 3.64490069 -1.95446752 3.6389001 -1.96113278 3 P 0 ;0,4=10,6=0.000000
L 3.6389001 -1.96113278 3.6318998 -1.96513435 3 P 0 ;0,4=10,6=0.000000
L 3.6318998 -1.96513435 3.60689961 -1.96513435 3 P 0 ;0,4=10,6=0.000000
L 3.6318998 -1.96513435 3.6469003 -2.0038 3 P 0 ;0,4=10,6=0.000000
L 3.33989902 -2.2538 3.33189892 -2.25246703 3 P 0 ;0,4=11,6=0.000000
L 3.33189892 -2.25246703 3.32490039 -2.24713484 3 P 0 ;0,4=11,6=0.000000
L 3.32490039 -2.24713484 3.3188999 -2.23913406 3 P 0 ;0,4=11,6=0.000000
L 3.3188999 -2.23913406 3.31489892 -2.2298003 3 P 0 ;0,4=11,6=0.000000
L 3.31489892 -2.2298003 3.31289931 -2.21913346 3 P 0 ;0,4=11,6=0.000000
L 3.31289931 -2.21913346 3.31289931 -2.20846663 3 P 0 ;0,4=11,6=0.000000
L 3.31289931 -2.20846663 3.31489892 -2.1977998 3 P 0 ;0,4=11,6=0.000000
L 3.31489892 -2.1977998 3.3188999 -2.18846604 3 P 0 ;0,4=11,6=0.000000
L 3.3188999 -2.18846604 3.32490039 -2.18046772 3 P 0 ;0,4=11,6=0.000000
L 3.32490039 -2.18046772 3.33189892 -2.17513307 3 P 0 ;0,4=11,6=0.000000
L 3.33189892 -2.17513307 3.33989902 -2.1738 3 P 0 ;0,4=11,6=0.000000
L 3.33989902 -2.1738 3.34789911 -2.17513307 3 P 0 ;0,4=11,6=0.000000
L 3.34789911 -2.17513307 3.35489951 -2.18046772 3 P 0 ;0,4=11,6=0.000000
L 3.35489951 -2.18046772 3.3609 -2.18846604 3 P 0 ;0,4=11,6=0.000000
L 3.3609 -2.18846604 3.36490098 -2.1977998 3 P 0 ;0,4=11,6=0.000000
L 3.36490098 -2.1977998 3.36690059 -2.20846663 3 P 0 ;0,4=11,6=0.000000
L 3.36690059 -2.20846663 3.36690059 -2.21913346 3 P 0 ;0,4=11,6=0.000000
L 3.36690059 -2.21913346 3.36490098 -2.2298003 3 P 0 ;0,4=11,6=0.000000
L 3.36490098 -2.2298003 3.3609 -2.23913406 3 P 0 ;0,4=11,6=0.000000
L 3.3609 -2.23913406 3.35489951 -2.24713484 3 P 0 ;0,4=11,6=0.000000
L 3.35489951 -2.24713484 3.34789911 -2.25246703 3 P 0 ;0,4=11,6=0.000000
L 3.34789911 -2.25246703 3.33989902 -2.2538 3 P 0 ;0,4=11,6=0.000000
L 3.39889941 -2.2538 3.39889941 -2.1738 3 P 0 ;0,4=11,6=0.000000
L 3.39889941 -2.1738 3.43690049 -2.1738 3 P 0 ;0,4=11,6=0.000000
L 3.4228998 -2.21246575 3.39889941 -2.21246575 3 P 0 ;0,4=11,6=0.000000
L 0.16489872 -1.0538 0.16489872 -1.1538 3 P 0 ;0,4=8,6=0.000000
L 0.13423376 -1.0538 0.19556614 -1.0538 3 P 0 ;0,4=8,6=0.000000
L 0.2588997 -1.0538 0.29089774 -1.0538 3 P 0 ;0,4=8,6=0.000000
L 0.27489872 -1.0538 0.27489872 -1.1538 3 P 0 ;0,4=8,6=0.000000
L 0.2588997 -1.1538 0.29089774 -1.1538 3 P 0 ;0,4=8,6=0.000000
L 0.38489872 -1.0538 0.38489872 -1.1538 3 P 0 ;0,4=8,6=0.000000
L 0.35423376 -1.0538 0.41556614 -1.0538 3 P 0 ;0,4=8,6=0.000000
L 0.46823287 -1.0538 0.46823287 -1.1538 3 P 0 ;0,4=8,6=0.000000
L 0.46823287 -1.1538 0.52156703 -1.1538 3 P 0 ;0,4=8,6=0.000000
L 0.63156703 -1.1538 0.57823287 -1.1538 3 P 0 ;0,4=8,6=0.000000
L 0.57823287 -1.1538 0.57823287 -1.0538 3 P 0 ;0,4=8,6=0.000000
L 0.57823287 -1.0538 0.63156703 -1.0538 3 P 0 ;0,4=8,6=0.000000
L 0.61023337 -1.10213219 0.57823287 -1.10213219 3 P 0 ;0,4=8,6=0.000000
L 4.18989892 -1.9538 4.21489902 -1.8738 3 P 0 ;0,4=12,6=0.000000
L 4.21489902 -1.8738 4.23990098 -1.9538 3 P 0 ;0,4=12,6=0.000000
L 4.23089931 -1.92580118 4.19889882 -1.92580118 3 P 0 ;0,4=12,6=0.000000
L 4.27289961 -1.9538 4.27289961 -1.8738 3 P 0 ;0,4=12,6=0.000000
L 4.27289961 -1.8738 4.2978998 -1.8738 3 P 0 ;0,4=12,6=0.000000
L 4.2978998 -1.8738 4.3058999 -1.87780167 3 P 0 ;0,4=12,6=0.000000
L 4.3058999 -1.87780167 4.31090069 -1.88313386 3 P 0 ;0,4=12,6=0.000000
L 4.31090069 -1.88313386 4.3129003 -1.89380069 3 P 0 ;0,4=12,6=0.000000
L 4.3129003 -1.89380069 4.31090069 -1.90446752 3 P 0 ;0,4=12,6=0.000000
L 4.31090069 -1.90446752 4.3049001 -1.91113278 3 P 0 ;0,4=12,6=0.000000
L 4.3049001 -1.91113278 4.2978998 -1.91513435 3 P 0 ;0,4=12,6=0.000000
L 4.2978998 -1.91513435 4.27289961 -1.91513435 3 P 0 ;0,4=12,6=0.000000
L 4.2978998 -1.91513435 4.3129003 -1.9538 3 P 0 ;0,4=12,6=0.000000
L 4.37089902 -1.8738 4.37089902 -1.9538 3 P 0 ;0,4=12,6=0.000000
L 4.3479003 -1.8738 4.39389961 -1.8738 3 P 0 ;0,4=12,6=0.000000
L 3.61989892 -2.2538 3.61989892 -2.1638 3 P 0 ;0,4=13,6=0.000000
L 3.61989892 -2.1638 3.6058997 -2.18179892 3 P 0 ;0,4=13,6=0.000000
L 3.6058997 -2.2538 3.63389803 -2.2538 3 P 0 ;0,4=13,6=0.000000
L 3.68773268 -2.17879961 3.69473337 -2.16980148 3 P 0 ;0,4=13,6=0.000000
L 3.69473337 -2.16980148 3.70290039 -2.1652997 3 P 0 ;0,4=13,6=0.000000
L 3.70290039 -2.1652997 3.71223386 -2.1638 3 P 0 ;0,4=13,6=0.000000
L 3.71223386 -2.1638 3.7239002 -2.16679941 3 P 0 ;0,4=13,6=0.000000
L 3.7239002 -2.16679941 3.73206722 -2.17430059 3 P 0 ;0,4=13,6=0.000000
L 3.73206722 -2.17430059 3.7344001 -2.18329862 3 P 0 ;0,4=13,6=0.000000
L 3.7344001 -2.18329862 3.73323366 -2.19230217 3 P 0 ;0,4=13,6=0.000000
L 3.73323366 -2.19230217 3.72856585 -2.19980059 3 P 0 ;0,4=13,6=0.000000
L 3.72856585 -2.19980059 3.70523317 -2.2148001 3 P 0 ;0,4=13,6=0.000000
L 3.70523317 -2.2148001 3.69473337 -2.22530069 3 P 0 ;0,4=13,6=0.000000
L 3.69473337 -2.22530069 3.68773268 -2.24030295 3 P 0 ;0,4=13,6=0.000000
L 3.68773268 -2.24030295 3.6853998 -2.2538 3 P 0 ;0,4=13,6=0.000000
L 3.6853998 -2.2538 3.7344001 -2.2538 3 P 0 ;0,4=13,6=0.000000
L 0.59099833 -1.36499882 0.5990003 -1.35750039 3 P 0 ;0,4=14,6=0.000000
L 0.5990003 -1.35750039 0.60499902 -1.34500315 3 P 0 ;0,4=14,6=0.000000
L 0.60499902 -1.34500315 0.60900187 -1.32749764 3 P 0 ;0,4=14,6=0.000000
L 0.60900187 -1.32749764 0.60499902 -1.31250089 3 P 0 ;0,4=14,6=0.000000
L 0.60499902 -1.31250089 0.59700079 -1.30250305 3 P 0 ;0,4=14,6=0.000000
L 0.59700079 -1.30250305 0.5830001 -1.295 3 P 0 ;0,4=14,6=0.000000
L 0.5830001 -1.295 0.52900059 -1.295 3 P 0 ;0,4=14,6=0.000000
L 0.52900059 -1.295 0.52900059 -1.445 3 P 0 ;0,4=14,6=0.000000
L 0.52900059 -1.445 0.59500118 -1.445 3 P 0 ;0,4=14,6=0.000000
L 0.59500118 -1.445 0.60900187 -1.43500217 3 P 0 ;0,4=14,6=0.000000
L 0.60900187 -1.43500217 0.6170001 -1.42000079 3 P 0 ;0,4=14,6=0.000000
L 0.6170001 -1.42000079 0.62099931 -1.4025 3 P 0 ;0,4=14,6=0.000000
L 0.62099931 -1.4025 0.6170001 -1.38500374 3 P 0 ;0,4=14,6=0.000000
L 0.6170001 -1.38500374 0.60499902 -1.37000236 3 P 0 ;0,4=14,6=0.000000
L 0.60499902 -1.37000236 0.59099833 -1.36499882 3 P 0 ;0,4=14,6=0.000000
L 0.59099833 -1.36499882 0.52900059 -1.36499882 3 P 0 ;0,4=14,6=0.000000
L 0.77100138 -1.445 0.77100138 -1.34500315 3 P 0 ;0,4=14,6=0.000000
L 0.77100138 -1.36249941 0.76299951 -1.35250148 3 P 0 ;0,4=14,6=0.000000
L 0.76299951 -1.35250148 0.75099833 -1.34750256 3 P 0 ;0,4=14,6=0.000000
L 0.75099833 -1.34750256 0.73700138 -1.34500315 3 P 0 ;0,4=14,6=0.000000
L 0.73700138 -1.34500315 0.72300069 -1.35000207 3 P 0 ;0,4=14,6=0.000000
L 0.72300069 -1.35000207 0.71099961 -1.3599999 3 P 0 ;0,4=14,6=0.000000
L 0.71099961 -1.3599999 0.70299764 -1.37500128 3 P 0 ;0,4=14,6=0.000000
L 0.70299764 -1.37500128 0.69899852 -1.39500157 3 P 0 ;0,4=14,6=0.000000
L 0.69899852 -1.39500157 0.70299764 -1.41500187 3 P 0 ;0,4=14,6=0.000000
L 0.70299764 -1.41500187 0.71099961 -1.43000325 3 P 0 ;0,4=14,6=0.000000
L 0.71099961 -1.43000325 0.72300069 -1.44000108 3 P 0 ;0,4=14,6=0.000000
L 0.72300069 -1.44000108 0.73700138 -1.445 3 P 0 ;0,4=14,6=0.000000
L 0.73700138 -1.445 0.75099833 -1.44250059 3 P 0 ;0,4=14,6=0.000000
L 0.75099833 -1.44250059 0.76299951 -1.43500217 3 P 0 ;0,4=14,6=0.000000
L 0.76299951 -1.43500217 0.77100138 -1.42500433 3 P 0 ;0,4=14,6=0.000000
L 0.86700039 -1.445 0.86700039 -1.34500315 3 P 0 ;0,4=14,6=0.000000
L 0.86700039 -1.36499882 0.87699833 -1.35500098 3 P 0 ;0,4=14,6=0.000000
L 0.87699833 -1.35500098 0.8869998 -1.34750256 3 P 0 ;0,4=14,6=0.000000
L 0.8869998 -1.34750256 0.90100049 -1.34500315 3 P 0 ;0,4=14,6=0.000000
L 0.90100049 -1.34500315 0.91099833 -1.34750256 3 P 0 ;0,4=14,6=0.000000
L 0.91099833 -1.34750256 0.92299951 -1.35500098 3 P 0 ;0,4=14,6=0.000000
L 1.02700039 -1.445 1.02700039 -1.34500315 3 P 0 ;0,4=14,6=0.000000
L 1.02700039 -1.36499882 1.03699833 -1.35500098 3 P 0 ;0,4=14,6=0.000000
L 1.03699833 -1.35500098 1.0469998 -1.34750256 3 P 0 ;0,4=14,6=0.000000
L 1.0469998 -1.34750256 1.06100049 -1.34500315 3 P 0 ;0,4=14,6=0.000000
L 1.06100049 -1.34500315 1.07099833 -1.34750256 3 P 0 ;0,4=14,6=0.000000
L 1.07099833 -1.34750256 1.08299951 -1.35500098 3 P 0 ;0,4=14,6=0.000000
L 1.18500089 -1.37750069 1.24900187 -1.37750069 3 P 0 ;0,4=14,6=0.000000
L 1.24900187 -1.37750069 1.24299951 -1.3599999 3 P 0 ;0,4=14,6=0.000000
L 1.24299951 -1.3599999 1.23300157 -1.35000207 3 P 0 ;0,4=14,6=0.000000
L 1.23300157 -1.35000207 1.21900089 -1.34500315 3 P 0 ;0,4=14,6=0.000000
L 1.21900089 -1.34500315 1.2050003 -1.34750256 3 P 0 ;0,4=14,6=0.000000
L 1.2050003 -1.34750256 1.19299911 -1.35500098 3 P 0 ;0,4=14,6=0.000000
L 1.19299911 -1.35500098 1.18500089 -1.37250177 3 P 0 ;0,4=14,6=0.000000
L 1.18500089 -1.37250177 1.18099803 -1.38750315 3 P 0 ;0,4=14,6=0.000000
L 1.18099803 -1.38750315 1.18099803 -1.4025 3 P 0 ;0,4=14,6=0.000000
L 1.18099803 -1.4025 1.18500089 -1.41750138 3 P 0 ;0,4=14,6=0.000000
L 1.18500089 -1.41750138 1.19499872 -1.43250276 3 P 0 ;0,4=14,6=0.000000
L 1.19499872 -1.43250276 1.2069998 -1.44250059 3 P 0 ;0,4=14,6=0.000000
L 1.2069998 -1.44250059 1.22100049 -1.445 3 P 0 ;0,4=14,6=0.000000
L 1.22100049 -1.445 1.23500118 -1.44000108 3 P 0 ;0,4=14,6=0.000000
L 1.23500118 -1.44000108 1.24900187 -1.42500433 3 P 0 ;0,4=14,6=0.000000
L 1.37499813 -1.445 1.37499813 -1.295 3 P 0 ;0,4=14,6=0.000000
L 1.50500089 -1.37750069 1.56900187 -1.37750069 3 P 0 ;0,4=14,6=0.000000
L 1.56900187 -1.37750069 1.56299951 -1.3599999 3 P 0 ;0,4=14,6=0.000000
L 1.56299951 -1.3599999 1.55300157 -1.35000207 3 P 0 ;0,4=14,6=0.000000
L 1.55300157 -1.35000207 1.53900089 -1.34500315 3 P 0 ;0,4=14,6=0.000000
L 1.53900089 -1.34500315 1.5250003 -1.34750256 3 P 0 ;0,4=14,6=0.000000
L 1.5250003 -1.34750256 1.51299911 -1.35500098 3 P 0 ;0,4=14,6=0.000000
L 1.51299911 -1.35500098 1.50500089 -1.37250177 3 P 0 ;0,4=14,6=0.000000
L 1.50500089 -1.37250177 1.50099803 -1.38750315 3 P 0 ;0,4=14,6=0.000000
L 1.50099803 -1.38750315 1.50099803 -1.4025 3 P 0 ;0,4=14,6=0.000000
L 1.50099803 -1.4025 1.50500089 -1.41750138 3 P 0 ;0,4=14,6=0.000000
L 1.50500089 -1.41750138 1.51499872 -1.43250276 3 P 0 ;0,4=14,6=0.000000
L 1.51499872 -1.43250276 1.5269998 -1.44250059 3 P 0 ;0,4=14,6=0.000000
L 1.5269998 -1.44250059 1.54100049 -1.445 3 P 0 ;0,4=14,6=0.000000
L 1.54100049 -1.445 1.55500118 -1.44000108 3 P 0 ;0,4=14,6=0.000000
L 1.55500118 -1.44000108 1.56900187 -1.42500433 3 P 0 ;0,4=14,6=0.000000
L 1.6529998 -1.48999951 1.66500089 -1.49499843 3 P 0 ;0,4=14,6=0.000000
L 1.66500089 -1.49499843 1.68100108 -1.48999951 3 P 0 ;0,4=14,6=0.000000
L 1.68100108 -1.48999951 1.69099902 -1.48000167 3 P 0 ;0,4=14,6=0.000000
L 1.69099902 -1.48000167 1.69900089 -1.4674997 3 P 0 ;0,4=14,6=0.000000
L 1.69900089 -1.4674997 1.71099833 -1.42750374 3 P 0 ;0,4=14,6=0.000000
L 1.71099833 -1.42750374 1.7370001 -1.34500315 3 P 0 ;0,4=14,6=0.000000
L 1.67299911 -1.34500315 1.71099833 -1.42750374 3 P 0 ;0,4=14,6=0.000000
L 1.82500089 -1.37750069 1.88900187 -1.37750069 3 P 0 ;0,4=14,6=0.000000
L 1.88900187 -1.37750069 1.88299951 -1.3599999 3 P 0 ;0,4=14,6=0.000000
L 1.88299951 -1.3599999 1.87300157 -1.35000207 3 P 0 ;0,4=14,6=0.000000
L 1.87300157 -1.35000207 1.85900089 -1.34500315 3 P 0 ;0,4=14,6=0.000000
L 1.85900089 -1.34500315 1.8450003 -1.34750256 3 P 0 ;0,4=14,6=0.000000
L 1.8450003 -1.34750256 1.83299911 -1.35500098 3 P 0 ;0,4=14,6=0.000000
L 1.83299911 -1.35500098 1.82500089 -1.37250177 3 P 0 ;0,4=14,6=0.000000
L 1.82500089 -1.37250177 1.82099803 -1.38750315 3 P 0 ;0,4=14,6=0.000000
L 1.82099803 -1.38750315 1.82099803 -1.4025 3 P 0 ;0,4=14,6=0.000000
L 1.82099803 -1.4025 1.82500089 -1.41750138 3 P 0 ;0,4=14,6=0.000000
L 1.82500089 -1.41750138 1.83499872 -1.43250276 3 P 0 ;0,4=14,6=0.000000
L 1.83499872 -1.43250276 1.8469998 -1.44250059 3 P 0 ;0,4=14,6=0.000000
L 1.8469998 -1.44250059 1.86100049 -1.445 3 P 0 ;0,4=14,6=0.000000
L 1.86100049 -1.445 1.87500118 -1.44000108 3 P 0 ;0,4=14,6=0.000000
L 1.87500118 -1.44000108 1.88900187 -1.42500433 3 P 0 ;0,4=14,6=0.000000
L 2.18699921 -1.37000236 2.22700167 -1.37000236 3 P 0 ;0,4=14,6=0.000000
L 2.22700167 -1.37000236 2.22700167 -1.41500187 3 P 0 ;0,4=14,6=0.000000
L 2.22700167 -1.41500187 2.21500059 -1.43000325 3 P 0 ;0,4=14,6=0.000000
L 2.21500059 -1.43000325 2.2009999 -1.44000108 3 P 0 ;0,4=14,6=0.000000
L 2.2009999 -1.44000108 2.18100049 -1.445 3 P 0 ;0,4=14,6=0.000000
L 2.18100049 -1.445 2.16100108 -1.44000108 3 P 0 ;0,4=14,6=0.000000
L 2.16100108 -1.44000108 2.14700039 -1.43000325 3 P 0 ;0,4=14,6=0.000000
L 2.14700039 -1.43000325 2.13499931 -1.41500187 3 P 0 ;0,4=14,6=0.000000
L 2.13499931 -1.41500187 2.12699734 -1.39750108 3 P 0 ;0,4=14,6=0.000000
L 2.12699734 -1.39750108 2.12299823 -1.37750069 3 P 0 ;0,4=14,6=0.000000
L 2.12299823 -1.37750069 2.12299823 -1.3599999 3 P 0 ;0,4=14,6=0.000000
L 2.12299823 -1.3599999 2.12699734 -1.34500315 3 P 0 ;0,4=14,6=0.000000
L 2.12699734 -1.34500315 2.13499931 -1.32749764 3 P 0 ;0,4=14,6=0.000000
L 2.13499931 -1.32749764 2.14700039 -1.31250089 3 P 0 ;0,4=14,6=0.000000
L 2.14700039 -1.31250089 2.15899783 -1.30250305 3 P 0 ;0,4=14,6=0.000000
L 2.15899783 -1.30250305 2.17499813 -1.295 3 P 0 ;0,4=14,6=0.000000
L 2.17499813 -1.295 2.18899882 -1.295 3 P 0 ;0,4=14,6=0.000000
L 2.18899882 -1.295 2.20499902 -1.29999902 3 P 0 ;0,4=14,6=0.000000
L 2.20499902 -1.29999902 2.2170001 -1.31000138 3 P 0 ;0,4=14,6=0.000000
L 2.29699892 -1.31999931 2.309 -1.30500246 3 P 0 ;0,4=14,6=0.000000
L 2.309 -1.30500246 2.32300069 -1.29749951 3 P 0 ;0,4=14,6=0.000000
L 2.32300069 -1.29749951 2.33900089 -1.295 3 P 0 ;0,4=14,6=0.000000
L 2.33900089 -1.295 2.3590003 -1.29999902 3 P 0 ;0,4=14,6=0.000000
L 2.3590003 -1.29999902 2.37300098 -1.31250089 3 P 0 ;0,4=14,6=0.000000
L 2.37300098 -1.31250089 2.3770001 -1.32749764 3 P 0 ;0,4=14,6=0.000000
L 2.3770001 -1.32749764 2.37500059 -1.34250364 3 P 0 ;0,4=14,6=0.000000
L 2.37500059 -1.34250364 2.36699862 -1.35500098 3 P 0 ;0,4=14,6=0.000000
L 2.36699862 -1.35500098 2.3269998 -1.3800002 3 P 0 ;0,4=14,6=0.000000
L 2.3269998 -1.3800002 2.309 -1.39750108 3 P 0 ;0,4=14,6=0.000000
L 2.309 -1.39750108 2.29699892 -1.42250482 3 P 0 ;0,4=14,6=0.000000
L 2.29699892 -1.42250482 2.2929998 -1.445 3 P 0 ;0,4=14,6=0.000000
L 2.2929998 -1.445 2.3770001 -1.445 3 P 0 ;0,4=14,6=0.000000
L 2.6129998 -1.42500433 2.629 -1.43750167 3 P 0 ;0,4=14,6=0.000000
L 2.629 -1.43750167 2.6469998 -1.445 3 P 0 ;0,4=14,6=0.000000
L 2.6469998 -1.445 2.6630001 -1.445 3 P 0 ;0,4=14,6=0.000000
L 2.6630001 -1.445 2.6790003 -1.43750167 3 P 0 ;0,4=14,6=0.000000
L 2.6790003 -1.43750167 2.69100138 -1.42500433 3 P 0 ;0,4=14,6=0.000000
L 2.69100138 -1.42500433 2.6970001 -1.40749892 3 P 0 ;0,4=14,6=0.000000
L 2.6970001 -1.40749892 2.69300098 -1.39000266 3 P 0 ;0,4=14,6=0.000000
L 2.69300098 -1.39000266 2.68299951 -1.37500128 3 P 0 ;0,4=14,6=0.000000
L 2.68299951 -1.37500128 2.66499961 -1.36499882 3 P 0 ;0,4=14,6=0.000000
L 2.66499961 -1.36499882 2.64100108 -1.3599999 3 P 0 ;0,4=14,6=0.000000
L 2.64100108 -1.3599999 2.62700039 -1.35000207 3 P 0 ;0,4=14,6=0.000000
L 2.62700039 -1.35000207 2.62099803 -1.33250118 3 P 0 ;0,4=14,6=0.000000
L 2.62099803 -1.33250118 2.62500089 -1.31500039 3 P 0 ;0,4=14,6=0.000000
L 2.62500089 -1.31500039 2.63499872 -1.30250305 3 P 0 ;0,4=14,6=0.000000
L 2.63499872 -1.30250305 2.64899941 -1.295 3 P 0 ;0,4=14,6=0.000000
L 2.64899941 -1.295 2.6630001 -1.295 3 P 0 ;0,4=14,6=0.000000
L 2.6630001 -1.295 2.67700079 -1.29999902 3 P 0 ;0,4=14,6=0.000000
L 2.67700079 -1.29999902 2.68900187 -1.31250089 3 P 0 ;0,4=14,6=0.000000
L 2.7729998 -1.445 2.8570001 -1.295 3 P 0 ;0,4=14,6=0.000000
L 2.7729998 -1.295 2.8570001 -1.445 3 P 0 ;0,4=14,6=0.000000
L 2.92299823 -1.445 2.92299823 -1.295 3 P 0 ;0,4=14,6=0.000000
L 2.92299823 -1.295 2.97499813 -1.42000079 3 P 0 ;0,4=14,6=0.000000
L 2.97499813 -1.42000079 3.02700167 -1.295 3 P 0 ;0,4=14,6=0.000000
L 3.02700167 -1.295 3.02700167 -1.445 3 P 0 ;0,4=14,6=0.000000
L 3.09699892 -1.31999931 3.109 -1.30500246 3 P 0 ;0,4=14,6=0.000000
L 3.109 -1.30500246 3.12300069 -1.29749951 3 P 0 ;0,4=14,6=0.000000
L 3.12300069 -1.29749951 3.13900089 -1.295 3 P 0 ;0,4=14,6=0.000000
L 3.13900089 -1.295 3.1590003 -1.29999902 3 P 0 ;0,4=14,6=0.000000
L 3.1590003 -1.29999902 3.17300098 -1.31250089 3 P 0 ;0,4=14,6=0.000000
L 3.17300098 -1.31250089 3.1770001 -1.32749764 3 P 0 ;0,4=14,6=0.000000
L 3.1770001 -1.32749764 3.17500059 -1.34250364 3 P 0 ;0,4=14,6=0.000000
L 3.17500059 -1.34250364 3.16699862 -1.35500098 3 P 0 ;0,4=14,6=0.000000
L 3.16699862 -1.35500098 3.1269998 -1.3800002 3 P 0 ;0,4=14,6=0.000000
L 3.1269998 -1.3800002 3.109 -1.39750108 3 P 0 ;0,4=14,6=0.000000
L 3.109 -1.39750108 3.09699892 -1.42250482 3 P 0 ;0,4=14,6=0.000000
L 3.09699892 -1.42250482 3.0929998 -1.445 3 P 0 ;0,4=14,6=0.000000
L 3.0929998 -1.445 3.1770001 -1.445 3 P 0 ;0,4=14,6=0.000000
L 3.269 -1.39500157 3.3209999 -1.39500157 3 P 0 ;0,4=14,6=0.000000
L 3.41499931 -1.445 3.41499931 -1.295 3 P 0 ;0,4=14,6=0.000000
L 3.41499931 -1.295 3.46499961 -1.295 3 P 0 ;0,4=14,6=0.000000
L 3.46499961 -1.295 3.4809999 -1.30250305 3 P 0 ;0,4=14,6=0.000000
L 3.4809999 -1.30250305 3.49100138 -1.31250089 3 P 0 ;0,4=14,6=0.000000
L 3.49100138 -1.31250089 3.49500059 -1.33250118 3 P 0 ;0,4=14,6=0.000000
L 3.49500059 -1.33250118 3.49100138 -1.35250148 3 P 0 ;0,4=14,6=0.000000
L 3.49100138 -1.35250148 3.4790003 -1.36499882 3 P 0 ;0,4=14,6=0.000000
L 3.4790003 -1.36499882 3.46499961 -1.37250177 3 P 0 ;0,4=14,6=0.000000
L 3.46499961 -1.37250177 3.41499931 -1.37250177 3 P 0 ;0,4=14,6=0.000000
L 3.46499961 -1.37250177 3.49500059 -1.445 3 P 0 ;0,4=14,6=0.000000
L 3.61499813 -1.34500315 3.61499813 -1.445 3 P 0 ;0,4=14,6=0.000000
L 3.61499813 -1.30500246 3.61099902 -1.30250305 3 P 0 ;0,4=14,6=0.000000
L 3.61099902 -1.30250305 3.61099902 -1.29749951 3 P 0 ;0,4=14,6=0.000000
L 3.61099902 -1.29749951 3.61499813 -1.295 3 P 0 ;0,4=14,6=0.000000
L 3.61499813 -1.295 3.61900089 -1.29749951 3 P 0 ;0,4=14,6=0.000000
L 3.61900089 -1.29749951 3.61900089 -1.30250305 3 P 0 ;0,4=14,6=0.000000
L 3.61900089 -1.30250305 3.61499813 -1.30500246 3 P 0 ;0,4=14,6=0.000000
L 3.74500089 -1.42750374 3.75499872 -1.43750167 3 P 0 ;0,4=14,6=0.000000
L 3.75499872 -1.43750167 3.76899941 -1.445 3 P 0 ;0,4=14,6=0.000000
L 3.76899941 -1.445 3.78100049 -1.445 3 P 0 ;0,4=14,6=0.000000
L 3.78100049 -1.445 3.79300157 -1.44000108 3 P 0 ;0,4=14,6=0.000000
L 3.79300157 -1.44000108 3.8009999 -1.43250276 3 P 0 ;0,4=14,6=0.000000
L 3.8009999 -1.43250276 3.80499902 -1.42250482 3 P 0 ;0,4=14,6=0.000000
L 3.80499902 -1.42250482 3.80299951 -1.40749892 3 P 0 ;0,4=14,6=0.000000
L 3.80299951 -1.40749892 3.79500118 -1.40000049 3 P 0 ;0,4=14,6=0.000000
L 3.79500118 -1.40000049 3.75899783 -1.38500374 3 P 0 ;0,4=14,6=0.000000
L 3.75899783 -1.38500374 3.75099961 -1.36749833 3 P 0 ;0,4=14,6=0.000000
L 3.75099961 -1.36749833 3.75499872 -1.35500098 3 P 0 ;0,4=14,6=0.000000
L 3.75499872 -1.35500098 3.76300069 -1.34750256 3 P 0 ;0,4=14,6=0.000000
L 3.76300069 -1.34750256 3.77499813 -1.34500315 3 P 0 ;0,4=14,6=0.000000
L 3.77499813 -1.34500315 3.78699921 -1.34750256 3 P 0 ;0,4=14,6=0.000000
L 3.78699921 -1.34750256 3.7990003 -1.35500098 3 P 0 ;0,4=14,6=0.000000
L 3.90500089 -1.37750069 3.96900187 -1.37750069 3 P 0 ;0,4=14,6=0.000000
L 3.96900187 -1.37750069 3.96299951 -1.3599999 3 P 0 ;0,4=14,6=0.000000
L 3.96299951 -1.3599999 3.95300157 -1.35000207 3 P 0 ;0,4=14,6=0.000000
L 3.95300157 -1.35000207 3.93900089 -1.34500315 3 P 0 ;0,4=14,6=0.000000
L 3.93900089 -1.34500315 3.9250003 -1.34750256 3 P 0 ;0,4=14,6=0.000000
L 3.9250003 -1.34750256 3.91299911 -1.35500098 3 P 0 ;0,4=14,6=0.000000
L 3.91299911 -1.35500098 3.90500089 -1.37250177 3 P 0 ;0,4=14,6=0.000000
L 3.90500089 -1.37250177 3.90099803 -1.38750315 3 P 0 ;0,4=14,6=0.000000
L 3.90099803 -1.38750315 3.90099803 -1.4025 3 P 0 ;0,4=14,6=0.000000
L 3.90099803 -1.4025 3.90500089 -1.41750138 3 P 0 ;0,4=14,6=0.000000
L 3.90500089 -1.41750138 3.91499872 -1.43250276 3 P 0 ;0,4=14,6=0.000000
L 3.91499872 -1.43250276 3.9269998 -1.44250059 3 P 0 ;0,4=14,6=0.000000
L 3.9269998 -1.44250059 3.94100049 -1.445 3 P 0 ;0,4=14,6=0.000000
L 3.94100049 -1.445 3.95500118 -1.44000108 3 P 0 ;0,4=14,6=0.000000
L 3.95500118 -1.44000108 3.96900187 -1.42500433 3 P 0 ;0,4=14,6=0.000000
L 4.06700039 -1.445 4.06700039 -1.34500315 3 P 0 ;0,4=14,6=0.000000
L 4.06700039 -1.36499882 4.07699833 -1.35500098 3 P 0 ;0,4=14,6=0.000000
L 4.07699833 -1.35500098 4.0869998 -1.34750256 3 P 0 ;0,4=14,6=0.000000
L 4.0869998 -1.34750256 4.10100049 -1.34500315 3 P 0 ;0,4=14,6=0.000000
L 4.10100049 -1.34500315 4.11099833 -1.34750256 3 P 0 ;0,4=14,6=0.000000
L 4.11099833 -1.34750256 4.12299951 -1.35500098 3 P 0 ;0,4=14,6=0.000000
L 4.16964783 -2.2038 4.21839813 -2.0478 3 P 0 ;0,4=15,6=0.000000
L 4.21839813 -2.0478 4.26715207 -2.2038 3 P 0 ;0,4=15,6=0.000000
L 4.24959862 -2.14920217 4.18719774 -2.14920217 3 P 0 ;0,4=15,6=0.000000
L 4.37939813 -2.2038 4.37939813 -2.0478 3 P 0 ;0,4=15,6=0.000000
L 4.37939813 -2.0478 4.35599961 -2.07899813 3 P 0 ;0,4=15,6=0.000000
L 4.35599961 -2.2038 4.40279675 -2.2038 3 P 0 ;0,4=15,6=0.000000
L 2.0009002 -0.9538 2.0009002 -0.8038 3 P 0 ;0,4=16,6=0.000000
L 2.0009002 -0.8038 2.04089902 -0.8038 3 P 0 ;0,4=16,6=0.000000
L 2.04089902 -0.8038 2.05689921 -0.81130305 3 P 0 ;0,4=16,6=0.000000
L 2.05689921 -0.81130305 2.0689003 -0.82130089 3 P 0 ;0,4=16,6=0.000000
L 2.0689003 -0.82130089 2.07890187 -0.83629764 3 P 0 ;0,4=16,6=0.000000
L 2.07890187 -0.83629764 2.0869001 -0.85380315 3 P 0 ;0,4=16,6=0.000000
L 2.0869001 -0.85380315 2.0888997 -0.87880236 3 P 0 ;0,4=16,6=0.000000
L 2.0888997 -0.87880236 2.0869001 -0.90380157 3 P 0 ;0,4=16,6=0.000000
L 2.0869001 -0.90380157 2.07890187 -0.92130246 3 P 0 ;0,4=16,6=0.000000
L 2.07890187 -0.92130246 2.0689003 -0.93630374 3 P 0 ;0,4=16,6=0.000000
L 2.0689003 -0.93630374 2.05689921 -0.94630167 3 P 0 ;0,4=16,6=0.000000
L 2.05689921 -0.94630167 2.04089902 -0.9538 3 P 0 ;0,4=16,6=0.000000
L 2.04089902 -0.9538 2.0009002 -0.9538 3 P 0 ;0,4=16,6=0.000000
L 2.15489783 -0.9538 2.20489813 -0.8038 3 P 0 ;0,4=16,6=0.000000
L 2.20489813 -0.8038 2.25490207 -0.9538 3 P 0 ;0,4=16,6=0.000000
L 2.23689862 -0.90130207 2.17289764 -0.90130207 3 P 0 ;0,4=16,6=0.000000
L 2.36489813 -0.8038 2.36489813 -0.9538 3 P 0 ;0,4=16,6=0.000000
L 2.31890059 -0.8038 2.41089931 -0.8038 3 P 0 ;0,4=16,6=0.000000
L 2.56490059 -0.9538 2.48489931 -0.9538 3 P 0 ;0,4=16,6=0.000000
L 2.48489931 -0.9538 2.48489931 -0.8038 3 P 0 ;0,4=16,6=0.000000
L 2.48489931 -0.8038 2.56490059 -0.8038 3 P 0 ;0,4=16,6=0.000000
L 2.5329001 -0.87629833 2.48489931 -0.87629833 3 P 0 ;0,4=16,6=0.000000
L 2.84489813 -0.9538 2.82889783 -0.95130059 3 P 0 ;0,4=16,6=0.000000
L 2.82889783 -0.95130059 2.81490089 -0.94130276 3 P 0 ;0,4=16,6=0.000000
L 2.81490089 -0.94130276 2.8028998 -0.92630138 3 P 0 ;0,4=16,6=0.000000
L 2.8028998 -0.92630138 2.79489783 -0.90880049 3 P 0 ;0,4=16,6=0.000000
L 2.79489783 -0.90880049 2.79089862 -0.8888002 3 P 0 ;0,4=16,6=0.000000
L 2.79089862 -0.8888002 2.79089862 -0.8687999 3 P 0 ;0,4=16,6=0.000000
L 2.79089862 -0.8687999 2.79489783 -0.84879961 3 P 0 ;0,4=16,6=0.000000
L 2.79489783 -0.84879961 2.8028998 -0.83129872 3 P 0 ;0,4=16,6=0.000000
L 2.8028998 -0.83129872 2.81490089 -0.81630197 3 P 0 ;0,4=16,6=0.000000
L 2.81490089 -0.81630197 2.82889783 -0.80629951 3 P 0 ;0,4=16,6=0.000000
L 2.82889783 -0.80629951 2.84489813 -0.8038 3 P 0 ;0,4=16,6=0.000000
L 2.84489813 -0.8038 2.86089833 -0.80629951 3 P 0 ;0,4=16,6=0.000000
L 2.86089833 -0.80629951 2.87489902 -0.81630197 3 P 0 ;0,4=16,6=0.000000
L 2.87489902 -0.81630197 2.8869001 -0.83129872 3 P 0 ;0,4=16,6=0.000000
L 2.8869001 -0.83129872 2.89490207 -0.84879961 3 P 0 ;0,4=16,6=0.000000
L 2.89490207 -0.84879961 2.89890128 -0.8687999 3 P 0 ;0,4=16,6=0.000000
L 2.89890128 -0.8687999 2.89890128 -0.8888002 3 P 0 ;0,4=16,6=0.000000
L 2.89890128 -0.8888002 2.89490207 -0.90880049 3 P 0 ;0,4=16,6=0.000000
L 2.89490207 -0.90880049 2.8869001 -0.92630138 3 P 0 ;0,4=16,6=0.000000
L 2.8869001 -0.92630138 2.87489902 -0.94130276 3 P 0 ;0,4=16,6=0.000000
L 2.87489902 -0.94130276 2.86089833 -0.95130059 3 P 0 ;0,4=16,6=0.000000
L 2.86089833 -0.95130059 2.84489813 -0.9538 3 P 0 ;0,4=16,6=0.000000
L 3.0488997 -0.81630197 3.03689862 -0.80879902 3 P 0 ;0,4=16,6=0.000000
L 3.03689862 -0.80879902 3.02290157 -0.8038 3 P 0 ;0,4=16,6=0.000000
L 3.02290157 -0.8038 3.00690138 -0.8038 3 P 0 ;0,4=16,6=0.000000
L 3.00690138 -0.8038 2.98889783 -0.81130305 3 P 0 ;0,4=16,6=0.000000
L 2.98889783 -0.81130305 2.97490089 -0.82380039 3 P 0 ;0,4=16,6=0.000000
L 2.97490089 -0.82380039 2.96489931 -0.83880177 3 P 0 ;0,4=16,6=0.000000
L 2.96489931 -0.83880177 2.95689734 -0.86380098 3 P 0 ;0,4=16,6=0.000000
L 2.95689734 -0.86380098 2.95489783 -0.88630069 3 P 0 ;0,4=16,6=0.000000
L 2.95489783 -0.88630069 2.95890059 -0.90880049 3 P 0 ;0,4=16,6=0.000000
L 2.95890059 -0.90880049 2.96489931 -0.92380187 3 P 0 ;0,4=16,6=0.000000
L 2.96489931 -0.92380187 2.97690039 -0.93880325 3 P 0 ;0,4=16,6=0.000000
L 2.97690039 -0.93880325 2.99090108 -0.94880108 3 P 0 ;0,4=16,6=0.000000
L 2.99090108 -0.94880108 3.00489813 -0.9538 3 P 0 ;0,4=16,6=0.000000
L 3.00489813 -0.9538 3.01889882 -0.9538 3 P 0 ;0,4=16,6=0.000000
L 3.01889882 -0.9538 3.03289951 -0.94880108 3 P 0 ;0,4=16,6=0.000000
L 3.03289951 -0.94880108 3.04490059 -0.94130276 3 P 0 ;0,4=16,6=0.000000
L 3.04490059 -0.94130276 3.05490207 -0.93130482 3 P 0 ;0,4=16,6=0.000000
L 3.16489813 -0.8038 3.16489813 -0.9538 3 P 0 ;0,4=16,6=0.000000
L 3.11890059 -0.8038 3.21089931 -0.8038 3 P 0 ;0,4=16,6=0.000000
L 3.28889852 -0.95879892 3.36090138 -0.8038 3 P 0 ;0,4=16,6=0.000000
L 3.44689892 -0.82879931 3.4589 -0.81380246 3 P 0 ;0,4=16,6=0.000000
L 3.4589 -0.81380246 3.47290069 -0.80629951 3 P 0 ;0,4=16,6=0.000000
L 3.47290069 -0.80629951 3.48890089 -0.8038 3 P 0 ;0,4=16,6=0.000000
L 3.48890089 -0.8038 3.5089003 -0.80879902 3 P 0 ;0,4=16,6=0.000000
L 3.5089003 -0.80879902 3.52290098 -0.82130089 3 P 0 ;0,4=16,6=0.000000
L 3.52290098 -0.82130089 3.5269001 -0.83629764 3 P 0 ;0,4=16,6=0.000000
L 3.5269001 -0.83629764 3.52490059 -0.85130364 3 P 0 ;0,4=16,6=0.000000
L 3.52490059 -0.85130364 3.51689862 -0.86380098 3 P 0 ;0,4=16,6=0.000000
L 3.51689862 -0.86380098 3.4768998 -0.8888002 3 P 0 ;0,4=16,6=0.000000
L 3.4768998 -0.8888002 3.4589 -0.90630108 3 P 0 ;0,4=16,6=0.000000
L 3.4589 -0.90630108 3.44689892 -0.93130482 3 P 0 ;0,4=16,6=0.000000
L 3.44689892 -0.93130482 3.4428998 -0.9538 3 P 0 ;0,4=16,6=0.000000
L 3.4428998 -0.9538 3.5269001 -0.9538 3 P 0 ;0,4=16,6=0.000000
L 3.64089902 -0.9538 3.64489813 -0.92130246 3 P 0 ;0,4=16,6=0.000000
L 3.64489813 -0.92130246 3.65090049 -0.89380374 3 P 0 ;0,4=16,6=0.000000
L 3.65090049 -0.89380374 3.65889882 -0.8687999 3 P 0 ;0,4=16,6=0.000000
L 3.65889882 -0.8687999 3.6689003 -0.84130118 3 P 0 ;0,4=16,6=0.000000
L 3.6689003 -0.84130118 3.68490059 -0.8038 3 P 0 ;0,4=16,6=0.000000
L 3.68490059 -0.8038 3.60489931 -0.8038 3 P 0 ;0,4=16,6=0.000000
L 3.76889852 -0.95879892 3.84090138 -0.8038 3 P 0 ;0,4=16,6=0.000000
L 3.92689892 -0.82879931 3.9389 -0.81380246 3 P 0 ;0,4=16,6=0.000000
L 3.9389 -0.81380246 3.95290069 -0.80629951 3 P 0 ;0,4=16,6=0.000000
L 3.95290069 -0.80629951 3.96890089 -0.8038 3 P 0 ;0,4=16,6=0.000000
L 3.96890089 -0.8038 3.9889003 -0.80879902 3 P 0 ;0,4=16,6=0.000000
L 3.9889003 -0.80879902 4.00290098 -0.82130089 3 P 0 ;0,4=16,6=0.000000
L 4.00290098 -0.82130089 4.0069001 -0.83629764 3 P 0 ;0,4=16,6=0.000000
L 4.0069001 -0.83629764 4.00490059 -0.85130364 3 P 0 ;0,4=16,6=0.000000
L 4.00490059 -0.85130364 3.99689862 -0.86380098 3 P 0 ;0,4=16,6=0.000000
L 3.99689862 -0.86380098 3.9568998 -0.8888002 3 P 0 ;0,4=16,6=0.000000
L 3.9568998 -0.8888002 3.9389 -0.90630108 3 P 0 ;0,4=16,6=0.000000
L 3.9389 -0.90630108 3.92689892 -0.93130482 3 P 0 ;0,4=16,6=0.000000
L 3.92689892 -0.93130482 3.9228998 -0.9538 3 P 0 ;0,4=16,6=0.000000
L 3.9228998 -0.9538 4.0069001 -0.9538 3 P 0 ;0,4=16,6=0.000000
L 4.12489813 -0.8038 4.10889783 -0.80879902 3 P 0 ;0,4=16,6=0.000000
L 4.10889783 -0.80879902 4.09690039 -0.82130089 3 P 0 ;0,4=16,6=0.000000
L 4.09690039 -0.82130089 4.08889852 -0.83629764 3 P 0 ;0,4=16,6=0.000000
L 4.08889852 -0.83629764 4.0828998 -0.85630256 3 P 0 ;0,4=16,6=0.000000
L 4.0828998 -0.85630256 4.0809002 -0.87880236 3 P 0 ;0,4=16,6=0.000000
L 4.0809002 -0.87880236 4.0828998 -0.90130207 3 P 0 ;0,4=16,6=0.000000
L 4.0828998 -0.90130207 4.08889852 -0.92130246 3 P 0 ;0,4=16,6=0.000000
L 4.08889852 -0.92130246 4.09690039 -0.93630374 3 P 0 ;0,4=16,6=0.000000
L 4.09690039 -0.93630374 4.10889783 -0.94880108 3 P 0 ;0,4=16,6=0.000000
L 4.10889783 -0.94880108 4.12489813 -0.9538 3 P 0 ;0,4=16,6=0.000000
L 4.12489813 -0.9538 4.14089833 -0.94880108 3 P 0 ;0,4=16,6=0.000000
L 4.14089833 -0.94880108 4.15289951 -0.93630374 3 P 0 ;0,4=16,6=0.000000
L 4.15289951 -0.93630374 4.16090138 -0.92130246 3 P 0 ;0,4=16,6=0.000000
L 4.16090138 -0.92130246 4.1669001 -0.90130207 3 P 0 ;0,4=16,6=0.000000
L 4.1669001 -0.90130207 4.1688997 -0.87880236 3 P 0 ;0,4=16,6=0.000000
L 4.1688997 -0.87880236 4.1669001 -0.85630256 3 P 0 ;0,4=16,6=0.000000
L 4.1669001 -0.85630256 4.16090138 -0.83629764 3 P 0 ;0,4=16,6=0.000000
L 4.16090138 -0.83629764 4.15289951 -0.82130089 3 P 0 ;0,4=16,6=0.000000
L 4.15289951 -0.82130089 4.14089833 -0.80879902 3 P 0 ;0,4=16,6=0.000000
L 4.14089833 -0.80879902 4.12489813 -0.8038 3 P 0 ;0,4=16,6=0.000000
L 4.28489813 -0.9538 4.28489813 -0.8038 3 P 0 ;0,4=16,6=0.000000
L 4.28489813 -0.8038 4.26089961 -0.83379823 3 P 0 ;0,4=16,6=0.000000
L 4.26089961 -0.9538 4.30889665 -0.9538 3 P 0 ;0,4=16,6=0.000000
L 4.44089902 -0.9538 4.44489813 -0.92130246 3 P 0 ;0,4=16,6=0.000000
L 4.44489813 -0.92130246 4.45090049 -0.89380374 3 P 0 ;0,4=16,6=0.000000
L 4.45090049 -0.89380374 4.45889882 -0.8687999 3 P 0 ;0,4=16,6=0.000000
L 4.45889882 -0.8687999 4.4689003 -0.84130118 3 P 0 ;0,4=16,6=0.000000
L 4.4689003 -0.84130118 4.48490059 -0.8038 3 P 0 ;0,4=16,6=0.000000
L 4.48490059 -0.8038 4.40489931 -0.8038 3 P 0 ;0,4=16,6=0.000000
L 1.9639003 -1.6638 1.93590197 -1.6638 3 P 0 ;0,2,4=17,6=0.000000
L 1.94990108 -1.6638 1.94990108 -1.7538 3 P 0 ;0,2,4=17,6=0.000000
L 1.9639003 -1.7538 1.93590197 -1.7538 3 P 0 ;0,2,4=17,6=0.000000
L 1.88673297 -1.7538 1.88673297 -1.6638 3 P 0 ;0,2,4=17,6=0.000000
L 1.88673297 -1.6638 1.83306713 -1.7538 3 P 0 ;0,2,4=17,6=0.000000
L 1.83306713 -1.7538 1.83306713 -1.6638 3 P 0 ;0,2,4=17,6=0.000000
L 1.76990108 -1.6638 1.76990108 -1.7538 3 P 0 ;0,2,4=17,6=0.000000
L 1.79673297 -1.6638 1.74306713 -1.6638 3 P 0 ;0,2,4=17,6=0.000000
L 1.65656634 -1.7538 1.70323376 -1.7538 3 P 0 ;0,2,4=17,6=0.000000
L 1.70323376 -1.7538 1.70323376 -1.6638 3 P 0 ;0,2,4=17,6=0.000000
L 1.70323376 -1.6638 1.65656634 -1.6638 3 P 0 ;0,2,4=17,6=0.000000
L 1.67523327 -1.70729902 1.70323376 -1.70729902 3 P 0 ;0,2,4=17,6=0.000000
L 1.61323376 -1.7538 1.61323376 -1.6638 3 P 0 ;0,2,4=17,6=0.000000
L 1.61323376 -1.6638 1.58406693 -1.6638 3 P 0 ;0,2,4=17,6=0.000000
L 1.58406693 -1.6638 1.57473346 -1.66830187 3 P 0 ;0,2,4=17,6=0.000000
L 1.57473346 -1.66830187 1.56889921 -1.67430059 3 P 0 ;0,2,4=17,6=0.000000
L 1.56889921 -1.67430059 1.56656634 -1.68630069 3 P 0 ;0,2,4=17,6=0.000000
L 1.56656634 -1.68630069 1.56889921 -1.69830089 3 P 0 ;0,2,4=17,6=0.000000
L 1.56889921 -1.69830089 1.5758998 -1.70579931 3 P 0 ;0,2,4=17,6=0.000000
L 1.5758998 -1.70579931 1.58406693 -1.71030108 3 P 0 ;0,2,4=17,6=0.000000
L 1.58406693 -1.71030108 1.61323376 -1.71030108 3 P 0 ;0,2,4=17,6=0.000000
L 1.58406693 -1.71030108 1.56656634 -1.7538 3 P 0 ;0,2,4=17,6=0.000000
L 1.52673297 -1.7538 1.52673297 -1.6638 3 P 0 ;0,2,4=17,6=0.000000
L 1.52673297 -1.6638 1.47306713 -1.7538 3 P 0 ;0,2,4=17,6=0.000000
L 1.47306713 -1.7538 1.47306713 -1.6638 3 P 0 ;0,2,4=17,6=0.000000
L 1.43906791 -1.7538 1.40990108 -1.6638 3 P 0 ;0,2,4=17,6=0.000000
L 1.40990108 -1.6638 1.38073219 -1.7538 3 P 0 ;0,2,4=17,6=0.000000
L 1.39123415 -1.72230128 1.42856811 -1.72230128 3 P 0 ;0,2,4=17,6=0.000000
L 1.34323376 -1.6638 1.34323376 -1.7538 3 P 0 ;0,2,4=17,6=0.000000
L 1.34323376 -1.7538 1.29656634 -1.7538 3 P 0 ;0,2,4=17,6=0.000000
L 1.16323376 -1.6638 1.16323376 -1.7538 3 P 0 ;0,2,4=17,6=0.000000
L 1.16323376 -1.7538 1.11656634 -1.7538 3 P 0 ;0,2,4=17,6=0.000000
L 1.07906791 -1.7538 1.04990108 -1.6638 3 P 0 ;0,2,4=17,6=0.000000
L 1.04990108 -1.6638 1.02073219 -1.7538 3 P 0 ;0,2,4=17,6=0.000000
L 1.03123415 -1.72230128 1.06856811 -1.72230128 3 P 0 ;0,2,4=17,6=0.000000
L 0.95990108 -1.7538 0.95990108 -1.71330049 3 P 0 ;0,2,4=17,6=0.000000
L 0.95990108 -1.71330049 0.98323376 -1.6638 3 P 0 ;0,2,4=17,6=0.000000
L 0.93656634 -1.6638 0.95990108 -1.71330049 3 P 0 ;0,2,4=17,6=0.000000
L 0.84656634 -1.7538 0.89323376 -1.7538 3 P 0 ;0,2,4=17,6=0.000000
L 0.89323376 -1.7538 0.89323376 -1.6638 3 P 0 ;0,2,4=17,6=0.000000
L 0.89323376 -1.6638 0.84656634 -1.6638 3 P 0 ;0,2,4=17,6=0.000000
L 0.86523327 -1.70729902 0.89323376 -1.70729902 3 P 0 ;0,2,4=17,6=0.000000
L 0.80323376 -1.7538 0.80323376 -1.6638 3 P 0 ;0,2,4=17,6=0.000000
L 0.80323376 -1.6638 0.77406693 -1.6638 3 P 0 ;0,2,4=17,6=0.000000
L 0.77406693 -1.6638 0.76473346 -1.66830187 3 P 0 ;0,2,4=17,6=0.000000
L 0.76473346 -1.66830187 0.75889921 -1.67430059 3 P 0 ;0,2,4=17,6=0.000000
L 0.75889921 -1.67430059 0.75656634 -1.68630069 3 P 0 ;0,2,4=17,6=0.000000
L 0.75656634 -1.68630069 0.75889921 -1.69830089 3 P 0 ;0,2,4=17,6=0.000000
L 0.75889921 -1.69830089 0.7658998 -1.70579931 3 P 0 ;0,2,4=17,6=0.000000
L 0.7658998 -1.70579931 0.77406693 -1.71030108 3 P 0 ;0,2,4=17,6=0.000000
L 0.77406693 -1.71030108 0.80323376 -1.71030108 3 P 0 ;0,2,4=17,6=0.000000
L 0.77406693 -1.71030108 0.75656634 -1.7538 3 P 0 ;0,2,4=17,6=0.000000
L 0.59990108 -1.7538 0.59990108 -1.6638 3 P 0 ;0,2,4=17,6=0.000000
L 0.59990108 -1.6638 0.6139003 -1.68179892 3 P 0 ;0,2,4=17,6=0.000000
L 0.6139003 -1.7538 0.58590197 -1.7538 3 P 0 ;0,2,4=17,6=0.000000
L 0.50990108 -1.6638 0.51923455 -1.66679941 3 P 0 ;0,2,4=17,6=0.000000
L 0.51923455 -1.66679941 0.52623307 -1.67430059 3 P 0 ;0,2,4=17,6=0.000000
L 0.52623307 -1.67430059 0.53090089 -1.68329862 3 P 0 ;0,2,4=17,6=0.000000
L 0.53090089 -1.68329862 0.5344002 -1.69530157 3 P 0 ;0,2,4=17,6=0.000000
L 0.5344002 -1.69530157 0.53556654 -1.70880138 3 P 0 ;0,2,4=17,6=0.000000
L 0.53556654 -1.70880138 0.5344002 -1.72230128 3 P 0 ;0,2,4=17,6=0.000000
L 0.5344002 -1.72230128 0.53090089 -1.73430148 3 P 0 ;0,2,4=17,6=0.000000
L 0.53090089 -1.73430148 0.52623307 -1.74330226 3 P 0 ;0,2,4=17,6=0.000000
L 0.52623307 -1.74330226 0.51923455 -1.75080069 3 P 0 ;0,2,4=17,6=0.000000
L 0.51923455 -1.75080069 0.50990108 -1.7538 3 P 0 ;0,2,4=17,6=0.000000
L 0.50990108 -1.7538 0.50056762 -1.75080069 3 P 0 ;0,2,4=17,6=0.000000
L 0.50056762 -1.75080069 0.49356703 -1.74330226 3 P 0 ;0,2,4=17,6=0.000000
L 0.49356703 -1.74330226 0.48889921 -1.73430148 3 P 0 ;0,2,4=17,6=0.000000
L 0.48889921 -1.73430148 0.4853999 -1.72230128 3 P 0 ;0,2,4=17,6=0.000000
L 0.4853999 -1.72230128 0.48423356 -1.70880138 3 P 0 ;0,2,4=17,6=0.000000
L 0.48423356 -1.70880138 0.4853999 -1.69530157 3 P 0 ;0,2,4=17,6=0.000000
L 0.4853999 -1.69530157 0.48889921 -1.68329862 3 P 0 ;0,2,4=17,6=0.000000
L 0.48889921 -1.68329862 0.49356703 -1.67430059 3 P 0 ;0,2,4=17,6=0.000000
L 0.49356703 -1.67430059 0.50056762 -1.66679941 3 P 0 ;0,2,4=17,6=0.000000
L 0.50056762 -1.66679941 0.50990108 -1.6638 3 P 0 ;0,2,4=17,6=0.000000
L 3.76989892 -2.0038 3.76989892 -1.9138 3 P 0 ;0,4=18,6=0.000000
L 3.76989892 -1.9138 3.7558997 -1.93179892 3 P 0 ;0,4=18,6=0.000000
L 3.7558997 -2.0038 3.78389803 -2.0038 3 P 0 ;0,4=18,6=0.000000
L 3.85989892 -1.9138 3.85056545 -1.91679941 3 P 0 ;0,4=18,6=0.000000
L 3.85056545 -1.91679941 3.84356693 -1.92430059 3 P 0 ;0,4=18,6=0.000000
L 3.84356693 -1.92430059 3.83889911 -1.93329862 3 P 0 ;0,4=18,6=0.000000
L 3.83889911 -1.93329862 3.8353998 -1.94530157 3 P 0 ;0,4=18,6=0.000000
L 3.8353998 -1.94530157 3.83423346 -1.95880138 3 P 0 ;0,4=18,6=0.000000
L 3.83423346 -1.95880138 3.8353998 -1.97230128 3 P 0 ;0,4=18,6=0.000000
L 3.8353998 -1.97230128 3.83889911 -1.98430148 3 P 0 ;0,4=18,6=0.000000
L 3.83889911 -1.98430148 3.84356693 -1.99330226 3 P 0 ;0,4=18,6=0.000000
L 3.84356693 -1.99330226 3.85056545 -2.00080069 3 P 0 ;0,4=18,6=0.000000
L 3.85056545 -2.00080069 3.85989892 -2.0038 3 P 0 ;0,4=18,6=0.000000
L 3.85989892 -2.0038 3.86923238 -2.00080069 3 P 0 ;0,4=18,6=0.000000
L 3.86923238 -2.00080069 3.87623297 -1.99330226 3 P 0 ;0,4=18,6=0.000000
L 3.87623297 -1.99330226 3.88090079 -1.98430148 3 P 0 ;0,4=18,6=0.000000
L 3.88090079 -1.98430148 3.8844001 -1.97230128 3 P 0 ;0,4=18,6=0.000000
L 3.8844001 -1.97230128 3.88556644 -1.95880138 3 P 0 ;0,4=18,6=0.000000
L 3.88556644 -1.95880138 3.8844001 -1.94530157 3 P 0 ;0,4=18,6=0.000000
L 3.8844001 -1.94530157 3.88090079 -1.93329862 3 P 0 ;0,4=18,6=0.000000
L 3.88090079 -1.93329862 3.87623297 -1.92430059 3 P 0 ;0,4=18,6=0.000000
L 3.87623297 -1.92430059 3.86923238 -1.91679941 3 P 0 ;0,4=18,6=0.000000
L 3.86923238 -1.91679941 3.85989892 -1.9138 3 P 0 ;0,4=18,6=0.000000
L 3.01989892 -2.2538 3.01989892 -2.1638 3 P 0 ;0,4=18,6=0.000000
L 3.01989892 -2.1638 3.0058997 -2.18179892 3 P 0 ;0,4=18,6=0.000000
L 3.0058997 -2.2538 3.03389803 -2.2538 3 P 0 ;0,4=18,6=0.000000
L 3.10989892 -2.1638 3.10056545 -2.16679941 3 P 0 ;0,4=18,6=0.000000
L 3.10056545 -2.16679941 3.09356693 -2.17430059 3 P 0 ;0,4=18,6=0.000000
L 3.09356693 -2.17430059 3.08889911 -2.18329862 3 P 0 ;0,4=18,6=0.000000
L 3.08889911 -2.18329862 3.0853998 -2.19530157 3 P 0 ;0,4=18,6=0.000000
L 3.0853998 -2.19530157 3.08423346 -2.20880138 3 P 0 ;0,4=18,6=0.000000
L 3.08423346 -2.20880138 3.0853998 -2.22230128 3 P 0 ;0,4=18,6=0.000000
L 3.0853998 -2.22230128 3.08889911 -2.23430148 3 P 0 ;0,4=18,6=0.000000
L 3.08889911 -2.23430148 3.09356693 -2.24330226 3 P 0 ;0,4=18,6=0.000000
L 3.09356693 -2.24330226 3.10056545 -2.25080069 3 P 0 ;0,4=18,6=0.000000
L 3.10056545 -2.25080069 3.10989892 -2.2538 3 P 0 ;0,4=18,6=0.000000
L 3.10989892 -2.2538 3.11923238 -2.25080069 3 P 0 ;0,4=18,6=0.000000
L 3.11923238 -2.25080069 3.12623297 -2.24330226 3 P 0 ;0,4=18,6=0.000000
L 3.12623297 -2.24330226 3.13090079 -2.23430148 3 P 0 ;0,4=18,6=0.000000
L 3.13090079 -2.23430148 3.1344001 -2.22230128 3 P 0 ;0,4=18,6=0.000000
L 3.1344001 -2.22230128 3.13556644 -2.20880138 3 P 0 ;0,4=18,6=0.000000
L 3.13556644 -2.20880138 3.1344001 -2.19530157 3 P 0 ;0,4=18,6=0.000000
L 3.1344001 -2.19530157 3.13090079 -2.18329862 3 P 0 ;0,4=18,6=0.000000
L 3.13090079 -2.18329862 3.12623297 -2.17430059 3 P 0 ;0,4=18,6=0.000000
L 3.12623297 -2.17430059 3.11923238 -2.16679941 3 P 0 ;0,4=18,6=0.000000
L 3.11923238 -2.16679941 3.10989892 -2.1638 3 P 0 ;0,4=18,6=0.000000
L 0.0825 0.8825 0.0825 0.8825 9 P 0 ;1
L 0.0825 0.9325 0.0825 0.9325 9 P 0 ;1
L 0.0825 4.8325 0.0825 4.8325 9 P 0 ;1
L 0.0825 4.8825 0.0825 4.8825 9 P 0 ;1
L 0.0825 4.9325 0.0825 4.9325 9 P 0 ;1
L 0.1325 0.1325 0.1325 0.1325 9 P 0 ;1
L 0.1325 0.1825 0.1325 0.1825 9 P 0 ;1
L 0.1325 0.2325 0.1325 0.2325 9 P 0 ;1
L 0.1325 0.2825 0.1325 0.2825 9 P 0 ;1
L 0.1325 1.0325 0.1325 1.0325 9 P 0 ;1
L 0.1325 1.0825 0.1325 1.0825 9 P 0 ;1
L 0.1325 1.1325 0.1325 1.1325 9 P 0 ;1
L 0.1325 1.1825 0.1325 1.1825 9 P 0 ;1
L 0.1325 1.2325 0.1325 1.2325 9 P 0 ;1
L 0.1325 4.7825 0.1325 4.7825 9 P 0 ;1
L 0.1325 5.5325 0.1325 5.5325 9 P 0 ;1
L 0.1325 5.5825 0.1325 5.5825 9 P 0 ;1
L 0.1325 5.6325 0.1325 5.6325 9 P 0 ;1
L 0.1325 5.6825 0.1325 5.6825 9 P 0 ;1
L 0.1825 0.1325 0.1825 0.1325 9 P 0 ;1
L 0.1825 0.1825 0.1825 0.1825 9 P 0 ;1
L 0.1825 0.2325 0.1825 0.2325 9 P 0 ;1
L 0.1825 0.2825 0.1825 0.2825 9 P 0 ;1
L 0.1825 1.0825 0.1825 1.0825 9 P 0 ;1
L 0.1825 1.1325 0.1825 1.1325 9 P 0 ;1
L 0.1825 1.1825 0.1825 1.1825 9 P 0 ;1
L 0.1825 1.2325 0.1825 1.2325 9 P 0 ;1
L 0.1825 5.5325 0.1825 5.5325 9 P 0 ;1
L 0.1825 5.5825 0.1825 5.5825 9 P 0 ;1
L 0.1825 5.6325 0.1825 5.6325 9 P 0 ;1
L 0.1825 5.6825 0.1825 5.6825 9 P 0 ;1
L 0.2325 0.1325 0.2325 0.1325 9 P 0 ;1
L 0.2325 0.1825 0.2325 0.1825 9 P 0 ;1
L 0.2325 0.2325 0.2325 0.2325 9 P 0 ;1
L 0.2325 0.2825 0.2325 0.2825 9 P 0 ;1
L 0.2325 1.0825 0.2325 1.0825 9 P 0 ;1
L 0.2325 1.1325 0.2325 1.1325 9 P 0 ;1
L 0.2325 1.1825 0.2325 1.1825 9 P 0 ;1
L 0.2325 1.2325 0.2325 1.2325 9 P 0 ;1
L 0.2325 5.5325 0.2325 5.5325 9 P 0 ;1
L 0.2325 5.5825 0.2325 5.5825 9 P 0 ;1
L 0.2325 5.6325 0.2325 5.6325 9 P 0 ;1
L 0.2325 5.6825 0.2325 5.6825 9 P 0 ;1
L 0.2825 0.1325 0.2825 0.1325 9 P 0 ;1
L 0.2825 0.1825 0.2825 0.1825 9 P 0 ;1
L 0.2825 0.2325 0.2825 0.2325 9 P 0 ;1
L 0.2825 0.2825 0.2825 0.2825 9 P 0 ;1
L 0.2825 1.0825 0.2825 1.0825 9 P 0 ;1
L 0.2825 1.1325 0.2825 1.1325 9 P 0 ;1
L 0.2825 1.1825 0.2825 1.1825 9 P 0 ;1
L 0.2825 1.2325 0.2825 1.2325 9 P 0 ;1
L 0.2825 5.5325 0.2825 5.5325 9 P 0 ;1
L 0.2825 5.5825 0.2825 5.5825 9 P 0 ;1
L 0.2825 5.6325 0.2825 5.6325 9 P 0 ;1
L 0.2825 5.6825 0.2825 5.6825 9 P 0 ;1
L 0.3325 0.1325 0.3325 0.1325 9 P 0 ;1
L 0.3325 0.1825 0.3325 0.1825 9 P 0 ;1
L 0.3325 0.2325 0.3325 0.2325 9 P 0 ;1
L 0.3325 0.2825 0.3325 0.2825 9 P 0 ;1
L 0.3325 0.3325 0.3325 0.3325 9 P 0 ;1
L 0.3325 1.0325 0.3325 1.0325 9 P 0 ;1
L 0.3325 1.0825 0.3325 1.0825 9 P 0 ;1
L 0.3325 1.1325 0.3325 1.1325 9 P 0 ;1
L 0.3325 1.1825 0.3325 1.1825 9 P 0 ;1
L 0.3325 1.2325 0.3325 1.2325 9 P 0 ;1
L 0.3325 4.7325 0.3325 4.7325 9 P 0 ;1
L 0.3325 4.7825 0.3325 4.7825 9 P 0 ;1
L 0.3325 4.9325 0.3325 4.9325 9 P 0 ;1
L 0.3325 5.4825 0.3325 5.4825 9 P 0 ;1
L 0.3325 5.5325 0.3325 5.5325 9 P 0 ;1
L 0.3325 5.5825 0.3325 5.5825 9 P 0 ;1
L 0.3325 5.6325 0.3325 5.6325 9 P 0 ;1
L 0.3325 5.6825 0.3325 5.6825 9 P 0 ;1
L 0.3325 5.7325 0.3325 5.7325 9 P 0 ;1
L 0.3325 5.7825 0.3325 5.7825 9 P 0 ;1
L 0.3325 5.8825 0.3325 5.8825 9 P 0 ;1
L 0.3825 0.1325 0.3825 0.1325 9 P 0 ;1
L 0.3825 0.1825 0.3825 0.1825 9 P 0 ;1
L 0.3825 0.2325 0.3825 0.2325 9 P 0 ;1
L 0.3825 0.2825 0.3825 0.2825 9 P 0 ;1
L 0.3825 0.3325 0.3825 0.3325 9 P 0 ;1
L 0.3825 0.3825 0.3825 0.3825 9 P 0 ;1
L 0.3825 0.4325 0.3825 0.4325 9 P 0 ;1
L 0.3825 0.4825 0.3825 0.4825 9 P 0 ;1
L 0.3825 0.5325 0.3825 0.5325 9 P 0 ;1
L 0.3825 0.8325 0.3825 0.8325 9 P 0 ;1
L 0.3825 0.8825 0.3825 0.8825 9 P 0 ;1
L 0.3825 0.9325 0.3825 0.9325 9 P 0 ;1
L 0.3825 0.9825 0.3825 0.9825 9 P 0 ;1
L 0.3825 1.0325 0.3825 1.0325 9 P 0 ;1
L 0.3825 1.0825 0.3825 1.0825 9 P 0 ;1
L 0.3825 1.1325 0.3825 1.1325 9 P 0 ;1
L 0.3825 1.1825 0.3825 1.1825 9 P 0 ;1
L 0.3825 1.2325 0.3825 1.2325 9 P 0 ;1
L 0.3825 1.2825 0.3825 1.2825 9 P 0 ;1
L 0.3825 4.7325 0.3825 4.7325 9 P 0 ;1
L 0.3825 4.7825 0.3825 4.7825 9 P 0 ;1
L 0.3825 4.8325 0.3825 4.8325 9 P 0 ;1
L 0.3825 4.8825 0.3825 4.8825 9 P 0 ;1
L 0.3825 4.9325 0.3825 4.9325 9 P 0 ;1
L 0.3825 4.9825 0.3825 4.9825 9 P 0 ;1
L 0.3825 5.2825 0.3825 5.2825 9 P 0 ;1
L 0.3825 5.3325 0.3825 5.3325 9 P 0 ;1
L 0.3825 5.3825 0.3825 5.3825 9 P 0 ;1
L 0.3825 5.4325 0.3825 5.4325 9 P 0 ;1
L 0.3825 5.4825 0.3825 5.4825 9 P 0 ;1
L 0.3825 5.5325 0.3825 5.5325 9 P 0 ;1
L 0.3825 5.5825 0.3825 5.5825 9 P 0 ;1
L 0.3825 5.6325 0.3825 5.6325 9 P 0 ;1
L 0.3825 5.6825 0.3825 5.6825 9 P 0 ;1
L 0.3825 5.7325 0.3825 5.7325 9 P 0 ;1
L 0.3825 5.7825 0.3825 5.7825 9 P 0 ;1
L 0.3825 5.8325 0.3825 5.8325 9 P 0 ;1
L 0.3825 5.8825 0.3825 5.8825 9 P 0 ;1
L 0.4325 0.1325 0.4325 0.1325 9 P 0 ;1
L 0.4325 0.1825 0.4325 0.1825 9 P 0 ;1
L 0.4325 0.2325 0.4325 0.2325 9 P 0 ;1
L 0.4325 0.2825 0.4325 0.2825 9 P 0 ;1
L 0.4325 0.3325 0.4325 0.3325 9 P 0 ;1
L 0.4325 0.3825 0.4325 0.3825 9 P 0 ;1
L 0.4325 0.4325 0.4325 0.4325 9 P 0 ;1
L 0.4325 0.4825 0.4325 0.4825 9 P 0 ;1
L 0.4325 0.5325 0.4325 0.5325 9 P 0 ;1
L 0.4325 0.5825 0.4325 0.5825 9 P 0 ;1
L 0.4325 0.6325 0.4325 0.6325 9 P 0 ;1
L 0.4325 0.6825 0.4325 0.6825 9 P 0 ;1
L 0.4325 0.7325 0.4325 0.7325 9 P 0 ;1
L 0.4325 0.7825 0.4325 0.7825 9 P 0 ;1
L 0.4325 0.8325 0.4325 0.8325 9 P 0 ;1
L 0.4325 0.8825 0.4325 0.8825 9 P 0 ;1
L 0.4325 0.9325 0.4325 0.9325 9 P 0 ;1
L 0.4325 0.9825 0.4325 0.9825 9 P 0 ;1
L 0.4325 1.0325 0.4325 1.0325 9 P 0 ;1
L 0.4325 1.0825 0.4325 1.0825 9 P 0 ;1
L 0.4325 1.1325 0.4325 1.1325 9 P 0 ;1
L 0.4325 1.1825 0.4325 1.1825 9 P 0 ;1
L 0.4325 1.2325 0.4325 1.2325 9 P 0 ;1
L 0.4325 1.2825 0.4325 1.2825 9 P 0 ;1
L 0.4325 1.3325 0.4325 1.3325 9 P 0 ;1
L 0.4325 1.7325 0.4325 1.7325 9 P 0 ;1
L 0.4325 1.7825 0.4325 1.7825 9 P 0 ;1
L 0.4325 1.8825 0.4325 1.8825 9 P 0 ;1
L 0.4325 4.6825 0.4325 4.6825 9 P 0 ;1
L 0.4325 4.7325 0.4325 4.7325 9 P 0 ;1
L 0.4325 4.7825 0.4325 4.7825 9 P 0 ;1
L 0.4325 4.8325 0.4325 4.8325 9 P 0 ;1
L 0.4325 4.8825 0.4325 4.8825 9 P 0 ;1
L 0.4325 4.9325 0.4325 4.9325 9 P 0 ;1
L 0.4325 4.9825 0.4325 4.9825 9 P 0 ;1
L 0.4325 5.0325 0.4325 5.0325 9 P 0 ;1
L 0.4325 5.0825 0.4325 5.0825 9 P 0 ;1
L 0.4325 5.1325 0.4325 5.1325 9 P 0 ;1
L 0.4325 5.1825 0.4325 5.1825 9 P 0 ;1
L 0.4325 5.2325 0.4325 5.2325 9 P 0 ;1
L 0.4325 5.2825 0.4325 5.2825 9 P 0 ;1
L 0.4325 5.3325 0.4325 5.3325 9 P 0 ;1
L 0.4325 5.3825 0.4325 5.3825 9 P 0 ;1
L 0.4325 5.4325 0.4325 5.4325 9 P 0 ;1
L 0.4325 5.4825 0.4325 5.4825 9 P 0 ;1
L 0.4325 5.5325 0.4325 5.5325 9 P 0 ;1
L 0.4325 5.5825 0.4325 5.5825 9 P 0 ;1
L 0.4325 5.6325 0.4325 5.6325 9 P 0 ;1
L 0.4325 5.6825 0.4325 5.6825 9 P 0 ;1
L 0.4325 5.7325 0.4325 5.7325 9 P 0 ;1
L 0.4325 5.7825 0.4325 5.7825 9 P 0 ;1
L 0.4325 5.8325 0.4325 5.8325 9 P 0 ;1
L 0.4825 0.1325 0.4825 0.1325 9 P 0 ;1
L 0.4825 0.1825 0.4825 0.1825 9 P 0 ;1
L 0.4825 0.2325 0.4825 0.2325 9 P 0 ;1
L 0.4825 0.2825 0.4825 0.2825 9 P 0 ;1
L 0.4825 0.3325 0.4825 0.3325 9 P 0 ;1
L 0.4825 0.3825 0.4825 0.3825 9 P 0 ;1
L 0.4825 0.4325 0.4825 0.4325 9 P 0 ;1
L 0.4825 0.4825 0.4825 0.4825 9 P 0 ;1
L 0.4825 0.5325 0.4825 0.5325 9 P 0 ;1
L 0.4825 0.5825 0.4825 0.5825 9 P 0 ;1
L 0.4825 0.6325 0.4825 0.6325 9 P 0 ;1
L 0.4825 0.6825 0.4825 0.6825 9 P 0 ;1
L 0.4825 0.7325 0.4825 0.7325 9 P 0 ;1
L 0.4825 0.7825 0.4825 0.7825 9 P 0 ;1
L 0.4825 0.8325 0.4825 0.8325 9 P 0 ;1
L 0.4825 0.8825 0.4825 0.8825 9 P 0 ;1
L 0.4825 0.9325 0.4825 0.9325 9 P 0 ;1
L 0.4825 0.9825 0.4825 0.9825 9 P 0 ;1
L 0.4825 1.0325 0.4825 1.0325 9 P 0 ;1
L 0.4825 1.0825 0.4825 1.0825 9 P 0 ;1
L 0.4825 1.1325 0.4825 1.1325 9 P 0 ;1
L 0.4825 1.1825 0.4825 1.1825 9 P 0 ;1
L 0.4825 1.2325 0.4825 1.2325 9 P 0 ;1
L 0.4825 1.2825 0.4825 1.2825 9 P 0 ;1
L 0.4825 1.3325 0.4825 1.3325 9 P 0 ;1
L 0.4825 1.3825 0.4825 1.3825 9 P 0 ;1
L 0.4825 1.4325 0.4825 1.4325 9 P 0 ;1
L 0.4825 1.4825 0.4825 1.4825 9 P 0 ;1
L 0.4825 1.5325 0.4825 1.5325 9 P 0 ;1
L 0.4825 1.5825 0.4825 1.5825 9 P 0 ;1
L 0.4825 1.6325 0.4825 1.6325 9 P 0 ;1
L 0.4825 1.6825 0.4825 1.6825 9 P 0 ;1
L 0.4825 1.7325 0.4825 1.7325 9 P 0 ;1
L 0.4825 1.7825 0.4825 1.7825 9 P 0 ;1
L 0.4825 1.8325 0.4825 1.8325 9 P 0 ;1
L 0.4825 1.8825 0.4825 1.8825 9 P 0 ;1
L 0.4825 1.9325 0.4825 1.9325 9 P 0 ;1
L 0.4825 1.9825 0.4825 1.9825 9 P 0 ;1
L 0.4825 2.0325 0.4825 2.0325 9 P 0 ;1
L 0.4825 2.3825 0.4825 2.3825 9 P 0 ;1
L 0.4825 3.5825 0.4825 3.5825 9 P 0 ;1
L 0.4825 3.6325 0.4825 3.6325 9 P 0 ;1
L 0.4825 4.1325 0.4825 4.1325 9 P 0 ;1
L 0.4825 4.1825 0.4825 4.1825 9 P 0 ;1
L 0.4825 4.6825 0.4825 4.6825 9 P 0 ;1
L 0.4825 4.7325 0.4825 4.7325 9 P 0 ;1
L 0.4825 4.7825 0.4825 4.7825 9 P 0 ;1
L 0.4825 4.8325 0.4825 4.8325 9 P 0 ;1
L 0.4825 4.8825 0.4825 4.8825 9 P 0 ;1
L 0.4825 4.9325 0.4825 4.9325 9 P 0 ;1
L 0.4825 4.9825 0.4825 4.9825 9 P 0 ;1
L 0.4825 5.0325 0.4825 5.0325 9 P 0 ;1
L 0.4825 5.0825 0.4825 5.0825 9 P 0 ;1
L 0.4825 5.1325 0.4825 5.1325 9 P 0 ;1
L 0.4825 5.1825 0.4825 5.1825 9 P 0 ;1
L 0.4825 5.2325 0.4825 5.2325 9 P 0 ;1
L 0.4825 5.2825 0.4825 5.2825 9 P 0 ;1
L 0.4825 5.3325 0.4825 5.3325 9 P 0 ;1
L 0.4825 5.3825 0.4825 5.3825 9 P 0 ;1
L 0.4825 5.4325 0.4825 5.4325 9 P 0 ;1
L 0.4825 5.4825 0.4825 5.4825 9 P 0 ;1
L 0.4825 5.5325 0.4825 5.5325 9 P 0 ;1
L 0.4825 5.5825 0.4825 5.5825 9 P 0 ;1
L 0.4825 5.6325 0.4825 5.6325 9 P 0 ;1
L 0.4825 5.6825 0.4825 5.6825 9 P 0 ;1
L 0.4825 5.7325 0.4825 5.7325 9 P 0 ;1
L 0.4825 5.7825 0.4825 5.7825 9 P 0 ;1
L 0.5325 0.1325 0.5325 0.1325 9 P 0 ;1
L 0.5325 0.1825 0.5325 0.1825 9 P 0 ;1
L 0.5325 0.2325 0.5325 0.2325 9 P 0 ;1
L 0.5325 0.3825 0.5325 0.3825 9 P 0 ;1
L 0.5325 0.4325 0.5325 0.4325 9 P 0 ;1
L 0.5325 0.4825 0.5325 0.4825 9 P 0 ;1
L 0.5325 0.5325 0.5325 0.5325 9 P 0 ;1
L 0.5325 0.5825 0.5325 0.5825 9 P 0 ;1
L 0.5325 0.6325 0.5325 0.6325 9 P 0 ;1
L 0.5325 0.6825 0.5325 0.6825 9 P 0 ;1
L 0.5325 0.7325 0.5325 0.7325 9 P 0 ;1
L 0.5325 0.7825 0.5325 0.7825 9 P 0 ;1
L 0.5325 0.8325 0.5325 0.8325 9 P 0 ;1
L 0.5325 0.8825 0.5325 0.8825 9 P 0 ;1
L 0.5325 0.9325 0.5325 0.9325 9 P 0 ;1
L 0.5325 0.9825 0.5325 0.9825 9 P 0 ;1
L 0.5325 1.0325 0.5325 1.0325 9 P 0 ;1
L 0.5325 1.0825 0.5325 1.0825 9 P 0 ;1
L 0.5325 1.1325 0.5325 1.1325 9 P 0 ;1
L 0.5325 1.1825 0.5325 1.1825 9 P 0 ;1
L 0.5325 1.2325 0.5325 1.2325 9 P 0 ;1
L 0.5325 1.2825 0.5325 1.2825 9 P 0 ;1
L 0.5325 1.3325 0.5325 1.3325 9 P 0 ;1
L 0.5325 1.3825 0.5325 1.3825 9 P 0 ;1
L 0.5325 1.4325 0.5325 1.4325 9 P 0 ;1
L 0.5325 1.4825 0.5325 1.4825 9 P 0 ;1
L 0.5325 1.5325 0.5325 1.5325 9 P 0 ;1
L 0.5325 1.5825 0.5325 1.5825 9 P 0 ;1
L 0.5325 1.6325 0.5325 1.6325 9 P 0 ;1
L 0.5325 1.6825 0.5325 1.6825 9 P 0 ;1
L 0.5325 1.7325 0.5325 1.7325 9 P 0 ;1
L 0.5325 1.7825 0.5325 1.7825 9 P 0 ;1
L 0.5325 1.8325 0.5325 1.8325 9 P 0 ;1
L 0.5325 1.8825 0.5325 1.8825 9 P 0 ;1
L 0.5325 1.9325 0.5325 1.9325 9 P 0 ;1
L 0.5325 1.9825 0.5325 1.9825 9 P 0 ;1
L 0.5325 2.0325 0.5325 2.0325 9 P 0 ;1
L 0.5325 2.0825 0.5325 2.0825 9 P 0 ;1
L 0.5325 2.3325 0.5325 2.3325 9 P 0 ;1
L 0.5325 2.3825 0.5325 2.3825 9 P 0 ;1
L 0.5325 2.4325 0.5325 2.4325 9 P 0 ;1
L 0.5325 3.5825 0.5325 3.5825 9 P 0 ;1
L 0.5325 4.0825 0.5325 4.0825 9 P 0 ;1
L 0.5325 4.1325 0.5325 4.1325 9 P 0 ;1
L 0.5325 4.1825 0.5325 4.1825 9 P 0 ;1
L 0.5325 4.2325 0.5325 4.2325 9 P 0 ;1
L 0.5325 4.6825 0.5325 4.6825 9 P 0 ;1
L 0.5325 4.7325 0.5325 4.7325 9 P 0 ;1
L 0.5325 4.7825 0.5325 4.7825 9 P 0 ;1
L 0.5325 4.8325 0.5325 4.8325 9 P 0 ;1
L 0.5325 4.8825 0.5325 4.8825 9 P 0 ;1
L 0.5325 4.9325 0.5325 4.9325 9 P 0 ;1
L 0.5325 4.9825 0.5325 4.9825 9 P 0 ;1
L 0.5325 5.0325 0.5325 5.0325 9 P 0 ;1
L 0.5325 5.0825 0.5325 5.0825 9 P 0 ;1
L 0.5325 5.1325 0.5325 5.1325 9 P 0 ;1
L 0.5325 5.1825 0.5325 5.1825 9 P 0 ;1
L 0.5325 5.2325 0.5325 5.2325 9 P 0 ;1
L 0.5325 5.2825 0.5325 5.2825 9 P 0 ;1
L 0.5325 5.3325 0.5325 5.3325 9 P 0 ;1
L 0.5325 5.3825 0.5325 5.3825 9 P 0 ;1
L 0.5325 5.4325 0.5325 5.4325 9 P 0 ;1
L 0.5325 5.4825 0.5325 5.4825 9 P 0 ;1
L 0.5325 5.6825 0.5325 5.6825 9 P 0 ;1
L 0.5325 5.7325 0.5325 5.7325 9 P 0 ;1
L 0.5325 5.7825 0.5325 5.7825 9 P 0 ;1
L 0.5325 5.8325 0.5325 5.8325 9 P 0 ;1
L 0.5825 0.1325 0.5825 0.1325 9 P 0 ;1
L 0.5825 0.4325 0.5825 0.4325 9 P 0 ;1
L 0.5825 0.4825 0.5825 0.4825 9 P 0 ;1
L 0.5825 0.5325 0.5825 0.5325 9 P 0 ;1
L 0.5825 0.5825 0.5825 0.5825 9 P 0 ;1
L 0.5825 0.6325 0.5825 0.6325 9 P 0 ;1
L 0.5825 0.6825 0.5825 0.6825 9 P 0 ;1
L 0.5825 0.7325 0.5825 0.7325 9 P 0 ;1
L 0.5825 0.7825 0.5825 0.7825 9 P 0 ;1
L 0.5825 0.8325 0.5825 0.8325 9 P 0 ;1
L 0.5825 0.8825 0.5825 0.8825 9 P 0 ;1
L 0.5825 0.9325 0.5825 0.9325 9 P 0 ;1
L 0.5825 0.9825 0.5825 0.9825 9 P 0 ;1
L 0.5825 1.0325 0.5825 1.0325 9 P 0 ;1
L 0.5825 1.0825 0.5825 1.0825 9 P 0 ;1
L 0.5825 1.1325 0.5825 1.1325 9 P 0 ;1
L 0.5825 1.1825 0.5825 1.1825 9 P 0 ;1
L 0.5825 1.2325 0.5825 1.2325 9 P 0 ;1
L 0.5825 1.2825 0.5825 1.2825 9 P 0 ;1
L 0.5825 1.3325 0.5825 1.3325 9 P 0 ;1
L 0.5825 1.3825 0.5825 1.3825 9 P 0 ;1
L 0.5825 1.4325 0.5825 1.4325 9 P 0 ;1
L 0.5825 1.4825 0.5825 1.4825 9 P 0 ;1
L 0.5825 1.5325 0.5825 1.5325 9 P 0 ;1
L 0.5825 1.5825 0.5825 1.5825 9 P 0 ;1
L 0.5825 1.7325 0.5825 1.7325 9 P 0 ;1
L 0.5825 1.7825 0.5825 1.7825 9 P 0 ;1
L 0.5825 1.9825 0.5825 1.9825 9 P 0 ;1
L 0.5825 2.0325 0.5825 2.0325 9 P 0 ;1
L 0.5825 2.0825 0.5825 2.0825 9 P 0 ;1
L 0.5825 2.3325 0.5825 2.3325 9 P 0 ;1
L 0.5825 3.5325 0.5825 3.5325 9 P 0 ;1
L 0.5825 4.0325 0.5825 4.0325 9 P 0 ;1
L 0.5825 4.0825 0.5825 4.0825 9 P 0 ;1
L 0.5825 4.1325 0.5825 4.1325 9 P 0 ;1
L 0.5825 4.1825 0.5825 4.1825 9 P 0 ;1
L 0.5825 4.2325 0.5825 4.2325 9 P 0 ;1
L 0.5825 4.6825 0.5825 4.6825 9 P 0 ;1
L 0.5825 4.7325 0.5825 4.7325 9 P 0 ;1
L 0.5825 4.7825 0.5825 4.7825 9 P 0 ;1
L 0.5825 4.8325 0.5825 4.8325 9 P 0 ;1
L 0.5825 4.8825 0.5825 4.8825 9 P 0 ;1
L 0.5825 4.9325 0.5825 4.9325 9 P 0 ;1
L 0.5825 4.9825 0.5825 4.9825 9 P 0 ;1
L 0.5825 5.0325 0.5825 5.0325 9 P 0 ;1
L 0.5825 5.0825 0.5825 5.0825 9 P 0 ;1
L 0.5825 5.1325 0.5825 5.1325 9 P 0 ;1
L 0.5825 5.1825 0.5825 5.1825 9 P 0 ;1
L 0.5825 5.2325 0.5825 5.2325 9 P 0 ;1
L 0.5825 5.2825 0.5825 5.2825 9 P 0 ;1
L 0.5825 5.3325 0.5825 5.3325 9 P 0 ;1
L 0.5825 5.3825 0.5825 5.3825 9 P 0 ;1
L 0.5825 5.4325 0.5825 5.4325 9 P 0 ;1
L 0.5825 5.4825 0.5825 5.4825 9 P 0 ;1
L 0.5825 5.6825 0.5825 5.6825 9 P 0 ;1
L 0.5825 5.7325 0.5825 5.7325 9 P 0 ;1
L 0.5825 5.7825 0.5825 5.7825 9 P 0 ;1
L 0.5825 5.8325 0.5825 5.8325 9 P 0 ;1
L 0.5825 5.8825 0.5825 5.8825 9 P 0 ;1
L 0.6325 0.1325 0.6325 0.1325 9 P 0 ;1
L 0.6325 0.4325 0.6325 0.4325 9 P 0 ;1
L 0.6325 0.4825 0.6325 0.4825 9 P 0 ;1
L 0.6325 0.5325 0.6325 0.5325 9 P 0 ;1
L 0.6325 0.5825 0.6325 0.5825 9 P 0 ;1
L 0.6325 0.6325 0.6325 0.6325 9 P 0 ;1
L 0.6325 0.6825 0.6325 0.6825 9 P 0 ;1
L 0.6325 0.7325 0.6325 0.7325 9 P 0 ;1
L 0.6325 0.7825 0.6325 0.7825 9 P 0 ;1
L 0.6325 0.8325 0.6325 0.8325 9 P 0 ;1
L 0.6325 0.8825 0.6325 0.8825 9 P 0 ;1
L 0.6325 0.9325 0.6325 0.9325 9 P 0 ;1
L 0.6325 0.9825 0.6325 0.9825 9 P 0 ;1
L 0.6325 1.0325 0.6325 1.0325 9 P 0 ;1
L 0.6325 1.0825 0.6325 1.0825 9 P 0 ;1
L 0.6325 1.1325 0.6325 1.1325 9 P 0 ;1
L 0.6325 1.1825 0.6325 1.1825 9 P 0 ;1
L 0.6325 1.2325 0.6325 1.2325 9 P 0 ;1
L 0.6325 1.2825 0.6325 1.2825 9 P 0 ;1
L 0.6325 1.3325 0.6325 1.3325 9 P 0 ;1
L 0.6325 1.3825 0.6325 1.3825 9 P 0 ;1
L 0.6325 3.1325 0.6325 3.1325 9 P 0 ;1
L 0.6325 3.1825 0.6325 3.1825 9 P 0 ;1
L 0.6325 3.2325 0.6325 3.2325 9 P 0 ;1
L 0.6325 3.8825 0.6325 3.8825 9 P 0 ;1
L 0.6325 3.9325 0.6325 3.9325 9 P 0 ;1
L 0.6325 3.9825 0.6325 3.9825 9 P 0 ;1
L 0.6325 4.0325 0.6325 4.0325 9 P 0 ;1
L 0.6325 4.0825 0.6325 4.0825 9 P 0 ;1
L 0.6325 4.1325 0.6325 4.1325 9 P 0 ;1
L 0.6325 4.1825 0.6325 4.1825 9 P 0 ;1
L 0.6325 4.2325 0.6325 4.2325 9 P 0 ;1
L 0.6325 4.2825 0.6325 4.2825 9 P 0 ;1
L 0.6325 4.6825 0.6325 4.6825 9 P 0 ;1
L 0.6325 4.7325 0.6325 4.7325 9 P 0 ;1
L 0.6325 4.7825 0.6325 4.7825 9 P 0 ;1
L 0.6325 4.8325 0.6325 4.8325 9 P 0 ;1
L 0.6325 4.8825 0.6325 4.8825 9 P 0 ;1
L 0.6325 4.9325 0.6325 4.9325 9 P 0 ;1
L 0.6325 4.9825 0.6325 4.9825 9 P 0 ;1
L 0.6325 5.0325 0.6325 5.0325 9 P 0 ;1
L 0.6325 5.0825 0.6325 5.0825 9 P 0 ;1
L 0.6325 5.1325 0.6325 5.1325 9 P 0 ;1
L 0.6325 5.1825 0.6325 5.1825 9 P 0 ;1
L 0.6325 5.4325 0.6325 5.4325 9 P 0 ;1
L 0.6325 5.4825 0.6325 5.4825 9 P 0 ;1
L 0.6325 5.6825 0.6325 5.6825 9 P 0 ;1
L 0.6325 5.7325 0.6325 5.7325 9 P 0 ;1
L 0.6325 5.7825 0.6325 5.7825 9 P 0 ;1
L 0.6325 5.8325 0.6325 5.8325 9 P 0 ;1
L 0.6325 5.8825 0.6325 5.8825 9 P 0 ;1
L 0.6825 0.1325 0.6825 0.1325 9 P 0 ;1
L 0.6825 0.4325 0.6825 0.4325 9 P 0 ;1
L 0.6825 0.4825 0.6825 0.4825 9 P 0 ;1
L 0.6825 0.5325 0.6825 0.5325 9 P 0 ;1
L 0.6825 0.5825 0.6825 0.5825 9 P 0 ;1
L 0.6825 0.6325 0.6825 0.6325 9 P 0 ;1
L 0.6825 0.6825 0.6825 0.6825 9 P 0 ;1
L 0.6825 0.7325 0.6825 0.7325 9 P 0 ;1
L 0.6825 0.7825 0.6825 0.7825 9 P 0 ;1
L 0.6825 0.8325 0.6825 0.8325 9 P 0 ;1
L 0.6825 0.8825 0.6825 0.8825 9 P 0 ;1
L 0.6825 0.9325 0.6825 0.9325 9 P 0 ;1
L 0.6825 0.9825 0.6825 0.9825 9 P 0 ;1
L 0.6825 1.0325 0.6825 1.0325 9 P 0 ;1
L 0.6825 1.0825 0.6825 1.0825 9 P 0 ;1
L 0.6825 1.1325 0.6825 1.1325 9 P 0 ;1
L 0.6825 1.1825 0.6825 1.1825 9 P 0 ;1
L 0.6825 1.2325 0.6825 1.2325 9 P 0 ;1
L 0.6825 1.2825 0.6825 1.2825 9 P 0 ;1
L 0.6825 1.3325 0.6825 1.3325 9 P 0 ;1
L 0.6825 2.9825 0.6825 2.9825 9 P 0 ;1
L 0.6825 3.0325 0.6825 3.0325 9 P 0 ;1
L 0.6825 3.0825 0.6825 3.0825 9 P 0 ;1
L 0.6825 3.1325 0.6825 3.1325 9 P 0 ;1
L 0.6825 3.1825 0.6825 3.1825 9 P 0 ;1
L 0.6825 3.2325 0.6825 3.2325 9 P 0 ;1
L 0.6825 3.8325 0.6825 3.8325 9 P 0 ;1
L 0.6825 3.8825 0.6825 3.8825 9 P 0 ;1
L 0.6825 3.9325 0.6825 3.9325 9 P 0 ;1
L 0.6825 3.9825 0.6825 3.9825 9 P 0 ;1
L 0.6825 4.0325 0.6825 4.0325 9 P 0 ;1
L 0.6825 4.0825 0.6825 4.0825 9 P 0 ;1
L 0.6825 4.1325 0.6825 4.1325 9 P 0 ;1
L 0.6825 4.1825 0.6825 4.1825 9 P 0 ;1
L 0.6825 4.2325 0.6825 4.2325 9 P 0 ;1
L 0.6825 4.2825 0.6825 4.2825 9 P 0 ;1
L 0.6825 4.6325 0.6825 4.6325 9 P 0 ;1
L 0.6825 4.6825 0.6825 4.6825 9 P 0 ;1
L 0.6825 4.7325 0.6825 4.7325 9 P 0 ;1
L 0.6825 4.7825 0.6825 4.7825 9 P 0 ;1
L 0.6825 4.8325 0.6825 4.8325 9 P 0 ;1
L 0.6825 4.8825 0.6825 4.8825 9 P 0 ;1
L 0.6825 5.0325 0.6825 5.0325 9 P 0 ;1
L 0.6825 5.0825 0.6825 5.0825 9 P 0 ;1
L 0.6825 5.5325 0.6825 5.5325 9 P 0 ;1
L 0.6825 5.6825 0.6825 5.6825 9 P 0 ;1
L 0.7325 0.1325 0.7325 0.1325 9 P 0 ;1
L 0.7325 0.4325 0.7325 0.4325 9 P 0 ;1
L 0.7325 0.4825 0.7325 0.4825 9 P 0 ;1
L 0.7325 0.5325 0.7325 0.5325 9 P 0 ;1
L 0.7325 0.5825 0.7325 0.5825 9 P 0 ;1
L 0.7325 0.6325 0.7325 0.6325 9 P 0 ;1
L 0.7325 0.6825 0.7325 0.6825 9 P 0 ;1
L 0.7325 0.7325 0.7325 0.7325 9 P 0 ;1
L 0.7325 0.7825 0.7325 0.7825 9 P 0 ;1
L 0.7325 0.8325 0.7325 0.8325 9 P 0 ;1
L 0.7325 0.8825 0.7325 0.8825 9 P 0 ;1
L 0.7325 0.9325 0.7325 0.9325 9 P 0 ;1
L 0.7325 0.9825 0.7325 0.9825 9 P 0 ;1
L 0.7325 1.0325 0.7325 1.0325 9 P 0 ;1
L 0.7325 1.0825 0.7325 1.0825 9 P 0 ;1
L 0.7325 1.1325 0.7325 1.1325 9 P 0 ;1
L 0.7325 1.1825 0.7325 1.1825 9 P 0 ;1
L 0.7325 1.2325 0.7325 1.2325 9 P 0 ;1
L 0.7325 1.6325 0.7325 1.6325 9 P 0 ;1
L 0.7325 1.6825 0.7325 1.6825 9 P 0 ;1
L 0.7325 1.7325 0.7325 1.7325 9 P 0 ;1
L 0.7325 1.7825 0.7325 1.7825 9 P 0 ;1
L 0.7325 1.9825 0.7325 1.9825 9 P 0 ;1
L 0.7325 2.8825 0.7325 2.8825 9 P 0 ;1
L 0.7325 2.9325 0.7325 2.9325 9 P 0 ;1
L 0.7325 2.9825 0.7325 2.9825 9 P 0 ;1
L 0.7325 3.0325 0.7325 3.0325 9 P 0 ;1
L 0.7325 3.0825 0.7325 3.0825 9 P 0 ;1
L 0.7325 3.1325 0.7325 3.1325 9 P 0 ;1
L 0.7325 3.1825 0.7325 3.1825 9 P 0 ;1
L 0.7325 3.7325 0.7325 3.7325 9 P 0 ;1
L 0.7325 3.7825 0.7325 3.7825 9 P 0 ;1
L 0.7325 3.8325 0.7325 3.8325 9 P 0 ;1
L 0.7325 3.8825 0.7325 3.8825 9 P 0 ;1
L 0.7325 3.9325 0.7325 3.9325 9 P 0 ;1
L 0.7325 3.9825 0.7325 3.9825 9 P 0 ;1
L 0.7325 4.0325 0.7325 4.0325 9 P 0 ;1
L 0.7325 4.0825 0.7325 4.0825 9 P 0 ;1
L 0.7325 4.1325 0.7325 4.1325 9 P 0 ;1
L 0.7325 4.1825 0.7325 4.1825 9 P 0 ;1
L 0.7325 4.2325 0.7325 4.2325 9 P 0 ;1
L 0.7325 4.2825 0.7325 4.2825 9 P 0 ;1
L 0.7325 4.6325 0.7325 4.6325 9 P 0 ;1
L 0.7325 4.6825 0.7325 4.6825 9 P 0 ;1
L 0.7325 4.7325 0.7325 4.7325 9 P 0 ;1
L 0.7325 4.7825 0.7325 4.7825 9 P 0 ;1
L 0.7325 4.8325 0.7325 4.8325 9 P 0 ;1
L 0.7325 5.0825 0.7325 5.0825 9 P 0 ;1
L 0.7825 0.1325 0.7825 0.1325 9 P 0 ;1
L 0.7825 0.1825 0.7825 0.1825 9 P 0 ;1
L 0.7825 0.3825 0.7825 0.3825 9 P 0 ;1
L 0.7825 0.4325 0.7825 0.4325 9 P 0 ;1
L 0.7825 0.4825 0.7825 0.4825 9 P 0 ;1
L 0.7825 0.5325 0.7825 0.5325 9 P 0 ;1
L 0.7825 0.5825 0.7825 0.5825 9 P 0 ;1
L 0.7825 0.6325 0.7825 0.6325 9 P 0 ;1
L 0.7825 0.6825 0.7825 0.6825 9 P 0 ;1
L 0.7825 0.7325 0.7825 0.7325 9 P 0 ;1
L 0.7825 0.7825 0.7825 0.7825 9 P 0 ;1
L 0.7825 0.8325 0.7825 0.8325 9 P 0 ;1
L 0.7825 0.8825 0.7825 0.8825 9 P 0 ;1
L 0.7825 0.9325 0.7825 0.9325 9 P 0 ;1
L 0.7825 0.9825 0.7825 0.9825 9 P 0 ;1
L 0.7825 1.0325 0.7825 1.0325 9 P 0 ;1
L 0.7825 1.0825 0.7825 1.0825 9 P 0 ;1
L 0.7825 1.1325 0.7825 1.1325 9 P 0 ;1
L 0.7825 1.1825 0.7825 1.1825 9 P 0 ;1
L 0.7825 1.2325 0.7825 1.2325 9 P 0 ;1
L 0.7825 1.6325 0.7825 1.6325 9 P 0 ;1
L 0.7825 1.6825 0.7825 1.6825 9 P 0 ;1
L 0.7825 1.7325 0.7825 1.7325 9 P 0 ;1
L 0.7825 1.7825 0.7825 1.7825 9 P 0 ;1
L 0.7825 1.8325 0.7825 1.8325 9 P 0 ;1
L 0.7825 1.8825 0.7825 1.8825 9 P 0 ;1
L 0.7825 1.9325 0.7825 1.9325 9 P 0 ;1
L 0.7825 2.8325 0.7825 2.8325 9 P 0 ;1
L 0.7825 2.8825 0.7825 2.8825 9 P 0 ;1
L 0.7825 2.9325 0.7825 2.9325 9 P 0 ;1
L 0.7825 2.9825 0.7825 2.9825 9 P 0 ;1
L 0.7825 3.0325 0.7825 3.0325 9 P 0 ;1
L 0.7825 3.0825 0.7825 3.0825 9 P 0 ;1
L 0.7825 3.1325 0.7825 3.1325 9 P 0 ;1
L 0.7825 3.6825 0.7825 3.6825 9 P 0 ;1
L 0.7825 3.7325 0.7825 3.7325 9 P 0 ;1
L 0.7825 3.7825 0.7825 3.7825 9 P 0 ;1
L 0.7825 3.8325 0.7825 3.8325 9 P 0 ;1
L 0.7825 3.8825 0.7825 3.8825 9 P 0 ;1
L 0.7825 3.9325 0.7825 3.9325 9 P 0 ;1
L 0.7825 3.9825 0.7825 3.9825 9 P 0 ;1
L 0.7825 4.0325 0.7825 4.0325 9 P 0 ;1
L 0.7825 4.0825 0.7825 4.0825 9 P 0 ;1
L 0.7825 4.1325 0.7825 4.1325 9 P 0 ;1
L 0.7825 4.2825 0.7825 4.2825 9 P 0 ;1
L 0.7825 4.6325 0.7825 4.6325 9 P 0 ;1
L 0.7825 4.6825 0.7825 4.6825 9 P 0 ;1
L 0.7825 4.7325 0.7825 4.7325 9 P 0 ;1
L 0.7825 4.7825 0.7825 4.7825 9 P 0 ;1
L 0.7825 4.8325 0.7825 4.8325 9 P 0 ;1
L 0.7825 4.8825 0.7825 4.8825 9 P 0 ;1
L 0.7825 5.0325 0.7825 5.0325 9 P 0 ;1
L 0.7825 5.0825 0.7825 5.0825 9 P 0 ;1
L 0.8325 0.1325 0.8325 0.1325 9 P 0 ;1
L 0.8325 0.1825 0.8325 0.1825 9 P 0 ;1
L 0.8325 0.2325 0.8325 0.2325 9 P 0 ;1
L 0.8325 0.2825 0.8325 0.2825 9 P 0 ;1
L 0.8325 0.3325 0.8325 0.3325 9 P 0 ;1
L 0.8325 0.3825 0.8325 0.3825 9 P 0 ;1
L 0.8325 0.4325 0.8325 0.4325 9 P 0 ;1
L 0.8325 0.4825 0.8325 0.4825 9 P 0 ;1
L 0.8325 0.5325 0.8325 0.5325 9 P 0 ;1
L 0.8325 0.5825 0.8325 0.5825 9 P 0 ;1
L 0.8325 0.6325 0.8325 0.6325 9 P 0 ;1
L 0.8325 0.6825 0.8325 0.6825 9 P 0 ;1
L 0.8325 0.7325 0.8325 0.7325 9 P 0 ;1
L 0.8325 0.7825 0.8325 0.7825 9 P 0 ;1
L 0.8325 0.8325 0.8325 0.8325 9 P 0 ;1
L 0.8325 0.8825 0.8325 0.8825 9 P 0 ;1
L 0.8325 0.9325 0.8325 0.9325 9 P 0 ;1
L 0.8325 0.9825 0.8325 0.9825 9 P 0 ;1
L 0.8325 1.0325 0.8325 1.0325 9 P 0 ;1
L 0.8325 1.0825 0.8325 1.0825 9 P 0 ;1
L 0.8325 1.1325 0.8325 1.1325 9 P 0 ;1
L 0.8325 1.1825 0.8325 1.1825 9 P 0 ;1
L 0.8325 1.7325 0.8325 1.7325 9 P 0 ;1
L 0.8325 1.7825 0.8325 1.7825 9 P 0 ;1
L 0.8325 1.8325 0.8325 1.8325 9 P 0 ;1
L 0.8325 2.7325 0.8325 2.7325 9 P 0 ;1
L 0.8325 2.7825 0.8325 2.7825 9 P 0 ;1
L 0.8325 2.8325 0.8325 2.8325 9 P 0 ;1
L 0.8325 2.8825 0.8325 2.8825 9 P 0 ;1
L 0.8325 2.9325 0.8325 2.9325 9 P 0 ;1
L 0.8325 2.9825 0.8325 2.9825 9 P 0 ;1
L 0.8325 3.0325 0.8325 3.0325 9 P 0 ;1
L 0.8325 3.0825 0.8325 3.0825 9 P 0 ;1
L 0.8325 3.1325 0.8325 3.1325 9 P 0 ;1
L 0.8325 3.5825 0.8325 3.5825 9 P 0 ;1
L 0.8325 3.6325 0.8325 3.6325 9 P 0 ;1
L 0.8325 3.6825 0.8325 3.6825 9 P 0 ;1
L 0.8325 3.7325 0.8325 3.7325 9 P 0 ;1
L 0.8325 3.7825 0.8325 3.7825 9 P 0 ;1
L 0.8325 3.8325 0.8325 3.8325 9 P 0 ;1
L 0.8325 3.8825 0.8325 3.8825 9 P 0 ;1
L 0.8325 3.9325 0.8325 3.9325 9 P 0 ;1
L 0.8325 3.9825 0.8325 3.9825 9 P 0 ;1
L 0.8325 4.0325 0.8325 4.0325 9 P 0 ;1
L 0.8325 4.6325 0.8325 4.6325 9 P 0 ;1
L 0.8325 4.6825 0.8325 4.6825 9 P 0 ;1
L 0.8325 4.7325 0.8325 4.7325 9 P 0 ;1
L 0.8325 4.7825 0.8325 4.7825 9 P 0 ;1
L 0.8325 4.8325 0.8325 4.8325 9 P 0 ;1
L 0.8325 4.8825 0.8325 4.8825 9 P 0 ;1
L 0.8325 4.9325 0.8325 4.9325 9 P 0 ;1
L 0.8325 4.9825 0.8325 4.9825 9 P 0 ;1
L 0.8325 5.0325 0.8325 5.0325 9 P 0 ;1
L 0.8825 0.1325 0.8825 0.1325 9 P 0 ;1
L 0.8825 0.1825 0.8825 0.1825 9 P 0 ;1
L 0.8825 0.2325 0.8825 0.2325 9 P 0 ;1
L 0.8825 0.2825 0.8825 0.2825 9 P 0 ;1
L 0.8825 0.3325 0.8825 0.3325 9 P 0 ;1
L 0.8825 0.3825 0.8825 0.3825 9 P 0 ;1
L 0.8825 0.4325 0.8825 0.4325 9 P 0 ;1
L 0.8825 0.4825 0.8825 0.4825 9 P 0 ;1
L 0.8825 0.5325 0.8825 0.5325 9 P 0 ;1
L 0.8825 0.5825 0.8825 0.5825 9 P 0 ;1
L 0.8825 0.6325 0.8825 0.6325 9 P 0 ;1
L 0.8825 0.6825 0.8825 0.6825 9 P 0 ;1
L 0.8825 0.7325 0.8825 0.7325 9 P 0 ;1
L 0.8825 0.7825 0.8825 0.7825 9 P 0 ;1
L 0.8825 0.8325 0.8825 0.8325 9 P 0 ;1
L 0.8825 0.8825 0.8825 0.8825 9 P 0 ;1
L 0.8825 0.9325 0.8825 0.9325 9 P 0 ;1
L 0.8825 0.9825 0.8825 0.9825 9 P 0 ;1
L 0.8825 1.0325 0.8825 1.0325 9 P 0 ;1
L 0.8825 1.0825 0.8825 1.0825 9 P 0 ;1
L 0.8825 1.1325 0.8825 1.1325 9 P 0 ;1
L 0.8825 1.7325 0.8825 1.7325 9 P 0 ;1
L 0.8825 1.7825 0.8825 1.7825 9 P 0 ;1
L 0.8825 2.6825 0.8825 2.6825 9 P 0 ;1
L 0.8825 2.7325 0.8825 2.7325 9 P 0 ;1
L 0.8825 2.7825 0.8825 2.7825 9 P 0 ;1
L 0.8825 2.8325 0.8825 2.8325 9 P 0 ;1
L 0.8825 2.8825 0.8825 2.8825 9 P 0 ;1
L 0.8825 2.9325 0.8825 2.9325 9 P 0 ;1
L 0.8825 2.9825 0.8825 2.9825 9 P 0 ;1
L 0.8825 3.0325 0.8825 3.0325 9 P 0 ;1
L 0.8825 3.5325 0.8825 3.5325 9 P 0 ;1
L 0.8825 3.5825 0.8825 3.5825 9 P 0 ;1
L 0.8825 3.6325 0.8825 3.6325 9 P 0 ;1
L 0.8825 3.6825 0.8825 3.6825 9 P 0 ;1
L 0.8825 3.7325 0.8825 3.7325 9 P 0 ;1
L 0.8825 3.7825 0.8825 3.7825 9 P 0 ;1
L 0.8825 3.8325 0.8825 3.8325 9 P 0 ;1
L 0.8825 3.8825 0.8825 3.8825 9 P 0 ;1
L 0.8825 3.9325 0.8825 3.9325 9 P 0 ;1
L 0.8825 3.9825 0.8825 3.9825 9 P 0 ;1
L 0.8825 4.0325 0.8825 4.0325 9 P 0 ;1
L 0.8825 4.6325 0.8825 4.6325 9 P 0 ;1
L 0.8825 4.6825 0.8825 4.6825 9 P 0 ;1
L 0.8825 4.7325 0.8825 4.7325 9 P 0 ;1
L 0.8825 4.7825 0.8825 4.7825 9 P 0 ;1
L 0.8825 4.8325 0.8825 4.8325 9 P 0 ;1
L 0.8825 4.8825 0.8825 4.8825 9 P 0 ;1
L 0.8825 4.9325 0.8825 4.9325 9 P 0 ;1
L 0.8825 4.9825 0.8825 4.9825 9 P 0 ;1
L 0.8825 5.4325 0.8825 5.4325 9 P 0 ;1
L 0.8825 5.5325 0.8825 5.5325 9 P 0 ;1
L 0.8825 5.5825 0.8825 5.5825 9 P 0 ;1
L 0.8825 5.6325 0.8825 5.6325 9 P 0 ;1
L 0.8825 5.6825 0.8825 5.6825 9 P 0 ;1
L 0.9325 0.1325 0.9325 0.1325 9 P 0 ;1
L 0.9325 0.1825 0.9325 0.1825 9 P 0 ;1
L 0.9325 0.2325 0.9325 0.2325 9 P 0 ;1
L 0.9325 0.2825 0.9325 0.2825 9 P 0 ;1
L 0.9325 0.3325 0.9325 0.3325 9 P 0 ;1
L 0.9325 0.3825 0.9325 0.3825 9 P 0 ;1
L 0.9325 0.4325 0.9325 0.4325 9 P 0 ;1
L 0.9325 0.4825 0.9325 0.4825 9 P 0 ;1
L 0.9325 0.5325 0.9325 0.5325 9 P 0 ;1
L 0.9325 0.5825 0.9325 0.5825 9 P 0 ;1
L 0.9325 0.6325 0.9325 0.6325 9 P 0 ;1
L 0.9325 0.6825 0.9325 0.6825 9 P 0 ;1
L 0.9325 0.7325 0.9325 0.7325 9 P 0 ;1
L 0.9325 0.7825 0.9325 0.7825 9 P 0 ;1
L 0.9325 0.8325 0.9325 0.8325 9 P 0 ;1
L 0.9325 0.8825 0.9325 0.8825 9 P 0 ;1
L 0.9325 0.9325 0.9325 0.9325 9 P 0 ;1
L 0.9325 0.9825 0.9325 0.9825 9 P 0 ;1
L 0.9325 1.0325 0.9325 1.0325 9 P 0 ;1
L 0.9325 1.0825 0.9325 1.0825 9 P 0 ;1
L 0.9325 1.1325 0.9325 1.1325 9 P 0 ;1
L 0.9325 1.7325 0.9325 1.7325 9 P 0 ;1
L 0.9325 2.7325 0.9325 2.7325 9 P 0 ;1
L 0.9325 2.7825 0.9325 2.7825 9 P 0 ;1
L 0.9325 2.8325 0.9325 2.8325 9 P 0 ;1
L 0.9325 2.8825 0.9325 2.8825 9 P 0 ;1
L 0.9325 2.9325 0.9325 2.9325 9 P 0 ;1
L 0.9325 2.9825 0.9325 2.9825 9 P 0 ;1
L 0.9325 3.4325 0.9325 3.4325 9 P 0 ;1
L 0.9325 3.4825 0.9325 3.4825 9 P 0 ;1
L 0.9325 3.5325 0.9325 3.5325 9 P 0 ;1
L 0.9325 3.5825 0.9325 3.5825 9 P 0 ;1
L 0.9325 3.6325 0.9325 3.6325 9 P 0 ;1
L 0.9325 3.6825 0.9325 3.6825 9 P 0 ;1
L 0.9325 3.7325 0.9325 3.7325 9 P 0 ;1
L 0.9325 3.7825 0.9325 3.7825 9 P 0 ;1
L 0.9325 3.8325 0.9325 3.8325 9 P 0 ;1
L 0.9325 3.8825 0.9325 3.8825 9 P 0 ;1
L 0.9325 3.9325 0.9325 3.9325 9 P 0 ;1
L 0.9325 3.9825 0.9325 3.9825 9 P 0 ;1
L 0.9325 4.6325 0.9325 4.6325 9 P 0 ;1
L 0.9325 4.6825 0.9325 4.6825 9 P 0 ;1
L 0.9325 4.7325 0.9325 4.7325 9 P 0 ;1
L 0.9325 4.7825 0.9325 4.7825 9 P 0 ;1
L 0.9325 4.8325 0.9325 4.8325 9 P 0 ;1
L 0.9325 4.8825 0.9325 4.8825 9 P 0 ;1
L 0.9325 4.9325 0.9325 4.9325 9 P 0 ;1
L 0.9325 4.9825 0.9325 4.9825 9 P 0 ;1
L 0.9325 5.1825 0.9325 5.1825 9 P 0 ;1
L 0.9325 5.2325 0.9325 5.2325 9 P 0 ;1
L 0.9325 5.5825 0.9325 5.5825 9 P 0 ;1
L 0.9325 5.6325 0.9325 5.6325 9 P 0 ;1
L 0.9325 5.6825 0.9325 5.6825 9 P 0 ;1
L 0.9825 0.1325 0.9825 0.1325 9 P 0 ;1
L 0.9825 0.1825 0.9825 0.1825 9 P 0 ;1
L 0.9825 0.2325 0.9825 0.2325 9 P 0 ;1
L 0.9825 0.2825 0.9825 0.2825 9 P 0 ;1
L 0.9825 0.3325 0.9825 0.3325 9 P 0 ;1
L 0.9825 0.3825 0.9825 0.3825 9 P 0 ;1
L 0.9825 0.4325 0.9825 0.4325 9 P 0 ;1
L 0.9825 0.4825 0.9825 0.4825 9 P 0 ;1
L 0.9825 0.5325 0.9825 0.5325 9 P 0 ;1
L 0.9825 0.5825 0.9825 0.5825 9 P 0 ;1
L 0.9825 0.6325 0.9825 0.6325 9 P 0 ;1
L 0.9825 0.6825 0.9825 0.6825 9 P 0 ;1
L 0.9825 0.7325 0.9825 0.7325 9 P 0 ;1
L 0.9825 0.7825 0.9825 0.7825 9 P 0 ;1
L 0.9825 0.8325 0.9825 0.8325 9 P 0 ;1
L 0.9825 0.8825 0.9825 0.8825 9 P 0 ;1
L 0.9825 0.9325 0.9825 0.9325 9 P 0 ;1
L 0.9825 0.9825 0.9825 0.9825 9 P 0 ;1
L 0.9825 1.0325 0.9825 1.0325 9 P 0 ;1
L 0.9825 1.0825 0.9825 1.0825 9 P 0 ;1
L 0.9825 2.7325 0.9825 2.7325 9 P 0 ;1
L 0.9825 2.7825 0.9825 2.7825 9 P 0 ;1
L 0.9825 2.8325 0.9825 2.8325 9 P 0 ;1
L 0.9825 2.8825 0.9825 2.8825 9 P 0 ;1
L 0.9825 3.3825 0.9825 3.3825 9 P 0 ;1
L 0.9825 3.4325 0.9825 3.4325 9 P 0 ;1
L 0.9825 3.4825 0.9825 3.4825 9 P 0 ;1
L 0.9825 3.5325 0.9825 3.5325 9 P 0 ;1
L 0.9825 3.5825 0.9825 3.5825 9 P 0 ;1
L 0.9825 3.6325 0.9825 3.6325 9 P 0 ;1
L 0.9825 3.6825 0.9825 3.6825 9 P 0 ;1
L 0.9825 3.7325 0.9825 3.7325 9 P 0 ;1
L 0.9825 3.7825 0.9825 3.7825 9 P 0 ;1
L 0.9825 3.8325 0.9825 3.8325 9 P 0 ;1
L 0.9825 3.8825 0.9825 3.8825 9 P 0 ;1
L 0.9825 3.9325 0.9825 3.9325 9 P 0 ;1
L 0.9825 3.9825 0.9825 3.9825 9 P 0 ;1
L 0.9825 4.5825 0.9825 4.5825 9 P 0 ;1
L 0.9825 4.6325 0.9825 4.6325 9 P 0 ;1
L 0.9825 4.6825 0.9825 4.6825 9 P 0 ;1
L 0.9825 4.7325 0.9825 4.7325 9 P 0 ;1
L 0.9825 4.7825 0.9825 4.7825 9 P 0 ;1
L 0.9825 4.8325 0.9825 4.8325 9 P 0 ;1
L 0.9825 4.8825 0.9825 4.8825 9 P 0 ;1
L 0.9825 5.2325 0.9825 5.2325 9 P 0 ;1
L 0.9825 5.5825 0.9825 5.5825 9 P 0 ;1
L 0.9825 5.6325 0.9825 5.6325 9 P 0 ;1
L 0.9825 5.6825 0.9825 5.6825 9 P 0 ;1
L 1.0325 0.1325 1.0325 0.1325 9 P 0 ;1
L 1.0325 0.1825 1.0325 0.1825 9 P 0 ;1
L 1.0325 0.2325 1.0325 0.2325 9 P 0 ;1
L 1.0325 0.2825 1.0325 0.2825 9 P 0 ;1
L 1.0325 0.3325 1.0325 0.3325 9 P 0 ;1
L 1.0325 0.3825 1.0325 0.3825 9 P 0 ;1
L 1.0325 0.4325 1.0325 0.4325 9 P 0 ;1
L 1.0325 0.4825 1.0325 0.4825 9 P 0 ;1
L 1.0325 0.5325 1.0325 0.5325 9 P 0 ;1
L 1.0325 0.5825 1.0325 0.5825 9 P 0 ;1
L 1.0325 0.6325 1.0325 0.6325 9 P 0 ;1
L 1.0325 0.6825 1.0325 0.6825 9 P 0 ;1
L 1.0325 0.7325 1.0325 0.7325 9 P 0 ;1
L 1.0325 0.7825 1.0325 0.7825 9 P 0 ;1
L 1.0325 0.8325 1.0325 0.8325 9 P 0 ;1
L 1.0325 0.8825 1.0325 0.8825 9 P 0 ;1
L 1.0325 0.9325 1.0325 0.9325 9 P 0 ;1
L 1.0325 0.9825 1.0325 0.9825 9 P 0 ;1
L 1.0325 1.0325 1.0325 1.0325 9 P 0 ;1
L 1.0325 1.2825 1.0325 1.2825 9 P 0 ;1
L 1.0325 1.3325 1.0325 1.3325 9 P 0 ;1
L 1.0325 2.7325 1.0325 2.7325 9 P 0 ;1
L 1.0325 2.7825 1.0325 2.7825 9 P 0 ;1
L 1.0325 2.8325 1.0325 2.8325 9 P 0 ;1
L 1.0325 3.3325 1.0325 3.3325 9 P 0 ;1
L 1.0325 3.3825 1.0325 3.3825 9 P 0 ;1
L 1.0325 3.4325 1.0325 3.4325 9 P 0 ;1
L 1.0325 3.4825 1.0325 3.4825 9 P 0 ;1
L 1.0325 3.5325 1.0325 3.5325 9 P 0 ;1
L 1.0325 3.5825 1.0325 3.5825 9 P 0 ;1
L 1.0325 3.6325 1.0325 3.6325 9 P 0 ;1
L 1.0325 3.6825 1.0325 3.6825 9 P 0 ;1
L 1.0325 3.7325 1.0325 3.7325 9 P 0 ;1
L 1.0325 3.7825 1.0325 3.7825 9 P 0 ;1
L 1.0325 3.8325 1.0325 3.8325 9 P 0 ;1
L 1.0325 3.8825 1.0325 3.8825 9 P 0 ;1
L 1.0325 3.9325 1.0325 3.9325 9 P 0 ;1
L 1.0325 3.9825 1.0325 3.9825 9 P 0 ;1
L 1.0325 4.0325 1.0325 4.0325 9 P 0 ;1
L 1.0325 4.5825 1.0325 4.5825 9 P 0 ;1
L 1.0325 4.6325 1.0325 4.6325 9 P 0 ;1
L 1.0325 4.6825 1.0325 4.6825 9 P 0 ;1
L 1.0325 4.7325 1.0325 4.7325 9 P 0 ;1
L 1.0325 4.7825 1.0325 4.7825 9 P 0 ;1
L 1.0325 4.8325 1.0325 4.8325 9 P 0 ;1
L 1.0325 5.2825 1.0325 5.2825 9 P 0 ;1
L 1.0325 5.5325 1.0325 5.5325 9 P 0 ;1
L 1.0325 5.5825 1.0325 5.5825 9 P 0 ;1
L 1.0325 5.6325 1.0325 5.6325 9 P 0 ;1
L 1.0325 5.6825 1.0325 5.6825 9 P 0 ;1
L 1.0325 5.7325 1.0325 5.7325 9 P 0 ;1
L 1.0825 0.1325 1.0825 0.1325 9 P 0 ;1
L 1.0825 0.1825 1.0825 0.1825 9 P 0 ;1
L 1.0825 0.2325 1.0825 0.2325 9 P 0 ;1
L 1.0825 0.2825 1.0825 0.2825 9 P 0 ;1
L 1.0825 0.3325 1.0825 0.3325 9 P 0 ;1
L 1.0825 0.3825 1.0825 0.3825 9 P 0 ;1
L 1.0825 0.4325 1.0825 0.4325 9 P 0 ;1
L 1.0825 0.4825 1.0825 0.4825 9 P 0 ;1
L 1.0825 0.5325 1.0825 0.5325 9 P 0 ;1
L 1.0825 0.5825 1.0825 0.5825 9 P 0 ;1
L 1.0825 0.6325 1.0825 0.6325 9 P 0 ;1
L 1.0825 0.6825 1.0825 0.6825 9 P 0 ;1
L 1.0825 0.7325 1.0825 0.7325 9 P 0 ;1
L 1.0825 0.7825 1.0825 0.7825 9 P 0 ;1
L 1.0825 0.8325 1.0825 0.8325 9 P 0 ;1
L 1.0825 0.8825 1.0825 0.8825 9 P 0 ;1
L 1.0825 0.9325 1.0825 0.9325 9 P 0 ;1
L 1.0825 0.9825 1.0825 0.9825 9 P 0 ;1
L 1.0825 1.0325 1.0825 1.0325 9 P 0 ;1
L 1.0825 1.2325 1.0825 1.2325 9 P 0 ;1
L 1.0825 1.2825 1.0825 1.2825 9 P 0 ;1
L 1.0825 1.3325 1.0825 1.3325 9 P 0 ;1
L 1.0825 2.3825 1.0825 2.3825 9 P 0 ;1
L 1.0825 2.4325 1.0825 2.4325 9 P 0 ;1
L 1.0825 2.7325 1.0825 2.7325 9 P 0 ;1
L 1.0825 3.2325 1.0825 3.2325 9 P 0 ;1
L 1.0825 3.2825 1.0825 3.2825 9 P 0 ;1
L 1.0825 3.3325 1.0825 3.3325 9 P 0 ;1
L 1.0825 3.3825 1.0825 3.3825 9 P 0 ;1
L 1.0825 3.4325 1.0825 3.4325 9 P 0 ;1
L 1.0825 3.4825 1.0825 3.4825 9 P 0 ;1
L 1.0825 3.5325 1.0825 3.5325 9 P 0 ;1
L 1.0825 3.5825 1.0825 3.5825 9 P 0 ;1
L 1.0825 3.6325 1.0825 3.6325 9 P 0 ;1
L 1.0825 3.6825 1.0825 3.6825 9 P 0 ;1
L 1.0825 3.7325 1.0825 3.7325 9 P 0 ;1
L 1.0825 3.7825 1.0825 3.7825 9 P 0 ;1
L 1.0825 3.8325 1.0825 3.8325 9 P 0 ;1
L 1.0825 3.8825 1.0825 3.8825 9 P 0 ;1
L 1.0825 3.9325 1.0825 3.9325 9 P 0 ;1
L 1.0825 3.9825 1.0825 3.9825 9 P 0 ;1
L 1.0825 4.0325 1.0825 4.0325 9 P 0 ;1
L 1.0825 4.5825 1.0825 4.5825 9 P 0 ;1
L 1.0825 4.6325 1.0825 4.6325 9 P 0 ;1
L 1.0825 4.6825 1.0825 4.6825 9 P 0 ;1
L 1.0825 4.7325 1.0825 4.7325 9 P 0 ;1
L 1.0825 4.7825 1.0825 4.7825 9 P 0 ;1
L 1.0825 4.8325 1.0825 4.8325 9 P 0 ;1
L 1.0825 4.8825 1.0825 4.8825 9 P 0 ;1
L 1.0825 5.2325 1.0825 5.2325 9 P 0 ;1
L 1.0825 5.5325 1.0825 5.5325 9 P 0 ;1
L 1.0825 5.5825 1.0825 5.5825 9 P 0 ;1
L 1.0825 5.6325 1.0825 5.6325 9 P 0 ;1
L 1.0825 5.6825 1.0825 5.6825 9 P 0 ;1
L 1.0825 5.7325 1.0825 5.7325 9 P 0 ;1
L 1.1325 0.1325 1.1325 0.1325 9 P 0 ;1
L 1.1325 0.1825 1.1325 0.1825 9 P 0 ;1
L 1.1325 0.2325 1.1325 0.2325 9 P 0 ;1
L 1.1325 0.2825 1.1325 0.2825 9 P 0 ;1
L 1.1325 0.3325 1.1325 0.3325 9 P 0 ;1
L 1.1325 0.3825 1.1325 0.3825 9 P 0 ;1
L 1.1325 0.4325 1.1325 0.4325 9 P 0 ;1
L 1.1325 0.4825 1.1325 0.4825 9 P 0 ;1
L 1.1325 0.5325 1.1325 0.5325 9 P 0 ;1
L 1.1325 0.5825 1.1325 0.5825 9 P 0 ;1
L 1.1325 0.6325 1.1325 0.6325 9 P 0 ;1
L 1.1325 0.6825 1.1325 0.6825 9 P 0 ;1
L 1.1325 0.7325 1.1325 0.7325 9 P 0 ;1
L 1.1325 0.7825 1.1325 0.7825 9 P 0 ;1
L 1.1325 0.8325 1.1325 0.8325 9 P 0 ;1
L 1.1325 0.8825 1.1325 0.8825 9 P 0 ;1
L 1.1325 0.9325 1.1325 0.9325 9 P 0 ;1
L 1.1325 0.9825 1.1325 0.9825 9 P 0 ;1
L 1.1325 1.2325 1.1325 1.2325 9 P 0 ;1
L 1.1325 1.2825 1.1325 1.2825 9 P 0 ;1
L 1.1325 1.3325 1.1325 1.3325 9 P 0 ;1
L 1.1325 1.3825 1.1325 1.3825 9 P 0 ;1
L 1.1325 1.4325 1.1325 1.4325 9 P 0 ;1
L 1.1325 2.3325 1.1325 2.3325 9 P 0 ;1
L 1.1325 2.3825 1.1325 2.3825 9 P 0 ;1
L 1.1325 2.4325 1.1325 2.4325 9 P 0 ;1
L 1.1325 3.1825 1.1325 3.1825 9 P 0 ;1
L 1.1325 3.2325 1.1325 3.2325 9 P 0 ;1
L 1.1325 3.2825 1.1325 3.2825 9 P 0 ;1
L 1.1325 3.3325 1.1325 3.3325 9 P 0 ;1
L 1.1325 3.3825 1.1325 3.3825 9 P 0 ;1
L 1.1325 3.4325 1.1325 3.4325 9 P 0 ;1
L 1.1325 3.4825 1.1325 3.4825 9 P 0 ;1
L 1.1325 3.5325 1.1325 3.5325 9 P 0 ;1
L 1.1325 3.5825 1.1325 3.5825 9 P 0 ;1
L 1.1325 3.6325 1.1325 3.6325 9 P 0 ;1
L 1.1325 3.6825 1.1325 3.6825 9 P 0 ;1
L 1.1325 3.7325 1.1325 3.7325 9 P 0 ;1
L 1.1325 3.7825 1.1325 3.7825 9 P 0 ;1
L 1.1325 3.8325 1.1325 3.8325 9 P 0 ;1
L 1.1325 3.8825 1.1325 3.8825 9 P 0 ;1
L 1.1325 3.9325 1.1325 3.9325 9 P 0 ;1
L 1.1325 3.9825 1.1325 3.9825 9 P 0 ;1
L 1.1325 4.0325 1.1325 4.0325 9 P 0 ;1
L 1.1325 4.0825 1.1325 4.0825 9 P 0 ;1
L 1.1325 4.1325 1.1325 4.1325 9 P 0 ;1
L 1.1325 4.2825 1.1325 4.2825 9 P 0 ;1
L 1.1325 4.5825 1.1325 4.5825 9 P 0 ;1
L 1.1325 4.6325 1.1325 4.6325 9 P 0 ;1
L 1.1325 4.6825 1.1325 4.6825 9 P 0 ;1
L 1.1325 4.7325 1.1325 4.7325 9 P 0 ;1
L 1.1325 4.7825 1.1325 4.7825 9 P 0 ;1
L 1.1325 4.8325 1.1325 4.8325 9 P 0 ;1
L 1.1325 4.8825 1.1325 4.8825 9 P 0 ;1
L 1.1325 5.2325 1.1325 5.2325 9 P 0 ;1
L 1.1325 5.2825 1.1325 5.2825 9 P 0 ;1
L 1.1325 5.5825 1.1325 5.5825 9 P 0 ;1
L 1.1325 5.6325 1.1325 5.6325 9 P 0 ;1
L 1.1325 5.6825 1.1325 5.6825 9 P 0 ;1
L 1.1325 5.7325 1.1325 5.7325 9 P 0 ;1
L 1.1825 0.1325 1.1825 0.1325 9 P 0 ;1
L 1.1825 0.1825 1.1825 0.1825 9 P 0 ;1
L 1.1825 0.2325 1.1825 0.2325 9 P 0 ;1
L 1.1825 0.2825 1.1825 0.2825 9 P 0 ;1
L 1.1825 0.3325 1.1825 0.3325 9 P 0 ;1
L 1.1825 0.3825 1.1825 0.3825 9 P 0 ;1
L 1.1825 0.4325 1.1825 0.4325 9 P 0 ;1
L 1.1825 0.4825 1.1825 0.4825 9 P 0 ;1
L 1.1825 0.5325 1.1825 0.5325 9 P 0 ;1
L 1.1825 0.5825 1.1825 0.5825 9 P 0 ;1
L 1.1825 0.6325 1.1825 0.6325 9 P 0 ;1
L 1.1825 0.6825 1.1825 0.6825 9 P 0 ;1
L 1.1825 0.7325 1.1825 0.7325 9 P 0 ;1
L 1.1825 0.7825 1.1825 0.7825 9 P 0 ;1
L 1.1825 0.8325 1.1825 0.8325 9 P 0 ;1
L 1.1825 0.8825 1.1825 0.8825 9 P 0 ;1
L 1.1825 0.9325 1.1825 0.9325 9 P 0 ;1
L 1.1825 0.9825 1.1825 0.9825 9 P 0 ;1
L 1.1825 1.1825 1.1825 1.1825 9 P 0 ;1
L 1.1825 1.2325 1.1825 1.2325 9 P 0 ;1
L 1.1825 1.2825 1.1825 1.2825 9 P 0 ;1
L 1.1825 1.3325 1.1825 1.3325 9 P 0 ;1
L 1.1825 1.3825 1.1825 1.3825 9 P 0 ;1
L 1.1825 1.4325 1.1825 1.4325 9 P 0 ;1
L 1.1825 1.4825 1.1825 1.4825 9 P 0 ;1
L 1.1825 1.5325 1.1825 1.5325 9 P 0 ;1
L 1.1825 2.2325 1.1825 2.2325 9 P 0 ;1
L 1.1825 2.2825 1.1825 2.2825 9 P 0 ;1
L 1.1825 2.3325 1.1825 2.3325 9 P 0 ;1
L 1.1825 2.3825 1.1825 2.3825 9 P 0 ;1
L 1.1825 2.4325 1.1825 2.4325 9 P 0 ;1
L 1.1825 3.0825 1.1825 3.0825 9 P 0 ;1
L 1.1825 3.1325 1.1825 3.1325 9 P 0 ;1
L 1.1825 3.1825 1.1825 3.1825 9 P 0 ;1
L 1.1825 3.2325 1.1825 3.2325 9 P 0 ;1
L 1.1825 3.2825 1.1825 3.2825 9 P 0 ;1
L 1.1825 3.3325 1.1825 3.3325 9 P 0 ;1
L 1.1825 3.3825 1.1825 3.3825 9 P 0 ;1
L 1.1825 3.4325 1.1825 3.4325 9 P 0 ;1
L 1.1825 3.4825 1.1825 3.4825 9 P 0 ;1
L 1.1825 3.5325 1.1825 3.5325 9 P 0 ;1
L 1.1825 3.5825 1.1825 3.5825 9 P 0 ;1
L 1.1825 3.6325 1.1825 3.6325 9 P 0 ;1
L 1.1825 3.6825 1.1825 3.6825 9 P 0 ;1
L 1.1825 3.7325 1.1825 3.7325 9 P 0 ;1
L 1.1825 3.7825 1.1825 3.7825 9 P 0 ;1
L 1.1825 3.8325 1.1825 3.8325 9 P 0 ;1
L 1.1825 3.8825 1.1825 3.8825 9 P 0 ;1
L 1.1825 3.9325 1.1825 3.9325 9 P 0 ;1
L 1.1825 3.9825 1.1825 3.9825 9 P 0 ;1
L 1.1825 4.0325 1.1825 4.0325 9 P 0 ;1
L 1.1825 4.0825 1.1825 4.0825 9 P 0 ;1
L 1.1825 4.1325 1.1825 4.1325 9 P 0 ;1
L 1.1825 4.1825 1.1825 4.1825 9 P 0 ;1
L 1.1825 4.2325 1.1825 4.2325 9 P 0 ;1
L 1.1825 4.2825 1.1825 4.2825 9 P 0 ;1
L 1.1825 4.7825 1.1825 4.7825 9 P 0 ;1
L 1.1825 4.8325 1.1825 4.8325 9 P 0 ;1
L 1.1825 5.2325 1.1825 5.2325 9 P 0 ;1
L 1.1825 5.2825 1.1825 5.2825 9 P 0 ;1
L 1.1825 5.3325 1.1825 5.3325 9 P 0 ;1
L 1.1825 5.5825 1.1825 5.5825 9 P 0 ;1
L 1.1825 5.6325 1.1825 5.6325 9 P 0 ;1
L 1.1825 5.6825 1.1825 5.6825 9 P 0 ;1
L 1.2325 0.1325 1.2325 0.1325 9 P 0 ;1
L 1.2325 0.1825 1.2325 0.1825 9 P 0 ;1
L 1.2325 0.2325 1.2325 0.2325 9 P 0 ;1
L 1.2325 0.2825 1.2325 0.2825 9 P 0 ;1
L 1.2325 0.3325 1.2325 0.3325 9 P 0 ;1
L 1.2325 0.3825 1.2325 0.3825 9 P 0 ;1
L 1.2325 0.4325 1.2325 0.4325 9 P 0 ;1
L 1.2325 0.4825 1.2325 0.4825 9 P 0 ;1
L 1.2325 0.5325 1.2325 0.5325 9 P 0 ;1
L 1.2325 0.5825 1.2325 0.5825 9 P 0 ;1
L 1.2325 0.6325 1.2325 0.6325 9 P 0 ;1
L 1.2325 0.6825 1.2325 0.6825 9 P 0 ;1
L 1.2325 0.7325 1.2325 0.7325 9 P 0 ;1
L 1.2325 0.7825 1.2325 0.7825 9 P 0 ;1
L 1.2325 0.8325 1.2325 0.8325 9 P 0 ;1
L 1.2325 0.8825 1.2325 0.8825 9 P 0 ;1
L 1.2325 0.9325 1.2325 0.9325 9 P 0 ;1
L 1.2325 0.9825 1.2325 0.9825 9 P 0 ;1
L 1.2325 1.1825 1.2325 1.1825 9 P 0 ;1
L 1.2325 1.2325 1.2325 1.2325 9 P 0 ;1
L 1.2325 1.2825 1.2325 1.2825 9 P 0 ;1
L 1.2325 1.3325 1.2325 1.3325 9 P 0 ;1
L 1.2325 1.3825 1.2325 1.3825 9 P 0 ;1
L 1.2325 1.4325 1.2325 1.4325 9 P 0 ;1
L 1.2325 1.4825 1.2325 1.4825 9 P 0 ;1
L 1.2325 2.1825 1.2325 2.1825 9 P 0 ;1
L 1.2325 2.2325 1.2325 2.2325 9 P 0 ;1
L 1.2325 2.2825 1.2325 2.2825 9 P 0 ;1
L 1.2325 2.3325 1.2325 2.3325 9 P 0 ;1
L 1.2325 2.3825 1.2325 2.3825 9 P 0 ;1
L 1.2325 2.4325 1.2325 2.4325 9 P 0 ;1
L 1.2325 2.4825 1.2325 2.4825 9 P 0 ;1
L 1.2325 2.5325 1.2325 2.5325 9 P 0 ;1
L 1.2325 3.0325 1.2325 3.0325 9 P 0 ;1
L 1.2325 3.0825 1.2325 3.0825 9 P 0 ;1
L 1.2325 3.1325 1.2325 3.1325 9 P 0 ;1
L 1.2325 3.1825 1.2325 3.1825 9 P 0 ;1
L 1.2325 3.2325 1.2325 3.2325 9 P 0 ;1
L 1.2325 3.2825 1.2325 3.2825 9 P 0 ;1
L 1.2325 3.3325 1.2325 3.3325 9 P 0 ;1
L 1.2325 3.3825 1.2325 3.3825 9 P 0 ;1
L 1.2325 3.4325 1.2325 3.4325 9 P 0 ;1
L 1.2325 3.4825 1.2325 3.4825 9 P 0 ;1
L 1.2325 3.5325 1.2325 3.5325 9 P 0 ;1
L 1.2325 3.5825 1.2325 3.5825 9 P 0 ;1
L 1.2325 3.6325 1.2325 3.6325 9 P 0 ;1
L 1.2325 3.6825 1.2325 3.6825 9 P 0 ;1
L 1.2325 3.7325 1.2325 3.7325 9 P 0 ;1
L 1.2325 3.7825 1.2325 3.7825 9 P 0 ;1
L 1.2325 3.8325 1.2325 3.8325 9 P 0 ;1
L 1.2325 3.8825 1.2325 3.8825 9 P 0 ;1
L 1.2325 3.9325 1.2325 3.9325 9 P 0 ;1
L 1.2325 3.9825 1.2325 3.9825 9 P 0 ;1
L 1.2325 4.0325 1.2325 4.0325 9 P 0 ;1
L 1.2325 4.0825 1.2325 4.0825 9 P 0 ;1
L 1.2325 4.1325 1.2325 4.1325 9 P 0 ;1
L 1.2325 4.1825 1.2325 4.1825 9 P 0 ;1
L 1.2325 4.2325 1.2325 4.2325 9 P 0 ;1
L 1.2325 4.2825 1.2325 4.2825 9 P 0 ;1
L 1.2325 4.7825 1.2325 4.7825 9 P 0 ;1
L 1.2325 4.8325 1.2325 4.8325 9 P 0 ;1
L 1.2325 4.8825 1.2325 4.8825 9 P 0 ;1
L 1.2325 5.2325 1.2325 5.2325 9 P 0 ;1
L 1.2325 5.2825 1.2325 5.2825 9 P 0 ;1
L 1.2325 5.3325 1.2325 5.3325 9 P 0 ;1
L 1.2325 5.3825 1.2325 5.3825 9 P 0 ;1
L 1.2325 5.5825 1.2325 5.5825 9 P 0 ;1
L 1.2325 5.6325 1.2325 5.6325 9 P 0 ;1
L 1.2325 5.6825 1.2325 5.6825 9 P 0 ;1
L 1.2825 0.1325 1.2825 0.1325 9 P 0 ;1
L 1.2825 0.1825 1.2825 0.1825 9 P 0 ;1
L 1.2825 0.2325 1.2825 0.2325 9 P 0 ;1
L 1.2825 0.2825 1.2825 0.2825 9 P 0 ;1
L 1.2825 0.3325 1.2825 0.3325 9 P 0 ;1
L 1.2825 0.3825 1.2825 0.3825 9 P 0 ;1
L 1.2825 0.4325 1.2825 0.4325 9 P 0 ;1
L 1.2825 0.4825 1.2825 0.4825 9 P 0 ;1
L 1.2825 0.5325 1.2825 0.5325 9 P 0 ;1
L 1.2825 0.5825 1.2825 0.5825 9 P 0 ;1
L 1.2825 0.6325 1.2825 0.6325 9 P 0 ;1
L 1.2825 0.6825 1.2825 0.6825 9 P 0 ;1
L 1.2825 0.7325 1.2825 0.7325 9 P 0 ;1
L 1.2825 0.7825 1.2825 0.7825 9 P 0 ;1
L 1.2825 0.8325 1.2825 0.8325 9 P 0 ;1
L 1.2825 0.8825 1.2825 0.8825 9 P 0 ;1
L 1.2825 0.9325 1.2825 0.9325 9 P 0 ;1
L 1.2825 0.9825 1.2825 0.9825 9 P 0 ;1
L 1.2825 1.1825 1.2825 1.1825 9 P 0 ;1
L 1.2825 1.2325 1.2825 1.2325 9 P 0 ;1
L 1.2825 1.2825 1.2825 1.2825 9 P 0 ;1
L 1.2825 1.3325 1.2825 1.3325 9 P 0 ;1
L 1.2825 1.3825 1.2825 1.3825 9 P 0 ;1
L 1.2825 1.4325 1.2825 1.4325 9 P 0 ;1
L 1.2825 2.1325 1.2825 2.1325 9 P 0 ;1
L 1.2825 2.1825 1.2825 2.1825 9 P 0 ;1
L 1.2825 2.2325 1.2825 2.2325 9 P 0 ;1
L 1.2825 2.2825 1.2825 2.2825 9 P 0 ;1
L 1.2825 2.3325 1.2825 2.3325 9 P 0 ;1
L 1.2825 2.3825 1.2825 2.3825 9 P 0 ;1
L 1.2825 2.4325 1.2825 2.4325 9 P 0 ;1
L 1.2825 2.4825 1.2825 2.4825 9 P 0 ;1
L 1.2825 2.9325 1.2825 2.9325 9 P 0 ;1
L 1.2825 2.9825 1.2825 2.9825 9 P 0 ;1
L 1.2825 3.0325 1.2825 3.0325 9 P 0 ;1
L 1.2825 3.0825 1.2825 3.0825 9 P 0 ;1
L 1.2825 3.1325 1.2825 3.1325 9 P 0 ;1
L 1.2825 3.1825 1.2825 3.1825 9 P 0 ;1
L 1.2825 3.2325 1.2825 3.2325 9 P 0 ;1
L 1.2825 3.2825 1.2825 3.2825 9 P 0 ;1
L 1.2825 3.3325 1.2825 3.3325 9 P 0 ;1
L 1.2825 3.3825 1.2825 3.3825 9 P 0 ;1
L 1.2825 3.4325 1.2825 3.4325 9 P 0 ;1
L 1.2825 3.4825 1.2825 3.4825 9 P 0 ;1
L 1.2825 3.5325 1.2825 3.5325 9 P 0 ;1
L 1.2825 3.5825 1.2825 3.5825 9 P 0 ;1
L 1.2825 3.6325 1.2825 3.6325 9 P 0 ;1
L 1.2825 3.6825 1.2825 3.6825 9 P 0 ;1
L 1.2825 3.7325 1.2825 3.7325 9 P 0 ;1
L 1.2825 3.7825 1.2825 3.7825 9 P 0 ;1
L 1.2825 3.8325 1.2825 3.8325 9 P 0 ;1
L 1.2825 3.8825 1.2825 3.8825 9 P 0 ;1
L 1.2825 3.9325 1.2825 3.9325 9 P 0 ;1
L 1.2825 3.9825 1.2825 3.9825 9 P 0 ;1
L 1.2825 4.0325 1.2825 4.0325 9 P 0 ;1
L 1.2825 4.0825 1.2825 4.0825 9 P 0 ;1
L 1.2825 4.1325 1.2825 4.1325 9 P 0 ;1
L 1.2825 4.1825 1.2825 4.1825 9 P 0 ;1
L 1.2825 4.2325 1.2825 4.2325 9 P 0 ;1
L 1.2825 4.2825 1.2825 4.2825 9 P 0 ;1
L 1.2825 4.5325 1.2825 4.5325 9 P 0 ;1
L 1.2825 4.7825 1.2825 4.7825 9 P 0 ;1
L 1.2825 4.9325 1.2825 4.9325 9 P 0 ;1
L 1.2825 5.2325 1.2825 5.2325 9 P 0 ;1
L 1.2825 5.5825 1.2825 5.5825 9 P 0 ;1
L 1.2825 5.6325 1.2825 5.6325 9 P 0 ;1
L 1.2825 5.6825 1.2825 5.6825 9 P 0 ;1
L 1.3325 0.1325 1.3325 0.1325 9 P 0 ;1
L 1.3325 0.1825 1.3325 0.1825 9 P 0 ;1
L 1.3325 0.2325 1.3325 0.2325 9 P 0 ;1
L 1.3325 0.2825 1.3325 0.2825 9 P 0 ;1
L 1.3325 0.3325 1.3325 0.3325 9 P 0 ;1
L 1.3325 0.3825 1.3325 0.3825 9 P 0 ;1
L 1.3325 0.4325 1.3325 0.4325 9 P 0 ;1
L 1.3325 0.4825 1.3325 0.4825 9 P 0 ;1
L 1.3325 0.5325 1.3325 0.5325 9 P 0 ;1
L 1.3325 0.5825 1.3325 0.5825 9 P 0 ;1
L 1.3325 0.6325 1.3325 0.6325 9 P 0 ;1
L 1.3325 0.6825 1.3325 0.6825 9 P 0 ;1
L 1.3325 0.7325 1.3325 0.7325 9 P 0 ;1
L 1.3325 0.7825 1.3325 0.7825 9 P 0 ;1
L 1.3325 0.8325 1.3325 0.8325 9 P 0 ;1
L 1.3325 0.8825 1.3325 0.8825 9 P 0 ;1
L 1.3325 0.9325 1.3325 0.9325 9 P 0 ;1
L 1.3325 0.9825 1.3325 0.9825 9 P 0 ;1
L 1.3325 1.1825 1.3325 1.1825 9 P 0 ;1
L 1.3325 1.2325 1.3325 1.2325 9 P 0 ;1
L 1.3325 1.2825 1.3325 1.2825 9 P 0 ;1
L 1.3325 1.3325 1.3325 1.3325 9 P 0 ;1
L 1.3325 1.3825 1.3325 1.3825 9 P 0 ;1
L 1.3325 2.0325 1.3325 2.0325 9 P 0 ;1
L 1.3325 2.0825 1.3325 2.0825 9 P 0 ;1
L 1.3325 2.1325 1.3325 2.1325 9 P 0 ;1
L 1.3325 2.1825 1.3325 2.1825 9 P 0 ;1
L 1.3325 2.2325 1.3325 2.2325 9 P 0 ;1
L 1.3325 2.2825 1.3325 2.2825 9 P 0 ;1
L 1.3325 2.3325 1.3325 2.3325 9 P 0 ;1
L 1.3325 2.3825 1.3325 2.3825 9 P 0 ;1
L 1.3325 2.8825 1.3325 2.8825 9 P 0 ;1
L 1.3325 2.9325 1.3325 2.9325 9 P 0 ;1
L 1.3325 2.9825 1.3325 2.9825 9 P 0 ;1
L 1.3325 3.0325 1.3325 3.0325 9 P 0 ;1
L 1.3325 3.0825 1.3325 3.0825 9 P 0 ;1
L 1.3325 3.1325 1.3325 3.1325 9 P 0 ;1
L 1.3325 3.1825 1.3325 3.1825 9 P 0 ;1
L 1.3325 3.2325 1.3325 3.2325 9 P 0 ;1
L 1.3325 3.2825 1.3325 3.2825 9 P 0 ;1
L 1.3325 3.3325 1.3325 3.3325 9 P 0 ;1
L 1.3325 3.3825 1.3325 3.3825 9 P 0 ;1
L 1.3325 3.4325 1.3325 3.4325 9 P 0 ;1
L 1.3325 3.4825 1.3325 3.4825 9 P 0 ;1
L 1.3325 3.5325 1.3325 3.5325 9 P 0 ;1
L 1.3325 3.5825 1.3325 3.5825 9 P 0 ;1
L 1.3325 3.6325 1.3325 3.6325 9 P 0 ;1
L 1.3325 3.6825 1.3325 3.6825 9 P 0 ;1
L 1.3325 3.7325 1.3325 3.7325 9 P 0 ;1
L 1.3325 3.7825 1.3325 3.7825 9 P 0 ;1
L 1.3325 3.8325 1.3325 3.8325 9 P 0 ;1
L 1.3325 3.8825 1.3325 3.8825 9 P 0 ;1
L 1.3325 3.9325 1.3325 3.9325 9 P 0 ;1
L 1.3325 3.9825 1.3325 3.9825 9 P 0 ;1
L 1.3325 4.0325 1.3325 4.0325 9 P 0 ;1
L 1.3325 4.0825 1.3325 4.0825 9 P 0 ;1
L 1.3325 4.1325 1.3325 4.1325 9 P 0 ;1
L 1.3325 4.1825 1.3325 4.1825 9 P 0 ;1
L 1.3325 4.2325 1.3325 4.2325 9 P 0 ;1
L 1.3325 4.2825 1.3325 4.2825 9 P 0 ;1
L 1.3325 5.2325 1.3325 5.2325 9 P 0 ;1
L 1.3325 5.5825 1.3325 5.5825 9 P 0 ;1
L 1.3325 5.6325 1.3325 5.6325 9 P 0 ;1
L 1.3325 5.6825 1.3325 5.6825 9 P 0 ;1
L 1.3825 0.1325 1.3825 0.1325 9 P 0 ;1
L 1.3825 0.1825 1.3825 0.1825 9 P 0 ;1
L 1.3825 0.2325 1.3825 0.2325 9 P 0 ;1
L 1.3825 0.2825 1.3825 0.2825 9 P 0 ;1
L 1.3825 0.3325 1.3825 0.3325 9 P 0 ;1
L 1.3825 0.3825 1.3825 0.3825 9 P 0 ;1
L 1.3825 0.4325 1.3825 0.4325 9 P 0 ;1
L 1.3825 0.4825 1.3825 0.4825 9 P 0 ;1
L 1.3825 0.5325 1.3825 0.5325 9 P 0 ;1
L 1.3825 0.5825 1.3825 0.5825 9 P 0 ;1
L 1.3825 0.6325 1.3825 0.6325 9 P 0 ;1
L 1.3825 0.6825 1.3825 0.6825 9 P 0 ;1
L 1.3825 0.7325 1.3825 0.7325 9 P 0 ;1
L 1.3825 0.7825 1.3825 0.7825 9 P 0 ;1
L 1.3825 0.8325 1.3825 0.8325 9 P 0 ;1
L 1.3825 0.8825 1.3825 0.8825 9 P 0 ;1
L 1.3825 0.9325 1.3825 0.9325 9 P 0 ;1
L 1.3825 0.9825 1.3825 0.9825 9 P 0 ;1
L 1.3825 1.1825 1.3825 1.1825 9 P 0 ;1
L 1.3825 1.2325 1.3825 1.2325 9 P 0 ;1
L 1.3825 1.2825 1.3825 1.2825 9 P 0 ;1
L 1.3825 1.3325 1.3825 1.3325 9 P 0 ;1
L 1.3825 1.3825 1.3825 1.3825 9 P 0 ;1
L 1.3825 1.9825 1.3825 1.9825 9 P 0 ;1
L 1.3825 2.0325 1.3825 2.0325 9 P 0 ;1
L 1.3825 2.0825 1.3825 2.0825 9 P 0 ;1
L 1.3825 2.1325 1.3825 2.1325 9 P 0 ;1
L 1.3825 2.1825 1.3825 2.1825 9 P 0 ;1
L 1.3825 2.2325 1.3825 2.2325 9 P 0 ;1
L 1.3825 2.2825 1.3825 2.2825 9 P 0 ;1
L 1.3825 2.3325 1.3825 2.3325 9 P 0 ;1
L 1.3825 2.8325 1.3825 2.8325 9 P 0 ;1
L 1.3825 2.8825 1.3825 2.8825 9 P 0 ;1
L 1.3825 2.9325 1.3825 2.9325 9 P 0 ;1
L 1.3825 2.9825 1.3825 2.9825 9 P 0 ;1
L 1.3825 3.0325 1.3825 3.0325 9 P 0 ;1
L 1.3825 3.0825 1.3825 3.0825 9 P 0 ;1
L 1.3825 3.1325 1.3825 3.1325 9 P 0 ;1
L 1.3825 3.1825 1.3825 3.1825 9 P 0 ;1
L 1.3825 3.2325 1.3825 3.2325 9 P 0 ;1
L 1.3825 3.2825 1.3825 3.2825 9 P 0 ;1
L 1.3825 3.3325 1.3825 3.3325 9 P 0 ;1
L 1.3825 3.3825 1.3825 3.3825 9 P 0 ;1
L 1.3825 3.4325 1.3825 3.4325 9 P 0 ;1
L 1.3825 3.4825 1.3825 3.4825 9 P 0 ;1
L 1.3825 3.5325 1.3825 3.5325 9 P 0 ;1
L 1.3825 3.5825 1.3825 3.5825 9 P 0 ;1
L 1.3825 3.6325 1.3825 3.6325 9 P 0 ;1
L 1.3825 3.6825 1.3825 3.6825 9 P 0 ;1
L 1.3825 3.7325 1.3825 3.7325 9 P 0 ;1
L 1.3825 3.7825 1.3825 3.7825 9 P 0 ;1
L 1.3825 3.8325 1.3825 3.8325 9 P 0 ;1
L 1.3825 3.8825 1.3825 3.8825 9 P 0 ;1
L 1.3825 3.9325 1.3825 3.9325 9 P 0 ;1
L 1.3825 3.9825 1.3825 3.9825 9 P 0 ;1
L 1.3825 4.0325 1.3825 4.0325 9 P 0 ;1
L 1.3825 4.0825 1.3825 4.0825 9 P 0 ;1
L 1.3825 4.1325 1.3825 4.1325 9 P 0 ;1
L 1.3825 4.1825 1.3825 4.1825 9 P 0 ;1
L 1.3825 4.2325 1.3825 4.2325 9 P 0 ;1
L 1.3825 4.2825 1.3825 4.2825 9 P 0 ;1
L 1.3825 4.5325 1.3825 4.5325 9 P 0 ;1
L 1.3825 4.7825 1.3825 4.7825 9 P 0 ;1
L 1.3825 4.9325 1.3825 4.9325 9 P 0 ;1
L 1.3825 4.9825 1.3825 4.9825 9 P 0 ;1
L 1.3825 5.0325 1.3825 5.0325 9 P 0 ;1
L 1.3825 5.2325 1.3825 5.2325 9 P 0 ;1
L 1.3825 5.5825 1.3825 5.5825 9 P 0 ;1
L 1.3825 5.6325 1.3825 5.6325 9 P 0 ;1
L 1.3825 5.6825 1.3825 5.6825 9 P 0 ;1
L 1.4325 0.1325 1.4325 0.1325 9 P 0 ;1
L 1.4325 0.1825 1.4325 0.1825 9 P 0 ;1
L 1.4325 0.2325 1.4325 0.2325 9 P 0 ;1
L 1.4325 0.2825 1.4325 0.2825 9 P 0 ;1
L 1.4325 0.3325 1.4325 0.3325 9 P 0 ;1
L 1.4325 0.3825 1.4325 0.3825 9 P 0 ;1
L 1.4325 0.4325 1.4325 0.4325 9 P 0 ;1
L 1.4325 0.4825 1.4325 0.4825 9 P 0 ;1
L 1.4325 0.5325 1.4325 0.5325 9 P 0 ;1
L 1.4325 0.5825 1.4325 0.5825 9 P 0 ;1
L 1.4325 0.6325 1.4325 0.6325 9 P 0 ;1
L 1.4325 0.6825 1.4325 0.6825 9 P 0 ;1
L 1.4325 0.7325 1.4325 0.7325 9 P 0 ;1
L 1.4325 0.7825 1.4325 0.7825 9 P 0 ;1
L 1.4325 0.8325 1.4325 0.8325 9 P 0 ;1
L 1.4325 0.8825 1.4325 0.8825 9 P 0 ;1
L 1.4325 0.9325 1.4325 0.9325 9 P 0 ;1
L 1.4325 1.1825 1.4325 1.1825 9 P 0 ;1
L 1.4325 1.2325 1.4325 1.2325 9 P 0 ;1
L 1.4325 1.2825 1.4325 1.2825 9 P 0 ;1
L 1.4325 1.3325 1.4325 1.3325 9 P 0 ;1
L 1.4325 1.9325 1.4325 1.9325 9 P 0 ;1
L 1.4325 1.9825 1.4325 1.9825 9 P 0 ;1
L 1.4325 2.0325 1.4325 2.0325 9 P 0 ;1
L 1.4325 2.0825 1.4325 2.0825 9 P 0 ;1
L 1.4325 2.1325 1.4325 2.1325 9 P 0 ;1
L 1.4325 2.1825 1.4325 2.1825 9 P 0 ;1
L 1.4325 2.2325 1.4325 2.2325 9 P 0 ;1
L 1.4325 2.7325 1.4325 2.7325 9 P 0 ;1
L 1.4325 2.7825 1.4325 2.7825 9 P 0 ;1
L 1.4325 2.8325 1.4325 2.8325 9 P 0 ;1
L 1.4325 2.8825 1.4325 2.8825 9 P 0 ;1
L 1.4325 2.9325 1.4325 2.9325 9 P 0 ;1
L 1.4325 2.9825 1.4325 2.9825 9 P 0 ;1
L 1.4325 3.0325 1.4325 3.0325 9 P 0 ;1
L 1.4325 3.0825 1.4325 3.0825 9 P 0 ;1
L 1.4325 3.1325 1.4325 3.1325 9 P 0 ;1
L 1.4325 3.1825 1.4325 3.1825 9 P 0 ;1
L 1.4325 3.2325 1.4325 3.2325 9 P 0 ;1
L 1.4325 3.2825 1.4325 3.2825 9 P 0 ;1
L 1.4325 3.3325 1.4325 3.3325 9 P 0 ;1
L 1.4325 3.3825 1.4325 3.3825 9 P 0 ;1
L 1.4325 3.4325 1.4325 3.4325 9 P 0 ;1
L 1.4325 3.4825 1.4325 3.4825 9 P 0 ;1
L 1.4325 3.5325 1.4325 3.5325 9 P 0 ;1
L 1.4325 3.5825 1.4325 3.5825 9 P 0 ;1
L 1.4325 3.6325 1.4325 3.6325 9 P 0 ;1
L 1.4325 3.6825 1.4325 3.6825 9 P 0 ;1
L 1.4325 3.7325 1.4325 3.7325 9 P 0 ;1
L 1.4325 3.7825 1.4325 3.7825 9 P 0 ;1
L 1.4325 3.8325 1.4325 3.8325 9 P 0 ;1
L 1.4325 3.8825 1.4325 3.8825 9 P 0 ;1
L 1.4325 3.9325 1.4325 3.9325 9 P 0 ;1
L 1.4325 3.9825 1.4325 3.9825 9 P 0 ;1
L 1.4325 4.0325 1.4325 4.0325 9 P 0 ;1
L 1.4325 4.0825 1.4325 4.0825 9 P 0 ;1
L 1.4325 4.1325 1.4325 4.1325 9 P 0 ;1
L 1.4325 4.1825 1.4325 4.1825 9 P 0 ;1
L 1.4325 4.2325 1.4325 4.2325 9 P 0 ;1
L 1.4325 4.5325 1.4325 4.5325 9 P 0 ;1
L 1.4325 4.5825 1.4325 4.5825 9 P 0 ;1
L 1.4325 4.6325 1.4325 4.6325 9 P 0 ;1
L 1.4325 4.6825 1.4325 4.6825 9 P 0 ;1
L 1.4325 4.7325 1.4325 4.7325 9 P 0 ;1
L 1.4325 4.8325 1.4325 4.8325 9 P 0 ;1
L 1.4325 4.8825 1.4325 4.8825 9 P 0 ;1
L 1.4325 4.9325 1.4325 4.9325 9 P 0 ;1
L 1.4325 4.9825 1.4325 4.9825 9 P 0 ;1
L 1.4325 5.0325 1.4325 5.0325 9 P 0 ;1
L 1.4325 5.0825 1.4325 5.0825 9 P 0 ;1
L 1.4325 5.2325 1.4325 5.2325 9 P 0 ;1
L 1.4825 0.1325 1.4825 0.1325 9 P 0 ;1
L 1.4825 0.1825 1.4825 0.1825 9 P 0 ;1
L 1.4825 0.2325 1.4825 0.2325 9 P 0 ;1
L 1.4825 0.2825 1.4825 0.2825 9 P 0 ;1
L 1.4825 0.3325 1.4825 0.3325 9 P 0 ;1
L 1.4825 0.3825 1.4825 0.3825 9 P 0 ;1
L 1.4825 0.4325 1.4825 0.4325 9 P 0 ;1
L 1.4825 0.4825 1.4825 0.4825 9 P 0 ;1
L 1.4825 0.5325 1.4825 0.5325 9 P 0 ;1
L 1.4825 0.5825 1.4825 0.5825 9 P 0 ;1
L 1.4825 0.6325 1.4825 0.6325 9 P 0 ;1
L 1.4825 0.6825 1.4825 0.6825 9 P 0 ;1
L 1.4825 0.7325 1.4825 0.7325 9 P 0 ;1
L 1.4825 0.7825 1.4825 0.7825 9 P 0 ;1
L 1.4825 0.8325 1.4825 0.8325 9 P 0 ;1
L 1.4825 0.8825 1.4825 0.8825 9 P 0 ;1
L 1.4825 0.9325 1.4825 0.9325 9 P 0 ;1
L 1.4825 1.1325 1.4825 1.1325 9 P 0 ;1
L 1.4825 1.1825 1.4825 1.1825 9 P 0 ;1
L 1.4825 1.2325 1.4825 1.2325 9 P 0 ;1
L 1.4825 1.2825 1.4825 1.2825 9 P 0 ;1
L 1.4825 1.8825 1.4825 1.8825 9 P 0 ;1
L 1.4825 1.9325 1.4825 1.9325 9 P 0 ;1
L 1.4825 1.9825 1.4825 1.9825 9 P 0 ;1
L 1.4825 2.0325 1.4825 2.0325 9 P 0 ;1
L 1.4825 2.0825 1.4825 2.0825 9 P 0 ;1
L 1.4825 2.1325 1.4825 2.1325 9 P 0 ;1
L 1.4825 2.1825 1.4825 2.1825 9 P 0 ;1
L 1.4825 2.6825 1.4825 2.6825 9 P 0 ;1
L 1.4825 2.7325 1.4825 2.7325 9 P 0 ;1
L 1.4825 2.7825 1.4825 2.7825 9 P 0 ;1
L 1.4825 2.8325 1.4825 2.8325 9 P 0 ;1
L 1.4825 2.8825 1.4825 2.8825 9 P 0 ;1
L 1.4825 2.9325 1.4825 2.9325 9 P 0 ;1
L 1.4825 2.9825 1.4825 2.9825 9 P 0 ;1
L 1.4825 3.0325 1.4825 3.0325 9 P 0 ;1
L 1.4825 3.0825 1.4825 3.0825 9 P 0 ;1
L 1.4825 3.1325 1.4825 3.1325 9 P 0 ;1
L 1.4825 3.1825 1.4825 3.1825 9 P 0 ;1
L 1.4825 3.2325 1.4825 3.2325 9 P 0 ;1
L 1.4825 3.2825 1.4825 3.2825 9 P 0 ;1
L 1.4825 3.3325 1.4825 3.3325 9 P 0 ;1
L 1.4825 3.3825 1.4825 3.3825 9 P 0 ;1
L 1.4825 3.4325 1.4825 3.4325 9 P 0 ;1
L 1.4825 3.4825 1.4825 3.4825 9 P 0 ;1
L 1.4825 3.5325 1.4825 3.5325 9 P 0 ;1
L 1.4825 3.5825 1.4825 3.5825 9 P 0 ;1
L 1.4825 3.6325 1.4825 3.6325 9 P 0 ;1
L 1.4825 3.6825 1.4825 3.6825 9 P 0 ;1
L 1.4825 3.7325 1.4825 3.7325 9 P 0 ;1
L 1.4825 3.7825 1.4825 3.7825 9 P 0 ;1
L 1.4825 3.8325 1.4825 3.8325 9 P 0 ;1
L 1.4825 3.8825 1.4825 3.8825 9 P 0 ;1
L 1.4825 3.9325 1.4825 3.9325 9 P 0 ;1
L 1.4825 3.9825 1.4825 3.9825 9 P 0 ;1
L 1.4825 4.0325 1.4825 4.0325 9 P 0 ;1
L 1.4825 4.0825 1.4825 4.0825 9 P 0 ;1
L 1.4825 4.1325 1.4825 4.1325 9 P 0 ;1
L 1.4825 4.1825 1.4825 4.1825 9 P 0 ;1
L 1.4825 4.2325 1.4825 4.2325 9 P 0 ;1
L 1.4825 4.5325 1.4825 4.5325 9 P 0 ;1
L 1.4825 4.5825 1.4825 4.5825 9 P 0 ;1
L 1.4825 4.6325 1.4825 4.6325 9 P 0 ;1
L 1.4825 4.6825 1.4825 4.6825 9 P 0 ;1
L 1.4825 5.1325 1.4825 5.1325 9 P 0 ;1
L 1.4825 5.1825 1.4825 5.1825 9 P 0 ;1
L 1.4825 5.2325 1.4825 5.2325 9 P 0 ;1
L 1.5325 0.1325 1.5325 0.1325 9 P 0 ;1
L 1.5325 0.1825 1.5325 0.1825 9 P 0 ;1
L 1.5325 0.2325 1.5325 0.2325 9 P 0 ;1
L 1.5325 0.2825 1.5325 0.2825 9 P 0 ;1
L 1.5325 0.3325 1.5325 0.3325 9 P 0 ;1
L 1.5325 0.3825 1.5325 0.3825 9 P 0 ;1
L 1.5325 0.4325 1.5325 0.4325 9 P 0 ;1
L 1.5325 0.4825 1.5325 0.4825 9 P 0 ;1
L 1.5325 0.5325 1.5325 0.5325 9 P 0 ;1
L 1.5325 0.5825 1.5325 0.5825 9 P 0 ;1
L 1.5325 0.6325 1.5325 0.6325 9 P 0 ;1
L 1.5325 0.6825 1.5325 0.6825 9 P 0 ;1
L 1.5325 0.7325 1.5325 0.7325 9 P 0 ;1
L 1.5325 0.7825 1.5325 0.7825 9 P 0 ;1
L 1.5325 0.8325 1.5325 0.8325 9 P 0 ;1
L 1.5325 0.8825 1.5325 0.8825 9 P 0 ;1
L 1.5325 0.9325 1.5325 0.9325 9 P 0 ;1
L 1.5325 1.1325 1.5325 1.1325 9 P 0 ;1
L 1.5325 1.1825 1.5325 1.1825 9 P 0 ;1
L 1.5325 1.2325 1.5325 1.2325 9 P 0 ;1
L 1.5325 1.2825 1.5325 1.2825 9 P 0 ;1
L 1.5325 1.8325 1.5325 1.8325 9 P 0 ;1
L 1.5325 1.8825 1.5325 1.8825 9 P 0 ;1
L 1.5325 1.9325 1.5325 1.9325 9 P 0 ;1
L 1.5325 1.9825 1.5325 1.9825 9 P 0 ;1
L 1.5325 2.0325 1.5325 2.0325 9 P 0 ;1
L 1.5325 2.0825 1.5325 2.0825 9 P 0 ;1
L 1.5325 2.1325 1.5325 2.1325 9 P 0 ;1
L 1.5325 2.5825 1.5325 2.5825 9 P 0 ;1
L 1.5325 2.6325 1.5325 2.6325 9 P 0 ;1
L 1.5325 2.6825 1.5325 2.6825 9 P 0 ;1
L 1.5325 2.7325 1.5325 2.7325 9 P 0 ;1
L 1.5325 2.7825 1.5325 2.7825 9 P 0 ;1
L 1.5325 2.8325 1.5325 2.8325 9 P 0 ;1
L 1.5325 2.8825 1.5325 2.8825 9 P 0 ;1
L 1.5325 2.9325 1.5325 2.9325 9 P 0 ;1
L 1.5325 2.9825 1.5325 2.9825 9 P 0 ;1
L 1.5325 3.0325 1.5325 3.0325 9 P 0 ;1
L 1.5325 3.0825 1.5325 3.0825 9 P 0 ;1
L 1.5325 3.1325 1.5325 3.1325 9 P 0 ;1
L 1.5325 3.1825 1.5325 3.1825 9 P 0 ;1
L 1.5325 3.2325 1.5325 3.2325 9 P 0 ;1
L 1.5325 3.2825 1.5325 3.2825 9 P 0 ;1
L 1.5325 3.3325 1.5325 3.3325 9 P 0 ;1
L 1.5325 3.3825 1.5325 3.3825 9 P 0 ;1
L 1.5325 3.4325 1.5325 3.4325 9 P 0 ;1
L 1.5325 3.4825 1.5325 3.4825 9 P 0 ;1
L 1.5325 3.5325 1.5325 3.5325 9 P 0 ;1
L 1.5325 3.5825 1.5325 3.5825 9 P 0 ;1
L 1.5325 3.6325 1.5325 3.6325 9 P 0 ;1
L 1.5325 3.6825 1.5325 3.6825 9 P 0 ;1
L 1.5325 3.7325 1.5325 3.7325 9 P 0 ;1
L 1.5325 3.7825 1.5325 3.7825 9 P 0 ;1
L 1.5325 3.8325 1.5325 3.8325 9 P 0 ;1
L 1.5325 3.8825 1.5325 3.8825 9 P 0 ;1
L 1.5325 3.9325 1.5325 3.9325 9 P 0 ;1
L 1.5325 3.9825 1.5325 3.9825 9 P 0 ;1
L 1.5325 4.0325 1.5325 4.0325 9 P 0 ;1
L 1.5325 4.0825 1.5325 4.0825 9 P 0 ;1
L 1.5325 4.1325 1.5325 4.1325 9 P 0 ;1
L 1.5325 4.1825 1.5325 4.1825 9 P 0 ;1
L 1.5325 4.2325 1.5325 4.2325 9 P 0 ;1
L 1.5325 4.4825 1.5325 4.4825 9 P 0 ;1
L 1.5325 4.5325 1.5325 4.5325 9 P 0 ;1
L 1.5325 4.5825 1.5325 4.5825 9 P 0 ;1
L 1.5325 5.2825 1.5325 5.2825 9 P 0 ;1
L 1.5825 0.1325 1.5825 0.1325 9 P 0 ;1
L 1.5825 0.1825 1.5825 0.1825 9 P 0 ;1
L 1.5825 0.2325 1.5825 0.2325 9 P 0 ;1
L 1.5825 0.2825 1.5825 0.2825 9 P 0 ;1
L 1.5825 0.3325 1.5825 0.3325 9 P 0 ;1
L 1.5825 0.3825 1.5825 0.3825 9 P 0 ;1
L 1.5825 0.4325 1.5825 0.4325 9 P 0 ;1
L 1.5825 0.4825 1.5825 0.4825 9 P 0 ;1
L 1.5825 0.5325 1.5825 0.5325 9 P 0 ;1
L 1.5825 0.5825 1.5825 0.5825 9 P 0 ;1
L 1.5825 0.6325 1.5825 0.6325 9 P 0 ;1
L 1.5825 0.6825 1.5825 0.6825 9 P 0 ;1
L 1.5825 0.7325 1.5825 0.7325 9 P 0 ;1
L 1.5825 0.7825 1.5825 0.7825 9 P 0 ;1
L 1.5825 0.8325 1.5825 0.8325 9 P 0 ;1
L 1.5825 0.8825 1.5825 0.8825 9 P 0 ;1
L 1.5825 0.9325 1.5825 0.9325 9 P 0 ;1
L 1.5825 1.1325 1.5825 1.1325 9 P 0 ;1
L 1.5825 1.1825 1.5825 1.1825 9 P 0 ;1
L 1.5825 1.2325 1.5825 1.2325 9 P 0 ;1
L 1.5825 1.8325 1.5825 1.8325 9 P 0 ;1
L 1.5825 1.8825 1.5825 1.8825 9 P 0 ;1
L 1.5825 1.9325 1.5825 1.9325 9 P 0 ;1
L 1.5825 1.9825 1.5825 1.9825 9 P 0 ;1
L 1.5825 2.0325 1.5825 2.0325 9 P 0 ;1
L 1.5825 2.5325 1.5825 2.5325 9 P 0 ;1
L 1.5825 2.5825 1.5825 2.5825 9 P 0 ;1
L 1.5825 2.6325 1.5825 2.6325 9 P 0 ;1
L 1.5825 2.6825 1.5825 2.6825 9 P 0 ;1
L 1.5825 2.7325 1.5825 2.7325 9 P 0 ;1
L 1.5825 2.7825 1.5825 2.7825 9 P 0 ;1
L 1.5825 2.8325 1.5825 2.8325 9 P 0 ;1
L 1.5825 2.8825 1.5825 2.8825 9 P 0 ;1
L 1.5825 2.9325 1.5825 2.9325 9 P 0 ;1
L 1.5825 2.9825 1.5825 2.9825 9 P 0 ;1
L 1.5825 3.0325 1.5825 3.0325 9 P 0 ;1
L 1.5825 3.0825 1.5825 3.0825 9 P 0 ;1
L 1.5825 3.1325 1.5825 3.1325 9 P 0 ;1
L 1.5825 3.1825 1.5825 3.1825 9 P 0 ;1
L 1.5825 3.2325 1.5825 3.2325 9 P 0 ;1
L 1.5825 3.2825 1.5825 3.2825 9 P 0 ;1
L 1.5825 3.3325 1.5825 3.3325 9 P 0 ;1
L 1.5825 3.3825 1.5825 3.3825 9 P 0 ;1
L 1.5825 3.4325 1.5825 3.4325 9 P 0 ;1
L 1.5825 3.4825 1.5825 3.4825 9 P 0 ;1
L 1.5825 3.5325 1.5825 3.5325 9 P 0 ;1
L 1.5825 3.5825 1.5825 3.5825 9 P 0 ;1
L 1.5825 3.6325 1.5825 3.6325 9 P 0 ;1
L 1.5825 3.6825 1.5825 3.6825 9 P 0 ;1
L 1.5825 3.7325 1.5825 3.7325 9 P 0 ;1
L 1.5825 3.7825 1.5825 3.7825 9 P 0 ;1
L 1.5825 3.8325 1.5825 3.8325 9 P 0 ;1
L 1.5825 3.8825 1.5825 3.8825 9 P 0 ;1
L 1.5825 3.9325 1.5825 3.9325 9 P 0 ;1
L 1.5825 3.9825 1.5825 3.9825 9 P 0 ;1
L 1.5825 4.0325 1.5825 4.0325 9 P 0 ;1
L 1.5825 4.0825 1.5825 4.0825 9 P 0 ;1
L 1.5825 4.1325 1.5825 4.1325 9 P 0 ;1
L 1.5825 4.1825 1.5825 4.1825 9 P 0 ;1
L 1.5825 4.4825 1.5825 4.4825 9 P 0 ;1
L 1.5825 4.5325 1.5825 4.5325 9 P 0 ;1
L 1.5825 4.5825 1.5825 4.5825 9 P 0 ;1
L 1.5825 5.2825 1.5825 5.2825 9 P 0 ;1
L 1.5825 5.3325 1.5825 5.3325 9 P 0 ;1
L 1.5825 5.3825 1.5825 5.3825 9 P 0 ;1
L 1.5825 5.5325 1.5825 5.5325 9 P 0 ;1
L 1.5825 5.5825 1.5825 5.5825 9 P 0 ;1
L 1.5825 5.6325 1.5825 5.6325 9 P 0 ;1
L 1.5825 5.6825 1.5825 5.6825 9 P 0 ;1
L 1.5825 5.7325 1.5825 5.7325 9 P 0 ;1
L 1.5825 5.8325 1.5825 5.8325 9 P 0 ;1
L 1.5825 5.8825 1.5825 5.8825 9 P 0 ;1
L 1.6325 0.1325 1.6325 0.1325 9 P 0 ;1
L 1.6325 0.1825 1.6325 0.1825 9 P 0 ;1
L 1.6325 0.2325 1.6325 0.2325 9 P 0 ;1
L 1.6325 0.2825 1.6325 0.2825 9 P 0 ;1
L 1.6325 0.3325 1.6325 0.3325 9 P 0 ;1
L 1.6325 0.3825 1.6325 0.3825 9 P 0 ;1
L 1.6325 0.4325 1.6325 0.4325 9 P 0 ;1
L 1.6325 0.4825 1.6325 0.4825 9 P 0 ;1
L 1.6325 0.5325 1.6325 0.5325 9 P 0 ;1
L 1.6325 0.5825 1.6325 0.5825 9 P 0 ;1
L 1.6325 0.6325 1.6325 0.6325 9 P 0 ;1
L 1.6325 0.6825 1.6325 0.6825 9 P 0 ;1
L 1.6325 0.7325 1.6325 0.7325 9 P 0 ;1
L 1.6325 0.7825 1.6325 0.7825 9 P 0 ;1
L 1.6325 0.8325 1.6325 0.8325 9 P 0 ;1
L 1.6325 0.8825 1.6325 0.8825 9 P 0 ;1
L 1.6325 0.9325 1.6325 0.9325 9 P 0 ;1
L 1.6325 1.1325 1.6325 1.1325 9 P 0 ;1
L 1.6325 1.1825 1.6325 1.1825 9 P 0 ;1
L 1.6325 1.7825 1.6325 1.7825 9 P 0 ;1
L 1.6325 1.8325 1.6325 1.8325 9 P 0 ;1
L 1.6325 1.8825 1.6325 1.8825 9 P 0 ;1
L 1.6325 1.9325 1.6325 1.9325 9 P 0 ;1
L 1.6325 1.9825 1.6325 1.9825 9 P 0 ;1
L 1.6325 2.4325 1.6325 2.4325 9 P 0 ;1
L 1.6325 2.4825 1.6325 2.4825 9 P 0 ;1
L 1.6325 2.5325 1.6325 2.5325 9 P 0 ;1
L 1.6325 2.5825 1.6325 2.5825 9 P 0 ;1
L 1.6325 2.6325 1.6325 2.6325 9 P 0 ;1
L 1.6325 2.6825 1.6325 2.6825 9 P 0 ;1
L 1.6325 2.7325 1.6325 2.7325 9 P 0 ;1
L 1.6325 2.7825 1.6325 2.7825 9 P 0 ;1
L 1.6325 2.8325 1.6325 2.8325 9 P 0 ;1
L 1.6325 2.8825 1.6325 2.8825 9 P 0 ;1
L 1.6325 2.9325 1.6325 2.9325 9 P 0 ;1
L 1.6325 2.9825 1.6325 2.9825 9 P 0 ;1
L 1.6325 3.0325 1.6325 3.0325 9 P 0 ;1
L 1.6325 3.0825 1.6325 3.0825 9 P 0 ;1
L 1.6325 3.1325 1.6325 3.1325 9 P 0 ;1
L 1.6325 3.1825 1.6325 3.1825 9 P 0 ;1
L 1.6325 3.2325 1.6325 3.2325 9 P 0 ;1
L 1.6325 3.2825 1.6325 3.2825 9 P 0 ;1
L 1.6325 3.3325 1.6325 3.3325 9 P 0 ;1
L 1.6325 3.3825 1.6325 3.3825 9 P 0 ;1
L 1.6325 3.4325 1.6325 3.4325 9 P 0 ;1
L 1.6325 3.4825 1.6325 3.4825 9 P 0 ;1
L 1.6325 3.5325 1.6325 3.5325 9 P 0 ;1
L 1.6325 3.5825 1.6325 3.5825 9 P 0 ;1
L 1.6325 3.6325 1.6325 3.6325 9 P 0 ;1
L 1.6325 3.6825 1.6325 3.6825 9 P 0 ;1
L 1.6325 3.7325 1.6325 3.7325 9 P 0 ;1
L 1.6325 3.7825 1.6325 3.7825 9 P 0 ;1
L 1.6325 3.8325 1.6325 3.8325 9 P 0 ;1
L 1.6325 3.8825 1.6325 3.8825 9 P 0 ;1
L 1.6325 3.9325 1.6325 3.9325 9 P 0 ;1
L 1.6325 3.9825 1.6325 3.9825 9 P 0 ;1
L 1.6325 4.0325 1.6325 4.0325 9 P 0 ;1
L 1.6325 4.0825 1.6325 4.0825 9 P 0 ;1
L 1.6325 4.1325 1.6325 4.1325 9 P 0 ;1
L 1.6325 4.4825 1.6325 4.4825 9 P 0 ;1
L 1.6325 4.5325 1.6325 4.5325 9 P 0 ;1
L 1.6325 4.5825 1.6325 4.5825 9 P 0 ;1
L 1.6325 5.2825 1.6325 5.2825 9 P 0 ;1
L 1.6325 5.3325 1.6325 5.3325 9 P 0 ;1
L 1.6325 5.3825 1.6325 5.3825 9 P 0 ;1
L 1.6325 5.4325 1.6325 5.4325 9 P 0 ;1
L 1.6325 5.4825 1.6325 5.4825 9 P 0 ;1
L 1.6325 5.5325 1.6325 5.5325 9 P 0 ;1
L 1.6325 5.5825 1.6325 5.5825 9 P 0 ;1
L 1.6325 5.6325 1.6325 5.6325 9 P 0 ;1
L 1.6325 5.6825 1.6325 5.6825 9 P 0 ;1
L 1.6325 5.7325 1.6325 5.7325 9 P 0 ;1
L 1.6325 5.7825 1.6325 5.7825 9 P 0 ;1
L 1.6325 5.8325 1.6325 5.8325 9 P 0 ;1
L 1.6325 5.8825 1.6325 5.8825 9 P 0 ;1
L 1.6825 0.1325 1.6825 0.1325 9 P 0 ;1
L 1.6825 0.1825 1.6825 0.1825 9 P 0 ;1
L 1.6825 0.2325 1.6825 0.2325 9 P 0 ;1
L 1.6825 0.2825 1.6825 0.2825 9 P 0 ;1
L 1.6825 0.3325 1.6825 0.3325 9 P 0 ;1
L 1.6825 0.3825 1.6825 0.3825 9 P 0 ;1
L 1.6825 0.4325 1.6825 0.4325 9 P 0 ;1
L 1.6825 0.4825 1.6825 0.4825 9 P 0 ;1
L 1.6825 0.5325 1.6825 0.5325 9 P 0 ;1
L 1.6825 0.5825 1.6825 0.5825 9 P 0 ;1
L 1.6825 0.6325 1.6825 0.6325 9 P 0 ;1
L 1.6825 0.6825 1.6825 0.6825 9 P 0 ;1
L 1.6825 0.7325 1.6825 0.7325 9 P 0 ;1
L 1.6825 0.7825 1.6825 0.7825 9 P 0 ;1
L 1.6825 0.8325 1.6825 0.8325 9 P 0 ;1
L 1.6825 0.8825 1.6825 0.8825 9 P 0 ;1
L 1.6825 0.9325 1.6825 0.9325 9 P 0 ;1
L 1.6825 1.1325 1.6825 1.1325 9 P 0 ;1
L 1.6825 1.1825 1.6825 1.1825 9 P 0 ;1
L 1.6825 1.7325 1.6825 1.7325 9 P 0 ;1
L 1.6825 1.7825 1.6825 1.7825 9 P 0 ;1
L 1.6825 1.8325 1.6825 1.8325 9 P 0 ;1
L 1.6825 1.8825 1.6825 1.8825 9 P 0 ;1
L 1.6825 2.3825 1.6825 2.3825 9 P 0 ;1
L 1.6825 2.4325 1.6825 2.4325 9 P 0 ;1
L 1.6825 2.4825 1.6825 2.4825 9 P 0 ;1
L 1.6825 2.5325 1.6825 2.5325 9 P 0 ;1
L 1.6825 2.5825 1.6825 2.5825 9 P 0 ;1
L 1.6825 2.6325 1.6825 2.6325 9 P 0 ;1
L 1.6825 2.6825 1.6825 2.6825 9 P 0 ;1
L 1.6825 2.7325 1.6825 2.7325 9 P 0 ;1
L 1.6825 2.7825 1.6825 2.7825 9 P 0 ;1
L 1.6825 2.8325 1.6825 2.8325 9 P 0 ;1
L 1.6825 2.8825 1.6825 2.8825 9 P 0 ;1
L 1.6825 2.9325 1.6825 2.9325 9 P 0 ;1
L 1.6825 2.9825 1.6825 2.9825 9 P 0 ;1
L 1.6825 3.0325 1.6825 3.0325 9 P 0 ;1
L 1.6825 3.0825 1.6825 3.0825 9 P 0 ;1
L 1.6825 3.1325 1.6825 3.1325 9 P 0 ;1
L 1.6825 3.1825 1.6825 3.1825 9 P 0 ;1
L 1.6825 3.2325 1.6825 3.2325 9 P 0 ;1
L 1.6825 3.2825 1.6825 3.2825 9 P 0 ;1
L 1.6825 3.3325 1.6825 3.3325 9 P 0 ;1
L 1.6825 3.3825 1.6825 3.3825 9 P 0 ;1
L 1.6825 3.4325 1.6825 3.4325 9 P 0 ;1
L 1.6825 3.4825 1.6825 3.4825 9 P 0 ;1
L 1.6825 3.5325 1.6825 3.5325 9 P 0 ;1
L 1.6825 3.5825 1.6825 3.5825 9 P 0 ;1
L 1.6825 3.6325 1.6825 3.6325 9 P 0 ;1
L 1.6825 3.6825 1.6825 3.6825 9 P 0 ;1
L 1.6825 3.7325 1.6825 3.7325 9 P 0 ;1
L 1.6825 3.7825 1.6825 3.7825 9 P 0 ;1
L 1.6825 3.8325 1.6825 3.8325 9 P 0 ;1
L 1.6825 3.8825 1.6825 3.8825 9 P 0 ;1
L 1.6825 3.9325 1.6825 3.9325 9 P 0 ;1
L 1.6825 3.9825 1.6825 3.9825 9 P 0 ;1
L 1.6825 4.0325 1.6825 4.0325 9 P 0 ;1
L 1.6825 4.0825 1.6825 4.0825 9 P 0 ;1
L 1.6825 4.1325 1.6825 4.1325 9 P 0 ;1
L 1.6825 4.4325 1.6825 4.4325 9 P 0 ;1
L 1.6825 4.4825 1.6825 4.4825 9 P 0 ;1
L 1.6825 4.5325 1.6825 4.5325 9 P 0 ;1
L 1.6825 4.5825 1.6825 4.5825 9 P 0 ;1
L 1.6825 5.2325 1.6825 5.2325 9 P 0 ;1
L 1.6825 5.2825 1.6825 5.2825 9 P 0 ;1
L 1.6825 5.3325 1.6825 5.3325 9 P 0 ;1
L 1.6825 5.3825 1.6825 5.3825 9 P 0 ;1
L 1.6825 5.4325 1.6825 5.4325 9 P 0 ;1
L 1.6825 5.4825 1.6825 5.4825 9 P 0 ;1
L 1.6825 5.5325 1.6825 5.5325 9 P 0 ;1
L 1.6825 5.5825 1.6825 5.5825 9 P 0 ;1
L 1.6825 5.6325 1.6825 5.6325 9 P 0 ;1
L 1.6825 5.6825 1.6825 5.6825 9 P 0 ;1
L 1.6825 5.7325 1.6825 5.7325 9 P 0 ;1
L 1.6825 5.7825 1.6825 5.7825 9 P 0 ;1
L 1.6825 5.8325 1.6825 5.8325 9 P 0 ;1
L 1.6825 5.8825 1.6825 5.8825 9 P 0 ;1
L 1.7325 0.1325 1.7325 0.1325 9 P 0 ;1
L 1.7325 0.1825 1.7325 0.1825 9 P 0 ;1
L 1.7325 0.2325 1.7325 0.2325 9 P 0 ;1
L 1.7325 0.2825 1.7325 0.2825 9 P 0 ;1
L 1.7325 0.3325 1.7325 0.3325 9 P 0 ;1
L 1.7325 0.3825 1.7325 0.3825 9 P 0 ;1
L 1.7325 0.4325 1.7325 0.4325 9 P 0 ;1
L 1.7325 0.4825 1.7325 0.4825 9 P 0 ;1
L 1.7325 0.5325 1.7325 0.5325 9 P 0 ;1
L 1.7325 0.5825 1.7325 0.5825 9 P 0 ;1
L 1.7325 0.6325 1.7325 0.6325 9 P 0 ;1
L 1.7325 0.6825 1.7325 0.6825 9 P 0 ;1
L 1.7325 0.7325 1.7325 0.7325 9 P 0 ;1
L 1.7325 0.7825 1.7325 0.7825 9 P 0 ;1
L 1.7325 0.8325 1.7325 0.8325 9 P 0 ;1
L 1.7325 0.8825 1.7325 0.8825 9 P 0 ;1
L 1.7325 1.0825 1.7325 1.0825 9 P 0 ;1
L 1.7325 1.1325 1.7325 1.1325 9 P 0 ;1
L 1.7325 1.7325 1.7325 1.7325 9 P 0 ;1
L 1.7325 1.7825 1.7325 1.7825 9 P 0 ;1
L 1.7325 1.8325 1.7325 1.8325 9 P 0 ;1
L 1.7325 2.3325 1.7325 2.3325 9 P 0 ;1
L 1.7325 2.3825 1.7325 2.3825 9 P 0 ;1
L 1.7325 2.5325 1.7325 2.5325 9 P 0 ;1
L 1.7325 2.5825 1.7325 2.5825 9 P 0 ;1
L 1.7325 2.6325 1.7325 2.6325 9 P 0 ;1
L 1.7325 2.6825 1.7325 2.6825 9 P 0 ;1
L 1.7325 2.7325 1.7325 2.7325 9 P 0 ;1
L 1.7325 2.7825 1.7325 2.7825 9 P 0 ;1
L 1.7325 2.8325 1.7325 2.8325 9 P 0 ;1
L 1.7325 2.8825 1.7325 2.8825 9 P 0 ;1
L 1.7325 2.9325 1.7325 2.9325 9 P 0 ;1
L 1.7325 2.9825 1.7325 2.9825 9 P 0 ;1
L 1.7325 3.0325 1.7325 3.0325 9 P 0 ;1
L 1.7325 3.0825 1.7325 3.0825 9 P 0 ;1
L 1.7325 3.1325 1.7325 3.1325 9 P 0 ;1
L 1.7325 3.1825 1.7325 3.1825 9 P 0 ;1
L 1.7325 3.2325 1.7325 3.2325 9 P 0 ;1
L 1.7325 3.2825 1.7325 3.2825 9 P 0 ;1
L 1.7325 3.3325 1.7325 3.3325 9 P 0 ;1
L 1.7325 3.3825 1.7325 3.3825 9 P 0 ;1
L 1.7325 3.4325 1.7325 3.4325 9 P 0 ;1
L 1.7325 3.4825 1.7325 3.4825 9 P 0 ;1
L 1.7325 3.5325 1.7325 3.5325 9 P 0 ;1
L 1.7325 3.5825 1.7325 3.5825 9 P 0 ;1
L 1.7325 3.6325 1.7325 3.6325 9 P 0 ;1
L 1.7325 3.6825 1.7325 3.6825 9 P 0 ;1
L 1.7325 3.7325 1.7325 3.7325 9 P 0 ;1
L 1.7325 3.7825 1.7325 3.7825 9 P 0 ;1
L 1.7325 3.8325 1.7325 3.8325 9 P 0 ;1
L 1.7325 3.8825 1.7325 3.8825 9 P 0 ;1
L 1.7325 3.9325 1.7325 3.9325 9 P 0 ;1
L 1.7325 3.9825 1.7325 3.9825 9 P 0 ;1
L 1.7325 4.0325 1.7325 4.0325 9 P 0 ;1
L 1.7325 4.0825 1.7325 4.0825 9 P 0 ;1
L 1.7325 4.3825 1.7325 4.3825 9 P 0 ;1
L 1.7325 4.4325 1.7325 4.4325 9 P 0 ;1
L 1.7325 4.5325 1.7325 4.5325 9 P 0 ;1
L 1.7325 4.5825 1.7325 4.5825 9 P 0 ;1
L 1.7325 4.6325 1.7325 4.6325 9 P 0 ;1
L 1.7325 5.1825 1.7325 5.1825 9 P 0 ;1
L 1.7325 5.2325 1.7325 5.2325 9 P 0 ;1
L 1.7325 5.2825 1.7325 5.2825 9 P 0 ;1
L 1.7325 5.3325 1.7325 5.3325 9 P 0 ;1
L 1.7325 5.3825 1.7325 5.3825 9 P 0 ;1
L 1.7325 5.4325 1.7325 5.4325 9 P 0 ;1
L 1.7325 5.4825 1.7325 5.4825 9 P 0 ;1
L 1.7325 5.5325 1.7325 5.5325 9 P 0 ;1
L 1.7325 5.5825 1.7325 5.5825 9 P 0 ;1
L 1.7325 5.6325 1.7325 5.6325 9 P 0 ;1
L 1.7325 5.6825 1.7325 5.6825 9 P 0 ;1
L 1.7325 5.7325 1.7325 5.7325 9 P 0 ;1
L 1.7325 5.7825 1.7325 5.7825 9 P 0 ;1
L 1.7325 5.8325 1.7325 5.8325 9 P 0 ;1
L 1.7325 5.8825 1.7325 5.8825 9 P 0 ;1
L 1.7825 0.1325 1.7825 0.1325 9 P 0 ;1
L 1.7825 0.1825 1.7825 0.1825 9 P 0 ;1
L 1.7825 0.2325 1.7825 0.2325 9 P 0 ;1
L 1.7825 0.2825 1.7825 0.2825 9 P 0 ;1
L 1.7825 0.3325 1.7825 0.3325 9 P 0 ;1
L 1.7825 0.3825 1.7825 0.3825 9 P 0 ;1
L 1.7825 0.4325 1.7825 0.4325 9 P 0 ;1
L 1.7825 0.4825 1.7825 0.4825 9 P 0 ;1
L 1.7825 0.5325 1.7825 0.5325 9 P 0 ;1
L 1.7825 0.5825 1.7825 0.5825 9 P 0 ;1
L 1.7825 0.6325 1.7825 0.6325 9 P 0 ;1
L 1.7825 0.6825 1.7825 0.6825 9 P 0 ;1
L 1.7825 0.7325 1.7825 0.7325 9 P 0 ;1
L 1.7825 0.7825 1.7825 0.7825 9 P 0 ;1
L 1.7825 0.8325 1.7825 0.8325 9 P 0 ;1
L 1.7825 0.8825 1.7825 0.8825 9 P 0 ;1
L 1.7825 1.0825 1.7825 1.0825 9 P 0 ;1
L 1.7825 1.6825 1.7825 1.6825 9 P 0 ;1
L 1.7825 1.7325 1.7825 1.7325 9 P 0 ;1
L 1.7825 2.2325 1.7825 2.2325 9 P 0 ;1
L 1.7825 2.2825 1.7825 2.2825 9 P 0 ;1
L 1.7825 2.3325 1.7825 2.3325 9 P 0 ;1
L 1.7825 2.3825 1.7825 2.3825 9 P 0 ;1
L 1.7825 2.5825 1.7825 2.5825 9 P 0 ;1
L 1.7825 2.6325 1.7825 2.6325 9 P 0 ;1
L 1.7825 2.6825 1.7825 2.6825 9 P 0 ;1
L 1.7825 2.7325 1.7825 2.7325 9 P 0 ;1
L 1.7825 2.7825 1.7825 2.7825 9 P 0 ;1
L 1.7825 2.8325 1.7825 2.8325 9 P 0 ;1
L 1.7825 2.8825 1.7825 2.8825 9 P 0 ;1
L 1.7825 2.9325 1.7825 2.9325 9 P 0 ;1
L 1.7825 2.9825 1.7825 2.9825 9 P 0 ;1
L 1.7825 3.0325 1.7825 3.0325 9 P 0 ;1
L 1.7825 3.0825 1.7825 3.0825 9 P 0 ;1
L 1.7825 3.1325 1.7825 3.1325 9 P 0 ;1
L 1.7825 3.1825 1.7825 3.1825 9 P 0 ;1
L 1.7825 3.2325 1.7825 3.2325 9 P 0 ;1
L 1.7825 3.2825 1.7825 3.2825 9 P 0 ;1
L 1.7825 3.3325 1.7825 3.3325 9 P 0 ;1
L 1.7825 3.3825 1.7825 3.3825 9 P 0 ;1
L 1.7825 3.4325 1.7825 3.4325 9 P 0 ;1
L 1.7825 3.4825 1.7825 3.4825 9 P 0 ;1
L 1.7825 3.5325 1.7825 3.5325 9 P 0 ;1
L 1.7825 3.5825 1.7825 3.5825 9 P 0 ;1
L 1.7825 3.6325 1.7825 3.6325 9 P 0 ;1
L 1.7825 3.6825 1.7825 3.6825 9 P 0 ;1
L 1.7825 3.7325 1.7825 3.7325 9 P 0 ;1
L 1.7825 3.7825 1.7825 3.7825 9 P 0 ;1
L 1.7825 3.8325 1.7825 3.8325 9 P 0 ;1
L 1.7825 3.8825 1.7825 3.8825 9 P 0 ;1
L 1.7825 3.9325 1.7825 3.9325 9 P 0 ;1
L 1.7825 3.9825 1.7825 3.9825 9 P 0 ;1
L 1.7825 4.0325 1.7825 4.0325 9 P 0 ;1
L 1.7825 4.3825 1.7825 4.3825 9 P 0 ;1
L 1.7825 5.1825 1.7825 5.1825 9 P 0 ;1
L 1.7825 5.2325 1.7825 5.2325 9 P 0 ;1
L 1.7825 5.2825 1.7825 5.2825 9 P 0 ;1
L 1.7825 5.3325 1.7825 5.3325 9 P 0 ;1
L 1.7825 5.3825 1.7825 5.3825 9 P 0 ;1
L 1.7825 5.4325 1.7825 5.4325 9 P 0 ;1
L 1.7825 5.4825 1.7825 5.4825 9 P 0 ;1
L 1.7825 5.5325 1.7825 5.5325 9 P 0 ;1
L 1.7825 5.5825 1.7825 5.5825 9 P 0 ;1
L 1.7825 5.6325 1.7825 5.6325 9 P 0 ;1
L 1.7825 5.6825 1.7825 5.6825 9 P 0 ;1
L 1.7825 5.7325 1.7825 5.7325 9 P 0 ;1
L 1.7825 5.7825 1.7825 5.7825 9 P 0 ;1
L 1.7825 5.8325 1.7825 5.8325 9 P 0 ;1
L 1.7825 5.8825 1.7825 5.8825 9 P 0 ;1
L 1.8325 0.1325 1.8325 0.1325 9 P 0 ;1
L 1.8325 0.1825 1.8325 0.1825 9 P 0 ;1
L 1.8325 0.2325 1.8325 0.2325 9 P 0 ;1
L 1.8325 0.2825 1.8325 0.2825 9 P 0 ;1
L 1.8325 0.3325 1.8325 0.3325 9 P 0 ;1
L 1.8325 0.3825 1.8325 0.3825 9 P 0 ;1
L 1.8325 0.4325 1.8325 0.4325 9 P 0 ;1
L 1.8325 0.4825 1.8325 0.4825 9 P 0 ;1
L 1.8325 0.5325 1.8325 0.5325 9 P 0 ;1
L 1.8325 0.5825 1.8325 0.5825 9 P 0 ;1
L 1.8325 0.6325 1.8325 0.6325 9 P 0 ;1
L 1.8325 0.6825 1.8325 0.6825 9 P 0 ;1
L 1.8325 0.7325 1.8325 0.7325 9 P 0 ;1
L 1.8325 0.7825 1.8325 0.7825 9 P 0 ;1
L 1.8325 0.8325 1.8325 0.8325 9 P 0 ;1
L 1.8325 0.8825 1.8325 0.8825 9 P 0 ;1
L 1.8325 1.6325 1.8325 1.6325 9 P 0 ;1
L 1.8325 1.6825 1.8325 1.6825 9 P 0 ;1
L 1.8325 2.1825 1.8325 2.1825 9 P 0 ;1
L 1.8325 2.2325 1.8325 2.2325 9 P 0 ;1
L 1.8325 2.2825 1.8325 2.2825 9 P 0 ;1
L 1.8325 2.3325 1.8325 2.3325 9 P 0 ;1
L 1.8325 2.3825 1.8325 2.3825 9 P 0 ;1
L 1.8325 2.5825 1.8325 2.5825 9 P 0 ;1
L 1.8325 2.6325 1.8325 2.6325 9 P 0 ;1
L 1.8325 2.6825 1.8325 2.6825 9 P 0 ;1
L 1.8325 2.7325 1.8325 2.7325 9 P 0 ;1
L 1.8325 2.7825 1.8325 2.7825 9 P 0 ;1
L 1.8325 2.8325 1.8325 2.8325 9 P 0 ;1
L 1.8325 2.8825 1.8325 2.8825 9 P 0 ;1
L 1.8325 2.9325 1.8325 2.9325 9 P 0 ;1
L 1.8325 2.9825 1.8325 2.9825 9 P 0 ;1
L 1.8325 3.0325 1.8325 3.0325 9 P 0 ;1
L 1.8325 3.0825 1.8325 3.0825 9 P 0 ;1
L 1.8325 3.1325 1.8325 3.1325 9 P 0 ;1
L 1.8325 3.1825 1.8325 3.1825 9 P 0 ;1
L 1.8325 3.2325 1.8325 3.2325 9 P 0 ;1
L 1.8325 3.2825 1.8325 3.2825 9 P 0 ;1
L 1.8325 3.3325 1.8325 3.3325 9 P 0 ;1
L 1.8325 3.3825 1.8325 3.3825 9 P 0 ;1
L 1.8325 3.4325 1.8325 3.4325 9 P 0 ;1
L 1.8325 3.4825 1.8325 3.4825 9 P 0 ;1
L 1.8325 3.5325 1.8325 3.5325 9 P 0 ;1
L 1.8325 3.5825 1.8325 3.5825 9 P 0 ;1
L 1.8325 3.6325 1.8325 3.6325 9 P 0 ;1
L 1.8325 3.6825 1.8325 3.6825 9 P 0 ;1
L 1.8325 3.7325 1.8325 3.7325 9 P 0 ;1
L 1.8325 3.7825 1.8325 3.7825 9 P 0 ;1
L 1.8325 3.8325 1.8325 3.8325 9 P 0 ;1
L 1.8325 3.8825 1.8325 3.8825 9 P 0 ;1
L 1.8325 3.9325 1.8325 3.9325 9 P 0 ;1
L 1.8325 3.9825 1.8325 3.9825 9 P 0 ;1
L 1.8325 4.0325 1.8325 4.0325 9 P 0 ;1
L 1.8325 4.3325 1.8325 4.3325 9 P 0 ;1
L 1.8325 4.3825 1.8325 4.3825 9 P 0 ;1
L 1.8325 5.2825 1.8325 5.2825 9 P 0 ;1
L 1.8325 5.3325 1.8325 5.3325 9 P 0 ;1
L 1.8325 5.3825 1.8325 5.3825 9 P 0 ;1
L 1.8325 5.4325 1.8325 5.4325 9 P 0 ;1
L 1.8325 5.4825 1.8325 5.4825 9 P 0 ;1
L 1.8325 5.5325 1.8325 5.5325 9 P 0 ;1
L 1.8325 5.5825 1.8325 5.5825 9 P 0 ;1
L 1.8325 5.6325 1.8325 5.6325 9 P 0 ;1
L 1.8325 5.6825 1.8325 5.6825 9 P 0 ;1
L 1.8325 5.7325 1.8325 5.7325 9 P 0 ;1
L 1.8325 5.7825 1.8325 5.7825 9 P 0 ;1
L 1.8325 5.8325 1.8325 5.8325 9 P 0 ;1
L 1.8325 5.8825 1.8325 5.8825 9 P 0 ;1
L 1.8825 0.1325 1.8825 0.1325 9 P 0 ;1
L 1.8825 0.1825 1.8825 0.1825 9 P 0 ;1
L 1.8825 0.2325 1.8825 0.2325 9 P 0 ;1
L 1.8825 0.2825 1.8825 0.2825 9 P 0 ;1
L 1.8825 0.3325 1.8825 0.3325 9 P 0 ;1
L 1.8825 0.3825 1.8825 0.3825 9 P 0 ;1
L 1.8825 0.4325 1.8825 0.4325 9 P 0 ;1
L 1.8825 0.4825 1.8825 0.4825 9 P 0 ;1
L 1.8825 0.5325 1.8825 0.5325 9 P 0 ;1
L 1.8825 0.5825 1.8825 0.5825 9 P 0 ;1
L 1.8825 0.6325 1.8825 0.6325 9 P 0 ;1
L 1.8825 0.6825 1.8825 0.6825 9 P 0 ;1
L 1.8825 0.7325 1.8825 0.7325 9 P 0 ;1
L 1.8825 0.7825 1.8825 0.7825 9 P 0 ;1
L 1.8825 0.8325 1.8825 0.8325 9 P 0 ;1
L 1.8825 0.8825 1.8825 0.8825 9 P 0 ;1
L 1.8825 1.5825 1.8825 1.5825 9 P 0 ;1
L 1.8825 1.6325 1.8825 1.6325 9 P 0 ;1
L 1.8825 1.6825 1.8825 1.6825 9 P 0 ;1
L 1.8825 2.0825 1.8825 2.0825 9 P 0 ;1
L 1.8825 2.1325 1.8825 2.1325 9 P 0 ;1
L 1.8825 2.1825 1.8825 2.1825 9 P 0 ;1
L 1.8825 2.2325 1.8825 2.2325 9 P 0 ;1
L 1.8825 2.2825 1.8825 2.2825 9 P 0 ;1
L 1.8825 2.3325 1.8825 2.3325 9 P 0 ;1
L 1.8825 2.3825 1.8825 2.3825 9 P 0 ;1
L 1.8825 2.4325 1.8825 2.4325 9 P 0 ;1
L 1.8825 2.4825 1.8825 2.4825 9 P 0 ;1
L 1.8825 2.5325 1.8825 2.5325 9 P 0 ;1
L 1.8825 2.5825 1.8825 2.5825 9 P 0 ;1
L 1.8825 2.6325 1.8825 2.6325 9 P 0 ;1
L 1.8825 2.6825 1.8825 2.6825 9 P 0 ;1
L 1.8825 2.7325 1.8825 2.7325 9 P 0 ;1
L 1.8825 2.7825 1.8825 2.7825 9 P 0 ;1
L 1.8825 2.8325 1.8825 2.8325 9 P 0 ;1
L 1.8825 2.8825 1.8825 2.8825 9 P 0 ;1
L 1.8825 2.9325 1.8825 2.9325 9 P 0 ;1
L 1.8825 2.9825 1.8825 2.9825 9 P 0 ;1
L 1.8825 3.0325 1.8825 3.0325 9 P 0 ;1
L 1.8825 3.0825 1.8825 3.0825 9 P 0 ;1
L 1.8825 3.1325 1.8825 3.1325 9 P 0 ;1
L 1.8825 3.1825 1.8825 3.1825 9 P 0 ;1
L 1.8825 3.2325 1.8825 3.2325 9 P 0 ;1
L 1.8825 3.2825 1.8825 3.2825 9 P 0 ;1
L 1.8825 3.3325 1.8825 3.3325 9 P 0 ;1
L 1.8825 3.3825 1.8825 3.3825 9 P 0 ;1
L 1.8825 3.4325 1.8825 3.4325 9 P 0 ;1
L 1.8825 3.4825 1.8825 3.4825 9 P 0 ;1
L 1.8825 3.5325 1.8825 3.5325 9 P 0 ;1
L 1.8825 3.5825 1.8825 3.5825 9 P 0 ;1
L 1.8825 3.6325 1.8825 3.6325 9 P 0 ;1
L 1.8825 3.6825 1.8825 3.6825 9 P 0 ;1
L 1.8825 3.7325 1.8825 3.7325 9 P 0 ;1
L 1.8825 3.7825 1.8825 3.7825 9 P 0 ;1
L 1.8825 3.8325 1.8825 3.8325 9 P 0 ;1
L 1.8825 3.8825 1.8825 3.8825 9 P 0 ;1
L 1.8825 3.9325 1.8825 3.9325 9 P 0 ;1
L 1.8825 3.9825 1.8825 3.9825 9 P 0 ;1
L 1.8825 4.2825 1.8825 4.2825 9 P 0 ;1
L 1.8825 4.3325 1.8825 4.3325 9 P 0 ;1
L 1.8825 4.3825 1.8825 4.3825 9 P 0 ;1
L 1.8825 5.2825 1.8825 5.2825 9 P 0 ;1
L 1.8825 5.4825 1.8825 5.4825 9 P 0 ;1
L 1.8825 5.5325 1.8825 5.5325 9 P 0 ;1
L 1.8825 5.5825 1.8825 5.5825 9 P 0 ;1
L 1.8825 5.6325 1.8825 5.6325 9 P 0 ;1
L 1.8825 5.6825 1.8825 5.6825 9 P 0 ;1
L 1.8825 5.7325 1.8825 5.7325 9 P 0 ;1
L 1.8825 5.7825 1.8825 5.7825 9 P 0 ;1
L 1.8825 5.8325 1.8825 5.8325 9 P 0 ;1
L 1.8825 5.8825 1.8825 5.8825 9 P 0 ;1
L 1.9325 0.1325 1.9325 0.1325 9 P 0 ;1
L 1.9325 0.1825 1.9325 0.1825 9 P 0 ;1
L 1.9325 0.2325 1.9325 0.2325 9 P 0 ;1
L 1.9325 0.2825 1.9325 0.2825 9 P 0 ;1
L 1.9325 0.3325 1.9325 0.3325 9 P 0 ;1
L 1.9325 0.3825 1.9325 0.3825 9 P 0 ;1
L 1.9325 0.4325 1.9325 0.4325 9 P 0 ;1
L 1.9325 0.4825 1.9325 0.4825 9 P 0 ;1
L 1.9325 0.5325 1.9325 0.5325 9 P 0 ;1
L 1.9325 0.5825 1.9325 0.5825 9 P 0 ;1
L 1.9325 0.6325 1.9325 0.6325 9 P 0 ;1
L 1.9325 0.6825 1.9325 0.6825 9 P 0 ;1
L 1.9325 0.7325 1.9325 0.7325 9 P 0 ;1
L 1.9325 0.7825 1.9325 0.7825 9 P 0 ;1
L 1.9325 0.8325 1.9325 0.8325 9 P 0 ;1
L 1.9325 0.8825 1.9325 0.8825 9 P 0 ;1
L 1.9325 1.5825 1.9325 1.5825 9 P 0 ;1
L 1.9325 1.6325 1.9325 1.6325 9 P 0 ;1
L 1.9325 2.0325 1.9325 2.0325 9 P 0 ;1
L 1.9325 2.0825 1.9325 2.0825 9 P 0 ;1
L 1.9325 2.1325 1.9325 2.1325 9 P 0 ;1
L 1.9325 2.1825 1.9325 2.1825 9 P 0 ;1
L 1.9325 2.2325 1.9325 2.2325 9 P 0 ;1
L 1.9325 2.2825 1.9325 2.2825 9 P 0 ;1
L 1.9325 2.3325 1.9325 2.3325 9 P 0 ;1
L 1.9325 2.3825 1.9325 2.3825 9 P 0 ;1
L 1.9325 2.4325 1.9325 2.4325 9 P 0 ;1
L 1.9325 2.4825 1.9325 2.4825 9 P 0 ;1
L 1.9325 2.5325 1.9325 2.5325 9 P 0 ;1
L 1.9325 2.5825 1.9325 2.5825 9 P 0 ;1
L 1.9325 2.6325 1.9325 2.6325 9 P 0 ;1
L 1.9325 2.9325 1.9325 2.9325 9 P 0 ;1
L 1.9325 2.9825 1.9325 2.9825 9 P 0 ;1
L 1.9325 3.0325 1.9325 3.0325 9 P 0 ;1
L 1.9325 3.0825 1.9325 3.0825 9 P 0 ;1
L 1.9325 3.1325 1.9325 3.1325 9 P 0 ;1
L 1.9325 3.1825 1.9325 3.1825 9 P 0 ;1
L 1.9325 3.2325 1.9325 3.2325 9 P 0 ;1
L 1.9325 3.2825 1.9325 3.2825 9 P 0 ;1
L 1.9325 3.3325 1.9325 3.3325 9 P 0 ;1
L 1.9325 3.6325 1.9325 3.6325 9 P 0 ;1
L 1.9325 3.6825 1.9325 3.6825 9 P 0 ;1
L 1.9325 3.7325 1.9325 3.7325 9 P 0 ;1
L 1.9325 3.7825 1.9325 3.7825 9 P 0 ;1
L 1.9325 3.8325 1.9325 3.8325 9 P 0 ;1
L 1.9325 3.8825 1.9325 3.8825 9 P 0 ;1
L 1.9325 3.9325 1.9325 3.9325 9 P 0 ;1
L 1.9325 4.2825 1.9325 4.2825 9 P 0 ;1
L 1.9325 4.3325 1.9325 4.3325 9 P 0 ;1
L 1.9325 4.3825 1.9325 4.3825 9 P 0 ;1
L 1.9325 4.4325 1.9325 4.4325 9 P 0 ;1
L 1.9325 4.5325 1.9325 4.5325 9 P 0 ;1
L 1.9325 4.7325 1.9325 4.7325 9 P 0 ;1
L 1.9325 5.4825 1.9325 5.4825 9 P 0 ;1
L 1.9325 5.5325 1.9325 5.5325 9 P 0 ;1
L 1.9325 5.5825 1.9325 5.5825 9 P 0 ;1
L 1.9325 5.6325 1.9325 5.6325 9 P 0 ;1
L 1.9325 5.6825 1.9325 5.6825 9 P 0 ;1
L 1.9325 5.7325 1.9325 5.7325 9 P 0 ;1
L 1.9325 5.7825 1.9325 5.7825 9 P 0 ;1
L 1.9325 5.8325 1.9325 5.8325 9 P 0 ;1
L 1.9325 5.8825 1.9325 5.8825 9 P 0 ;1
L 1.9825 0.1325 1.9825 0.1325 9 P 0 ;1
L 1.9825 0.1825 1.9825 0.1825 9 P 0 ;1
L 1.9825 0.2325 1.9825 0.2325 9 P 0 ;1
L 1.9825 0.2825 1.9825 0.2825 9 P 0 ;1
L 1.9825 0.3325 1.9825 0.3325 9 P 0 ;1
L 1.9825 0.3825 1.9825 0.3825 9 P 0 ;1
L 1.9825 0.4325 1.9825 0.4325 9 P 0 ;1
L 1.9825 0.4825 1.9825 0.4825 9 P 0 ;1
L 1.9825 0.5325 1.9825 0.5325 9 P 0 ;1
L 1.9825 0.5825 1.9825 0.5825 9 P 0 ;1
L 1.9825 0.6325 1.9825 0.6325 9 P 0 ;1
L 1.9825 0.6825 1.9825 0.6825 9 P 0 ;1
L 1.9825 0.7325 1.9825 0.7325 9 P 0 ;1
L 1.9825 0.7825 1.9825 0.7825 9 P 0 ;1
L 1.9825 0.8325 1.9825 0.8325 9 P 0 ;1
L 1.9825 1.5325 1.9825 1.5325 9 P 0 ;1
L 1.9825 1.5825 1.9825 1.5825 9 P 0 ;1
L 1.9825 1.6325 1.9825 1.6325 9 P 0 ;1
L 1.9825 3.9325 1.9825 3.9325 9 P 0 ;1
L 1.9825 4.2325 1.9825 4.2325 9 P 0 ;1
L 1.9825 4.2825 1.9825 4.2825 9 P 0 ;1
L 1.9825 4.3325 1.9825 4.3325 9 P 0 ;1
L 1.9825 4.3825 1.9825 4.3825 9 P 0 ;1
L 1.9825 4.4325 1.9825 4.4325 9 P 0 ;1
L 1.9825 4.4825 1.9825 4.4825 9 P 0 ;1
L 1.9825 4.5325 1.9825 4.5325 9 P 0 ;1
L 1.9825 5.1825 1.9825 5.1825 9 P 0 ;1
L 1.9825 5.4325 1.9825 5.4325 9 P 0 ;1
L 1.9825 5.4825 1.9825 5.4825 9 P 0 ;1
L 1.9825 5.5325 1.9825 5.5325 9 P 0 ;1
L 1.9825 5.5825 1.9825 5.5825 9 P 0 ;1
L 1.9825 5.6325 1.9825 5.6325 9 P 0 ;1
L 1.9825 5.6825 1.9825 5.6825 9 P 0 ;1
L 1.9825 5.7325 1.9825 5.7325 9 P 0 ;1
L 1.9825 5.7825 1.9825 5.7825 9 P 0 ;1
L 1.9825 5.8325 1.9825 5.8325 9 P 0 ;1
L 1.9825 5.8825 1.9825 5.8825 9 P 0 ;1
L 2.0325 0.1325 2.0325 0.1325 9 P 0 ;1
L 2.0325 0.1825 2.0325 0.1825 9 P 0 ;1
L 2.0325 0.2325 2.0325 0.2325 9 P 0 ;1
L 2.0325 0.2825 2.0325 0.2825 9 P 0 ;1
L 2.0325 0.3325 2.0325 0.3325 9 P 0 ;1
L 2.0325 0.3825 2.0325 0.3825 9 P 0 ;1
L 2.0325 0.4325 2.0325 0.4325 9 P 0 ;1
L 2.0325 0.4825 2.0325 0.4825 9 P 0 ;1
L 2.0325 0.5325 2.0325 0.5325 9 P 0 ;1
L 2.0325 0.5825 2.0325 0.5825 9 P 0 ;1
L 2.0325 0.6325 2.0325 0.6325 9 P 0 ;1
L 2.0325 0.6825 2.0325 0.6825 9 P 0 ;1
L 2.0325 0.7325 2.0325 0.7325 9 P 0 ;1
L 2.0325 0.7825 2.0325 0.7825 9 P 0 ;1
L 2.0325 0.8325 2.0325 0.8325 9 P 0 ;1
L 2.0325 1.4825 2.0325 1.4825 9 P 0 ;1
L 2.0325 1.5325 2.0325 1.5325 9 P 0 ;1
L 2.0325 1.5825 2.0325 1.5825 9 P 0 ;1
L 2.0325 1.6325 2.0325 1.6325 9 P 0 ;1
L 2.0325 4.1825 2.0325 4.1825 9 P 0 ;1
L 2.0325 4.2325 2.0325 4.2325 9 P 0 ;1
L 2.0325 4.2825 2.0325 4.2825 9 P 0 ;1
L 2.0325 4.3325 2.0325 4.3325 9 P 0 ;1
L 2.0325 4.3825 2.0325 4.3825 9 P 0 ;1
L 2.0325 4.4325 2.0325 4.4325 9 P 0 ;1
L 2.0325 4.4825 2.0325 4.4825 9 P 0 ;1
L 2.0325 4.5325 2.0325 4.5325 9 P 0 ;1
L 2.0325 5.3825 2.0325 5.3825 9 P 0 ;1
L 2.0325 5.4325 2.0325 5.4325 9 P 0 ;1
L 2.0325 5.4825 2.0325 5.4825 9 P 0 ;1
L 2.0325 5.5325 2.0325 5.5325 9 P 0 ;1
L 2.0325 5.5825 2.0325 5.5825 9 P 0 ;1
L 2.0325 5.6325 2.0325 5.6325 9 P 0 ;1
L 2.0325 5.6825 2.0325 5.6825 9 P 0 ;1
L 2.0325 5.7325 2.0325 5.7325 9 P 0 ;1
L 2.0325 5.7825 2.0325 5.7825 9 P 0 ;1
L 2.0325 5.8325 2.0325 5.8325 9 P 0 ;1
L 2.0325 5.8825 2.0325 5.8825 9 P 0 ;1
L 2.0825 0.1325 2.0825 0.1325 9 P 0 ;1
L 2.0825 0.1825 2.0825 0.1825 9 P 0 ;1
L 2.0825 0.2325 2.0825 0.2325 9 P 0 ;1
L 2.0825 0.2825 2.0825 0.2825 9 P 0 ;1
L 2.0825 0.3325 2.0825 0.3325 9 P 0 ;1
L 2.0825 0.3825 2.0825 0.3825 9 P 0 ;1
L 2.0825 0.4325 2.0825 0.4325 9 P 0 ;1
L 2.0825 0.4825 2.0825 0.4825 9 P 0 ;1
L 2.0825 0.5325 2.0825 0.5325 9 P 0 ;1
L 2.0825 0.5825 2.0825 0.5825 9 P 0 ;1
L 2.0825 0.6325 2.0825 0.6325 9 P 0 ;1
L 2.0825 0.6825 2.0825 0.6825 9 P 0 ;1
L 2.0825 0.7325 2.0825 0.7325 9 P 0 ;1
L 2.0825 0.7825 2.0825 0.7825 9 P 0 ;1
L 2.0825 0.8325 2.0825 0.8325 9 P 0 ;1
L 2.0825 4.3825 2.0825 4.3825 9 P 0 ;1
L 2.0825 4.4325 2.0825 4.4325 9 P 0 ;1
L 2.0825 4.4825 2.0825 4.4825 9 P 0 ;1
L 2.0825 4.5325 2.0825 4.5325 9 P 0 ;1
L 2.0825 5.4325 2.0825 5.4325 9 P 0 ;1
L 2.0825 5.4825 2.0825 5.4825 9 P 0 ;1
L 2.0825 5.5325 2.0825 5.5325 9 P 0 ;1
L 2.0825 5.5825 2.0825 5.5825 9 P 0 ;1
L 2.0825 5.6325 2.0825 5.6325 9 P 0 ;1
L 2.0825 5.6825 2.0825 5.6825 9 P 0 ;1
L 2.0825 5.7325 2.0825 5.7325 9 P 0 ;1
L 2.0825 5.7825 2.0825 5.7825 9 P 0 ;1
L 2.0825 5.8325 2.0825 5.8325 9 P 0 ;1
L 2.0825 5.8825 2.0825 5.8825 9 P 0 ;1
L 2.1325 0.1325 2.1325 0.1325 9 P 0 ;1
L 2.1325 0.1825 2.1325 0.1825 9 P 0 ;1
L 2.1325 0.2325 2.1325 0.2325 9 P 0 ;1
L 2.1325 0.2825 2.1325 0.2825 9 P 0 ;1
L 2.1325 0.3325 2.1325 0.3325 9 P 0 ;1
L 2.1325 0.3825 2.1325 0.3825 9 P 0 ;1
L 2.1325 0.4325 2.1325 0.4325 9 P 0 ;1
L 2.1325 0.4825 2.1325 0.4825 9 P 0 ;1
L 2.1325 0.5325 2.1325 0.5325 9 P 0 ;1
L 2.1325 0.5825 2.1325 0.5825 9 P 0 ;1
L 2.1325 0.6325 2.1325 0.6325 9 P 0 ;1
L 2.1325 0.6825 2.1325 0.6825 9 P 0 ;1
L 2.1325 0.7325 2.1325 0.7325 9 P 0 ;1
L 2.1325 0.7825 2.1325 0.7825 9 P 0 ;1
L 2.1325 0.8325 2.1325 0.8325 9 P 0 ;1
L 2.1325 4.4325 2.1325 4.4325 9 P 0 ;1
L 2.1325 4.4825 2.1325 4.4825 9 P 0 ;1
L 2.1325 4.5325 2.1325 4.5325 9 P 0 ;1
L 2.1325 5.4825 2.1325 5.4825 9 P 0 ;1
L 2.1325 5.5325 2.1325 5.5325 9 P 0 ;1
L 2.1325 5.5825 2.1325 5.5825 9 P 0 ;1
L 2.1325 5.6325 2.1325 5.6325 9 P 0 ;1
L 2.1325 5.6825 2.1325 5.6825 9 P 0 ;1
L 2.1325 5.7325 2.1325 5.7325 9 P 0 ;1
L 2.1325 5.7825 2.1325 5.7825 9 P 0 ;1
L 2.1325 5.8325 2.1325 5.8325 9 P 0 ;1
L 2.1325 5.8825 2.1325 5.8825 9 P 0 ;1
L 2.1825 0.1325 2.1825 0.1325 9 P 0 ;1
L 2.1825 0.1825 2.1825 0.1825 9 P 0 ;1
L 2.1825 0.2325 2.1825 0.2325 9 P 0 ;1
L 2.1825 0.2825 2.1825 0.2825 9 P 0 ;1
L 2.1825 0.3325 2.1825 0.3325 9 P 0 ;1
L 2.1825 0.3825 2.1825 0.3825 9 P 0 ;1
L 2.1825 0.4325 2.1825 0.4325 9 P 0 ;1
L 2.1825 0.4825 2.1825 0.4825 9 P 0 ;1
L 2.1825 0.5325 2.1825 0.5325 9 P 0 ;1
L 2.1825 0.5825 2.1825 0.5825 9 P 0 ;1
L 2.1825 0.6325 2.1825 0.6325 9 P 0 ;1
L 2.1825 0.6825 2.1825 0.6825 9 P 0 ;1
L 2.1825 0.7325 2.1825 0.7325 9 P 0 ;1
L 2.1825 0.7825 2.1825 0.7825 9 P 0 ;1
L 2.1825 0.8325 2.1825 0.8325 9 P 0 ;1
L 2.1825 4.4325 2.1825 4.4325 9 P 0 ;1
L 2.1825 4.4825 2.1825 4.4825 9 P 0 ;1
L 2.1825 4.5325 2.1825 4.5325 9 P 0 ;1
L 2.1825 5.2325 2.1825 5.2325 9 P 0 ;1
L 2.1825 5.2825 2.1825 5.2825 9 P 0 ;1
L 2.1825 5.4825 2.1825 5.4825 9 P 0 ;1
L 2.1825 5.5325 2.1825 5.5325 9 P 0 ;1
L 2.1825 5.5825 2.1825 5.5825 9 P 0 ;1
L 2.1825 5.6325 2.1825 5.6325 9 P 0 ;1
L 2.1825 5.6825 2.1825 5.6825 9 P 0 ;1
L 2.1825 5.7325 2.1825 5.7325 9 P 0 ;1
L 2.1825 5.7825 2.1825 5.7825 9 P 0 ;1
L 2.1825 5.8325 2.1825 5.8325 9 P 0 ;1
L 2.1825 5.8825 2.1825 5.8825 9 P 0 ;1
L 2.2325 0.1325 2.2325 0.1325 9 P 0 ;1
L 2.2325 0.1825 2.2325 0.1825 9 P 0 ;1
L 2.2325 0.2325 2.2325 0.2325 9 P 0 ;1
L 2.2325 0.2825 2.2325 0.2825 9 P 0 ;1
L 2.2325 0.3325 2.2325 0.3325 9 P 0 ;1
L 2.2325 0.3825 2.2325 0.3825 9 P 0 ;1
L 2.2325 0.4325 2.2325 0.4325 9 P 0 ;1
L 2.2325 0.4825 2.2325 0.4825 9 P 0 ;1
L 2.2325 0.5325 2.2325 0.5325 9 P 0 ;1
L 2.2325 0.5825 2.2325 0.5825 9 P 0 ;1
L 2.2325 0.6325 2.2325 0.6325 9 P 0 ;1
L 2.2325 0.6825 2.2325 0.6825 9 P 0 ;1
L 2.2325 0.7325 2.2325 0.7325 9 P 0 ;1
L 2.2325 0.7825 2.2325 0.7825 9 P 0 ;1
L 2.2325 0.8325 2.2325 0.8325 9 P 0 ;1
L 2.2325 4.4325 2.2325 4.4325 9 P 0 ;1
L 2.2325 4.4825 2.2325 4.4825 9 P 0 ;1
L 2.2325 4.5325 2.2325 4.5325 9 P 0 ;1
L 2.2325 5.1825 2.2325 5.1825 9 P 0 ;1
L 2.2325 5.2325 2.2325 5.2325 9 P 0 ;1
L 2.2325 5.2825 2.2325 5.2825 9 P 0 ;1
L 2.2325 5.3325 2.2325 5.3325 9 P 0 ;1
L 2.2325 5.3825 2.2325 5.3825 9 P 0 ;1
L 2.2325 5.4325 2.2325 5.4325 9 P 0 ;1
L 2.2325 5.4825 2.2325 5.4825 9 P 0 ;1
L 2.2325 5.5325 2.2325 5.5325 9 P 0 ;1
L 2.2325 5.5825 2.2325 5.5825 9 P 0 ;1
L 2.2325 5.6325 2.2325 5.6325 9 P 0 ;1
L 2.2325 5.6825 2.2325 5.6825 9 P 0 ;1
L 2.2325 5.7325 2.2325 5.7325 9 P 0 ;1
L 2.2325 5.7825 2.2325 5.7825 9 P 0 ;1
L 2.2325 5.8325 2.2325 5.8325 9 P 0 ;1
L 2.2325 5.8825 2.2325 5.8825 9 P 0 ;1
L 2.2825 0.1325 2.2825 0.1325 9 P 0 ;1
L 2.2825 0.1825 2.2825 0.1825 9 P 0 ;1
L 2.2825 0.2325 2.2825 0.2325 9 P 0 ;1
L 2.2825 0.2825 2.2825 0.2825 9 P 0 ;1
L 2.2825 0.3325 2.2825 0.3325 9 P 0 ;1
L 2.2825 0.3825 2.2825 0.3825 9 P 0 ;1
L 2.2825 0.4325 2.2825 0.4325 9 P 0 ;1
L 2.2825 0.4825 2.2825 0.4825 9 P 0 ;1
L 2.2825 0.5325 2.2825 0.5325 9 P 0 ;1
L 2.2825 0.5825 2.2825 0.5825 9 P 0 ;1
L 2.2825 0.6325 2.2825 0.6325 9 P 0 ;1
L 2.2825 0.6825 2.2825 0.6825 9 P 0 ;1
L 2.2825 0.7325 2.2825 0.7325 9 P 0 ;1
L 2.2825 0.7825 2.2825 0.7825 9 P 0 ;1
L 2.2825 4.4325 2.2825 4.4325 9 P 0 ;1
L 2.2825 4.4825 2.2825 4.4825 9 P 0 ;1
L 2.2825 4.5325 2.2825 4.5325 9 P 0 ;1
L 2.2825 5.2325 2.2825 5.2325 9 P 0 ;1
L 2.2825 5.2825 2.2825 5.2825 9 P 0 ;1
L 2.2825 5.3325 2.2825 5.3325 9 P 0 ;1
L 2.2825 5.3825 2.2825 5.3825 9 P 0 ;1
L 2.2825 5.4325 2.2825 5.4325 9 P 0 ;1
L 2.2825 5.4825 2.2825 5.4825 9 P 0 ;1
L 2.2825 5.5325 2.2825 5.5325 9 P 0 ;1
L 2.2825 5.5825 2.2825 5.5825 9 P 0 ;1
L 2.2825 5.6325 2.2825 5.6325 9 P 0 ;1
L 2.2825 5.6825 2.2825 5.6825 9 P 0 ;1
L 2.2825 5.7325 2.2825 5.7325 9 P 0 ;1
L 2.2825 5.7825 2.2825 5.7825 9 P 0 ;1
L 2.2825 5.8325 2.2825 5.8325 9 P 0 ;1
L 2.2825 5.8825 2.2825 5.8825 9 P 0 ;1
L 2.3325 0.1325 2.3325 0.1325 9 P 0 ;1
L 2.3325 0.1825 2.3325 0.1825 9 P 0 ;1
L 2.3325 0.2325 2.3325 0.2325 9 P 0 ;1
L 2.3325 0.2825 2.3325 0.2825 9 P 0 ;1
L 2.3325 0.3325 2.3325 0.3325 9 P 0 ;1
L 2.3325 0.3825 2.3325 0.3825 9 P 0 ;1
L 2.3325 0.4325 2.3325 0.4325 9 P 0 ;1
L 2.3325 0.4825 2.3325 0.4825 9 P 0 ;1
L 2.3325 0.5325 2.3325 0.5325 9 P 0 ;1
L 2.3325 0.5825 2.3325 0.5825 9 P 0 ;1
L 2.3325 0.6325 2.3325 0.6325 9 P 0 ;1
L 2.3325 0.6825 2.3325 0.6825 9 P 0 ;1
L 2.3325 0.7325 2.3325 0.7325 9 P 0 ;1
L 2.3325 0.7825 2.3325 0.7825 9 P 0 ;1
L 2.3325 4.4325 2.3325 4.4325 9 P 0 ;1
L 2.3325 4.4825 2.3325 4.4825 9 P 0 ;1
L 2.3325 4.5325 2.3325 4.5325 9 P 0 ;1
L 2.3325 5.2325 2.3325 5.2325 9 P 0 ;1
L 2.3325 5.2825 2.3325 5.2825 9 P 0 ;1
L 2.3325 5.3325 2.3325 5.3325 9 P 0 ;1
L 2.3325 5.3825 2.3325 5.3825 9 P 0 ;1
L 2.3325 5.4325 2.3325 5.4325 9 P 0 ;1
L 2.3325 5.4825 2.3325 5.4825 9 P 0 ;1
L 2.3325 5.5325 2.3325 5.5325 9 P 0 ;1
L 2.3325 5.5825 2.3325 5.5825 9 P 0 ;1
L 2.3325 5.6325 2.3325 5.6325 9 P 0 ;1
L 2.3325 5.6825 2.3325 5.6825 9 P 0 ;1
L 2.3325 5.7325 2.3325 5.7325 9 P 0 ;1
L 2.3325 5.7825 2.3325 5.7825 9 P 0 ;1
L 2.3325 5.8325 2.3325 5.8325 9 P 0 ;1
L 2.3325 5.8825 2.3325 5.8825 9 P 0 ;1
L 2.3825 0.1325 2.3825 0.1325 9 P 0 ;1
L 2.3825 0.1825 2.3825 0.1825 9 P 0 ;1
L 2.3825 0.2325 2.3825 0.2325 9 P 0 ;1
L 2.3825 0.2825 2.3825 0.2825 9 P 0 ;1
L 2.3825 0.3325 2.3825 0.3325 9 P 0 ;1
L 2.3825 0.3825 2.3825 0.3825 9 P 0 ;1
L 2.3825 0.4325 2.3825 0.4325 9 P 0 ;1
L 2.3825 0.4825 2.3825 0.4825 9 P 0 ;1
L 2.3825 0.5325 2.3825 0.5325 9 P 0 ;1
L 2.3825 0.5825 2.3825 0.5825 9 P 0 ;1
L 2.3825 0.6325 2.3825 0.6325 9 P 0 ;1
L 2.3825 0.6825 2.3825 0.6825 9 P 0 ;1
L 2.3825 0.7325 2.3825 0.7325 9 P 0 ;1
L 2.3825 0.7825 2.3825 0.7825 9 P 0 ;1
L 2.3825 4.4325 2.3825 4.4325 9 P 0 ;1
L 2.3825 4.4825 2.3825 4.4825 9 P 0 ;1
L 2.3825 4.5325 2.3825 4.5325 9 P 0 ;1
L 2.3825 4.5825 2.3825 4.5825 9 P 0 ;1
L 2.3825 5.2325 2.3825 5.2325 9 P 0 ;1
L 2.3825 5.2825 2.3825 5.2825 9 P 0 ;1
L 2.3825 5.3325 2.3825 5.3325 9 P 0 ;1
L 2.3825 5.3825 2.3825 5.3825 9 P 0 ;1
L 2.3825 5.4325 2.3825 5.4325 9 P 0 ;1
L 2.3825 5.4825 2.3825 5.4825 9 P 0 ;1
L 2.3825 5.5325 2.3825 5.5325 9 P 0 ;1
L 2.3825 5.5825 2.3825 5.5825 9 P 0 ;1
L 2.3825 5.6325 2.3825 5.6325 9 P 0 ;1
L 2.3825 5.6825 2.3825 5.6825 9 P 0 ;1
L 2.3825 5.7325 2.3825 5.7325 9 P 0 ;1
L 2.3825 5.7825 2.3825 5.7825 9 P 0 ;1
L 2.3825 5.8325 2.3825 5.8325 9 P 0 ;1
L 2.3825 5.8825 2.3825 5.8825 9 P 0 ;1
L 2.4325 0.1325 2.4325 0.1325 9 P 0 ;1
L 2.4325 0.1825 2.4325 0.1825 9 P 0 ;1
L 2.4325 0.2325 2.4325 0.2325 9 P 0 ;1
L 2.4325 0.2825 2.4325 0.2825 9 P 0 ;1
L 2.4325 0.3325 2.4325 0.3325 9 P 0 ;1
L 2.4325 0.3825 2.4325 0.3825 9 P 0 ;1
L 2.4325 0.4325 2.4325 0.4325 9 P 0 ;1
L 2.4325 0.4825 2.4325 0.4825 9 P 0 ;1
L 2.4325 0.5325 2.4325 0.5325 9 P 0 ;1
L 2.4325 0.5825 2.4325 0.5825 9 P 0 ;1
L 2.4325 0.6325 2.4325 0.6325 9 P 0 ;1
L 2.4325 0.6825 2.4325 0.6825 9 P 0 ;1
L 2.4325 0.7325 2.4325 0.7325 9 P 0 ;1
L 2.4325 0.7825 2.4325 0.7825 9 P 0 ;1
L 2.4325 1.3325 2.4325 1.3325 9 P 0 ;1
L 2.4325 1.3825 2.4325 1.3825 9 P 0 ;1
L 2.4325 1.4325 2.4325 1.4325 9 P 0 ;1
L 2.4325 1.5825 2.4325 1.5825 9 P 0 ;1
L 2.4325 4.1325 2.4325 4.1325 9 P 0 ;1
L 2.4325 4.2825 2.4325 4.2825 9 P 0 ;1
L 2.4325 4.3325 2.4325 4.3325 9 P 0 ;1
L 2.4325 4.3825 2.4325 4.3825 9 P 0 ;1
L 2.4325 4.4325 2.4325 4.4325 9 P 0 ;1
L 2.4325 4.4825 2.4325 4.4825 9 P 0 ;1
L 2.4325 4.5325 2.4325 4.5325 9 P 0 ;1
L 2.4325 4.5825 2.4325 4.5825 9 P 0 ;1
L 2.4325 5.2325 2.4325 5.2325 9 P 0 ;1
L 2.4325 5.2825 2.4325 5.2825 9 P 0 ;1
L 2.4325 5.3325 2.4325 5.3325 9 P 0 ;1
L 2.4325 5.3825 2.4325 5.3825 9 P 0 ;1
L 2.4325 5.4325 2.4325 5.4325 9 P 0 ;1
L 2.4325 5.4825 2.4325 5.4825 9 P 0 ;1
L 2.4325 5.5325 2.4325 5.5325 9 P 0 ;1
L 2.4325 5.5825 2.4325 5.5825 9 P 0 ;1
L 2.4325 5.6325 2.4325 5.6325 9 P 0 ;1
L 2.4325 5.6825 2.4325 5.6825 9 P 0 ;1
L 2.4325 5.7325 2.4325 5.7325 9 P 0 ;1
L 2.4325 5.7825 2.4325 5.7825 9 P 0 ;1
L 2.4325 5.8325 2.4325 5.8325 9 P 0 ;1
L 2.4325 5.8825 2.4325 5.8825 9 P 0 ;1
L 2.4825 0.1325 2.4825 0.1325 9 P 0 ;1
L 2.4825 0.1825 2.4825 0.1825 9 P 0 ;1
L 2.4825 0.2325 2.4825 0.2325 9 P 0 ;1
L 2.4825 0.2825 2.4825 0.2825 9 P 0 ;1
L 2.4825 0.3325 2.4825 0.3325 9 P 0 ;1
L 2.4825 0.3825 2.4825 0.3825 9 P 0 ;1
L 2.4825 0.4325 2.4825 0.4325 9 P 0 ;1
L 2.4825 0.4825 2.4825 0.4825 9 P 0 ;1
L 2.4825 0.5325 2.4825 0.5325 9 P 0 ;1
L 2.4825 0.5825 2.4825 0.5825 9 P 0 ;1
L 2.4825 0.6325 2.4825 0.6325 9 P 0 ;1
L 2.4825 0.6825 2.4825 0.6825 9 P 0 ;1
L 2.4825 0.7325 2.4825 0.7325 9 P 0 ;1
L 2.4825 0.7825 2.4825 0.7825 9 P 0 ;1
L 2.4825 1.3325 2.4825 1.3325 9 P 0 ;1
L 2.4825 1.3825 2.4825 1.3825 9 P 0 ;1
L 2.4825 1.4325 2.4825 1.4325 9 P 0 ;1
L 2.4825 1.4825 2.4825 1.4825 9 P 0 ;1
L 2.4825 1.5325 2.4825 1.5325 9 P 0 ;1
L 2.4825 1.5825 2.4825 1.5825 9 P 0 ;1
L 2.4825 4.1325 2.4825 4.1325 9 P 0 ;1
L 2.4825 4.1825 2.4825 4.1825 9 P 0 ;1
L 2.4825 4.2325 2.4825 4.2325 9 P 0 ;1
L 2.4825 4.2825 2.4825 4.2825 9 P 0 ;1
L 2.4825 4.3325 2.4825 4.3325 9 P 0 ;1
L 2.4825 4.3825 2.4825 4.3825 9 P 0 ;1
L 2.4825 4.4325 2.4825 4.4325 9 P 0 ;1
L 2.4825 4.4825 2.4825 4.4825 9 P 0 ;1
L 2.4825 4.5325 2.4825 4.5325 9 P 0 ;1
L 2.4825 4.5825 2.4825 4.5825 9 P 0 ;1
L 2.4825 4.6325 2.4825 4.6325 9 P 0 ;1
L 2.4825 5.1825 2.4825 5.1825 9 P 0 ;1
L 2.4825 5.2325 2.4825 5.2325 9 P 0 ;1
L 2.4825 5.2825 2.4825 5.2825 9 P 0 ;1
L 2.4825 5.3325 2.4825 5.3325 9 P 0 ;1
L 2.4825 5.3825 2.4825 5.3825 9 P 0 ;1
L 2.4825 5.4325 2.4825 5.4325 9 P 0 ;1
L 2.4825 5.4825 2.4825 5.4825 9 P 0 ;1
L 2.4825 5.5325 2.4825 5.5325 9 P 0 ;1
L 2.4825 5.5825 2.4825 5.5825 9 P 0 ;1
L 2.4825 5.6325 2.4825 5.6325 9 P 0 ;1
L 2.4825 5.6825 2.4825 5.6825 9 P 0 ;1
L 2.4825 5.7325 2.4825 5.7325 9 P 0 ;1
L 2.4825 5.7825 2.4825 5.7825 9 P 0 ;1
L 2.4825 5.8325 2.4825 5.8325 9 P 0 ;1
L 2.4825 5.8825 2.4825 5.8825 9 P 0 ;1
L 2.5325 0.1325 2.5325 0.1325 9 P 0 ;1
L 2.5325 0.1825 2.5325 0.1825 9 P 0 ;1
L 2.5325 0.2325 2.5325 0.2325 9 P 0 ;1
L 2.5325 0.2825 2.5325 0.2825 9 P 0 ;1
L 2.5325 0.3325 2.5325 0.3325 9 P 0 ;1
L 2.5325 0.3825 2.5325 0.3825 9 P 0 ;1
L 2.5325 0.4325 2.5325 0.4325 9 P 0 ;1
L 2.5325 0.4825 2.5325 0.4825 9 P 0 ;1
L 2.5325 0.5325 2.5325 0.5325 9 P 0 ;1
L 2.5325 0.5825 2.5325 0.5825 9 P 0 ;1
L 2.5325 0.6325 2.5325 0.6325 9 P 0 ;1
L 2.5325 0.6825 2.5325 0.6825 9 P 0 ;1
L 2.5325 0.7325 2.5325 0.7325 9 P 0 ;1
L 2.5325 0.7825 2.5325 0.7825 9 P 0 ;1
L 2.5325 1.3325 2.5325 1.3325 9 P 0 ;1
L 2.5325 1.3825 2.5325 1.3825 9 P 0 ;1
L 2.5325 1.4325 2.5325 1.4325 9 P 0 ;1
L 2.5325 1.4825 2.5325 1.4825 9 P 0 ;1
L 2.5325 1.5325 2.5325 1.5325 9 P 0 ;1
L 2.5325 1.5825 2.5325 1.5825 9 P 0 ;1
L 2.5325 4.1325 2.5325 4.1325 9 P 0 ;1
L 2.5325 4.1825 2.5325 4.1825 9 P 0 ;1
L 2.5325 4.2325 2.5325 4.2325 9 P 0 ;1
L 2.5325 4.2825 2.5325 4.2825 9 P 0 ;1
L 2.5325 4.3325 2.5325 4.3325 9 P 0 ;1
L 2.5325 4.3825 2.5325 4.3825 9 P 0 ;1
L 2.5325 4.4325 2.5325 4.4325 9 P 0 ;1
L 2.5325 4.4825 2.5325 4.4825 9 P 0 ;1
L 2.5325 4.5325 2.5325 4.5325 9 P 0 ;1
L 2.5325 4.5825 2.5325 4.5825 9 P 0 ;1
L 2.5325 4.6325 2.5325 4.6325 9 P 0 ;1
L 2.5325 4.6825 2.5325 4.6825 9 P 0 ;1
L 2.5325 4.8825 2.5325 4.8825 9 P 0 ;1
L 2.5325 4.9325 2.5325 4.9325 9 P 0 ;1
L 2.5325 4.9825 2.5325 4.9825 9 P 0 ;1
L 2.5325 5.0325 2.5325 5.0325 9 P 0 ;1
L 2.5325 5.0825 2.5325 5.0825 9 P 0 ;1
L 2.5325 5.1325 2.5325 5.1325 9 P 0 ;1
L 2.5325 5.1825 2.5325 5.1825 9 P 0 ;1
L 2.5325 5.2325 2.5325 5.2325 9 P 0 ;1
L 2.5325 5.2825 2.5325 5.2825 9 P 0 ;1
L 2.5325 5.3325 2.5325 5.3325 9 P 0 ;1
L 2.5325 5.3825 2.5325 5.3825 9 P 0 ;1
L 2.5325 5.4325 2.5325 5.4325 9 P 0 ;1
L 2.5325 5.4825 2.5325 5.4825 9 P 0 ;1
L 2.5325 5.5325 2.5325 5.5325 9 P 0 ;1
L 2.5325 5.5825 2.5325 5.5825 9 P 0 ;1
L 2.5325 5.6325 2.5325 5.6325 9 P 0 ;1
L 2.5325 5.6825 2.5325 5.6825 9 P 0 ;1
L 2.5325 5.7325 2.5325 5.7325 9 P 0 ;1
L 2.5325 5.7825 2.5325 5.7825 9 P 0 ;1
L 2.5325 5.8325 2.5325 5.8325 9 P 0 ;1
L 2.5325 5.8825 2.5325 5.8825 9 P 0 ;1
L 2.5825 0.1325 2.5825 0.1325 9 P 0 ;1
L 2.5825 0.1825 2.5825 0.1825 9 P 0 ;1
L 2.5825 0.2325 2.5825 0.2325 9 P 0 ;1
L 2.5825 0.2825 2.5825 0.2825 9 P 0 ;1
L 2.5825 0.3325 2.5825 0.3325 9 P 0 ;1
L 2.5825 0.3825 2.5825 0.3825 9 P 0 ;1
L 2.5825 0.4325 2.5825 0.4325 9 P 0 ;1
L 2.5825 0.4825 2.5825 0.4825 9 P 0 ;1
L 2.5825 0.5325 2.5825 0.5325 9 P 0 ;1
L 2.5825 0.5825 2.5825 0.5825 9 P 0 ;1
L 2.5825 0.6325 2.5825 0.6325 9 P 0 ;1
L 2.5825 0.6825 2.5825 0.6825 9 P 0 ;1
L 2.5825 0.7325 2.5825 0.7325 9 P 0 ;1
L 2.5825 1.3325 2.5825 1.3325 9 P 0 ;1
L 2.5825 1.3825 2.5825 1.3825 9 P 0 ;1
L 2.5825 1.4325 2.5825 1.4325 9 P 0 ;1
L 2.5825 1.4825 2.5825 1.4825 9 P 0 ;1
L 2.5825 1.5325 2.5825 1.5325 9 P 0 ;1
L 2.5825 1.5825 2.5825 1.5825 9 P 0 ;1
L 2.5825 1.8825 2.5825 1.8825 9 P 0 ;1
L 2.5825 1.9325 2.5825 1.9325 9 P 0 ;1
L 2.5825 1.9825 2.5825 1.9825 9 P 0 ;1
L 2.5825 2.0325 2.5825 2.0325 9 P 0 ;1
L 2.5825 2.0825 2.5825 2.0825 9 P 0 ;1
L 2.5825 2.1325 2.5825 2.1325 9 P 0 ;1
L 2.5825 2.1825 2.5825 2.1825 9 P 0 ;1
L 2.5825 2.2325 2.5825 2.2325 9 P 0 ;1
L 2.5825 2.2825 2.5825 2.2825 9 P 0 ;1
L 2.5825 2.3325 2.5825 2.3325 9 P 0 ;1
L 2.5825 2.3825 2.5825 2.3825 9 P 0 ;1
L 2.5825 2.4325 2.5825 2.4325 9 P 0 ;1
L 2.5825 2.4825 2.5825 2.4825 9 P 0 ;1
L 2.5825 2.5325 2.5825 2.5325 9 P 0 ;1
L 2.5825 2.5825 2.5825 2.5825 9 P 0 ;1
L 2.5825 2.6325 2.5825 2.6325 9 P 0 ;1
L 2.5825 2.6825 2.5825 2.6825 9 P 0 ;1
L 2.5825 2.7325 2.5825 2.7325 9 P 0 ;1
L 2.5825 2.7825 2.5825 2.7825 9 P 0 ;1
L 2.5825 2.8325 2.5825 2.8325 9 P 0 ;1
L 2.5825 2.8825 2.5825 2.8825 9 P 0 ;1
L 2.5825 2.9325 2.5825 2.9325 9 P 0 ;1
L 2.5825 2.9825 2.5825 2.9825 9 P 0 ;1
L 2.5825 3.0325 2.5825 3.0325 9 P 0 ;1
L 2.5825 3.0825 2.5825 3.0825 9 P 0 ;1
L 2.5825 3.1325 2.5825 3.1325 9 P 0 ;1
L 2.5825 3.1825 2.5825 3.1825 9 P 0 ;1
L 2.5825 3.2325 2.5825 3.2325 9 P 0 ;1
L 2.5825 3.2825 2.5825 3.2825 9 P 0 ;1
L 2.5825 3.3325 2.5825 3.3325 9 P 0 ;1
L 2.5825 3.3825 2.5825 3.3825 9 P 0 ;1
L 2.5825 3.4325 2.5825 3.4325 9 P 0 ;1
L 2.5825 3.4825 2.5825 3.4825 9 P 0 ;1
L 2.5825 3.5325 2.5825 3.5325 9 P 0 ;1
L 2.5825 3.5825 2.5825 3.5825 9 P 0 ;1
L 2.5825 3.6325 2.5825 3.6325 9 P 0 ;1
L 2.5825 3.6825 2.5825 3.6825 9 P 0 ;1
L 2.5825 3.7325 2.5825 3.7325 9 P 0 ;1
L 2.5825 3.7825 2.5825 3.7825 9 P 0 ;1
L 2.5825 3.8325 2.5825 3.8325 9 P 0 ;1
L 2.5825 3.8825 2.5825 3.8825 9 P 0 ;1
L 2.5825 4.1825 2.5825 4.1825 9 P 0 ;1
L 2.5825 4.2325 2.5825 4.2325 9 P 0 ;1
L 2.5825 4.2825 2.5825 4.2825 9 P 0 ;1
L 2.5825 4.3325 2.5825 4.3325 9 P 0 ;1
L 2.5825 4.3825 2.5825 4.3825 9 P 0 ;1
L 2.5825 4.4325 2.5825 4.4325 9 P 0 ;1
L 2.5825 4.4825 2.5825 4.4825 9 P 0 ;1
L 2.5825 4.5325 2.5825 4.5325 9 P 0 ;1
L 2.5825 4.5825 2.5825 4.5825 9 P 0 ;1
L 2.5825 4.6325 2.5825 4.6325 9 P 0 ;1
L 2.5825 4.6825 2.5825 4.6825 9 P 0 ;1
L 2.5825 4.7325 2.5825 4.7325 9 P 0 ;1
L 2.5825 4.7825 2.5825 4.7825 9 P 0 ;1
L 2.5825 4.8325 2.5825 4.8325 9 P 0 ;1
L 2.5825 4.8825 2.5825 4.8825 9 P 0 ;1
L 2.5825 4.9325 2.5825 4.9325 9 P 0 ;1
L 2.5825 4.9825 2.5825 4.9825 9 P 0 ;1
L 2.5825 5.0325 2.5825 5.0325 9 P 0 ;1
L 2.5825 5.0825 2.5825 5.0825 9 P 0 ;1
L 2.5825 5.1325 2.5825 5.1325 9 P 0 ;1
L 2.5825 5.1825 2.5825 5.1825 9 P 0 ;1
L 2.5825 5.2325 2.5825 5.2325 9 P 0 ;1
L 2.5825 5.2825 2.5825 5.2825 9 P 0 ;1
L 2.5825 5.3325 2.5825 5.3325 9 P 0 ;1
L 2.5825 5.3825 2.5825 5.3825 9 P 0 ;1
L 2.5825 5.4325 2.5825 5.4325 9 P 0 ;1
L 2.5825 5.4825 2.5825 5.4825 9 P 0 ;1
L 2.5825 5.5325 2.5825 5.5325 9 P 0 ;1
L 2.5825 5.5825 2.5825 5.5825 9 P 0 ;1
L 2.5825 5.6325 2.5825 5.6325 9 P 0 ;1
L 2.5825 5.6825 2.5825 5.6825 9 P 0 ;1
L 2.5825 5.7325 2.5825 5.7325 9 P 0 ;1
L 2.5825 5.7825 2.5825 5.7825 9 P 0 ;1
L 2.5825 5.8325 2.5825 5.8325 9 P 0 ;1
L 2.5825 5.8825 2.5825 5.8825 9 P 0 ;1
L 2.6325 0.1325 2.6325 0.1325 9 P 0 ;1
L 2.6325 0.1825 2.6325 0.1825 9 P 0 ;1
L 2.6325 0.2325 2.6325 0.2325 9 P 0 ;1
L 2.6325 0.2825 2.6325 0.2825 9 P 0 ;1
L 2.6325 0.3325 2.6325 0.3325 9 P 0 ;1
L 2.6325 0.3825 2.6325 0.3825 9 P 0 ;1
L 2.6325 0.4325 2.6325 0.4325 9 P 0 ;1
L 2.6325 0.4825 2.6325 0.4825 9 P 0 ;1
L 2.6325 0.5325 2.6325 0.5325 9 P 0 ;1
L 2.6325 0.5825 2.6325 0.5825 9 P 0 ;1
L 2.6325 0.6325 2.6325 0.6325 9 P 0 ;1
L 2.6325 0.6825 2.6325 0.6825 9 P 0 ;1
L 2.6325 0.7325 2.6325 0.7325 9 P 0 ;1
L 2.6325 1.3325 2.6325 1.3325 9 P 0 ;1
L 2.6325 1.3825 2.6325 1.3825 9 P 0 ;1
L 2.6325 1.4325 2.6325 1.4325 9 P 0 ;1
L 2.6325 1.4825 2.6325 1.4825 9 P 0 ;1
L 2.6325 1.5325 2.6325 1.5325 9 P 0 ;1
L 2.6325 1.8325 2.6325 1.8325 9 P 0 ;1
L 2.6325 1.8825 2.6325 1.8825 9 P 0 ;1
L 2.6325 1.9325 2.6325 1.9325 9 P 0 ;1
L 2.6325 1.9825 2.6325 1.9825 9 P 0 ;1
L 2.6325 2.0325 2.6325 2.0325 9 P 0 ;1
L 2.6325 2.0825 2.6325 2.0825 9 P 0 ;1
L 2.6325 2.1325 2.6325 2.1325 9 P 0 ;1
L 2.6325 2.1825 2.6325 2.1825 9 P 0 ;1
L 2.6325 2.2325 2.6325 2.2325 9 P 0 ;1
L 2.6325 2.2825 2.6325 2.2825 9 P 0 ;1
L 2.6325 2.3325 2.6325 2.3325 9 P 0 ;1
L 2.6325 2.3825 2.6325 2.3825 9 P 0 ;1
L 2.6325 2.4325 2.6325 2.4325 9 P 0 ;1
L 2.6325 2.4825 2.6325 2.4825 9 P 0 ;1
L 2.6325 2.5325 2.6325 2.5325 9 P 0 ;1
L 2.6325 2.5825 2.6325 2.5825 9 P 0 ;1
L 2.6325 2.6325 2.6325 2.6325 9 P 0 ;1
L 2.6325 2.6825 2.6325 2.6825 9 P 0 ;1
L 2.6325 2.7325 2.6325 2.7325 9 P 0 ;1
L 2.6325 2.7825 2.6325 2.7825 9 P 0 ;1
L 2.6325 2.8325 2.6325 2.8325 9 P 0 ;1
L 2.6325 2.8825 2.6325 2.8825 9 P 0 ;1
L 2.6325 2.9325 2.6325 2.9325 9 P 0 ;1
L 2.6325 2.9825 2.6325 2.9825 9 P 0 ;1
L 2.6325 3.0325 2.6325 3.0325 9 P 0 ;1
L 2.6325 3.0825 2.6325 3.0825 9 P 0 ;1
L 2.6325 3.1325 2.6325 3.1325 9 P 0 ;1
L 2.6325 3.1825 2.6325 3.1825 9 P 0 ;1
L 2.6325 3.2325 2.6325 3.2325 9 P 0 ;1
L 2.6325 3.2825 2.6325 3.2825 9 P 0 ;1
L 2.6325 3.3325 2.6325 3.3325 9 P 0 ;1
L 2.6325 3.3825 2.6325 3.3825 9 P 0 ;1
L 2.6325 3.4325 2.6325 3.4325 9 P 0 ;1
L 2.6325 3.4825 2.6325 3.4825 9 P 0 ;1
L 2.6325 3.5325 2.6325 3.5325 9 P 0 ;1
L 2.6325 3.5825 2.6325 3.5825 9 P 0 ;1
L 2.6325 3.6325 2.6325 3.6325 9 P 0 ;1
L 2.6325 3.6825 2.6325 3.6825 9 P 0 ;1
L 2.6325 3.7325 2.6325 3.7325 9 P 0 ;1
L 2.6325 3.7825 2.6325 3.7825 9 P 0 ;1
L 2.6325 3.8325 2.6325 3.8325 9 P 0 ;1
L 2.6325 3.8825 2.6325 3.8825 9 P 0 ;1
L 2.6325 4.1825 2.6325 4.1825 9 P 0 ;1
L 2.6325 4.2325 2.6325 4.2325 9 P 0 ;1
L 2.6325 4.2825 2.6325 4.2825 9 P 0 ;1
L 2.6325 4.3325 2.6325 4.3325 9 P 0 ;1
L 2.6325 4.3825 2.6325 4.3825 9 P 0 ;1
L 2.6325 4.4325 2.6325 4.4325 9 P 0 ;1
L 2.6325 4.4825 2.6325 4.4825 9 P 0 ;1
L 2.6325 4.5325 2.6325 4.5325 9 P 0 ;1
L 2.6325 4.5825 2.6325 4.5825 9 P 0 ;1
L 2.6325 4.6325 2.6325 4.6325 9 P 0 ;1
L 2.6325 4.6825 2.6325 4.6825 9 P 0 ;1
L 2.6325 4.9825 2.6325 4.9825 9 P 0 ;1
L 2.6325 5.1325 2.6325 5.1325 9 P 0 ;1
L 2.6325 5.1825 2.6325 5.1825 9 P 0 ;1
L 2.6325 5.2325 2.6325 5.2325 9 P 0 ;1
L 2.6325 5.2825 2.6325 5.2825 9 P 0 ;1
L 2.6325 5.3325 2.6325 5.3325 9 P 0 ;1
L 2.6325 5.3825 2.6325 5.3825 9 P 0 ;1
L 2.6325 5.4325 2.6325 5.4325 9 P 0 ;1
L 2.6325 5.4825 2.6325 5.4825 9 P 0 ;1
L 2.6325 5.5325 2.6325 5.5325 9 P 0 ;1
L 2.6325 5.5825 2.6325 5.5825 9 P 0 ;1
L 2.6325 5.6325 2.6325 5.6325 9 P 0 ;1
L 2.6325 5.6825 2.6325 5.6825 9 P 0 ;1
L 2.6325 5.7325 2.6325 5.7325 9 P 0 ;1
L 2.6325 5.7825 2.6325 5.7825 9 P 0 ;1
L 2.6325 5.8325 2.6325 5.8325 9 P 0 ;1
L 2.6325 5.8825 2.6325 5.8825 9 P 0 ;1
L 2.6825 0.1325 2.6825 0.1325 9 P 0 ;1
L 2.6825 0.1825 2.6825 0.1825 9 P 0 ;1
L 2.6825 0.2325 2.6825 0.2325 9 P 0 ;1
L 2.6825 0.2825 2.6825 0.2825 9 P 0 ;1
L 2.6825 0.3325 2.6825 0.3325 9 P 0 ;1
L 2.6825 0.3825 2.6825 0.3825 9 P 0 ;1
L 2.6825 0.4325 2.6825 0.4325 9 P 0 ;1
L 2.6825 0.4825 2.6825 0.4825 9 P 0 ;1
L 2.6825 0.5325 2.6825 0.5325 9 P 0 ;1
L 2.6825 0.5825 2.6825 0.5825 9 P 0 ;1
L 2.6825 0.6325 2.6825 0.6325 9 P 0 ;1
L 2.6825 0.6825 2.6825 0.6825 9 P 0 ;1
L 2.6825 0.7325 2.6825 0.7325 9 P 0 ;1
L 2.6825 1.2825 2.6825 1.2825 9 P 0 ;1
L 2.6825 1.3325 2.6825 1.3325 9 P 0 ;1
L 2.6825 1.3825 2.6825 1.3825 9 P 0 ;1
L 2.6825 1.4325 2.6825 1.4325 9 P 0 ;1
L 2.6825 1.4825 2.6825 1.4825 9 P 0 ;1
L 2.6825 1.5325 2.6825 1.5325 9 P 0 ;1
L 2.6825 1.8325 2.6825 1.8325 9 P 0 ;1
L 2.6825 1.8825 2.6825 1.8825 9 P 0 ;1
L 2.6825 1.9325 2.6825 1.9325 9 P 0 ;1
L 2.6825 1.9825 2.6825 1.9825 9 P 0 ;1
L 2.6825 2.0325 2.6825 2.0325 9 P 0 ;1
L 2.6825 2.0825 2.6825 2.0825 9 P 0 ;1
L 2.6825 2.1325 2.6825 2.1325 9 P 0 ;1
L 2.6825 2.1825 2.6825 2.1825 9 P 0 ;1
L 2.6825 2.2325 2.6825 2.2325 9 P 0 ;1
L 2.6825 2.2825 2.6825 2.2825 9 P 0 ;1
L 2.6825 2.3325 2.6825 2.3325 9 P 0 ;1
L 2.6825 2.3825 2.6825 2.3825 9 P 0 ;1
L 2.6825 2.4325 2.6825 2.4325 9 P 0 ;1
L 2.6825 2.4825 2.6825 2.4825 9 P 0 ;1
L 2.6825 2.5325 2.6825 2.5325 9 P 0 ;1
L 2.6825 2.5825 2.6825 2.5825 9 P 0 ;1
L 2.6825 2.6325 2.6825 2.6325 9 P 0 ;1
L 2.6825 2.6825 2.6825 2.6825 9 P 0 ;1
L 2.6825 2.7325 2.6825 2.7325 9 P 0 ;1
L 2.6825 2.7825 2.6825 2.7825 9 P 0 ;1
L 2.6825 2.8325 2.6825 2.8325 9 P 0 ;1
L 2.6825 2.8825 2.6825 2.8825 9 P 0 ;1
L 2.6825 2.9325 2.6825 2.9325 9 P 0 ;1
L 2.6825 2.9825 2.6825 2.9825 9 P 0 ;1
L 2.6825 3.0325 2.6825 3.0325 9 P 0 ;1
L 2.6825 3.0825 2.6825 3.0825 9 P 0 ;1
L 2.6825 3.1325 2.6825 3.1325 9 P 0 ;1
L 2.6825 3.1825 2.6825 3.1825 9 P 0 ;1
L 2.6825 3.2325 2.6825 3.2325 9 P 0 ;1
L 2.6825 3.2825 2.6825 3.2825 9 P 0 ;1
L 2.6825 3.3325 2.6825 3.3325 9 P 0 ;1
L 2.6825 3.3825 2.6825 3.3825 9 P 0 ;1
L 2.6825 3.4325 2.6825 3.4325 9 P 0 ;1
L 2.6825 3.4825 2.6825 3.4825 9 P 0 ;1
L 2.6825 3.5325 2.6825 3.5325 9 P 0 ;1
L 2.6825 3.5825 2.6825 3.5825 9 P 0 ;1
L 2.6825 3.6325 2.6825 3.6325 9 P 0 ;1
L 2.6825 3.6825 2.6825 3.6825 9 P 0 ;1
L 2.6825 3.7325 2.6825 3.7325 9 P 0 ;1
L 2.6825 3.7825 2.6825 3.7825 9 P 0 ;1
L 2.6825 3.8325 2.6825 3.8325 9 P 0 ;1
L 2.6825 3.8825 2.6825 3.8825 9 P 0 ;1
L 2.6825 3.9325 2.6825 3.9325 9 P 0 ;1
L 2.6825 4.1825 2.6825 4.1825 9 P 0 ;1
L 2.6825 4.2325 2.6825 4.2325 9 P 0 ;1
L 2.6825 4.2825 2.6825 4.2825 9 P 0 ;1
L 2.6825 4.3325 2.6825 4.3325 9 P 0 ;1
L 2.6825 4.3825 2.6825 4.3825 9 P 0 ;1
L 2.6825 4.4325 2.6825 4.4325 9 P 0 ;1
L 2.6825 4.4825 2.6825 4.4825 9 P 0 ;1
L 2.6825 4.5325 2.6825 4.5325 9 P 0 ;1
L 2.6825 4.5825 2.6825 4.5825 9 P 0 ;1
L 2.6825 5.2825 2.6825 5.2825 9 P 0 ;1
L 2.6825 5.3325 2.6825 5.3325 9 P 0 ;1
L 2.6825 5.3825 2.6825 5.3825 9 P 0 ;1
L 2.6825 5.4325 2.6825 5.4325 9 P 0 ;1
L 2.6825 5.4825 2.6825 5.4825 9 P 0 ;1
L 2.6825 5.5325 2.6825 5.5325 9 P 0 ;1
L 2.6825 5.5825 2.6825 5.5825 9 P 0 ;1
L 2.6825 5.6325 2.6825 5.6325 9 P 0 ;1
L 2.6825 5.6825 2.6825 5.6825 9 P 0 ;1
L 2.6825 5.7325 2.6825 5.7325 9 P 0 ;1
L 2.6825 5.7825 2.6825 5.7825 9 P 0 ;1
L 2.6825 5.8325 2.6825 5.8325 9 P 0 ;1
L 2.6825 5.8825 2.6825 5.8825 9 P 0 ;1
L 2.7325 0.1325 2.7325 0.1325 9 P 0 ;1
L 2.7325 0.1825 2.7325 0.1825 9 P 0 ;1
L 2.7325 0.2325 2.7325 0.2325 9 P 0 ;1
L 2.7325 0.2825 2.7325 0.2825 9 P 0 ;1
L 2.7325 0.3325 2.7325 0.3325 9 P 0 ;1
L 2.7325 0.3825 2.7325 0.3825 9 P 0 ;1
L 2.7325 0.4325 2.7325 0.4325 9 P 0 ;1
L 2.7325 0.4825 2.7325 0.4825 9 P 0 ;1
L 2.7325 0.5325 2.7325 0.5325 9 P 0 ;1
L 2.7325 0.5825 2.7325 0.5825 9 P 0 ;1
L 2.7325 0.6325 2.7325 0.6325 9 P 0 ;1
L 2.7325 0.6825 2.7325 0.6825 9 P 0 ;1
L 2.7325 0.7325 2.7325 0.7325 9 P 0 ;1
L 2.7325 1.2825 2.7325 1.2825 9 P 0 ;1
L 2.7325 1.3325 2.7325 1.3325 9 P 0 ;1
L 2.7325 1.3825 2.7325 1.3825 9 P 0 ;1
L 2.7325 1.4325 2.7325 1.4325 9 P 0 ;1
L 2.7325 1.4825 2.7325 1.4825 9 P 0 ;1
L 2.7325 1.5325 2.7325 1.5325 9 P 0 ;1
L 2.7325 1.8325 2.7325 1.8325 9 P 0 ;1
L 2.7325 1.8825 2.7325 1.8825 9 P 0 ;1
L 2.7325 1.9325 2.7325 1.9325 9 P 0 ;1
L 2.7325 1.9825 2.7325 1.9825 9 P 0 ;1
L 2.7325 2.0325 2.7325 2.0325 9 P 0 ;1
L 2.7325 2.0825 2.7325 2.0825 9 P 0 ;1
L 2.7325 2.1325 2.7325 2.1325 9 P 0 ;1
L 2.7325 2.1825 2.7325 2.1825 9 P 0 ;1
L 2.7325 2.2325 2.7325 2.2325 9 P 0 ;1
L 2.7325 2.2825 2.7325 2.2825 9 P 0 ;1
L 2.7325 2.3325 2.7325 2.3325 9 P 0 ;1
L 2.7325 2.3825 2.7325 2.3825 9 P 0 ;1
L 2.7325 2.4325 2.7325 2.4325 9 P 0 ;1
L 2.7325 2.4825 2.7325 2.4825 9 P 0 ;1
L 2.7325 2.5325 2.7325 2.5325 9 P 0 ;1
L 2.7325 2.5825 2.7325 2.5825 9 P 0 ;1
L 2.7325 2.6325 2.7325 2.6325 9 P 0 ;1
L 2.7325 2.6825 2.7325 2.6825 9 P 0 ;1
L 2.7325 2.7325 2.7325 2.7325 9 P 0 ;1
L 2.7325 2.7825 2.7325 2.7825 9 P 0 ;1
L 2.7325 2.8325 2.7325 2.8325 9 P 0 ;1
L 2.7325 2.8825 2.7325 2.8825 9 P 0 ;1
L 2.7325 2.9325 2.7325 2.9325 9 P 0 ;1
L 2.7325 2.9825 2.7325 2.9825 9 P 0 ;1
L 2.7325 3.0325 2.7325 3.0325 9 P 0 ;1
L 2.7325 3.0825 2.7325 3.0825 9 P 0 ;1
L 2.7325 3.1325 2.7325 3.1325 9 P 0 ;1
L 2.7325 3.1825 2.7325 3.1825 9 P 0 ;1
L 2.7325 3.2325 2.7325 3.2325 9 P 0 ;1
L 2.7325 3.2825 2.7325 3.2825 9 P 0 ;1
L 2.7325 3.3325 2.7325 3.3325 9 P 0 ;1
L 2.7325 3.3825 2.7325 3.3825 9 P 0 ;1
L 2.7325 3.4325 2.7325 3.4325 9 P 0 ;1
L 2.7325 3.4825 2.7325 3.4825 9 P 0 ;1
L 2.7325 3.5325 2.7325 3.5325 9 P 0 ;1
L 2.7325 3.5825 2.7325 3.5825 9 P 0 ;1
L 2.7325 3.6325 2.7325 3.6325 9 P 0 ;1
L 2.7325 3.6825 2.7325 3.6825 9 P 0 ;1
L 2.7325 3.7325 2.7325 3.7325 9 P 0 ;1
L 2.7325 3.7825 2.7325 3.7825 9 P 0 ;1
L 2.7325 3.8325 2.7325 3.8325 9 P 0 ;1
L 2.7325 3.8825 2.7325 3.8825 9 P 0 ;1
L 2.7325 3.9325 2.7325 3.9325 9 P 0 ;1
L 2.7325 4.1825 2.7325 4.1825 9 P 0 ;1
L 2.7325 4.2325 2.7325 4.2325 9 P 0 ;1
L 2.7325 4.2825 2.7325 4.2825 9 P 0 ;1
L 2.7325 4.3325 2.7325 4.3325 9 P 0 ;1
L 2.7325 4.3825 2.7325 4.3825 9 P 0 ;1
L 2.7325 4.4325 2.7325 4.4325 9 P 0 ;1
L 2.7325 4.4825 2.7325 4.4825 9 P 0 ;1
L 2.7325 4.5325 2.7325 4.5325 9 P 0 ;1
L 2.7325 4.5825 2.7325 4.5825 9 P 0 ;1
L 2.7325 5.2825 2.7325 5.2825 9 P 0 ;1
L 2.7325 5.3325 2.7325 5.3325 9 P 0 ;1
L 2.7325 5.3825 2.7325 5.3825 9 P 0 ;1
L 2.7325 5.4325 2.7325 5.4325 9 P 0 ;1
L 2.7325 5.4825 2.7325 5.4825 9 P 0 ;1
L 2.7325 5.5325 2.7325 5.5325 9 P 0 ;1
L 2.7325 5.5825 2.7325 5.5825 9 P 0 ;1
L 2.7325 5.6325 2.7325 5.6325 9 P 0 ;1
L 2.7325 5.6825 2.7325 5.6825 9 P 0 ;1
L 2.7325 5.7325 2.7325 5.7325 9 P 0 ;1
L 2.7325 5.7825 2.7325 5.7825 9 P 0 ;1
L 2.7325 5.8325 2.7325 5.8325 9 P 0 ;1
L 2.7325 5.8825 2.7325 5.8825 9 P 0 ;1
L 2.7825 0.1325 2.7825 0.1325 9 P 0 ;1
L 2.7825 0.1825 2.7825 0.1825 9 P 0 ;1
L 2.7825 0.2325 2.7825 0.2325 9 P 0 ;1
L 2.7825 0.2825 2.7825 0.2825 9 P 0 ;1
L 2.7825 0.3325 2.7825 0.3325 9 P 0 ;1
L 2.7825 0.3825 2.7825 0.3825 9 P 0 ;1
L 2.7825 0.4325 2.7825 0.4325 9 P 0 ;1
L 2.7825 0.4825 2.7825 0.4825 9 P 0 ;1
L 2.7825 0.5325 2.7825 0.5325 9 P 0 ;1
L 2.7825 0.5825 2.7825 0.5825 9 P 0 ;1
L 2.7825 0.6325 2.7825 0.6325 9 P 0 ;1
L 2.7825 0.6825 2.7825 0.6825 9 P 0 ;1
L 2.7825 0.7325 2.7825 0.7325 9 P 0 ;1
L 2.7825 1.3325 2.7825 1.3325 9 P 0 ;1
L 2.7825 1.3825 2.7825 1.3825 9 P 0 ;1
L 2.7825 1.4325 2.7825 1.4325 9 P 0 ;1
L 2.7825 1.4825 2.7825 1.4825 9 P 0 ;1
L 2.7825 1.5325 2.7825 1.5325 9 P 0 ;1
L 2.7825 1.8325 2.7825 1.8325 9 P 0 ;1
L 2.7825 1.8825 2.7825 1.8825 9 P 0 ;1
L 2.7825 1.9325 2.7825 1.9325 9 P 0 ;1
L 2.7825 1.9825 2.7825 1.9825 9 P 0 ;1
L 2.7825 2.0325 2.7825 2.0325 9 P 0 ;1
L 2.7825 2.0825 2.7825 2.0825 9 P 0 ;1
L 2.7825 2.1325 2.7825 2.1325 9 P 0 ;1
L 2.7825 2.1825 2.7825 2.1825 9 P 0 ;1
L 2.7825 2.2325 2.7825 2.2325 9 P 0 ;1
L 2.7825 2.2825 2.7825 2.2825 9 P 0 ;1
L 2.7825 2.3325 2.7825 2.3325 9 P 0 ;1
L 2.7825 2.3825 2.7825 2.3825 9 P 0 ;1
L 2.7825 2.4325 2.7825 2.4325 9 P 0 ;1
L 2.7825 2.4825 2.7825 2.4825 9 P 0 ;1
L 2.7825 2.5325 2.7825 2.5325 9 P 0 ;1
L 2.7825 2.5825 2.7825 2.5825 9 P 0 ;1
L 2.7825 2.6325 2.7825 2.6325 9 P 0 ;1
L 2.7825 2.6825 2.7825 2.6825 9 P 0 ;1
L 2.7825 2.7325 2.7825 2.7325 9 P 0 ;1
L 2.7825 2.7825 2.7825 2.7825 9 P 0 ;1
L 2.7825 2.8325 2.7825 2.8325 9 P 0 ;1
L 2.7825 2.8825 2.7825 2.8825 9 P 0 ;1
L 2.7825 2.9325 2.7825 2.9325 9 P 0 ;1
L 2.7825 2.9825 2.7825 2.9825 9 P 0 ;1
L 2.7825 3.0325 2.7825 3.0325 9 P 0 ;1
L 2.7825 3.0825 2.7825 3.0825 9 P 0 ;1
L 2.7825 3.1325 2.7825 3.1325 9 P 0 ;1
L 2.7825 3.1825 2.7825 3.1825 9 P 0 ;1
L 2.7825 3.2325 2.7825 3.2325 9 P 0 ;1
L 2.7825 3.2825 2.7825 3.2825 9 P 0 ;1
L 2.7825 3.3325 2.7825 3.3325 9 P 0 ;1
L 2.7825 3.3825 2.7825 3.3825 9 P 0 ;1
L 2.7825 3.4325 2.7825 3.4325 9 P 0 ;1
L 2.7825 3.4825 2.7825 3.4825 9 P 0 ;1
L 2.7825 3.5325 2.7825 3.5325 9 P 0 ;1
L 2.7825 3.5825 2.7825 3.5825 9 P 0 ;1
L 2.7825 3.6325 2.7825 3.6325 9 P 0 ;1
L 2.7825 3.6825 2.7825 3.6825 9 P 0 ;1
L 2.7825 3.7325 2.7825 3.7325 9 P 0 ;1
L 2.7825 3.7825 2.7825 3.7825 9 P 0 ;1
L 2.7825 3.8325 2.7825 3.8325 9 P 0 ;1
L 2.7825 3.8825 2.7825 3.8825 9 P 0 ;1
L 2.7825 3.9325 2.7825 3.9325 9 P 0 ;1
L 2.7825 4.1825 2.7825 4.1825 9 P 0 ;1
L 2.7825 4.2325 2.7825 4.2325 9 P 0 ;1
L 2.7825 4.2825 2.7825 4.2825 9 P 0 ;1
L 2.7825 4.3325 2.7825 4.3325 9 P 0 ;1
L 2.7825 4.3825 2.7825 4.3825 9 P 0 ;1
L 2.7825 4.4325 2.7825 4.4325 9 P 0 ;1
L 2.7825 4.4825 2.7825 4.4825 9 P 0 ;1
L 2.7825 4.5325 2.7825 4.5325 9 P 0 ;1
L 2.7825 4.5825 2.7825 4.5825 9 P 0 ;1
L 2.7825 5.2825 2.7825 5.2825 9 P 0 ;1
L 2.7825 5.3325 2.7825 5.3325 9 P 0 ;1
L 2.7825 5.3825 2.7825 5.3825 9 P 0 ;1
L 2.7825 5.4325 2.7825 5.4325 9 P 0 ;1
L 2.7825 5.4825 2.7825 5.4825 9 P 0 ;1
L 2.7825 5.5325 2.7825 5.5325 9 P 0 ;1
L 2.7825 5.5825 2.7825 5.5825 9 P 0 ;1
L 2.7825 5.6325 2.7825 5.6325 9 P 0 ;1
L 2.7825 5.6825 2.7825 5.6825 9 P 0 ;1
L 2.7825 5.7325 2.7825 5.7325 9 P 0 ;1
L 2.7825 5.7825 2.7825 5.7825 9 P 0 ;1
L 2.7825 5.8325 2.7825 5.8325 9 P 0 ;1
L 2.7825 5.8825 2.7825 5.8825 9 P 0 ;1
L 2.8325 0.1325 2.8325 0.1325 9 P 0 ;1
L 2.8325 0.1825 2.8325 0.1825 9 P 0 ;1
L 2.8325 0.2325 2.8325 0.2325 9 P 0 ;1
L 2.8325 0.2825 2.8325 0.2825 9 P 0 ;1
L 2.8325 0.3325 2.8325 0.3325 9 P 0 ;1
L 2.8325 0.3825 2.8325 0.3825 9 P 0 ;1
L 2.8325 0.4325 2.8325 0.4325 9 P 0 ;1
L 2.8325 0.4825 2.8325 0.4825 9 P 0 ;1
L 2.8325 0.5325 2.8325 0.5325 9 P 0 ;1
L 2.8325 0.5825 2.8325 0.5825 9 P 0 ;1
L 2.8325 0.6325 2.8325 0.6325 9 P 0 ;1
L 2.8325 0.6825 2.8325 0.6825 9 P 0 ;1
L 2.8325 1.3325 2.8325 1.3325 9 P 0 ;1
L 2.8325 1.3825 2.8325 1.3825 9 P 0 ;1
L 2.8325 1.4325 2.8325 1.4325 9 P 0 ;1
L 2.8325 1.4825 2.8325 1.4825 9 P 0 ;1
L 2.8325 1.5325 2.8325 1.5325 9 P 0 ;1
L 2.8325 1.8325 2.8325 1.8325 9 P 0 ;1
L 2.8325 1.8825 2.8325 1.8825 9 P 0 ;1
L 2.8325 1.9325 2.8325 1.9325 9 P 0 ;1
L 2.8325 1.9825 2.8325 1.9825 9 P 0 ;1
L 2.8325 2.0325 2.8325 2.0325 9 P 0 ;1
L 2.8325 2.0825 2.8325 2.0825 9 P 0 ;1
L 2.8325 2.1325 2.8325 2.1325 9 P 0 ;1
L 2.8325 2.1825 2.8325 2.1825 9 P 0 ;1
L 2.8325 2.2325 2.8325 2.2325 9 P 0 ;1
L 2.8325 2.2825 2.8325 2.2825 9 P 0 ;1
L 2.8325 2.3325 2.8325 2.3325 9 P 0 ;1
L 2.8325 2.3825 2.8325 2.3825 9 P 0 ;1
L 2.8325 2.4325 2.8325 2.4325 9 P 0 ;1
L 2.8325 2.4825 2.8325 2.4825 9 P 0 ;1
L 2.8325 2.5325 2.8325 2.5325 9 P 0 ;1
L 2.8325 2.5825 2.8325 2.5825 9 P 0 ;1
L 2.8325 2.6325 2.8325 2.6325 9 P 0 ;1
L 2.8325 2.6825 2.8325 2.6825 9 P 0 ;1
L 2.8325 2.7325 2.8325 2.7325 9 P 0 ;1
L 2.8325 2.7825 2.8325 2.7825 9 P 0 ;1
L 2.8325 2.8325 2.8325 2.8325 9 P 0 ;1
L 2.8325 2.8825 2.8325 2.8825 9 P 0 ;1
L 2.8325 2.9325 2.8325 2.9325 9 P 0 ;1
L 2.8325 2.9825 2.8325 2.9825 9 P 0 ;1
L 2.8325 3.0325 2.8325 3.0325 9 P 0 ;1
L 2.8325 3.0825 2.8325 3.0825 9 P 0 ;1
L 2.8325 3.1325 2.8325 3.1325 9 P 0 ;1
L 2.8325 3.1825 2.8325 3.1825 9 P 0 ;1
L 2.8325 3.2325 2.8325 3.2325 9 P 0 ;1
L 2.8325 3.2825 2.8325 3.2825 9 P 0 ;1
L 2.8325 3.3325 2.8325 3.3325 9 P 0 ;1
L 2.8325 3.3825 2.8325 3.3825 9 P 0 ;1
L 2.8325 3.4325 2.8325 3.4325 9 P 0 ;1
L 2.8325 3.4825 2.8325 3.4825 9 P 0 ;1
L 2.8325 3.5325 2.8325 3.5325 9 P 0 ;1
L 2.8325 3.5825 2.8325 3.5825 9 P 0 ;1
L 2.8325 3.6325 2.8325 3.6325 9 P 0 ;1
L 2.8325 3.6825 2.8325 3.6825 9 P 0 ;1
L 2.8325 3.7325 2.8325 3.7325 9 P 0 ;1
L 2.8325 3.7825 2.8325 3.7825 9 P 0 ;1
L 2.8325 3.8325 2.8325 3.8325 9 P 0 ;1
L 2.8325 3.8825 2.8325 3.8825 9 P 0 ;1
L 2.8325 3.9325 2.8325 3.9325 9 P 0 ;1
L 2.8325 4.2325 2.8325 4.2325 9 P 0 ;1
L 2.8325 4.2825 2.8325 4.2825 9 P 0 ;1
L 2.8325 4.3325 2.8325 4.3325 9 P 0 ;1
L 2.8325 4.3825 2.8325 4.3825 9 P 0 ;1
L 2.8325 4.4325 2.8325 4.4325 9 P 0 ;1
L 2.8325 4.4825 2.8325 4.4825 9 P 0 ;1
L 2.8325 4.5325 2.8325 4.5325 9 P 0 ;1
L 2.8325 4.5825 2.8325 4.5825 9 P 0 ;1
L 2.8325 5.2825 2.8325 5.2825 9 P 0 ;1
L 2.8325 5.3325 2.8325 5.3325 9 P 0 ;1
L 2.8325 5.3825 2.8325 5.3825 9 P 0 ;1
L 2.8325 5.4325 2.8325 5.4325 9 P 0 ;1
L 2.8325 5.4825 2.8325 5.4825 9 P 0 ;1
L 2.8325 5.5325 2.8325 5.5325 9 P 0 ;1
L 2.8325 5.5825 2.8325 5.5825 9 P 0 ;1
L 2.8325 5.6325 2.8325 5.6325 9 P 0 ;1
L 2.8325 5.6825 2.8325 5.6825 9 P 0 ;1
L 2.8325 5.7325 2.8325 5.7325 9 P 0 ;1
L 2.8325 5.7825 2.8325 5.7825 9 P 0 ;1
L 2.8325 5.8325 2.8325 5.8325 9 P 0 ;1
L 2.8325 5.8825 2.8325 5.8825 9 P 0 ;1
L 2.8825 0.1325 2.8825 0.1325 9 P 0 ;1
L 2.8825 0.1825 2.8825 0.1825 9 P 0 ;1
L 2.8825 0.2325 2.8825 0.2325 9 P 0 ;1
L 2.8825 0.2825 2.8825 0.2825 9 P 0 ;1
L 2.8825 0.3325 2.8825 0.3325 9 P 0 ;1
L 2.8825 0.3825 2.8825 0.3825 9 P 0 ;1
L 2.8825 0.4325 2.8825 0.4325 9 P 0 ;1
L 2.8825 0.4825 2.8825 0.4825 9 P 0 ;1
L 2.8825 0.5325 2.8825 0.5325 9 P 0 ;1
L 2.8825 0.5825 2.8825 0.5825 9 P 0 ;1
L 2.8825 0.6325 2.8825 0.6325 9 P 0 ;1
L 2.8825 0.6825 2.8825 0.6825 9 P 0 ;1
L 2.8825 1.3325 2.8825 1.3325 9 P 0 ;1
L 2.8825 1.3825 2.8825 1.3825 9 P 0 ;1
L 2.8825 1.4325 2.8825 1.4325 9 P 0 ;1
L 2.8825 1.4825 2.8825 1.4825 9 P 0 ;1
L 2.8825 1.5325 2.8825 1.5325 9 P 0 ;1
L 2.8825 1.7825 2.8825 1.7825 9 P 0 ;1
L 2.8825 1.8325 2.8825 1.8325 9 P 0 ;1
L 2.8825 1.8825 2.8825 1.8825 9 P 0 ;1
L 2.8825 1.9325 2.8825 1.9325 9 P 0 ;1
L 2.8825 1.9825 2.8825 1.9825 9 P 0 ;1
L 2.8825 2.0325 2.8825 2.0325 9 P 0 ;1
L 2.8825 2.0825 2.8825 2.0825 9 P 0 ;1
L 2.8825 2.1325 2.8825 2.1325 9 P 0 ;1
L 2.8825 2.1825 2.8825 2.1825 9 P 0 ;1
L 2.8825 2.2325 2.8825 2.2325 9 P 0 ;1
L 2.8825 2.2825 2.8825 2.2825 9 P 0 ;1
L 2.8825 2.3325 2.8825 2.3325 9 P 0 ;1
L 2.8825 2.3825 2.8825 2.3825 9 P 0 ;1
L 2.8825 2.4325 2.8825 2.4325 9 P 0 ;1
L 2.8825 2.4825 2.8825 2.4825 9 P 0 ;1
L 2.8825 2.5325 2.8825 2.5325 9 P 0 ;1
L 2.8825 2.5825 2.8825 2.5825 9 P 0 ;1
L 2.8825 2.6325 2.8825 2.6325 9 P 0 ;1
L 2.8825 2.6825 2.8825 2.6825 9 P 0 ;1
L 2.8825 2.7325 2.8825 2.7325 9 P 0 ;1
L 2.8825 2.7825 2.8825 2.7825 9 P 0 ;1
L 2.8825 2.8325 2.8825 2.8325 9 P 0 ;1
L 2.8825 2.9825 2.8825 2.9825 9 P 0 ;1
L 2.8825 3.0325 2.8825 3.0325 9 P 0 ;1
L 2.8825 3.0825 2.8825 3.0825 9 P 0 ;1
L 2.8825 3.1325 2.8825 3.1325 9 P 0 ;1
L 2.8825 3.1825 2.8825 3.1825 9 P 0 ;1
L 2.8825 3.2325 2.8825 3.2325 9 P 0 ;1
L 2.8825 3.2825 2.8825 3.2825 9 P 0 ;1
L 2.8825 3.3325 2.8825 3.3325 9 P 0 ;1
L 2.8825 3.3825 2.8825 3.3825 9 P 0 ;1
L 2.8825 3.4325 2.8825 3.4325 9 P 0 ;1
L 2.8825 3.4825 2.8825 3.4825 9 P 0 ;1
L 2.8825 3.5325 2.8825 3.5325 9 P 0 ;1
L 2.8825 3.5825 2.8825 3.5825 9 P 0 ;1
L 2.8825 3.6325 2.8825 3.6325 9 P 0 ;1
L 2.8825 3.6825 2.8825 3.6825 9 P 0 ;1
L 2.8825 3.7325 2.8825 3.7325 9 P 0 ;1
L 2.8825 3.7825 2.8825 3.7825 9 P 0 ;1
L 2.8825 3.8325 2.8825 3.8325 9 P 0 ;1
L 2.8825 3.8825 2.8825 3.8825 9 P 0 ;1
L 2.8825 3.9325 2.8825 3.9325 9 P 0 ;1
L 2.8825 4.2325 2.8825 4.2325 9 P 0 ;1
L 2.8825 4.2825 2.8825 4.2825 9 P 0 ;1
L 2.8825 4.3325 2.8825 4.3325 9 P 0 ;1
L 2.8825 4.3825 2.8825 4.3825 9 P 0 ;1
L 2.8825 4.4325 2.8825 4.4325 9 P 0 ;1
L 2.8825 4.4825 2.8825 4.4825 9 P 0 ;1
L 2.8825 4.5325 2.8825 4.5325 9 P 0 ;1
L 2.8825 4.5825 2.8825 4.5825 9 P 0 ;1
L 2.8825 5.3325 2.8825 5.3325 9 P 0 ;1
L 2.8825 5.3825 2.8825 5.3825 9 P 0 ;1
L 2.8825 5.4325 2.8825 5.4325 9 P 0 ;1
L 2.8825 5.4825 2.8825 5.4825 9 P 0 ;1
L 2.8825 5.5325 2.8825 5.5325 9 P 0 ;1
L 2.8825 5.5825 2.8825 5.5825 9 P 0 ;1
L 2.8825 5.6325 2.8825 5.6325 9 P 0 ;1
L 2.8825 5.6825 2.8825 5.6825 9 P 0 ;1
L 2.8825 5.7325 2.8825 5.7325 9 P 0 ;1
L 2.8825 5.7825 2.8825 5.7825 9 P 0 ;1
L 2.8825 5.8325 2.8825 5.8325 9 P 0 ;1
L 2.8825 5.8825 2.8825 5.8825 9 P 0 ;1
L 2.9325 0.1325 2.9325 0.1325 9 P 0 ;1
L 2.9325 0.1825 2.9325 0.1825 9 P 0 ;1
L 2.9325 0.2325 2.9325 0.2325 9 P 0 ;1
L 2.9325 0.2825 2.9325 0.2825 9 P 0 ;1
L 2.9325 0.3325 2.9325 0.3325 9 P 0 ;1
L 2.9325 0.3825 2.9325 0.3825 9 P 0 ;1
L 2.9325 0.4325 2.9325 0.4325 9 P 0 ;1
L 2.9325 0.4825 2.9325 0.4825 9 P 0 ;1
L 2.9325 0.5325 2.9325 0.5325 9 P 0 ;1
L 2.9325 0.5825 2.9325 0.5825 9 P 0 ;1
L 2.9325 0.6325 2.9325 0.6325 9 P 0 ;1
L 2.9325 0.6825 2.9325 0.6825 9 P 0 ;1
L 2.9325 1.3325 2.9325 1.3325 9 P 0 ;1
L 2.9325 1.3825 2.9325 1.3825 9 P 0 ;1
L 2.9325 1.4325 2.9325 1.4325 9 P 0 ;1
L 2.9325 1.4825 2.9325 1.4825 9 P 0 ;1
L 2.9325 1.7825 2.9325 1.7825 9 P 0 ;1
L 2.9325 1.8325 2.9325 1.8325 9 P 0 ;1
L 2.9325 1.8825 2.9325 1.8825 9 P 0 ;1
L 2.9325 1.9325 2.9325 1.9325 9 P 0 ;1
L 2.9325 1.9825 2.9325 1.9825 9 P 0 ;1
L 2.9325 2.0325 2.9325 2.0325 9 P 0 ;1
L 2.9325 2.0825 2.9325 2.0825 9 P 0 ;1
L 2.9325 2.1325 2.9325 2.1325 9 P 0 ;1
L 2.9325 2.1825 2.9325 2.1825 9 P 0 ;1
L 2.9325 2.2325 2.9325 2.2325 9 P 0 ;1
L 2.9325 2.2825 2.9325 2.2825 9 P 0 ;1
L 2.9325 2.3325 2.9325 2.3325 9 P 0 ;1
L 2.9325 2.3825 2.9325 2.3825 9 P 0 ;1
L 2.9325 2.4325 2.9325 2.4325 9 P 0 ;1
L 2.9325 2.4825 2.9325 2.4825 9 P 0 ;1
L 2.9325 2.5325 2.9325 2.5325 9 P 0 ;1
L 2.9325 2.5825 2.9325 2.5825 9 P 0 ;1
L 2.9325 2.6325 2.9325 2.6325 9 P 0 ;1
L 2.9325 2.6825 2.9325 2.6825 9 P 0 ;1
L 2.9325 3.0325 2.9325 3.0325 9 P 0 ;1
L 2.9325 3.0825 2.9325 3.0825 9 P 0 ;1
L 2.9325 3.1325 2.9325 3.1325 9 P 0 ;1
L 2.9325 3.1825 2.9325 3.1825 9 P 0 ;1
L 2.9325 3.2325 2.9325 3.2325 9 P 0 ;1
L 2.9325 3.2825 2.9325 3.2825 9 P 0 ;1
L 2.9325 3.3325 2.9325 3.3325 9 P 0 ;1
L 2.9325 3.3825 2.9325 3.3825 9 P 0 ;1
L 2.9325 3.4325 2.9325 3.4325 9 P 0 ;1
L 2.9325 3.4825 2.9325 3.4825 9 P 0 ;1
L 2.9325 3.5325 2.9325 3.5325 9 P 0 ;1
L 2.9325 3.5825 2.9325 3.5825 9 P 0 ;1
L 2.9325 3.6325 2.9325 3.6325 9 P 0 ;1
L 2.9325 3.6825 2.9325 3.6825 9 P 0 ;1
L 2.9325 3.7325 2.9325 3.7325 9 P 0 ;1
L 2.9325 3.7825 2.9325 3.7825 9 P 0 ;1
L 2.9325 3.8325 2.9325 3.8325 9 P 0 ;1
L 2.9325 3.8825 2.9325 3.8825 9 P 0 ;1
L 2.9325 3.9325 2.9325 3.9325 9 P 0 ;1
L 2.9325 3.9825 2.9325 3.9825 9 P 0 ;1
L 2.9325 4.2325 2.9325 4.2325 9 P 0 ;1
L 2.9325 4.2825 2.9325 4.2825 9 P 0 ;1
L 2.9325 4.3325 2.9325 4.3325 9 P 0 ;1
L 2.9325 4.3825 2.9325 4.3825 9 P 0 ;1
L 2.9325 4.4325 2.9325 4.4325 9 P 0 ;1
L 2.9325 4.4825 2.9325 4.4825 9 P 0 ;1
L 2.9325 4.5325 2.9325 4.5325 9 P 0 ;1
L 2.9325 4.5825 2.9325 4.5825 9 P 0 ;1
L 2.9325 5.3325 2.9325 5.3325 9 P 0 ;1
L 2.9325 5.3825 2.9325 5.3825 9 P 0 ;1
L 2.9325 5.4325 2.9325 5.4325 9 P 0 ;1
L 2.9325 5.4825 2.9325 5.4825 9 P 0 ;1
L 2.9325 5.5325 2.9325 5.5325 9 P 0 ;1
L 2.9325 5.5825 2.9325 5.5825 9 P 0 ;1
L 2.9325 5.6325 2.9325 5.6325 9 P 0 ;1
L 2.9325 5.6825 2.9325 5.6825 9 P 0 ;1
L 2.9325 5.7325 2.9325 5.7325 9 P 0 ;1
L 2.9325 5.7825 2.9325 5.7825 9 P 0 ;1
L 2.9325 5.8325 2.9325 5.8325 9 P 0 ;1
L 2.9325 5.8825 2.9325 5.8825 9 P 0 ;1
L 2.9825 0.1325 2.9825 0.1325 9 P 0 ;1
L 2.9825 0.1825 2.9825 0.1825 9 P 0 ;1
L 2.9825 0.2325 2.9825 0.2325 9 P 0 ;1
L 2.9825 0.2825 2.9825 0.2825 9 P 0 ;1
L 2.9825 0.3325 2.9825 0.3325 9 P 0 ;1
L 2.9825 0.3825 2.9825 0.3825 9 P 0 ;1
L 2.9825 0.4325 2.9825 0.4325 9 P 0 ;1
L 2.9825 0.4825 2.9825 0.4825 9 P 0 ;1
L 2.9825 0.5325 2.9825 0.5325 9 P 0 ;1
L 2.9825 0.5825 2.9825 0.5825 9 P 0 ;1
L 2.9825 0.6325 2.9825 0.6325 9 P 0 ;1
L 2.9825 0.6825 2.9825 0.6825 9 P 0 ;1
L 2.9825 1.3325 2.9825 1.3325 9 P 0 ;1
L 2.9825 1.3825 2.9825 1.3825 9 P 0 ;1
L 2.9825 1.4325 2.9825 1.4325 9 P 0 ;1
L 2.9825 1.4825 2.9825 1.4825 9 P 0 ;1
L 2.9825 1.7825 2.9825 1.7825 9 P 0 ;1
L 2.9825 1.8325 2.9825 1.8325 9 P 0 ;1
L 2.9825 1.8825 2.9825 1.8825 9 P 0 ;1
L 2.9825 1.9325 2.9825 1.9325 9 P 0 ;1
L 2.9825 1.9825 2.9825 1.9825 9 P 0 ;1
L 2.9825 2.0325 2.9825 2.0325 9 P 0 ;1
L 2.9825 2.0825 2.9825 2.0825 9 P 0 ;1
L 2.9825 2.1325 2.9825 2.1325 9 P 0 ;1
L 2.9825 2.1825 2.9825 2.1825 9 P 0 ;1
L 2.9825 2.2325 2.9825 2.2325 9 P 0 ;1
L 2.9825 2.2825 2.9825 2.2825 9 P 0 ;1
L 2.9825 2.3325 2.9825 2.3325 9 P 0 ;1
L 2.9825 2.3825 2.9825 2.3825 9 P 0 ;1
L 2.9825 2.4325 2.9825 2.4325 9 P 0 ;1
L 2.9825 2.4825 2.9825 2.4825 9 P 0 ;1
L 2.9825 2.5325 2.9825 2.5325 9 P 0 ;1
L 2.9825 2.5825 2.9825 2.5825 9 P 0 ;1
L 2.9825 2.6325 2.9825 2.6325 9 P 0 ;1
L 2.9825 2.6825 2.9825 2.6825 9 P 0 ;1
L 2.9825 3.0325 2.9825 3.0325 9 P 0 ;1
L 2.9825 3.0825 2.9825 3.0825 9 P 0 ;1
L 2.9825 3.1325 2.9825 3.1325 9 P 0 ;1
L 2.9825 3.1825 2.9825 3.1825 9 P 0 ;1
L 2.9825 3.2325 2.9825 3.2325 9 P 0 ;1
L 2.9825 3.2825 2.9825 3.2825 9 P 0 ;1
L 2.9825 3.3325 2.9825 3.3325 9 P 0 ;1
L 2.9825 3.3825 2.9825 3.3825 9 P 0 ;1
L 2.9825 3.4325 2.9825 3.4325 9 P 0 ;1
L 2.9825 3.4825 2.9825 3.4825 9 P 0 ;1
L 2.9825 3.5325 2.9825 3.5325 9 P 0 ;1
L 2.9825 3.5825 2.9825 3.5825 9 P 0 ;1
L 2.9825 3.6325 2.9825 3.6325 9 P 0 ;1
L 2.9825 3.6825 2.9825 3.6825 9 P 0 ;1
L 2.9825 3.7325 2.9825 3.7325 9 P 0 ;1
L 2.9825 3.7825 2.9825 3.7825 9 P 0 ;1
L 2.9825 3.8325 2.9825 3.8325 9 P 0 ;1
L 2.9825 3.8825 2.9825 3.8825 9 P 0 ;1
L 2.9825 3.9325 2.9825 3.9325 9 P 0 ;1
L 2.9825 3.9825 2.9825 3.9825 9 P 0 ;1
L 2.9825 4.2325 2.9825 4.2325 9 P 0 ;1
L 2.9825 4.2825 2.9825 4.2825 9 P 0 ;1
L 2.9825 4.3325 2.9825 4.3325 9 P 0 ;1
L 2.9825 4.3825 2.9825 4.3825 9 P 0 ;1
L 2.9825 4.4325 2.9825 4.4325 9 P 0 ;1
L 2.9825 4.4825 2.9825 4.4825 9 P 0 ;1
L 2.9825 4.5325 2.9825 4.5325 9 P 0 ;1
L 2.9825 4.5825 2.9825 4.5825 9 P 0 ;1
L 2.9825 5.2825 2.9825 5.2825 9 P 0 ;1
L 2.9825 5.3325 2.9825 5.3325 9 P 0 ;1
L 2.9825 5.3825 2.9825 5.3825 9 P 0 ;1
L 2.9825 5.4325 2.9825 5.4325 9 P 0 ;1
L 2.9825 5.4825 2.9825 5.4825 9 P 0 ;1
L 2.9825 5.5325 2.9825 5.5325 9 P 0 ;1
L 2.9825 5.5825 2.9825 5.5825 9 P 0 ;1
L 2.9825 5.6325 2.9825 5.6325 9 P 0 ;1
L 2.9825 5.6825 2.9825 5.6825 9 P 0 ;1
L 2.9825 5.7325 2.9825 5.7325 9 P 0 ;1
L 2.9825 5.7825 2.9825 5.7825 9 P 0 ;1
L 2.9825 5.8325 2.9825 5.8325 9 P 0 ;1
L 2.9825 5.8825 2.9825 5.8825 9 P 0 ;1
L 3.0325 0.1325 3.0325 0.1325 9 P 0 ;1
L 3.0325 0.1825 3.0325 0.1825 9 P 0 ;1
L 3.0325 0.2325 3.0325 0.2325 9 P 0 ;1
L 3.0325 0.2825 3.0325 0.2825 9 P 0 ;1
L 3.0325 0.3325 3.0325 0.3325 9 P 0 ;1
L 3.0325 0.3825 3.0325 0.3825 9 P 0 ;1
L 3.0325 0.4325 3.0325 0.4325 9 P 0 ;1
L 3.0325 0.4825 3.0325 0.4825 9 P 0 ;1
L 3.0325 0.5325 3.0325 0.5325 9 P 0 ;1
L 3.0325 0.5825 3.0325 0.5825 9 P 0 ;1
L 3.0325 0.6325 3.0325 0.6325 9 P 0 ;1
L 3.0325 0.6825 3.0325 0.6825 9 P 0 ;1
L 3.0325 0.8825 3.0325 0.8825 9 P 0 ;1
L 3.0325 1.3325 3.0325 1.3325 9 P 0 ;1
L 3.0325 1.3825 3.0325 1.3825 9 P 0 ;1
L 3.0325 1.4325 3.0325 1.4325 9 P 0 ;1
L 3.0325 1.4825 3.0325 1.4825 9 P 0 ;1
L 3.0325 1.7825 3.0325 1.7825 9 P 0 ;1
L 3.0325 1.8325 3.0325 1.8325 9 P 0 ;1
L 3.0325 1.8825 3.0325 1.8825 9 P 0 ;1
L 3.0325 1.9325 3.0325 1.9325 9 P 0 ;1
L 3.0325 1.9825 3.0325 1.9825 9 P 0 ;1
L 3.0325 2.0325 3.0325 2.0325 9 P 0 ;1
L 3.0325 2.0825 3.0325 2.0825 9 P 0 ;1
L 3.0325 2.1325 3.0325 2.1325 9 P 0 ;1
L 3.0325 2.1825 3.0325 2.1825 9 P 0 ;1
L 3.0325 2.2325 3.0325 2.2325 9 P 0 ;1
L 3.0325 2.2825 3.0325 2.2825 9 P 0 ;1
L 3.0325 2.3325 3.0325 2.3325 9 P 0 ;1
L 3.0325 2.3825 3.0325 2.3825 9 P 0 ;1
L 3.0325 2.4325 3.0325 2.4325 9 P 0 ;1
L 3.0325 2.4825 3.0325 2.4825 9 P 0 ;1
L 3.0325 2.5325 3.0325 2.5325 9 P 0 ;1
L 3.0325 2.5825 3.0325 2.5825 9 P 0 ;1
L 3.0325 2.6325 3.0325 2.6325 9 P 0 ;1
L 3.0325 2.6825 3.0325 2.6825 9 P 0 ;1
L 3.0325 2.9825 3.0325 2.9825 9 P 0 ;1
L 3.0325 3.0325 3.0325 3.0325 9 P 0 ;1
L 3.0325 3.0825 3.0325 3.0825 9 P 0 ;1
L 3.0325 3.1325 3.0325 3.1325 9 P 0 ;1
L 3.0325 3.1825 3.0325 3.1825 9 P 0 ;1
L 3.0325 3.2325 3.0325 3.2325 9 P 0 ;1
L 3.0325 3.2825 3.0325 3.2825 9 P 0 ;1
L 3.0325 3.3325 3.0325 3.3325 9 P 0 ;1
L 3.0325 3.3825 3.0325 3.3825 9 P 0 ;1
L 3.0325 3.4325 3.0325 3.4325 9 P 0 ;1
L 3.0325 3.4825 3.0325 3.4825 9 P 0 ;1
L 3.0325 3.5325 3.0325 3.5325 9 P 0 ;1
L 3.0325 3.5825 3.0325 3.5825 9 P 0 ;1
L 3.0325 3.6325 3.0325 3.6325 9 P 0 ;1
L 3.0325 3.6825 3.0325 3.6825 9 P 0 ;1
L 3.0325 3.7325 3.0325 3.7325 9 P 0 ;1
L 3.0325 3.7825 3.0325 3.7825 9 P 0 ;1
L 3.0325 3.8325 3.0325 3.8325 9 P 0 ;1
L 3.0325 3.8825 3.0325 3.8825 9 P 0 ;1
L 3.0325 3.9325 3.0325 3.9325 9 P 0 ;1
L 3.0325 3.9825 3.0325 3.9825 9 P 0 ;1
L 3.0325 4.2325 3.0325 4.2325 9 P 0 ;1
L 3.0325 4.2825 3.0325 4.2825 9 P 0 ;1
L 3.0325 4.3325 3.0325 4.3325 9 P 0 ;1
L 3.0325 4.5325 3.0325 4.5325 9 P 0 ;1
L 3.0325 4.5825 3.0325 4.5825 9 P 0 ;1
L 3.0325 5.4325 3.0325 5.4325 9 P 0 ;1
L 3.0325 5.4825 3.0325 5.4825 9 P 0 ;1
L 3.0325 5.5325 3.0325 5.5325 9 P 0 ;1
L 3.0325 5.5825 3.0325 5.5825 9 P 0 ;1
L 3.0325 5.6325 3.0325 5.6325 9 P 0 ;1
L 3.0325 5.6825 3.0325 5.6825 9 P 0 ;1
L 3.0325 5.7325 3.0325 5.7325 9 P 0 ;1
L 3.0325 5.7825 3.0325 5.7825 9 P 0 ;1
L 3.0325 5.8325 3.0325 5.8325 9 P 0 ;1
L 3.0325 5.8825 3.0325 5.8825 9 P 0 ;1
L 3.0825 0.1325 3.0825 0.1325 9 P 0 ;1
L 3.0825 0.1825 3.0825 0.1825 9 P 0 ;1
L 3.0825 0.2325 3.0825 0.2325 9 P 0 ;1
L 3.0825 0.2825 3.0825 0.2825 9 P 0 ;1
L 3.0825 0.3325 3.0825 0.3325 9 P 0 ;1
L 3.0825 0.3825 3.0825 0.3825 9 P 0 ;1
L 3.0825 0.4325 3.0825 0.4325 9 P 0 ;1
L 3.0825 0.4825 3.0825 0.4825 9 P 0 ;1
L 3.0825 0.5325 3.0825 0.5325 9 P 0 ;1
L 3.0825 0.5825 3.0825 0.5825 9 P 0 ;1
L 3.0825 0.6325 3.0825 0.6325 9 P 0 ;1
L 3.0825 0.6825 3.0825 0.6825 9 P 0 ;1
L 3.0825 0.8825 3.0825 0.8825 9 P 0 ;1
L 3.0825 1.3825 3.0825 1.3825 9 P 0 ;1
L 3.0825 1.4325 3.0825 1.4325 9 P 0 ;1
L 3.0825 1.4825 3.0825 1.4825 9 P 0 ;1
L 3.0825 1.7825 3.0825 1.7825 9 P 0 ;1
L 3.0825 1.8325 3.0825 1.8325 9 P 0 ;1
L 3.0825 1.8825 3.0825 1.8825 9 P 0 ;1
L 3.0825 1.9325 3.0825 1.9325 9 P 0 ;1
L 3.0825 1.9825 3.0825 1.9825 9 P 0 ;1
L 3.0825 2.0325 3.0825 2.0325 9 P 0 ;1
L 3.0825 2.0825 3.0825 2.0825 9 P 0 ;1
L 3.0825 2.1325 3.0825 2.1325 9 P 0 ;1
L 3.0825 2.1825 3.0825 2.1825 9 P 0 ;1
L 3.0825 2.2325 3.0825 2.2325 9 P 0 ;1
L 3.0825 2.2825 3.0825 2.2825 9 P 0 ;1
L 3.0825 2.3325 3.0825 2.3325 9 P 0 ;1
L 3.0825 2.3825 3.0825 2.3825 9 P 0 ;1
L 3.0825 2.4325 3.0825 2.4325 9 P 0 ;1
L 3.0825 2.4825 3.0825 2.4825 9 P 0 ;1
L 3.0825 2.5325 3.0825 2.5325 9 P 0 ;1
L 3.0825 2.5825 3.0825 2.5825 9 P 0 ;1
L 3.0825 2.6325 3.0825 2.6325 9 P 0 ;1
L 3.0825 2.6825 3.0825 2.6825 9 P 0 ;1
L 3.0825 2.7325 3.0825 2.7325 9 P 0 ;1
L 3.0825 2.7825 3.0825 2.7825 9 P 0 ;1
L 3.0825 2.8325 3.0825 2.8325 9 P 0 ;1
L 3.0825 2.8825 3.0825 2.8825 9 P 0 ;1
L 3.0825 2.9325 3.0825 2.9325 9 P 0 ;1
L 3.0825 2.9825 3.0825 2.9825 9 P 0 ;1
L 3.0825 3.0325 3.0825 3.0325 9 P 0 ;1
L 3.0825 3.0825 3.0825 3.0825 9 P 0 ;1
L 3.0825 3.1325 3.0825 3.1325 9 P 0 ;1
L 3.0825 3.1825 3.0825 3.1825 9 P 0 ;1
L 3.0825 3.2325 3.0825 3.2325 9 P 0 ;1
L 3.0825 3.2825 3.0825 3.2825 9 P 0 ;1
L 3.0825 3.3325 3.0825 3.3325 9 P 0 ;1
L 3.0825 3.3825 3.0825 3.3825 9 P 0 ;1
L 3.0825 3.4325 3.0825 3.4325 9 P 0 ;1
L 3.0825 3.4825 3.0825 3.4825 9 P 0 ;1
L 3.0825 3.5325 3.0825 3.5325 9 P 0 ;1
L 3.0825 3.5825 3.0825 3.5825 9 P 0 ;1
L 3.0825 3.6325 3.0825 3.6325 9 P 0 ;1
L 3.0825 3.6825 3.0825 3.6825 9 P 0 ;1
L 3.0825 3.7325 3.0825 3.7325 9 P 0 ;1
L 3.0825 3.7825 3.0825 3.7825 9 P 0 ;1
L 3.0825 3.8325 3.0825 3.8325 9 P 0 ;1
L 3.0825 3.8825 3.0825 3.8825 9 P 0 ;1
L 3.0825 3.9325 3.0825 3.9325 9 P 0 ;1
L 3.0825 3.9825 3.0825 3.9825 9 P 0 ;1
L 3.0825 4.2325 3.0825 4.2325 9 P 0 ;1
L 3.0825 4.2825 3.0825 4.2825 9 P 0 ;1
L 3.0825 4.3325 3.0825 4.3325 9 P 0 ;1
L 3.0825 4.5825 3.0825 4.5825 9 P 0 ;1
L 3.0825 5.4325 3.0825 5.4325 9 P 0 ;1
L 3.0825 5.4825 3.0825 5.4825 9 P 0 ;1
L 3.0825 5.5325 3.0825 5.5325 9 P 0 ;1
L 3.0825 5.5825 3.0825 5.5825 9 P 0 ;1
L 3.0825 5.6325 3.0825 5.6325 9 P 0 ;1
L 3.0825 5.6825 3.0825 5.6825 9 P 0 ;1
L 3.0825 5.7325 3.0825 5.7325 9 P 0 ;1
L 3.0825 5.7825 3.0825 5.7825 9 P 0 ;1
L 3.0825 5.8325 3.0825 5.8325 9 P 0 ;1
L 3.0825 5.8825 3.0825 5.8825 9 P 0 ;1
L 3.1325 0.1325 3.1325 0.1325 9 P 0 ;1
L 3.1325 0.1825 3.1325 0.1825 9 P 0 ;1
L 3.1325 0.2325 3.1325 0.2325 9 P 0 ;1
L 3.1325 0.2825 3.1325 0.2825 9 P 0 ;1
L 3.1325 0.3325 3.1325 0.3325 9 P 0 ;1
L 3.1325 0.3825 3.1325 0.3825 9 P 0 ;1
L 3.1325 0.4325 3.1325 0.4325 9 P 0 ;1
L 3.1325 0.4825 3.1325 0.4825 9 P 0 ;1
L 3.1325 0.5325 3.1325 0.5325 9 P 0 ;1
L 3.1325 0.5825 3.1325 0.5825 9 P 0 ;1
L 3.1325 0.6325 3.1325 0.6325 9 P 0 ;1
L 3.1325 0.8825 3.1325 0.8825 9 P 0 ;1
L 3.1325 1.3825 3.1325 1.3825 9 P 0 ;1
L 3.1325 1.4325 3.1325 1.4325 9 P 0 ;1
L 3.1325 1.4825 3.1325 1.4825 9 P 0 ;1
L 3.1325 1.7825 3.1325 1.7825 9 P 0 ;1
L 3.1325 1.8325 3.1325 1.8325 9 P 0 ;1
L 3.1325 1.8825 3.1325 1.8825 9 P 0 ;1
L 3.1325 1.9325 3.1325 1.9325 9 P 0 ;1
L 3.1325 1.9825 3.1325 1.9825 9 P 0 ;1
L 3.1325 2.0325 3.1325 2.0325 9 P 0 ;1
L 3.1325 2.0825 3.1325 2.0825 9 P 0 ;1
L 3.1325 2.1325 3.1325 2.1325 9 P 0 ;1
L 3.1325 2.1825 3.1325 2.1825 9 P 0 ;1
L 3.1325 2.2325 3.1325 2.2325 9 P 0 ;1
L 3.1325 2.2825 3.1325 2.2825 9 P 0 ;1
L 3.1325 2.3325 3.1325 2.3325 9 P 0 ;1
L 3.1325 2.3825 3.1325 2.3825 9 P 0 ;1
L 3.1325 2.4325 3.1325 2.4325 9 P 0 ;1
L 3.1325 2.4825 3.1325 2.4825 9 P 0 ;1
L 3.1325 2.5325 3.1325 2.5325 9 P 0 ;1
L 3.1325 2.5825 3.1325 2.5825 9 P 0 ;1
L 3.1325 2.6325 3.1325 2.6325 9 P 0 ;1
L 3.1325 2.6825 3.1325 2.6825 9 P 0 ;1
L 3.1325 2.7325 3.1325 2.7325 9 P 0 ;1
L 3.1325 2.7825 3.1325 2.7825 9 P 0 ;1
L 3.1325 2.8325 3.1325 2.8325 9 P 0 ;1
L 3.1325 2.8825 3.1325 2.8825 9 P 0 ;1
L 3.1325 2.9325 3.1325 2.9325 9 P 0 ;1
L 3.1325 2.9825 3.1325 2.9825 9 P 0 ;1
L 3.1325 3.0325 3.1325 3.0325 9 P 0 ;1
L 3.1325 3.0825 3.1325 3.0825 9 P 0 ;1
L 3.1325 3.1325 3.1325 3.1325 9 P 0 ;1
L 3.1325 3.1825 3.1325 3.1825 9 P 0 ;1
L 3.1325 3.2325 3.1325 3.2325 9 P 0 ;1
L 3.1325 3.2825 3.1325 3.2825 9 P 0 ;1
L 3.1325 3.3325 3.1325 3.3325 9 P 0 ;1
L 3.1325 3.3825 3.1325 3.3825 9 P 0 ;1
L 3.1325 3.4325 3.1325 3.4325 9 P 0 ;1
L 3.1325 3.4825 3.1325 3.4825 9 P 0 ;1
L 3.1325 3.5325 3.1325 3.5325 9 P 0 ;1
L 3.1325 3.5825 3.1325 3.5825 9 P 0 ;1
L 3.1325 3.6325 3.1325 3.6325 9 P 0 ;1
L 3.1325 3.6825 3.1325 3.6825 9 P 0 ;1
L 3.1325 3.7325 3.1325 3.7325 9 P 0 ;1
L 3.1325 3.7825 3.1325 3.7825 9 P 0 ;1
L 3.1325 3.8325 3.1325 3.8325 9 P 0 ;1
L 3.1325 3.8825 3.1325 3.8825 9 P 0 ;1
L 3.1325 3.9325 3.1325 3.9325 9 P 0 ;1
L 3.1325 3.9825 3.1325 3.9825 9 P 0 ;1
L 3.1325 4.2825 3.1325 4.2825 9 P 0 ;1
L 3.1325 4.3325 3.1325 4.3325 9 P 0 ;1
L 3.1325 4.5825 3.1325 4.5825 9 P 0 ;1
L 3.1325 5.3825 3.1325 5.3825 9 P 0 ;1
L 3.1325 5.4325 3.1325 5.4325 9 P 0 ;1
L 3.1325 5.4825 3.1325 5.4825 9 P 0 ;1
L 3.1325 5.5325 3.1325 5.5325 9 P 0 ;1
L 3.1325 5.5825 3.1325 5.5825 9 P 0 ;1
L 3.1325 5.6325 3.1325 5.6325 9 P 0 ;1
L 3.1325 5.6825 3.1325 5.6825 9 P 0 ;1
L 3.1325 5.7325 3.1325 5.7325 9 P 0 ;1
L 3.1325 5.7825 3.1325 5.7825 9 P 0 ;1
L 3.1325 5.8325 3.1325 5.8325 9 P 0 ;1
L 3.1325 5.8825 3.1325 5.8825 9 P 0 ;1
L 3.1825 0.1325 3.1825 0.1325 9 P 0 ;1
L 3.1825 0.1825 3.1825 0.1825 9 P 0 ;1
L 3.1825 0.2325 3.1825 0.2325 9 P 0 ;1
L 3.1825 0.2825 3.1825 0.2825 9 P 0 ;1
L 3.1825 0.3325 3.1825 0.3325 9 P 0 ;1
L 3.1825 0.3825 3.1825 0.3825 9 P 0 ;1
L 3.1825 0.4325 3.1825 0.4325 9 P 0 ;1
L 3.1825 0.4825 3.1825 0.4825 9 P 0 ;1
L 3.1825 0.5325 3.1825 0.5325 9 P 0 ;1
L 3.1825 0.5825 3.1825 0.5825 9 P 0 ;1
L 3.1825 0.6325 3.1825 0.6325 9 P 0 ;1
L 3.1825 0.8325 3.1825 0.8325 9 P 0 ;1
L 3.1825 0.8825 3.1825 0.8825 9 P 0 ;1
L 3.1825 1.3825 3.1825 1.3825 9 P 0 ;1
L 3.1825 1.4325 3.1825 1.4325 9 P 0 ;1
L 3.1825 1.4825 3.1825 1.4825 9 P 0 ;1
L 3.1825 1.7325 3.1825 1.7325 9 P 0 ;1
L 3.1825 1.7825 3.1825 1.7825 9 P 0 ;1
L 3.1825 1.8325 3.1825 1.8325 9 P 0 ;1
L 3.1825 1.8825 3.1825 1.8825 9 P 0 ;1
L 3.1825 1.9325 3.1825 1.9325 9 P 0 ;1
L 3.1825 1.9825 3.1825 1.9825 9 P 0 ;1
L 3.1825 2.0325 3.1825 2.0325 9 P 0 ;1
L 3.1825 2.0825 3.1825 2.0825 9 P 0 ;1
L 3.1825 2.1325 3.1825 2.1325 9 P 0 ;1
L 3.1825 2.1825 3.1825 2.1825 9 P 0 ;1
L 3.1825 2.2325 3.1825 2.2325 9 P 0 ;1
L 3.1825 2.2825 3.1825 2.2825 9 P 0 ;1
L 3.1825 2.3325 3.1825 2.3325 9 P 0 ;1
L 3.1825 2.3825 3.1825 2.3825 9 P 0 ;1
L 3.1825 2.4325 3.1825 2.4325 9 P 0 ;1
L 3.1825 2.4825 3.1825 2.4825 9 P 0 ;1
L 3.1825 2.5325 3.1825 2.5325 9 P 0 ;1
L 3.1825 2.5825 3.1825 2.5825 9 P 0 ;1
L 3.1825 2.6325 3.1825 2.6325 9 P 0 ;1
L 3.1825 2.6825 3.1825 2.6825 9 P 0 ;1
L 3.1825 2.7325 3.1825 2.7325 9 P 0 ;1
L 3.1825 2.7825 3.1825 2.7825 9 P 0 ;1
L 3.1825 2.8325 3.1825 2.8325 9 P 0 ;1
L 3.1825 2.8825 3.1825 2.8825 9 P 0 ;1
L 3.1825 2.9325 3.1825 2.9325 9 P 0 ;1
L 3.1825 2.9825 3.1825 2.9825 9 P 0 ;1
L 3.1825 3.0325 3.1825 3.0325 9 P 0 ;1
L 3.1825 3.0825 3.1825 3.0825 9 P 0 ;1
L 3.1825 3.1325 3.1825 3.1325 9 P 0 ;1
L 3.1825 3.1825 3.1825 3.1825 9 P 0 ;1
L 3.1825 3.2325 3.1825 3.2325 9 P 0 ;1
L 3.1825 3.2825 3.1825 3.2825 9 P 0 ;1
L 3.1825 3.3325 3.1825 3.3325 9 P 0 ;1
L 3.1825 3.3825 3.1825 3.3825 9 P 0 ;1
L 3.1825 3.4325 3.1825 3.4325 9 P 0 ;1
L 3.1825 3.4825 3.1825 3.4825 9 P 0 ;1
L 3.1825 3.5325 3.1825 3.5325 9 P 0 ;1
L 3.1825 3.5825 3.1825 3.5825 9 P 0 ;1
L 3.1825 3.6325 3.1825 3.6325 9 P 0 ;1
L 3.1825 3.6825 3.1825 3.6825 9 P 0 ;1
L 3.1825 3.7325 3.1825 3.7325 9 P 0 ;1
L 3.1825 3.7825 3.1825 3.7825 9 P 0 ;1
L 3.1825 3.8325 3.1825 3.8325 9 P 0 ;1
L 3.1825 3.8825 3.1825 3.8825 9 P 0 ;1
L 3.1825 3.9325 3.1825 3.9325 9 P 0 ;1
L 3.1825 3.9825 3.1825 3.9825 9 P 0 ;1
L 3.1825 4.2825 3.1825 4.2825 9 P 0 ;1
L 3.1825 4.3325 3.1825 4.3325 9 P 0 ;1
L 3.1825 4.3825 3.1825 4.3825 9 P 0 ;1
L 3.1825 4.4325 3.1825 4.4325 9 P 0 ;1
L 3.1825 4.4825 3.1825 4.4825 9 P 0 ;1
L 3.1825 4.5325 3.1825 4.5325 9 P 0 ;1
L 3.1825 4.5825 3.1825 4.5825 9 P 0 ;1
L 3.1825 5.3825 3.1825 5.3825 9 P 0 ;1
L 3.1825 5.4325 3.1825 5.4325 9 P 0 ;1
L 3.1825 5.4825 3.1825 5.4825 9 P 0 ;1
L 3.1825 5.5325 3.1825 5.5325 9 P 0 ;1
L 3.1825 5.5825 3.1825 5.5825 9 P 0 ;1
L 3.1825 5.6325 3.1825 5.6325 9 P 0 ;1
L 3.1825 5.6825 3.1825 5.6825 9 P 0 ;1
L 3.1825 5.7325 3.1825 5.7325 9 P 0 ;1
L 3.1825 5.7825 3.1825 5.7825 9 P 0 ;1
L 3.1825 5.8325 3.1825 5.8325 9 P 0 ;1
L 3.1825 5.8825 3.1825 5.8825 9 P 0 ;1
L 3.2325 0.1325 3.2325 0.1325 9 P 0 ;1
L 3.2325 0.1825 3.2325 0.1825 9 P 0 ;1
L 3.2325 0.2325 3.2325 0.2325 9 P 0 ;1
L 3.2325 0.2825 3.2325 0.2825 9 P 0 ;1
L 3.2325 0.3325 3.2325 0.3325 9 P 0 ;1
L 3.2325 0.3825 3.2325 0.3825 9 P 0 ;1
L 3.2325 0.4325 3.2325 0.4325 9 P 0 ;1
L 3.2325 0.4825 3.2325 0.4825 9 P 0 ;1
L 3.2325 0.5325 3.2325 0.5325 9 P 0 ;1
L 3.2325 0.5825 3.2325 0.5825 9 P 0 ;1
L 3.2325 0.6325 3.2325 0.6325 9 P 0 ;1
L 3.2325 0.8325 3.2325 0.8325 9 P 0 ;1
L 3.2325 0.8825 3.2325 0.8825 9 P 0 ;1
L 3.2325 1.3825 3.2325 1.3825 9 P 0 ;1
L 3.2325 1.4325 3.2325 1.4325 9 P 0 ;1
L 3.2325 1.4825 3.2325 1.4825 9 P 0 ;1
L 3.2325 1.7325 3.2325 1.7325 9 P 0 ;1
L 3.2325 1.7825 3.2325 1.7825 9 P 0 ;1
L 3.2325 1.8325 3.2325 1.8325 9 P 0 ;1
L 3.2325 1.8825 3.2325 1.8825 9 P 0 ;1
L 3.2325 1.9325 3.2325 1.9325 9 P 0 ;1
L 3.2325 1.9825 3.2325 1.9825 9 P 0 ;1
L 3.2325 2.0325 3.2325 2.0325 9 P 0 ;1
L 3.2325 2.0825 3.2325 2.0825 9 P 0 ;1
L 3.2325 2.1325 3.2325 2.1325 9 P 0 ;1
L 3.2325 2.1825 3.2325 2.1825 9 P 0 ;1
L 3.2325 2.2325 3.2325 2.2325 9 P 0 ;1
L 3.2325 2.2825 3.2325 2.2825 9 P 0 ;1
L 3.2325 2.3325 3.2325 2.3325 9 P 0 ;1
L 3.2325 2.3825 3.2325 2.3825 9 P 0 ;1
L 3.2325 2.4325 3.2325 2.4325 9 P 0 ;1
L 3.2325 2.4825 3.2325 2.4825 9 P 0 ;1
L 3.2325 2.5325 3.2325 2.5325 9 P 0 ;1
L 3.2325 2.5825 3.2325 2.5825 9 P 0 ;1
L 3.2325 2.6325 3.2325 2.6325 9 P 0 ;1
L 3.2325 2.6825 3.2325 2.6825 9 P 0 ;1
L 3.2325 2.7325 3.2325 2.7325 9 P 0 ;1
L 3.2325 2.7825 3.2325 2.7825 9 P 0 ;1
L 3.2325 2.8325 3.2325 2.8325 9 P 0 ;1
L 3.2325 2.8825 3.2325 2.8825 9 P 0 ;1
L 3.2325 2.9325 3.2325 2.9325 9 P 0 ;1
L 3.2325 2.9825 3.2325 2.9825 9 P 0 ;1
L 3.2325 3.0325 3.2325 3.0325 9 P 0 ;1
L 3.2325 3.0825 3.2325 3.0825 9 P 0 ;1
L 3.2325 3.1325 3.2325 3.1325 9 P 0 ;1
L 3.2325 3.1825 3.2325 3.1825 9 P 0 ;1
L 3.2325 3.2325 3.2325 3.2325 9 P 0 ;1
L 3.2325 3.2825 3.2325 3.2825 9 P 0 ;1
L 3.2325 3.3325 3.2325 3.3325 9 P 0 ;1
L 3.2325 3.3825 3.2325 3.3825 9 P 0 ;1
L 3.2325 3.4325 3.2325 3.4325 9 P 0 ;1
L 3.2325 3.4825 3.2325 3.4825 9 P 0 ;1
L 3.2325 3.5325 3.2325 3.5325 9 P 0 ;1
L 3.2325 3.5825 3.2325 3.5825 9 P 0 ;1
L 3.2325 3.6325 3.2325 3.6325 9 P 0 ;1
L 3.2325 3.6825 3.2325 3.6825 9 P 0 ;1
L 3.2325 3.7325 3.2325 3.7325 9 P 0 ;1
L 3.2325 3.7825 3.2325 3.7825 9 P 0 ;1
L 3.2325 3.8325 3.2325 3.8325 9 P 0 ;1
L 3.2325 3.8825 3.2325 3.8825 9 P 0 ;1
L 3.2325 3.9325 3.2325 3.9325 9 P 0 ;1
L 3.2325 3.9825 3.2325 3.9825 9 P 0 ;1
L 3.2325 4.0325 3.2325 4.0325 9 P 0 ;1
L 3.2325 4.2825 3.2325 4.2825 9 P 0 ;1
L 3.2325 4.3325 3.2325 4.3325 9 P 0 ;1
L 3.2325 4.3825 3.2325 4.3825 9 P 0 ;1
L 3.2325 4.4325 3.2325 4.4325 9 P 0 ;1
L 3.2325 4.4825 3.2325 4.4825 9 P 0 ;1
L 3.2325 4.5325 3.2325 4.5325 9 P 0 ;1
L 3.2325 5.4325 3.2325 5.4325 9 P 0 ;1
L 3.2325 5.4825 3.2325 5.4825 9 P 0 ;1
L 3.2325 5.5325 3.2325 5.5325 9 P 0 ;1
L 3.2325 5.5825 3.2325 5.5825 9 P 0 ;1
L 3.2325 5.6325 3.2325 5.6325 9 P 0 ;1
L 3.2325 5.6825 3.2325 5.6825 9 P 0 ;1
L 3.2325 5.7325 3.2325 5.7325 9 P 0 ;1
L 3.2325 5.7825 3.2325 5.7825 9 P 0 ;1
L 3.2325 5.8325 3.2325 5.8325 9 P 0 ;1
L 3.2325 5.8825 3.2325 5.8825 9 P 0 ;1
L 3.2825 0.1325 3.2825 0.1325 9 P 0 ;1
L 3.2825 0.1825 3.2825 0.1825 9 P 0 ;1
L 3.2825 0.2325 3.2825 0.2325 9 P 0 ;1
L 3.2825 0.2825 3.2825 0.2825 9 P 0 ;1
L 3.2825 0.3325 3.2825 0.3325 9 P 0 ;1
L 3.2825 0.3825 3.2825 0.3825 9 P 0 ;1
L 3.2825 0.4325 3.2825 0.4325 9 P 0 ;1
L 3.2825 0.4825 3.2825 0.4825 9 P 0 ;1
L 3.2825 0.5325 3.2825 0.5325 9 P 0 ;1
L 3.2825 0.5825 3.2825 0.5825 9 P 0 ;1
L 3.2825 0.6325 3.2825 0.6325 9 P 0 ;1
L 3.2825 0.8325 3.2825 0.8325 9 P 0 ;1
L 3.2825 0.8825 3.2825 0.8825 9 P 0 ;1
L 3.2825 0.9325 3.2825 0.9325 9 P 0 ;1
L 3.2825 1.3825 3.2825 1.3825 9 P 0 ;1
L 3.2825 1.4325 3.2825 1.4325 9 P 0 ;1
L 3.2825 1.4825 3.2825 1.4825 9 P 0 ;1
L 3.2825 1.7825 3.2825 1.7825 9 P 0 ;1
L 3.2825 1.8325 3.2825 1.8325 9 P 0 ;1
L 3.2825 1.8825 3.2825 1.8825 9 P 0 ;1
L 3.2825 1.9325 3.2825 1.9325 9 P 0 ;1
L 3.2825 1.9825 3.2825 1.9825 9 P 0 ;1
L 3.2825 2.0325 3.2825 2.0325 9 P 0 ;1
L 3.2825 2.0825 3.2825 2.0825 9 P 0 ;1
L 3.2825 2.1325 3.2825 2.1325 9 P 0 ;1
L 3.2825 2.1825 3.2825 2.1825 9 P 0 ;1
L 3.2825 2.2325 3.2825 2.2325 9 P 0 ;1
L 3.2825 2.2825 3.2825 2.2825 9 P 0 ;1
L 3.2825 2.3325 3.2825 2.3325 9 P 0 ;1
L 3.2825 2.3825 3.2825 2.3825 9 P 0 ;1
L 3.2825 2.4325 3.2825 2.4325 9 P 0 ;1
L 3.2825 2.4825 3.2825 2.4825 9 P 0 ;1
L 3.2825 2.5325 3.2825 2.5325 9 P 0 ;1
L 3.2825 2.5825 3.2825 2.5825 9 P 0 ;1
L 3.2825 2.6325 3.2825 2.6325 9 P 0 ;1
L 3.2825 2.6825 3.2825 2.6825 9 P 0 ;1
L 3.2825 2.7325 3.2825 2.7325 9 P 0 ;1
L 3.2825 2.7825 3.2825 2.7825 9 P 0 ;1
L 3.2825 2.8325 3.2825 2.8325 9 P 0 ;1
L 3.2825 2.8825 3.2825 2.8825 9 P 0 ;1
L 3.2825 2.9325 3.2825 2.9325 9 P 0 ;1
L 3.2825 2.9825 3.2825 2.9825 9 P 0 ;1
L 3.2825 3.0325 3.2825 3.0325 9 P 0 ;1
L 3.2825 3.0825 3.2825 3.0825 9 P 0 ;1
L 3.2825 3.1325 3.2825 3.1325 9 P 0 ;1
L 3.2825 3.1825 3.2825 3.1825 9 P 0 ;1
L 3.2825 3.2325 3.2825 3.2325 9 P 0 ;1
L 3.2825 3.2825 3.2825 3.2825 9 P 0 ;1
L 3.2825 3.3325 3.2825 3.3325 9 P 0 ;1
L 3.2825 3.3825 3.2825 3.3825 9 P 0 ;1
L 3.2825 3.4325 3.2825 3.4325 9 P 0 ;1
L 3.2825 3.4825 3.2825 3.4825 9 P 0 ;1
L 3.2825 3.5325 3.2825 3.5325 9 P 0 ;1
L 3.2825 3.5825 3.2825 3.5825 9 P 0 ;1
L 3.2825 3.6325 3.2825 3.6325 9 P 0 ;1
L 3.2825 3.6825 3.2825 3.6825 9 P 0 ;1
L 3.2825 3.7325 3.2825 3.7325 9 P 0 ;1
L 3.2825 3.7825 3.2825 3.7825 9 P 0 ;1
L 3.2825 3.8325 3.2825 3.8325 9 P 0 ;1
L 3.2825 3.8825 3.2825 3.8825 9 P 0 ;1
L 3.2825 3.9325 3.2825 3.9325 9 P 0 ;1
L 3.2825 3.9825 3.2825 3.9825 9 P 0 ;1
L 3.2825 4.0325 3.2825 4.0325 9 P 0 ;1
L 3.2825 4.2825 3.2825 4.2825 9 P 0 ;1
L 3.2825 4.3325 3.2825 4.3325 9 P 0 ;1
L 3.2825 4.3825 3.2825 4.3825 9 P 0 ;1
L 3.2825 4.4325 3.2825 4.4325 9 P 0 ;1
L 3.2825 4.4825 3.2825 4.4825 9 P 0 ;1
L 3.2825 4.5325 3.2825 4.5325 9 P 0 ;1
L 3.2825 5.4325 3.2825 5.4325 9 P 0 ;1
L 3.2825 5.4825 3.2825 5.4825 9 P 0 ;1
L 3.2825 5.5325 3.2825 5.5325 9 P 0 ;1
L 3.2825 5.5825 3.2825 5.5825 9 P 0 ;1
L 3.2825 5.6325 3.2825 5.6325 9 P 0 ;1
L 3.2825 5.6825 3.2825 5.6825 9 P 0 ;1
L 3.2825 5.7325 3.2825 5.7325 9 P 0 ;1
L 3.2825 5.7825 3.2825 5.7825 9 P 0 ;1
L 3.2825 5.8325 3.2825 5.8325 9 P 0 ;1
L 3.2825 5.8825 3.2825 5.8825 9 P 0 ;1
L 3.3325 0.1325 3.3325 0.1325 9 P 0 ;1
L 3.3325 0.1825 3.3325 0.1825 9 P 0 ;1
L 3.3325 0.2325 3.3325 0.2325 9 P 0 ;1
L 3.3325 0.2825 3.3325 0.2825 9 P 0 ;1
L 3.3325 0.3325 3.3325 0.3325 9 P 0 ;1
L 3.3325 0.3825 3.3325 0.3825 9 P 0 ;1
L 3.3325 0.4325 3.3325 0.4325 9 P 0 ;1
L 3.3325 0.4825 3.3325 0.4825 9 P 0 ;1
L 3.3325 0.5325 3.3325 0.5325 9 P 0 ;1
L 3.3325 0.5825 3.3325 0.5825 9 P 0 ;1
L 3.3325 0.6325 3.3325 0.6325 9 P 0 ;1
L 3.3325 0.8325 3.3325 0.8325 9 P 0 ;1
L 3.3325 0.8825 3.3325 0.8825 9 P 0 ;1
L 3.3325 0.9325 3.3325 0.9325 9 P 0 ;1
L 3.3325 1.3825 3.3325 1.3825 9 P 0 ;1
L 3.3325 1.4325 3.3325 1.4325 9 P 0 ;1
L 3.3325 1.4825 3.3325 1.4825 9 P 0 ;1
L 3.3325 1.7825 3.3325 1.7825 9 P 0 ;1
L 3.3325 1.8325 3.3325 1.8325 9 P 0 ;1
L 3.3325 1.8825 3.3325 1.8825 9 P 0 ;1
L 3.3325 1.9325 3.3325 1.9325 9 P 0 ;1
L 3.3325 1.9825 3.3325 1.9825 9 P 0 ;1
L 3.3325 2.0325 3.3325 2.0325 9 P 0 ;1
L 3.3325 2.0825 3.3325 2.0825 9 P 0 ;1
L 3.3325 2.1325 3.3325 2.1325 9 P 0 ;1
L 3.3325 2.1825 3.3325 2.1825 9 P 0 ;1
L 3.3325 2.2325 3.3325 2.2325 9 P 0 ;1
L 3.3325 2.2825 3.3325 2.2825 9 P 0 ;1
L 3.3325 2.3325 3.3325 2.3325 9 P 0 ;1
L 3.3325 2.3825 3.3325 2.3825 9 P 0 ;1
L 3.3325 2.4325 3.3325 2.4325 9 P 0 ;1
L 3.3325 2.4825 3.3325 2.4825 9 P 0 ;1
L 3.3325 2.5325 3.3325 2.5325 9 P 0 ;1
L 3.3325 2.5825 3.3325 2.5825 9 P 0 ;1
L 3.3325 2.6325 3.3325 2.6325 9 P 0 ;1
L 3.3325 2.6825 3.3325 2.6825 9 P 0 ;1
L 3.3325 2.7325 3.3325 2.7325 9 P 0 ;1
L 3.3325 2.7825 3.3325 2.7825 9 P 0 ;1
L 3.3325 2.8325 3.3325 2.8325 9 P 0 ;1
L 3.3325 2.8825 3.3325 2.8825 9 P 0 ;1
L 3.3325 2.9325 3.3325 2.9325 9 P 0 ;1
L 3.3325 2.9825 3.3325 2.9825 9 P 0 ;1
L 3.3325 3.0325 3.3325 3.0325 9 P 0 ;1
L 3.3325 3.0825 3.3325 3.0825 9 P 0 ;1
L 3.3325 3.1325 3.3325 3.1325 9 P 0 ;1
L 3.3325 3.1825 3.3325 3.1825 9 P 0 ;1
L 3.3325 3.2325 3.3325 3.2325 9 P 0 ;1
L 3.3325 3.2825 3.3325 3.2825 9 P 0 ;1
L 3.3325 3.3325 3.3325 3.3325 9 P 0 ;1
L 3.3325 3.3825 3.3325 3.3825 9 P 0 ;1
L 3.3325 3.4325 3.3325 3.4325 9 P 0 ;1
L 3.3325 3.4825 3.3325 3.4825 9 P 0 ;1
L 3.3325 3.5325 3.3325 3.5325 9 P 0 ;1
L 3.3325 3.5825 3.3325 3.5825 9 P 0 ;1
L 3.3325 3.6325 3.3325 3.6325 9 P 0 ;1
L 3.3325 3.6825 3.3325 3.6825 9 P 0 ;1
L 3.3325 3.7325 3.3325 3.7325 9 P 0 ;1
L 3.3325 3.7825 3.3325 3.7825 9 P 0 ;1
L 3.3325 3.8325 3.3325 3.8325 9 P 0 ;1
L 3.3325 3.8825 3.3325 3.8825 9 P 0 ;1
L 3.3325 3.9325 3.3325 3.9325 9 P 0 ;1
L 3.3325 3.9825 3.3325 3.9825 9 P 0 ;1
L 3.3325 4.0325 3.3325 4.0325 9 P 0 ;1
L 3.3325 4.2825 3.3325 4.2825 9 P 0 ;1
L 3.3325 4.3325 3.3325 4.3325 9 P 0 ;1
L 3.3325 4.3825 3.3325 4.3825 9 P 0 ;1
L 3.3325 4.4325 3.3325 4.4325 9 P 0 ;1
L 3.3325 4.4825 3.3325 4.4825 9 P 0 ;1
L 3.3325 4.5325 3.3325 4.5325 9 P 0 ;1
L 3.3325 4.5825 3.3325 4.5825 9 P 0 ;1
L 3.3325 5.3825 3.3325 5.3825 9 P 0 ;1
L 3.3325 5.4325 3.3325 5.4325 9 P 0 ;1
L 3.3325 5.4825 3.3325 5.4825 9 P 0 ;1
L 3.3325 5.5325 3.3325 5.5325 9 P 0 ;1
L 3.3325 5.5825 3.3325 5.5825 9 P 0 ;1
L 3.3325 5.6325 3.3325 5.6325 9 P 0 ;1
L 3.3325 5.6825 3.3325 5.6825 9 P 0 ;1
L 3.3325 5.7325 3.3325 5.7325 9 P 0 ;1
L 3.3325 5.7825 3.3325 5.7825 9 P 0 ;1
L 3.3325 5.8325 3.3325 5.8325 9 P 0 ;1
L 3.3325 5.8825 3.3325 5.8825 9 P 0 ;1
L 3.3825 0.1325 3.3825 0.1325 9 P 0 ;1
L 3.3825 0.1825 3.3825 0.1825 9 P 0 ;1
L 3.3825 0.2325 3.3825 0.2325 9 P 0 ;1
L 3.3825 0.2825 3.3825 0.2825 9 P 0 ;1
L 3.3825 0.3325 3.3825 0.3325 9 P 0 ;1
L 3.3825 0.3825 3.3825 0.3825 9 P 0 ;1
L 3.3825 0.4325 3.3825 0.4325 9 P 0 ;1
L 3.3825 0.4825 3.3825 0.4825 9 P 0 ;1
L 3.3825 0.5325 3.3825 0.5325 9 P 0 ;1
L 3.3825 0.5825 3.3825 0.5825 9 P 0 ;1
L 3.3825 0.6325 3.3825 0.6325 9 P 0 ;1
L 3.3825 0.8325 3.3825 0.8325 9 P 0 ;1
L 3.3825 0.8825 3.3825 0.8825 9 P 0 ;1
L 3.3825 0.9325 3.3825 0.9325 9 P 0 ;1
L 3.3825 1.4325 3.3825 1.4325 9 P 0 ;1
L 3.3825 1.4825 3.3825 1.4825 9 P 0 ;1
L 3.3825 1.7825 3.3825 1.7825 9 P 0 ;1
L 3.3825 1.8325 3.3825 1.8325 9 P 0 ;1
L 3.3825 1.8825 3.3825 1.8825 9 P 0 ;1
L 3.3825 1.9325 3.3825 1.9325 9 P 0 ;1
L 3.3825 1.9825 3.3825 1.9825 9 P 0 ;1
L 3.3825 2.0325 3.3825 2.0325 9 P 0 ;1
L 3.3825 2.0825 3.3825 2.0825 9 P 0 ;1
L 3.3825 2.1325 3.3825 2.1325 9 P 0 ;1
L 3.3825 2.1825 3.3825 2.1825 9 P 0 ;1
L 3.3825 2.2325 3.3825 2.2325 9 P 0 ;1
L 3.3825 2.2825 3.3825 2.2825 9 P 0 ;1
L 3.3825 2.3325 3.3825 2.3325 9 P 0 ;1
L 3.3825 2.3825 3.3825 2.3825 9 P 0 ;1
L 3.3825 2.4325 3.3825 2.4325 9 P 0 ;1
L 3.3825 2.4825 3.3825 2.4825 9 P 0 ;1
L 3.3825 2.5325 3.3825 2.5325 9 P 0 ;1
L 3.3825 2.5825 3.3825 2.5825 9 P 0 ;1
L 3.3825 2.6325 3.3825 2.6325 9 P 0 ;1
L 3.3825 2.6825 3.3825 2.6825 9 P 0 ;1
L 3.3825 2.7325 3.3825 2.7325 9 P 0 ;1
L 3.3825 2.7825 3.3825 2.7825 9 P 0 ;1
L 3.3825 2.8325 3.3825 2.8325 9 P 0 ;1
L 3.3825 2.8825 3.3825 2.8825 9 P 0 ;1
L 3.3825 2.9325 3.3825 2.9325 9 P 0 ;1
L 3.3825 2.9825 3.3825 2.9825 9 P 0 ;1
L 3.3825 3.0325 3.3825 3.0325 9 P 0 ;1
L 3.3825 3.0825 3.3825 3.0825 9 P 0 ;1
L 3.3825 3.1325 3.3825 3.1325 9 P 0 ;1
L 3.3825 3.1825 3.3825 3.1825 9 P 0 ;1
L 3.3825 3.2325 3.3825 3.2325 9 P 0 ;1
L 3.3825 3.2825 3.3825 3.2825 9 P 0 ;1
L 3.3825 3.3325 3.3825 3.3325 9 P 0 ;1
L 3.3825 3.3825 3.3825 3.3825 9 P 0 ;1
L 3.3825 3.4325 3.3825 3.4325 9 P 0 ;1
L 3.3825 3.4825 3.3825 3.4825 9 P 0 ;1
L 3.3825 3.5325 3.3825 3.5325 9 P 0 ;1
L 3.3825 3.5825 3.3825 3.5825 9 P 0 ;1
L 3.3825 3.6325 3.3825 3.6325 9 P 0 ;1
L 3.3825 3.6825 3.3825 3.6825 9 P 0 ;1
L 3.3825 3.7325 3.3825 3.7325 9 P 0 ;1
L 3.3825 3.7825 3.3825 3.7825 9 P 0 ;1
L 3.3825 3.8325 3.3825 3.8325 9 P 0 ;1
L 3.3825 3.8825 3.3825 3.8825 9 P 0 ;1
L 3.3825 3.9325 3.3825 3.9325 9 P 0 ;1
L 3.3825 3.9825 3.3825 3.9825 9 P 0 ;1
L 3.3825 4.0325 3.3825 4.0325 9 P 0 ;1
L 3.3825 4.2825 3.3825 4.2825 9 P 0 ;1
L 3.3825 4.3325 3.3825 4.3325 9 P 0 ;1
L 3.3825 4.3825 3.3825 4.3825 9 P 0 ;1
L 3.3825 4.4325 3.3825 4.4325 9 P 0 ;1
L 3.3825 4.4825 3.3825 4.4825 9 P 0 ;1
L 3.3825 4.5325 3.3825 4.5325 9 P 0 ;1
L 3.3825 5.4325 3.3825 5.4325 9 P 0 ;1
L 3.3825 5.4825 3.3825 5.4825 9 P 0 ;1
L 3.3825 5.5325 3.3825 5.5325 9 P 0 ;1
L 3.3825 5.5825 3.3825 5.5825 9 P 0 ;1
L 3.3825 5.6325 3.3825 5.6325 9 P 0 ;1
L 3.3825 5.6825 3.3825 5.6825 9 P 0 ;1
L 3.3825 5.7325 3.3825 5.7325 9 P 0 ;1
L 3.3825 5.7825 3.3825 5.7825 9 P 0 ;1
L 3.3825 5.8325 3.3825 5.8325 9 P 0 ;1
L 3.3825 5.8825 3.3825 5.8825 9 P 0 ;1
L 3.4325 0.1325 3.4325 0.1325 9 P 0 ;1
L 3.4325 0.1825 3.4325 0.1825 9 P 0 ;1
L 3.4325 0.2325 3.4325 0.2325 9 P 0 ;1
L 3.4325 0.2825 3.4325 0.2825 9 P 0 ;1
L 3.4325 0.3325 3.4325 0.3325 9 P 0 ;1
L 3.4325 0.3825 3.4325 0.3825 9 P 0 ;1
L 3.4325 0.4325 3.4325 0.4325 9 P 0 ;1
L 3.4325 0.4825 3.4325 0.4825 9 P 0 ;1
L 3.4325 0.5325 3.4325 0.5325 9 P 0 ;1
L 3.4325 0.5825 3.4325 0.5825 9 P 0 ;1
L 3.4325 0.7825 3.4325 0.7825 9 P 0 ;1
L 3.4325 0.8325 3.4325 0.8325 9 P 0 ;1
L 3.4325 0.8825 3.4325 0.8825 9 P 0 ;1
L 3.4325 0.9325 3.4325 0.9325 9 P 0 ;1
L 3.4325 1.4325 3.4325 1.4325 9 P 0 ;1
L 3.4325 1.4825 3.4325 1.4825 9 P 0 ;1
L 3.4325 1.7825 3.4325 1.7825 9 P 0 ;1
L 3.4325 1.8325 3.4325 1.8325 9 P 0 ;1
L 3.4325 1.8825 3.4325 1.8825 9 P 0 ;1
L 3.4325 1.9325 3.4325 1.9325 9 P 0 ;1
L 3.4325 1.9825 3.4325 1.9825 9 P 0 ;1
L 3.4325 2.0325 3.4325 2.0325 9 P 0 ;1
L 3.4325 2.0825 3.4325 2.0825 9 P 0 ;1
L 3.4325 2.1325 3.4325 2.1325 9 P 0 ;1
L 3.4325 2.1825 3.4325 2.1825 9 P 0 ;1
L 3.4325 2.2325 3.4325 2.2325 9 P 0 ;1
L 3.4325 2.2825 3.4325 2.2825 9 P 0 ;1
L 3.4325 2.3325 3.4325 2.3325 9 P 0 ;1
L 3.4325 2.3825 3.4325 2.3825 9 P 0 ;1
L 3.4325 2.4325 3.4325 2.4325 9 P 0 ;1
L 3.4325 2.4825 3.4325 2.4825 9 P 0 ;1
L 3.4325 2.5325 3.4325 2.5325 9 P 0 ;1
L 3.4325 2.5825 3.4325 2.5825 9 P 0 ;1
L 3.4325 2.6325 3.4325 2.6325 9 P 0 ;1
L 3.4325 2.6825 3.4325 2.6825 9 P 0 ;1
L 3.4325 2.7325 3.4325 2.7325 9 P 0 ;1
L 3.4325 2.7825 3.4325 2.7825 9 P 0 ;1
L 3.4325 2.8325 3.4325 2.8325 9 P 0 ;1
L 3.4325 2.8825 3.4325 2.8825 9 P 0 ;1
L 3.4325 2.9325 3.4325 2.9325 9 P 0 ;1
L 3.4325 2.9825 3.4325 2.9825 9 P 0 ;1
L 3.4325 3.0325 3.4325 3.0325 9 P 0 ;1
L 3.4325 3.0825 3.4325 3.0825 9 P 0 ;1
L 3.4325 3.1325 3.4325 3.1325 9 P 0 ;1
L 3.4325 3.1825 3.4325 3.1825 9 P 0 ;1
L 3.4325 3.2325 3.4325 3.2325 9 P 0 ;1
L 3.4325 3.2825 3.4325 3.2825 9 P 0 ;1
L 3.4325 3.3325 3.4325 3.3325 9 P 0 ;1
L 3.4325 3.3825 3.4325 3.3825 9 P 0 ;1
L 3.4325 3.4325 3.4325 3.4325 9 P 0 ;1
L 3.4325 3.4825 3.4325 3.4825 9 P 0 ;1
L 3.4325 3.5325 3.4325 3.5325 9 P 0 ;1
L 3.4325 3.5825 3.4325 3.5825 9 P 0 ;1
L 3.4325 3.6325 3.4325 3.6325 9 P 0 ;1
L 3.4325 3.6825 3.4325 3.6825 9 P 0 ;1
L 3.4325 3.7325 3.4325 3.7325 9 P 0 ;1
L 3.4325 3.7825 3.4325 3.7825 9 P 0 ;1
L 3.4325 3.8325 3.4325 3.8325 9 P 0 ;1
L 3.4325 3.8825 3.4325 3.8825 9 P 0 ;1
L 3.4325 3.9325 3.4325 3.9325 9 P 0 ;1
L 3.4325 3.9825 3.4325 3.9825 9 P 0 ;1
L 3.4325 4.0325 3.4325 4.0325 9 P 0 ;1
L 3.4325 4.3325 3.4325 4.3325 9 P 0 ;1
L 3.4325 4.3825 3.4325 4.3825 9 P 0 ;1
L 3.4325 4.4325 3.4325 4.4325 9 P 0 ;1
L 3.4325 4.4825 3.4325 4.4825 9 P 0 ;1
L 3.4325 5.4325 3.4325 5.4325 9 P 0 ;1
L 3.4325 5.4825 3.4325 5.4825 9 P 0 ;1
L 3.4325 5.5325 3.4325 5.5325 9 P 0 ;1
L 3.4325 5.5825 3.4325 5.5825 9 P 0 ;1
L 3.4325 5.6325 3.4325 5.6325 9 P 0 ;1
L 3.4325 5.6825 3.4325 5.6825 9 P 0 ;1
L 3.4325 5.7325 3.4325 5.7325 9 P 0 ;1
L 3.4325 5.7825 3.4325 5.7825 9 P 0 ;1
L 3.4325 5.8325 3.4325 5.8325 9 P 0 ;1
L 3.4325 5.8825 3.4325 5.8825 9 P 0 ;1
L 3.4825 0.1325 3.4825 0.1325 9 P 0 ;1
L 3.4825 0.1825 3.4825 0.1825 9 P 0 ;1
L 3.4825 0.2325 3.4825 0.2325 9 P 0 ;1
L 3.4825 0.2825 3.4825 0.2825 9 P 0 ;1
L 3.4825 0.3325 3.4825 0.3325 9 P 0 ;1
L 3.4825 0.3825 3.4825 0.3825 9 P 0 ;1
L 3.4825 0.4325 3.4825 0.4325 9 P 0 ;1
L 3.4825 0.5325 3.4825 0.5325 9 P 0 ;1
L 3.4825 0.5825 3.4825 0.5825 9 P 0 ;1
L 3.4825 0.7825 3.4825 0.7825 9 P 0 ;1
L 3.4825 0.8325 3.4825 0.8325 9 P 0 ;1
L 3.4825 0.8825 3.4825 0.8825 9 P 0 ;1
L 3.4825 0.9325 3.4825 0.9325 9 P 0 ;1
L 3.4825 1.4325 3.4825 1.4325 9 P 0 ;1
L 3.4825 1.4825 3.4825 1.4825 9 P 0 ;1
L 3.4825 1.5325 3.4825 1.5325 9 P 0 ;1
L 3.4825 1.7825 3.4825 1.7825 9 P 0 ;1
L 3.4825 1.8325 3.4825 1.8325 9 P 0 ;1
L 3.4825 1.8825 3.4825 1.8825 9 P 0 ;1
L 3.4825 1.9325 3.4825 1.9325 9 P 0 ;1
L 3.4825 1.9825 3.4825 1.9825 9 P 0 ;1
L 3.4825 2.0325 3.4825 2.0325 9 P 0 ;1
L 3.4825 2.0825 3.4825 2.0825 9 P 0 ;1
L 3.4825 2.1325 3.4825 2.1325 9 P 0 ;1
L 3.4825 2.1825 3.4825 2.1825 9 P 0 ;1
L 3.4825 2.2325 3.4825 2.2325 9 P 0 ;1
L 3.4825 2.2825 3.4825 2.2825 9 P 0 ;1
L 3.4825 2.3325 3.4825 2.3325 9 P 0 ;1
L 3.4825 2.3825 3.4825 2.3825 9 P 0 ;1
L 3.4825 2.4325 3.4825 2.4325 9 P 0 ;1
L 3.4825 2.4825 3.4825 2.4825 9 P 0 ;1
L 3.4825 2.5325 3.4825 2.5325 9 P 0 ;1
L 3.4825 2.5825 3.4825 2.5825 9 P 0 ;1
L 3.4825 2.6325 3.4825 2.6325 9 P 0 ;1
L 3.4825 2.6825 3.4825 2.6825 9 P 0 ;1
L 3.4825 2.7325 3.4825 2.7325 9 P 0 ;1
L 3.4825 2.7825 3.4825 2.7825 9 P 0 ;1
L 3.4825 2.8325 3.4825 2.8325 9 P 0 ;1
L 3.4825 2.8825 3.4825 2.8825 9 P 0 ;1
L 3.4825 2.9325 3.4825 2.9325 9 P 0 ;1
L 3.4825 2.9825 3.4825 2.9825 9 P 0 ;1
L 3.4825 3.0325 3.4825 3.0325 9 P 0 ;1
L 3.4825 3.0825 3.4825 3.0825 9 P 0 ;1
L 3.4825 3.1325 3.4825 3.1325 9 P 0 ;1
L 3.4825 3.1825 3.4825 3.1825 9 P 0 ;1
L 3.4825 3.2325 3.4825 3.2325 9 P 0 ;1
L 3.4825 3.2825 3.4825 3.2825 9 P 0 ;1
L 3.4825 3.3325 3.4825 3.3325 9 P 0 ;1
L 3.4825 3.3825 3.4825 3.3825 9 P 0 ;1
L 3.4825 3.4325 3.4825 3.4325 9 P 0 ;1
L 3.4825 3.4825 3.4825 3.4825 9 P 0 ;1
L 3.4825 3.5325 3.4825 3.5325 9 P 0 ;1
L 3.4825 3.5825 3.4825 3.5825 9 P 0 ;1
L 3.4825 3.6325 3.4825 3.6325 9 P 0 ;1
L 3.4825 3.6825 3.4825 3.6825 9 P 0 ;1
L 3.4825 3.7325 3.4825 3.7325 9 P 0 ;1
L 3.4825 3.7825 3.4825 3.7825 9 P 0 ;1
L 3.4825 3.8325 3.4825 3.8325 9 P 0 ;1
L 3.4825 3.8825 3.4825 3.8825 9 P 0 ;1
L 3.4825 3.9325 3.4825 3.9325 9 P 0 ;1
L 3.4825 3.9825 3.4825 3.9825 9 P 0 ;1
L 3.4825 4.0325 3.4825 4.0325 9 P 0 ;1
L 3.4825 4.3325 3.4825 4.3325 9 P 0 ;1
L 3.4825 4.3825 3.4825 4.3825 9 P 0 ;1
L 3.4825 4.4325 3.4825 4.4325 9 P 0 ;1
L 3.4825 4.4825 3.4825 4.4825 9 P 0 ;1
L 3.4825 5.3825 3.4825 5.3825 9 P 0 ;1
L 3.4825 5.4325 3.4825 5.4325 9 P 0 ;1
L 3.4825 5.4825 3.4825 5.4825 9 P 0 ;1
L 3.4825 5.5325 3.4825 5.5325 9 P 0 ;1
L 3.4825 5.5825 3.4825 5.5825 9 P 0 ;1
L 3.4825 5.6325 3.4825 5.6325 9 P 0 ;1
L 3.4825 5.6825 3.4825 5.6825 9 P 0 ;1
L 3.4825 5.7325 3.4825 5.7325 9 P 0 ;1
L 3.4825 5.7825 3.4825 5.7825 9 P 0 ;1
L 3.4825 5.8325 3.4825 5.8325 9 P 0 ;1
L 3.4825 5.8825 3.4825 5.8825 9 P 0 ;1
L 3.5325 0.1325 3.5325 0.1325 9 P 0 ;1
L 3.5325 0.1825 3.5325 0.1825 9 P 0 ;1
L 3.5325 0.2825 3.5325 0.2825 9 P 0 ;1
L 3.5325 0.3325 3.5325 0.3325 9 P 0 ;1
L 3.5325 0.3825 3.5325 0.3825 9 P 0 ;1
L 3.5325 0.5825 3.5325 0.5825 9 P 0 ;1
L 3.5325 0.7825 3.5325 0.7825 9 P 0 ;1
L 3.5325 0.8325 3.5325 0.8325 9 P 0 ;1
L 3.5325 0.8825 3.5325 0.8825 9 P 0 ;1
L 3.5325 0.9325 3.5325 0.9325 9 P 0 ;1
L 3.5325 1.4325 3.5325 1.4325 9 P 0 ;1
L 3.5325 1.4825 3.5325 1.4825 9 P 0 ;1
L 3.5325 1.5325 3.5325 1.5325 9 P 0 ;1
L 3.5325 1.8325 3.5325 1.8325 9 P 0 ;1
L 3.5325 1.8825 3.5325 1.8825 9 P 0 ;1
L 3.5325 1.9325 3.5325 1.9325 9 P 0 ;1
L 3.5325 1.9825 3.5325 1.9825 9 P 0 ;1
L 3.5325 2.0325 3.5325 2.0325 9 P 0 ;1
L 3.5325 2.0825 3.5325 2.0825 9 P 0 ;1
L 3.5325 2.1325 3.5325 2.1325 9 P 0 ;1
L 3.5325 2.1825 3.5325 2.1825 9 P 0 ;1
L 3.5325 2.2325 3.5325 2.2325 9 P 0 ;1
L 3.5325 2.2825 3.5325 2.2825 9 P 0 ;1
L 3.5325 2.3325 3.5325 2.3325 9 P 0 ;1
L 3.5325 2.3825 3.5325 2.3825 9 P 0 ;1
L 3.5325 2.4325 3.5325 2.4325 9 P 0 ;1
L 3.5325 2.4825 3.5325 2.4825 9 P 0 ;1
L 3.5325 2.5325 3.5325 2.5325 9 P 0 ;1
L 3.5325 2.5825 3.5325 2.5825 9 P 0 ;1
L 3.5325 2.6325 3.5325 2.6325 9 P 0 ;1
L 3.5325 2.6825 3.5325 2.6825 9 P 0 ;1
L 3.5325 2.7325 3.5325 2.7325 9 P 0 ;1
L 3.5325 2.7825 3.5325 2.7825 9 P 0 ;1
L 3.5325 2.8325 3.5325 2.8325 9 P 0 ;1
L 3.5325 2.8825 3.5325 2.8825 9 P 0 ;1
L 3.5325 2.9325 3.5325 2.9325 9 P 0 ;1
L 3.5325 2.9825 3.5325 2.9825 9 P 0 ;1
L 3.5325 3.0325 3.5325 3.0325 9 P 0 ;1
L 3.5325 3.0825 3.5325 3.0825 9 P 0 ;1
L 3.5325 3.1325 3.5325 3.1325 9 P 0 ;1
L 3.5325 3.1825 3.5325 3.1825 9 P 0 ;1
L 3.5325 3.2325 3.5325 3.2325 9 P 0 ;1
L 3.5325 3.2825 3.5325 3.2825 9 P 0 ;1
L 3.5325 3.3325 3.5325 3.3325 9 P 0 ;1
L 3.5325 3.3825 3.5325 3.3825 9 P 0 ;1
L 3.5325 3.4325 3.5325 3.4325 9 P 0 ;1
L 3.5325 3.4825 3.5325 3.4825 9 P 0 ;1
L 3.5325 3.5325 3.5325 3.5325 9 P 0 ;1
L 3.5325 3.5825 3.5325 3.5825 9 P 0 ;1
L 3.5325 3.6325 3.5325 3.6325 9 P 0 ;1
L 3.5325 3.6825 3.5325 3.6825 9 P 0 ;1
L 3.5325 3.7325 3.5325 3.7325 9 P 0 ;1
L 3.5325 3.7825 3.5325 3.7825 9 P 0 ;1
L 3.5325 3.8325 3.5325 3.8325 9 P 0 ;1
L 3.5325 3.8825 3.5325 3.8825 9 P 0 ;1
L 3.5325 3.9325 3.5325 3.9325 9 P 0 ;1
L 3.5325 3.9825 3.5325 3.9825 9 P 0 ;1
L 3.5325 4.0325 3.5325 4.0325 9 P 0 ;1
L 3.5325 4.0825 3.5325 4.0825 9 P 0 ;1
L 3.5325 4.3325 3.5325 4.3325 9 P 0 ;1
L 3.5325 5.3325 3.5325 5.3325 9 P 0 ;1
L 3.5325 5.3825 3.5325 5.3825 9 P 0 ;1
L 3.5325 5.4325 3.5325 5.4325 9 P 0 ;1
L 3.5325 5.4825 3.5325 5.4825 9 P 0 ;1
L 3.5325 5.5325 3.5325 5.5325 9 P 0 ;1
L 3.5325 5.5825 3.5325 5.5825 9 P 0 ;1
L 3.5325 5.6325 3.5325 5.6325 9 P 0 ;1
L 3.5325 5.6825 3.5325 5.6825 9 P 0 ;1
L 3.5325 5.7325 3.5325 5.7325 9 P 0 ;1
L 3.5325 5.7825 3.5325 5.7825 9 P 0 ;1
L 3.5325 5.8325 3.5325 5.8325 9 P 0 ;1
L 3.5325 5.8825 3.5325 5.8825 9 P 0 ;1
L 3.5825 0.1325 3.5825 0.1325 9 P 0 ;1
L 3.5825 0.3325 3.5825 0.3325 9 P 0 ;1
L 3.5825 0.3825 3.5825 0.3825 9 P 0 ;1
L 3.5825 0.5825 3.5825 0.5825 9 P 0 ;1
L 3.5825 0.7825 3.5825 0.7825 9 P 0 ;1
L 3.5825 0.8325 3.5825 0.8325 9 P 0 ;1
L 3.5825 0.8825 3.5825 0.8825 9 P 0 ;1
L 3.5825 0.9325 3.5825 0.9325 9 P 0 ;1
L 3.5825 0.9825 3.5825 0.9825 9 P 0 ;1
L 3.5825 1.4325 3.5825 1.4325 9 P 0 ;1
L 3.5825 1.4825 3.5825 1.4825 9 P 0 ;1
L 3.5825 1.5325 3.5825 1.5325 9 P 0 ;1
L 3.5825 1.8325 3.5825 1.8325 9 P 0 ;1
L 3.5825 1.8825 3.5825 1.8825 9 P 0 ;1
L 3.5825 1.9325 3.5825 1.9325 9 P 0 ;1
L 3.5825 1.9825 3.5825 1.9825 9 P 0 ;1
L 3.5825 2.0325 3.5825 2.0325 9 P 0 ;1
L 3.5825 2.0825 3.5825 2.0825 9 P 0 ;1
L 3.5825 2.1325 3.5825 2.1325 9 P 0 ;1
L 3.5825 2.1825 3.5825 2.1825 9 P 0 ;1
L 3.5825 2.2325 3.5825 2.2325 9 P 0 ;1
L 3.5825 2.2825 3.5825 2.2825 9 P 0 ;1
L 3.5825 2.3325 3.5825 2.3325 9 P 0 ;1
L 3.5825 2.3825 3.5825 2.3825 9 P 0 ;1
L 3.5825 2.4325 3.5825 2.4325 9 P 0 ;1
L 3.5825 2.4825 3.5825 2.4825 9 P 0 ;1
L 3.5825 2.5325 3.5825 2.5325 9 P 0 ;1
L 3.5825 2.5825 3.5825 2.5825 9 P 0 ;1
L 3.5825 2.6325 3.5825 2.6325 9 P 0 ;1
L 3.5825 2.6825 3.5825 2.6825 9 P 0 ;1
L 3.5825 2.7325 3.5825 2.7325 9 P 0 ;1
L 3.5825 2.7825 3.5825 2.7825 9 P 0 ;1
L 3.5825 2.8325 3.5825 2.8325 9 P 0 ;1
L 3.5825 2.8825 3.5825 2.8825 9 P 0 ;1
L 3.5825 2.9325 3.5825 2.9325 9 P 0 ;1
L 3.5825 2.9825 3.5825 2.9825 9 P 0 ;1
L 3.5825 3.0325 3.5825 3.0325 9 P 0 ;1
L 3.5825 3.0825 3.5825 3.0825 9 P 0 ;1
L 3.5825 3.1325 3.5825 3.1325 9 P 0 ;1
L 3.5825 3.1825 3.5825 3.1825 9 P 0 ;1
L 3.5825 3.2325 3.5825 3.2325 9 P 0 ;1
L 3.5825 3.2825 3.5825 3.2825 9 P 0 ;1
L 3.5825 3.3325 3.5825 3.3325 9 P 0 ;1
L 3.5825 3.3825 3.5825 3.3825 9 P 0 ;1
L 3.5825 3.4325 3.5825 3.4325 9 P 0 ;1
L 3.5825 3.4825 3.5825 3.4825 9 P 0 ;1
L 3.5825 3.5325 3.5825 3.5325 9 P 0 ;1
L 3.5825 3.5825 3.5825 3.5825 9 P 0 ;1
L 3.5825 3.6325 3.5825 3.6325 9 P 0 ;1
L 3.5825 3.6825 3.5825 3.6825 9 P 0 ;1
L 3.5825 3.7325 3.5825 3.7325 9 P 0 ;1
L 3.5825 3.7825 3.5825 3.7825 9 P 0 ;1
L 3.5825 3.8325 3.5825 3.8325 9 P 0 ;1
L 3.5825 3.8825 3.5825 3.8825 9 P 0 ;1
L 3.5825 3.9325 3.5825 3.9325 9 P 0 ;1
L 3.5825 3.9825 3.5825 3.9825 9 P 0 ;1
L 3.5825 4.0325 3.5825 4.0325 9 P 0 ;1
L 3.5825 4.0825 3.5825 4.0825 9 P 0 ;1
L 3.5825 4.3325 3.5825 4.3325 9 P 0 ;1
L 3.5825 4.5325 3.5825 4.5325 9 P 0 ;1
L 3.5825 4.5825 3.5825 4.5825 9 P 0 ;1
L 3.5825 5.2825 3.5825 5.2825 9 P 0 ;1
L 3.5825 5.3325 3.5825 5.3325 9 P 0 ;1
L 3.5825 5.3825 3.5825 5.3825 9 P 0 ;1
L 3.5825 5.4325 3.5825 5.4325 9 P 0 ;1
L 3.5825 5.4825 3.5825 5.4825 9 P 0 ;1
L 3.5825 5.5325 3.5825 5.5325 9 P 0 ;1
L 3.5825 5.5825 3.5825 5.5825 9 P 0 ;1
L 3.5825 5.6325 3.5825 5.6325 9 P 0 ;1
L 3.5825 5.6825 3.5825 5.6825 9 P 0 ;1
L 3.5825 5.7325 3.5825 5.7325 9 P 0 ;1
L 3.5825 5.7825 3.5825 5.7825 9 P 0 ;1
L 3.5825 5.8325 3.5825 5.8325 9 P 0 ;1
L 3.5825 5.8825 3.5825 5.8825 9 P 0 ;1
L 3.6325 0.1325 3.6325 0.1325 9 P 0 ;1
L 3.6325 0.5825 3.6325 0.5825 9 P 0 ;1
L 3.6325 0.8325 3.6325 0.8325 9 P 0 ;1
L 3.6325 0.8825 3.6325 0.8825 9 P 0 ;1
L 3.6325 0.9325 3.6325 0.9325 9 P 0 ;1
L 3.6325 0.9825 3.6325 0.9825 9 P 0 ;1
L 3.6325 1.4825 3.6325 1.4825 9 P 0 ;1
L 3.6325 1.5325 3.6325 1.5325 9 P 0 ;1
L 3.6325 1.8325 3.6325 1.8325 9 P 0 ;1
L 3.6325 1.8825 3.6325 1.8825 9 P 0 ;1
L 3.6325 1.9325 3.6325 1.9325 9 P 0 ;1
L 3.6325 1.9825 3.6325 1.9825 9 P 0 ;1
L 3.6325 2.0325 3.6325 2.0325 9 P 0 ;1
L 3.6325 2.0825 3.6325 2.0825 9 P 0 ;1
L 3.6325 2.1325 3.6325 2.1325 9 P 0 ;1
L 3.6325 2.1825 3.6325 2.1825 9 P 0 ;1
L 3.6325 2.2325 3.6325 2.2325 9 P 0 ;1
L 3.6325 2.2825 3.6325 2.2825 9 P 0 ;1
L 3.6325 2.3325 3.6325 2.3325 9 P 0 ;1
L 3.6325 2.3825 3.6325 2.3825 9 P 0 ;1
L 3.6325 2.4325 3.6325 2.4325 9 P 0 ;1
L 3.6325 2.4825 3.6325 2.4825 9 P 0 ;1
L 3.6325 2.5325 3.6325 2.5325 9 P 0 ;1
L 3.6325 2.5825 3.6325 2.5825 9 P 0 ;1
L 3.6325 2.6325 3.6325 2.6325 9 P 0 ;1
L 3.6325 2.6825 3.6325 2.6825 9 P 0 ;1
L 3.6325 2.7325 3.6325 2.7325 9 P 0 ;1
L 3.6325 2.7825 3.6325 2.7825 9 P 0 ;1
L 3.6325 2.8325 3.6325 2.8325 9 P 0 ;1
L 3.6325 2.8825 3.6325 2.8825 9 P 0 ;1
L 3.6325 2.9325 3.6325 2.9325 9 P 0 ;1
L 3.6325 2.9825 3.6325 2.9825 9 P 0 ;1
L 3.6325 3.0325 3.6325 3.0325 9 P 0 ;1
L 3.6325 3.0825 3.6325 3.0825 9 P 0 ;1
L 3.6325 3.1325 3.6325 3.1325 9 P 0 ;1
L 3.6325 3.1825 3.6325 3.1825 9 P 0 ;1
L 3.6325 3.2325 3.6325 3.2325 9 P 0 ;1
L 3.6325 3.2825 3.6325 3.2825 9 P 0 ;1
L 3.6325 3.3325 3.6325 3.3325 9 P 0 ;1
L 3.6325 3.3825 3.6325 3.3825 9 P 0 ;1
L 3.6325 3.4325 3.6325 3.4325 9 P 0 ;1
L 3.6325 3.4825 3.6325 3.4825 9 P 0 ;1
L 3.6325 3.5325 3.6325 3.5325 9 P 0 ;1
L 3.6325 3.5825 3.6325 3.5825 9 P 0 ;1
L 3.6325 3.6325 3.6325 3.6325 9 P 0 ;1
L 3.6325 3.6825 3.6325 3.6825 9 P 0 ;1
L 3.6325 3.7325 3.6325 3.7325 9 P 0 ;1
L 3.6325 3.7825 3.6325 3.7825 9 P 0 ;1
L 3.6325 3.8325 3.6325 3.8325 9 P 0 ;1
L 3.6325 3.8825 3.6325 3.8825 9 P 0 ;1
L 3.6325 3.9325 3.6325 3.9325 9 P 0 ;1
L 3.6325 3.9825 3.6325 3.9825 9 P 0 ;1
L 3.6325 4.0325 3.6325 4.0325 9 P 0 ;1
L 3.6325 4.3325 3.6325 4.3325 9 P 0 ;1
L 3.6325 4.5325 3.6325 4.5325 9 P 0 ;1
L 3.6325 5.2325 3.6325 5.2325 9 P 0 ;1
L 3.6325 5.2825 3.6325 5.2825 9 P 0 ;1
L 3.6325 5.3325 3.6325 5.3325 9 P 0 ;1
L 3.6325 5.3825 3.6325 5.3825 9 P 0 ;1
L 3.6325 5.4325 3.6325 5.4325 9 P 0 ;1
L 3.6325 5.4825 3.6325 5.4825 9 P 0 ;1
L 3.6325 5.5325 3.6325 5.5325 9 P 0 ;1
L 3.6325 5.5825 3.6325 5.5825 9 P 0 ;1
L 3.6325 5.6325 3.6325 5.6325 9 P 0 ;1
L 3.6325 5.8325 3.6325 5.8325 9 P 0 ;1
L 3.6325 5.8825 3.6325 5.8825 9 P 0 ;1
L 3.6825 0.1325 3.6825 0.1325 9 P 0 ;1
L 3.6825 0.1825 3.6825 0.1825 9 P 0 ;1
L 3.6825 0.8825 3.6825 0.8825 9 P 0 ;1
L 3.6825 0.9325 3.6825 0.9325 9 P 0 ;1
L 3.6825 0.9825 3.6825 0.9825 9 P 0 ;1
L 3.6825 1.4825 3.6825 1.4825 9 P 0 ;1
L 3.6825 1.5325 3.6825 1.5325 9 P 0 ;1
L 3.6825 1.8325 3.6825 1.8325 9 P 0 ;1
L 3.6825 1.8825 3.6825 1.8825 9 P 0 ;1
L 3.6825 1.9325 3.6825 1.9325 9 P 0 ;1
L 3.6825 1.9825 3.6825 1.9825 9 P 0 ;1
L 3.6825 2.0325 3.6825 2.0325 9 P 0 ;1
L 3.6825 2.0825 3.6825 2.0825 9 P 0 ;1
L 3.6825 2.1325 3.6825 2.1325 9 P 0 ;1
L 3.6825 2.1825 3.6825 2.1825 9 P 0 ;1
L 3.6825 2.2325 3.6825 2.2325 9 P 0 ;1
L 3.6825 2.2825 3.6825 2.2825 9 P 0 ;1
L 3.6825 2.3325 3.6825 2.3325 9 P 0 ;1
L 3.6825 2.3825 3.6825 2.3825 9 P 0 ;1
L 3.6825 2.4325 3.6825 2.4325 9 P 0 ;1
L 3.6825 2.4825 3.6825 2.4825 9 P 0 ;1
L 3.6825 2.5325 3.6825 2.5325 9 P 0 ;1
L 3.6825 2.5825 3.6825 2.5825 9 P 0 ;1
L 3.6825 2.6325 3.6825 2.6325 9 P 0 ;1
L 3.6825 2.6825 3.6825 2.6825 9 P 0 ;1
L 3.6825 2.7325 3.6825 2.7325 9 P 0 ;1
L 3.6825 2.7825 3.6825 2.7825 9 P 0 ;1
L 3.6825 2.8325 3.6825 2.8325 9 P 0 ;1
L 3.6825 2.8825 3.6825 2.8825 9 P 0 ;1
L 3.6825 2.9325 3.6825 2.9325 9 P 0 ;1
L 3.6825 2.9825 3.6825 2.9825 9 P 0 ;1
L 3.6825 3.0325 3.6825 3.0325 9 P 0 ;1
L 3.6825 3.0825 3.6825 3.0825 9 P 0 ;1
L 3.6825 3.1325 3.6825 3.1325 9 P 0 ;1
L 3.6825 3.1825 3.6825 3.1825 9 P 0 ;1
L 3.6825 3.2325 3.6825 3.2325 9 P 0 ;1
L 3.6825 3.2825 3.6825 3.2825 9 P 0 ;1
L 3.6825 3.3325 3.6825 3.3325 9 P 0 ;1
L 3.6825 3.3825 3.6825 3.3825 9 P 0 ;1
L 3.6825 3.4325 3.6825 3.4325 9 P 0 ;1
L 3.6825 3.4825 3.6825 3.4825 9 P 0 ;1
L 3.6825 3.5325 3.6825 3.5325 9 P 0 ;1
L 3.6825 3.5825 3.6825 3.5825 9 P 0 ;1
L 3.6825 3.6325 3.6825 3.6325 9 P 0 ;1
L 3.6825 3.6825 3.6825 3.6825 9 P 0 ;1
L 3.6825 3.7325 3.6825 3.7325 9 P 0 ;1
L 3.6825 3.7825 3.6825 3.7825 9 P 0 ;1
L 3.6825 3.8325 3.6825 3.8325 9 P 0 ;1
L 3.6825 3.8825 3.6825 3.8825 9 P 0 ;1
L 3.6825 3.9325 3.6825 3.9325 9 P 0 ;1
L 3.6825 3.9825 3.6825 3.9825 9 P 0 ;1
L 3.6825 4.0325 3.6825 4.0325 9 P 0 ;1
L 3.6825 4.2825 3.6825 4.2825 9 P 0 ;1
L 3.6825 4.3325 3.6825 4.3325 9 P 0 ;1
L 3.6825 4.7325 3.6825 4.7325 9 P 0 ;1
L 3.6825 4.8325 3.6825 4.8325 9 P 0 ;1
L 3.6825 4.8825 3.6825 4.8825 9 P 0 ;1
L 3.6825 4.9325 3.6825 4.9325 9 P 0 ;1
L 3.6825 4.9825 3.6825 4.9825 9 P 0 ;1
L 3.6825 5.1825 3.6825 5.1825 9 P 0 ;1
L 3.6825 5.2325 3.6825 5.2325 9 P 0 ;1
L 3.6825 5.2825 3.6825 5.2825 9 P 0 ;1
L 3.6825 5.3325 3.6825 5.3325 9 P 0 ;1
L 3.6825 5.3825 3.6825 5.3825 9 P 0 ;1
L 3.6825 5.4325 3.6825 5.4325 9 P 0 ;1
L 3.6825 5.4825 3.6825 5.4825 9 P 0 ;1
L 3.6825 5.5325 3.6825 5.5325 9 P 0 ;1
L 3.6825 5.5825 3.6825 5.5825 9 P 0 ;1
L 3.6825 5.6325 3.6825 5.6325 9 P 0 ;1
L 3.6825 5.8325 3.6825 5.8325 9 P 0 ;1
L 3.6825 5.8825 3.6825 5.8825 9 P 0 ;1
L 3.7325 0.1325 3.7325 0.1325 9 P 0 ;1
L 3.7325 0.4325 3.7325 0.4325 9 P 0 ;1
L 3.7325 0.4825 3.7325 0.4825 9 P 0 ;1
L 3.7325 0.5325 3.7325 0.5325 9 P 0 ;1
L 3.7325 0.8825 3.7325 0.8825 9 P 0 ;1
L 3.7325 0.9325 3.7325 0.9325 9 P 0 ;1
L 3.7325 0.9825 3.7325 0.9825 9 P 0 ;1
L 3.7325 1.4825 3.7325 1.4825 9 P 0 ;1
L 3.7325 1.5325 3.7325 1.5325 9 P 0 ;1
L 3.7325 1.8325 3.7325 1.8325 9 P 0 ;1
L 3.7325 1.8825 3.7325 1.8825 9 P 0 ;1
L 3.7325 1.9325 3.7325 1.9325 9 P 0 ;1
L 3.7325 1.9825 3.7325 1.9825 9 P 0 ;1
L 3.7325 2.0325 3.7325 2.0325 9 P 0 ;1
L 3.7325 2.0825 3.7325 2.0825 9 P 0 ;1
L 3.7325 2.1325 3.7325 2.1325 9 P 0 ;1
L 3.7325 2.1825 3.7325 2.1825 9 P 0 ;1
L 3.7325 2.2325 3.7325 2.2325 9 P 0 ;1
L 3.7325 2.2825 3.7325 2.2825 9 P 0 ;1
L 3.7325 2.3325 3.7325 2.3325 9 P 0 ;1
L 3.7325 2.3825 3.7325 2.3825 9 P 0 ;1
L 3.7325 2.4325 3.7325 2.4325 9 P 0 ;1
L 3.7325 2.4825 3.7325 2.4825 9 P 0 ;1
L 3.7325 2.5325 3.7325 2.5325 9 P 0 ;1
L 3.7325 2.5825 3.7325 2.5825 9 P 0 ;1
L 3.7325 2.6325 3.7325 2.6325 9 P 0 ;1
L 3.7325 2.6825 3.7325 2.6825 9 P 0 ;1
L 3.7325 2.7325 3.7325 2.7325 9 P 0 ;1
L 3.7325 2.7825 3.7325 2.7825 9 P 0 ;1
L 3.7325 2.8325 3.7325 2.8325 9 P 0 ;1
L 3.7325 2.8825 3.7325 2.8825 9 P 0 ;1
L 3.7325 2.9325 3.7325 2.9325 9 P 0 ;1
L 3.7325 2.9825 3.7325 2.9825 9 P 0 ;1
L 3.7325 3.0325 3.7325 3.0325 9 P 0 ;1
L 3.7325 3.0825 3.7325 3.0825 9 P 0 ;1
L 3.7325 3.1325 3.7325 3.1325 9 P 0 ;1
L 3.7325 3.1825 3.7325 3.1825 9 P 0 ;1
L 3.7325 3.2325 3.7325 3.2325 9 P 0 ;1
L 3.7325 3.2825 3.7325 3.2825 9 P 0 ;1
L 3.7325 3.3325 3.7325 3.3325 9 P 0 ;1
L 3.7325 3.3825 3.7325 3.3825 9 P 0 ;1
L 3.7325 3.4325 3.7325 3.4325 9 P 0 ;1
L 3.7325 3.4825 3.7325 3.4825 9 P 0 ;1
L 3.7325 3.5325 3.7325 3.5325 9 P 0 ;1
L 3.7325 3.5825 3.7325 3.5825 9 P 0 ;1
L 3.7325 3.6325 3.7325 3.6325 9 P 0 ;1
L 3.7325 3.6825 3.7325 3.6825 9 P 0 ;1
L 3.7325 3.7325 3.7325 3.7325 9 P 0 ;1
L 3.7325 3.7825 3.7325 3.7825 9 P 0 ;1
L 3.7325 3.8325 3.7325 3.8325 9 P 0 ;1
L 3.7325 3.8825 3.7325 3.8825 9 P 0 ;1
L 3.7325 3.9325 3.7325 3.9325 9 P 0 ;1
L 3.7325 3.9825 3.7325 3.9825 9 P 0 ;1
L 3.7325 4.0325 3.7325 4.0325 9 P 0 ;1
L 3.7325 4.2825 3.7325 4.2825 9 P 0 ;1
L 3.7325 4.3325 3.7325 4.3325 9 P 0 ;1
L 3.7325 4.6825 3.7325 4.6825 9 P 0 ;1
L 3.7325 4.9325 3.7325 4.9325 9 P 0 ;1
L 3.7325 4.9825 3.7325 4.9825 9 P 0 ;1
L 3.7325 5.1825 3.7325 5.1825 9 P 0 ;1
L 3.7325 5.3825 3.7325 5.3825 9 P 0 ;1
L 3.7325 5.4325 3.7325 5.4325 9 P 0 ;1
L 3.7325 5.4825 3.7325 5.4825 9 P 0 ;1
L 3.7325 5.5325 3.7325 5.5325 9 P 0 ;1
L 3.7325 5.5825 3.7325 5.5825 9 P 0 ;1
L 3.7325 5.6325 3.7325 5.6325 9 P 0 ;1
L 3.7325 5.8325 3.7325 5.8325 9 P 0 ;1
L 3.7325 5.8825 3.7325 5.8825 9 P 0 ;1
L 3.7825 0.1325 3.7825 0.1325 9 P 0 ;1
L 3.7825 0.4325 3.7825 0.4325 9 P 0 ;1
L 3.7825 0.4825 3.7825 0.4825 9 P 0 ;1
L 3.7825 0.5325 3.7825 0.5325 9 P 0 ;1
L 3.7825 0.8325 3.7825 0.8325 9 P 0 ;1
L 3.7825 0.8825 3.7825 0.8825 9 P 0 ;1
L 3.7825 0.9325 3.7825 0.9325 9 P 0 ;1
L 3.7825 0.9825 3.7825 0.9825 9 P 0 ;1
L 3.7825 1.4825 3.7825 1.4825 9 P 0 ;1
L 3.7825 1.5325 3.7825 1.5325 9 P 0 ;1
L 3.7825 1.5825 3.7825 1.5825 9 P 0 ;1
L 3.7825 1.8325 3.7825 1.8325 9 P 0 ;1
L 3.7825 1.8825 3.7825 1.8825 9 P 0 ;1
L 3.7825 1.9325 3.7825 1.9325 9 P 0 ;1
L 3.7825 1.9825 3.7825 1.9825 9 P 0 ;1
L 3.7825 2.0325 3.7825 2.0325 9 P 0 ;1
L 3.7825 2.0825 3.7825 2.0825 9 P 0 ;1
L 3.7825 2.1325 3.7825 2.1325 9 P 0 ;1
L 3.7825 2.1825 3.7825 2.1825 9 P 0 ;1
L 3.7825 2.2325 3.7825 2.2325 9 P 0 ;1
L 3.7825 2.2825 3.7825 2.2825 9 P 0 ;1
L 3.7825 2.3325 3.7825 2.3325 9 P 0 ;1
L 3.7825 2.3825 3.7825 2.3825 9 P 0 ;1
L 3.7825 2.4325 3.7825 2.4325 9 P 0 ;1
L 3.7825 2.4825 3.7825 2.4825 9 P 0 ;1
L 3.7825 2.5325 3.7825 2.5325 9 P 0 ;1
L 3.7825 2.5825 3.7825 2.5825 9 P 0 ;1
L 3.7825 2.6325 3.7825 2.6325 9 P 0 ;1
L 3.7825 2.6825 3.7825 2.6825 9 P 0 ;1
L 3.7825 2.7325 3.7825 2.7325 9 P 0 ;1
L 3.7825 2.7825 3.7825 2.7825 9 P 0 ;1
L 3.7825 2.8325 3.7825 2.8325 9 P 0 ;1
L 3.7825 2.8825 3.7825 2.8825 9 P 0 ;1
L 3.7825 2.9325 3.7825 2.9325 9 P 0 ;1
L 3.7825 2.9825 3.7825 2.9825 9 P 0 ;1
L 3.7825 3.0325 3.7825 3.0325 9 P 0 ;1
L 3.7825 3.0825 3.7825 3.0825 9 P 0 ;1
L 3.7825 3.1325 3.7825 3.1325 9 P 0 ;1
L 3.7825 3.1825 3.7825 3.1825 9 P 0 ;1
L 3.7825 3.2325 3.7825 3.2325 9 P 0 ;1
L 3.7825 3.2825 3.7825 3.2825 9 P 0 ;1
L 3.7825 3.3325 3.7825 3.3325 9 P 0 ;1
L 3.7825 3.3825 3.7825 3.3825 9 P 0 ;1
L 3.7825 3.4325 3.7825 3.4325 9 P 0 ;1
L 3.7825 3.4825 3.7825 3.4825 9 P 0 ;1
L 3.7825 3.5325 3.7825 3.5325 9 P 0 ;1
L 3.7825 3.5825 3.7825 3.5825 9 P 0 ;1
L 3.7825 3.6325 3.7825 3.6325 9 P 0 ;1
L 3.7825 3.6825 3.7825 3.6825 9 P 0 ;1
L 3.7825 3.7325 3.7825 3.7325 9 P 0 ;1
L 3.7825 3.7825 3.7825 3.7825 9 P 0 ;1
L 3.7825 3.8325 3.7825 3.8325 9 P 0 ;1
L 3.7825 3.8825 3.7825 3.8825 9 P 0 ;1
L 3.7825 3.9325 3.7825 3.9325 9 P 0 ;1
L 3.7825 3.9825 3.7825 3.9825 9 P 0 ;1
L 3.7825 4.0325 3.7825 4.0325 9 P 0 ;1
L 3.7825 4.2825 3.7825 4.2825 9 P 0 ;1
L 3.7825 4.3325 3.7825 4.3325 9 P 0 ;1
L 3.7825 4.3825 3.7825 4.3825 9 P 0 ;1
L 3.7825 4.6825 3.7825 4.6825 9 P 0 ;1
L 3.7825 4.9825 3.7825 4.9825 9 P 0 ;1
L 3.7825 5.1825 3.7825 5.1825 9 P 0 ;1
L 3.7825 5.3825 3.7825 5.3825 9 P 0 ;1
L 3.7825 5.4325 3.7825 5.4325 9 P 0 ;1
L 3.7825 5.4825 3.7825 5.4825 9 P 0 ;1
L 3.7825 5.5325 3.7825 5.5325 9 P 0 ;1
L 3.7825 5.5825 3.7825 5.5825 9 P 0 ;1
L 3.7825 5.6325 3.7825 5.6325 9 P 0 ;1
L 3.7825 5.6825 3.7825 5.6825 9 P 0 ;1
L 3.7825 5.7325 3.7825 5.7325 9 P 0 ;1
L 3.8325 0.1325 3.8325 0.1325 9 P 0 ;1
L 3.8325 0.1825 3.8325 0.1825 9 P 0 ;1
L 3.8325 0.2825 3.8325 0.2825 9 P 0 ;1
L 3.8325 0.3825 3.8325 0.3825 9 P 0 ;1
L 3.8325 0.4325 3.8325 0.4325 9 P 0 ;1
L 3.8325 0.4825 3.8325 0.4825 9 P 0 ;1
L 3.8325 0.5325 3.8325 0.5325 9 P 0 ;1
L 3.8325 0.8825 3.8325 0.8825 9 P 0 ;1
L 3.8325 0.9325 3.8325 0.9325 9 P 0 ;1
L 3.8325 0.9825 3.8325 0.9825 9 P 0 ;1
L 3.8325 1.4825 3.8325 1.4825 9 P 0 ;1
L 3.8325 1.5325 3.8325 1.5325 9 P 0 ;1
L 3.8325 1.5825 3.8325 1.5825 9 P 0 ;1
L 3.8325 1.8825 3.8325 1.8825 9 P 0 ;1
L 3.8325 1.9325 3.8325 1.9325 9 P 0 ;1
L 3.8325 1.9825 3.8325 1.9825 9 P 0 ;1
L 3.8325 2.0325 3.8325 2.0325 9 P 0 ;1
L 3.8325 2.0825 3.8325 2.0825 9 P 0 ;1
L 3.8325 2.1325 3.8325 2.1325 9 P 0 ;1
L 3.8325 2.1825 3.8325 2.1825 9 P 0 ;1
L 3.8325 2.2325 3.8325 2.2325 9 P 0 ;1
L 3.8325 2.2825 3.8325 2.2825 9 P 0 ;1
L 3.8325 2.3325 3.8325 2.3325 9 P 0 ;1
L 3.8325 2.3825 3.8325 2.3825 9 P 0 ;1
L 3.8325 2.4325 3.8325 2.4325 9 P 0 ;1
L 3.8325 2.4825 3.8325 2.4825 9 P 0 ;1
L 3.8325 2.5325 3.8325 2.5325 9 P 0 ;1
L 3.8325 2.7325 3.8325 2.7325 9 P 0 ;1
L 3.8325 2.7825 3.8325 2.7825 9 P 0 ;1
L 3.8325 2.8325 3.8325 2.8325 9 P 0 ;1
L 3.8325 2.8825 3.8325 2.8825 9 P 0 ;1
L 3.8325 2.9325 3.8325 2.9325 9 P 0 ;1
L 3.8325 2.9825 3.8325 2.9825 9 P 0 ;1
L 3.8325 3.0325 3.8325 3.0325 9 P 0 ;1
L 3.8325 3.0825 3.8325 3.0825 9 P 0 ;1
L 3.8325 3.1325 3.8325 3.1325 9 P 0 ;1
L 3.8325 3.1825 3.8325 3.1825 9 P 0 ;1
L 3.8325 3.2325 3.8325 3.2325 9 P 0 ;1
L 3.8325 3.2825 3.8325 3.2825 9 P 0 ;1
L 3.8325 3.3325 3.8325 3.3325 9 P 0 ;1
L 3.8325 3.3825 3.8325 3.3825 9 P 0 ;1
L 3.8325 3.4325 3.8325 3.4325 9 P 0 ;1
L 3.8325 3.4825 3.8325 3.4825 9 P 0 ;1
L 3.8325 3.5325 3.8325 3.5325 9 P 0 ;1
L 3.8325 3.5825 3.8325 3.5825 9 P 0 ;1
L 3.8325 3.6325 3.8325 3.6325 9 P 0 ;1
L 3.8325 3.6825 3.8325 3.6825 9 P 0 ;1
L 3.8325 3.7325 3.8325 3.7325 9 P 0 ;1
L 3.8325 3.7825 3.8325 3.7825 9 P 0 ;1
L 3.8325 3.8325 3.8325 3.8325 9 P 0 ;1
L 3.8325 3.8825 3.8325 3.8825 9 P 0 ;1
L 3.8325 3.9325 3.8325 3.9325 9 P 0 ;1
L 3.8325 3.9825 3.8325 3.9825 9 P 0 ;1
L 3.8325 4.0325 3.8325 4.0325 9 P 0 ;1
L 3.8325 4.2825 3.8325 4.2825 9 P 0 ;1
L 3.8325 4.3325 3.8325 4.3325 9 P 0 ;1
L 3.8325 4.3825 3.8325 4.3825 9 P 0 ;1
L 3.8325 4.4325 3.8325 4.4325 9 P 0 ;1
L 3.8325 4.9325 3.8325 4.9325 9 P 0 ;1
L 3.8325 4.9825 3.8325 4.9825 9 P 0 ;1
L 3.8325 5.0325 3.8325 5.0325 9 P 0 ;1
L 3.8325 5.2325 3.8325 5.2325 9 P 0 ;1
L 3.8325 5.3825 3.8325 5.3825 9 P 0 ;1
L 3.8325 5.4325 3.8325 5.4325 9 P 0 ;1
L 3.8325 5.4825 3.8325 5.4825 9 P 0 ;1
L 3.8325 5.5325 3.8325 5.5325 9 P 0 ;1
L 3.8325 5.5825 3.8325 5.5825 9 P 0 ;1
L 3.8325 5.6325 3.8325 5.6325 9 P 0 ;1
L 3.8325 5.6825 3.8325 5.6825 9 P 0 ;1
L 3.8325 5.7325 3.8325 5.7325 9 P 0 ;1
L 3.8825 0.1325 3.8825 0.1325 9 P 0 ;1
L 3.8825 0.1825 3.8825 0.1825 9 P 0 ;1
L 3.8825 0.2325 3.8825 0.2325 9 P 0 ;1
L 3.8825 0.2825 3.8825 0.2825 9 P 0 ;1
L 3.8825 0.3325 3.8825 0.3325 9 P 0 ;1
L 3.8825 0.3825 3.8825 0.3825 9 P 0 ;1
L 3.8825 0.4325 3.8825 0.4325 9 P 0 ;1
L 3.8825 0.4825 3.8825 0.4825 9 P 0 ;1
L 3.8825 0.5325 3.8825 0.5325 9 P 0 ;1
L 3.8825 0.5825 3.8825 0.5825 9 P 0 ;1
L 3.8825 0.8825 3.8825 0.8825 9 P 0 ;1
L 3.8825 0.9325 3.8825 0.9325 9 P 0 ;1
L 3.8825 0.9825 3.8825 0.9825 9 P 0 ;1
L 3.8825 1.0325 3.8825 1.0325 9 P 0 ;1
L 3.8825 1.4825 3.8825 1.4825 9 P 0 ;1
L 3.8825 1.5325 3.8825 1.5325 9 P 0 ;1
L 3.8825 1.5825 3.8825 1.5825 9 P 0 ;1
L 3.8825 1.8825 3.8825 1.8825 9 P 0 ;1
L 3.8825 1.9325 3.8825 1.9325 9 P 0 ;1
L 3.8825 1.9825 3.8825 1.9825 9 P 0 ;1
L 3.8825 2.0325 3.8825 2.0325 9 P 0 ;1
L 3.8825 2.0825 3.8825 2.0825 9 P 0 ;1
L 3.8825 2.1325 3.8825 2.1325 9 P 0 ;1
L 3.8825 2.1825 3.8825 2.1825 9 P 0 ;1
L 3.8825 2.2325 3.8825 2.2325 9 P 0 ;1
L 3.8825 2.2825 3.8825 2.2825 9 P 0 ;1
L 3.8825 2.3325 3.8825 2.3325 9 P 0 ;1
L 3.8825 2.3825 3.8825 2.3825 9 P 0 ;1
L 3.8825 2.4325 3.8825 2.4325 9 P 0 ;1
L 3.8825 2.4825 3.8825 2.4825 9 P 0 ;1
L 3.8825 2.5325 3.8825 2.5325 9 P 0 ;1
L 3.8825 2.7325 3.8825 2.7325 9 P 0 ;1
L 3.8825 2.7825 3.8825 2.7825 9 P 0 ;1
L 3.8825 2.8325 3.8825 2.8325 9 P 0 ;1
L 3.8825 2.8825 3.8825 2.8825 9 P 0 ;1
L 3.8825 2.9325 3.8825 2.9325 9 P 0 ;1
L 3.8825 2.9825 3.8825 2.9825 9 P 0 ;1
L 3.8825 3.0325 3.8825 3.0325 9 P 0 ;1
L 3.8825 3.0825 3.8825 3.0825 9 P 0 ;1
L 3.8825 3.1325 3.8825 3.1325 9 P 0 ;1
L 3.8825 3.1825 3.8825 3.1825 9 P 0 ;1
L 3.8825 3.2325 3.8825 3.2325 9 P 0 ;1
L 3.8825 3.2825 3.8825 3.2825 9 P 0 ;1
L 3.8825 3.3325 3.8825 3.3325 9 P 0 ;1
L 3.8825 3.3825 3.8825 3.3825 9 P 0 ;1
L 3.8825 3.4325 3.8825 3.4325 9 P 0 ;1
L 3.8825 3.4825 3.8825 3.4825 9 P 0 ;1
L 3.8825 3.5325 3.8825 3.5325 9 P 0 ;1
L 3.8825 3.5825 3.8825 3.5825 9 P 0 ;1
L 3.8825 3.6325 3.8825 3.6325 9 P 0 ;1
L 3.8825 3.6825 3.8825 3.6825 9 P 0 ;1
L 3.8825 3.7325 3.8825 3.7325 9 P 0 ;1
L 3.8825 3.7825 3.8825 3.7825 9 P 0 ;1
L 3.8825 3.8325 3.8825 3.8325 9 P 0 ;1
L 3.8825 3.8825 3.8825 3.8825 9 P 0 ;1
L 3.8825 3.9325 3.8825 3.9325 9 P 0 ;1
L 3.8825 3.9825 3.8825 3.9825 9 P 0 ;1
L 3.8825 4.0325 3.8825 4.0325 9 P 0 ;1
L 3.8825 4.2825 3.8825 4.2825 9 P 0 ;1
L 3.8825 4.3325 3.8825 4.3325 9 P 0 ;1
L 3.8825 4.8825 3.8825 4.8825 9 P 0 ;1
L 3.8825 4.9325 3.8825 4.9325 9 P 0 ;1
L 3.8825 4.9825 3.8825 4.9825 9 P 0 ;1
L 3.8825 5.0325 3.8825 5.0325 9 P 0 ;1
L 3.8825 5.2325 3.8825 5.2325 9 P 0 ;1
L 3.8825 5.2825 3.8825 5.2825 9 P 0 ;1
L 3.8825 5.6325 3.8825 5.6325 9 P 0 ;1
L 3.8825 5.6825 3.8825 5.6825 9 P 0 ;1
L 3.8825 5.7325 3.8825 5.7325 9 P 0 ;1
L 3.8825 5.8825 3.8825 5.8825 9 P 0 ;1
L 3.9325 0.1325 3.9325 0.1325 9 P 0 ;1
L 3.9325 0.1825 3.9325 0.1825 9 P 0 ;1
L 3.9325 0.2325 3.9325 0.2325 9 P 0 ;1
L 3.9325 0.2825 3.9325 0.2825 9 P 0 ;1
L 3.9325 0.3325 3.9325 0.3325 9 P 0 ;1
L 3.9325 0.3825 3.9325 0.3825 9 P 0 ;1
L 3.9325 0.4325 3.9325 0.4325 9 P 0 ;1
L 3.9325 0.4825 3.9325 0.4825 9 P 0 ;1
L 3.9325 0.5325 3.9325 0.5325 9 P 0 ;1
L 3.9325 0.5825 3.9325 0.5825 9 P 0 ;1
L 3.9325 0.8325 3.9325 0.8325 9 P 0 ;1
L 3.9325 0.8825 3.9325 0.8825 9 P 0 ;1
L 3.9325 0.9325 3.9325 0.9325 9 P 0 ;1
L 3.9325 0.9825 3.9325 0.9825 9 P 0 ;1
L 3.9325 1.0325 3.9325 1.0325 9 P 0 ;1
L 3.9325 1.5325 3.9325 1.5325 9 P 0 ;1
L 3.9325 1.5825 3.9325 1.5825 9 P 0 ;1
L 3.9325 1.8825 3.9325 1.8825 9 P 0 ;1
L 3.9325 1.9325 3.9325 1.9325 9 P 0 ;1
L 3.9325 1.9825 3.9325 1.9825 9 P 0 ;1
L 3.9325 2.0325 3.9325 2.0325 9 P 0 ;1
L 3.9325 2.0825 3.9325 2.0825 9 P 0 ;1
L 3.9325 2.1325 3.9325 2.1325 9 P 0 ;1
L 3.9325 2.1825 3.9325 2.1825 9 P 0 ;1
L 3.9325 2.2325 3.9325 2.2325 9 P 0 ;1
L 3.9325 2.2825 3.9325 2.2825 9 P 0 ;1
L 3.9325 2.3325 3.9325 2.3325 9 P 0 ;1
L 3.9325 2.3825 3.9325 2.3825 9 P 0 ;1
L 3.9325 2.4325 3.9325 2.4325 9 P 0 ;1
L 3.9325 2.4825 3.9325 2.4825 9 P 0 ;1
L 3.9325 2.5325 3.9325 2.5325 9 P 0 ;1
L 3.9325 2.5825 3.9325 2.5825 9 P 0 ;1
L 3.9325 2.7325 3.9325 2.7325 9 P 0 ;1
L 3.9325 2.7825 3.9325 2.7825 9 P 0 ;1
L 3.9325 2.8325 3.9325 2.8325 9 P 0 ;1
L 3.9325 2.8825 3.9325 2.8825 9 P 0 ;1
L 3.9325 2.9325 3.9325 2.9325 9 P 0 ;1
L 3.9325 2.9825 3.9325 2.9825 9 P 0 ;1
L 3.9325 3.0325 3.9325 3.0325 9 P 0 ;1
L 3.9325 3.0825 3.9325 3.0825 9 P 0 ;1
L 3.9325 3.1325 3.9325 3.1325 9 P 0 ;1
L 3.9325 3.1825 3.9325 3.1825 9 P 0 ;1
L 3.9325 3.2325 3.9325 3.2325 9 P 0 ;1
L 3.9325 3.2825 3.9325 3.2825 9 P 0 ;1
L 3.9325 3.3325 3.9325 3.3325 9 P 0 ;1
L 3.9325 3.3825 3.9325 3.3825 9 P 0 ;1
L 3.9325 3.4325 3.9325 3.4325 9 P 0 ;1
L 3.9325 3.4825 3.9325 3.4825 9 P 0 ;1
L 3.9325 3.5325 3.9325 3.5325 9 P 0 ;1
L 3.9325 3.5825 3.9325 3.5825 9 P 0 ;1
L 3.9325 3.6325 3.9325 3.6325 9 P 0 ;1
L 3.9325 3.6825 3.9325 3.6825 9 P 0 ;1
L 3.9325 3.7325 3.9325 3.7325 9 P 0 ;1
L 3.9325 3.7825 3.9325 3.7825 9 P 0 ;1
L 3.9325 3.8325 3.9325 3.8325 9 P 0 ;1
L 3.9325 3.8825 3.9325 3.8825 9 P 0 ;1
L 3.9325 3.9325 3.9325 3.9325 9 P 0 ;1
L 3.9325 3.9825 3.9325 3.9825 9 P 0 ;1
L 3.9325 4.2825 3.9325 4.2825 9 P 0 ;1
L 3.9325 4.3325 3.9325 4.3325 9 P 0 ;1
L 3.9325 4.9825 3.9325 4.9825 9 P 0 ;1
L 3.9325 5.0325 3.9325 5.0325 9 P 0 ;1
L 3.9325 5.1825 3.9325 5.1825 9 P 0 ;1
L 3.9325 5.2325 3.9325 5.2325 9 P 0 ;1
L 3.9325 5.6325 3.9325 5.6325 9 P 0 ;1
L 3.9325 5.6825 3.9325 5.6825 9 P 0 ;1
L 3.9325 5.7325 3.9325 5.7325 9 P 0 ;1
L 3.9325 5.7825 3.9325 5.7825 9 P 0 ;1
L 3.9325 5.8325 3.9325 5.8325 9 P 0 ;1
L 3.9325 5.8825 3.9325 5.8825 9 P 0 ;1
L 3.9825 0.1325 3.9825 0.1325 9 P 0 ;1
L 3.9825 0.1825 3.9825 0.1825 9 P 0 ;1
L 3.9825 0.2325 3.9825 0.2325 9 P 0 ;1
L 3.9825 0.2825 3.9825 0.2825 9 P 0 ;1
L 3.9825 0.3325 3.9825 0.3325 9 P 0 ;1
L 3.9825 0.3825 3.9825 0.3825 9 P 0 ;1
L 3.9825 0.4325 3.9825 0.4325 9 P 0 ;1
L 3.9825 0.4825 3.9825 0.4825 9 P 0 ;1
L 3.9825 0.5325 3.9825 0.5325 9 P 0 ;1
L 3.9825 0.5825 3.9825 0.5825 9 P 0 ;1
L 3.9825 0.7825 3.9825 0.7825 9 P 0 ;1
L 3.9825 0.8325 3.9825 0.8325 9 P 0 ;1
L 3.9825 0.8825 3.9825 0.8825 9 P 0 ;1
L 3.9825 0.9325 3.9825 0.9325 9 P 0 ;1
L 3.9825 0.9825 3.9825 0.9825 9 P 0 ;1
L 3.9825 1.0325 3.9825 1.0325 9 P 0 ;1
L 3.9825 1.5325 3.9825 1.5325 9 P 0 ;1
L 3.9825 1.5825 3.9825 1.5825 9 P 0 ;1
L 3.9825 1.8825 3.9825 1.8825 9 P 0 ;1
L 3.9825 1.9325 3.9825 1.9325 9 P 0 ;1
L 3.9825 1.9825 3.9825 1.9825 9 P 0 ;1
L 3.9825 2.0325 3.9825 2.0325 9 P 0 ;1
L 3.9825 2.0825 3.9825 2.0825 9 P 0 ;1
L 3.9825 2.1325 3.9825 2.1325 9 P 0 ;1
L 3.9825 2.1825 3.9825 2.1825 9 P 0 ;1
L 3.9825 2.2325 3.9825 2.2325 9 P 0 ;1
L 3.9825 2.2825 3.9825 2.2825 9 P 0 ;1
L 3.9825 2.3325 3.9825 2.3325 9 P 0 ;1
L 3.9825 2.3825 3.9825 2.3825 9 P 0 ;1
L 3.9825 2.4325 3.9825 2.4325 9 P 0 ;1
L 3.9825 2.4825 3.9825 2.4825 9 P 0 ;1
L 3.9825 2.6825 3.9825 2.6825 9 P 0 ;1
L 3.9825 2.7325 3.9825 2.7325 9 P 0 ;1
L 3.9825 2.7825 3.9825 2.7825 9 P 0 ;1
L 3.9825 2.8325 3.9825 2.8325 9 P 0 ;1
L 3.9825 2.8825 3.9825 2.8825 9 P 0 ;1
L 3.9825 2.9325 3.9825 2.9325 9 P 0 ;1
L 3.9825 2.9825 3.9825 2.9825 9 P 0 ;1
L 3.9825 3.0325 3.9825 3.0325 9 P 0 ;1
L 3.9825 3.0825 3.9825 3.0825 9 P 0 ;1
L 3.9825 3.1325 3.9825 3.1325 9 P 0 ;1
L 3.9825 3.1825 3.9825 3.1825 9 P 0 ;1
L 3.9825 3.2325 3.9825 3.2325 9 P 0 ;1
L 3.9825 3.2825 3.9825 3.2825 9 P 0 ;1
L 3.9825 3.3325 3.9825 3.3325 9 P 0 ;1
L 3.9825 3.3825 3.9825 3.3825 9 P 0 ;1
L 3.9825 3.4325 3.9825 3.4325 9 P 0 ;1
L 3.9825 3.4825 3.9825 3.4825 9 P 0 ;1
L 3.9825 3.5325 3.9825 3.5325 9 P 0 ;1
L 3.9825 3.5825 3.9825 3.5825 9 P 0 ;1
L 3.9825 3.6325 3.9825 3.6325 9 P 0 ;1
L 3.9825 3.6825 3.9825 3.6825 9 P 0 ;1
L 3.9825 3.7325 3.9825 3.7325 9 P 0 ;1
L 3.9825 3.7825 3.9825 3.7825 9 P 0 ;1
L 3.9825 3.8325 3.9825 3.8325 9 P 0 ;1
L 3.9825 3.8825 3.9825 3.8825 9 P 0 ;1
L 3.9825 3.9325 3.9825 3.9325 9 P 0 ;1
L 3.9825 3.9825 3.9825 3.9825 9 P 0 ;1
L 3.9825 4.2325 3.9825 4.2325 9 P 0 ;1
L 3.9825 4.2825 3.9825 4.2825 9 P 0 ;1
L 3.9825 4.9825 3.9825 4.9825 9 P 0 ;1
L 3.9825 5.0325 3.9825 5.0325 9 P 0 ;1
L 3.9825 5.0825 3.9825 5.0825 9 P 0 ;1
L 3.9825 5.1325 3.9825 5.1325 9 P 0 ;1
L 3.9825 5.1825 3.9825 5.1825 9 P 0 ;1
L 3.9825 5.5825 3.9825 5.5825 9 P 0 ;1
L 3.9825 5.6325 3.9825 5.6325 9 P 0 ;1
L 3.9825 5.6825 3.9825 5.6825 9 P 0 ;1
L 3.9825 5.7325 3.9825 5.7325 9 P 0 ;1
L 3.9825 5.7825 3.9825 5.7825 9 P 0 ;1
L 3.9825 5.8325 3.9825 5.8325 9 P 0 ;1
L 3.9825 5.8825 3.9825 5.8825 9 P 0 ;1
L 4.0325 0.1325 4.0325 0.1325 9 P 0 ;1
L 4.0325 0.1825 4.0325 0.1825 9 P 0 ;1
L 4.0325 0.2325 4.0325 0.2325 9 P 0 ;1
L 4.0325 0.2825 4.0325 0.2825 9 P 0 ;1
L 4.0325 0.3325 4.0325 0.3325 9 P 0 ;1
L 4.0325 0.3825 4.0325 0.3825 9 P 0 ;1
L 4.0325 0.4325 4.0325 0.4325 9 P 0 ;1
L 4.0325 0.4825 4.0325 0.4825 9 P 0 ;1
L 4.0325 0.5325 4.0325 0.5325 9 P 0 ;1
L 4.0325 0.5825 4.0325 0.5825 9 P 0 ;1
L 4.0325 0.7825 4.0325 0.7825 9 P 0 ;1
L 4.0325 0.8325 4.0325 0.8325 9 P 0 ;1
L 4.0325 0.8825 4.0325 0.8825 9 P 0 ;1
L 4.0325 0.9325 4.0325 0.9325 9 P 0 ;1
L 4.0325 0.9825 4.0325 0.9825 9 P 0 ;1
L 4.0325 1.0325 4.0325 1.0325 9 P 0 ;1
L 4.0325 1.5325 4.0325 1.5325 9 P 0 ;1
L 4.0325 1.5825 4.0325 1.5825 9 P 0 ;1
L 4.0325 1.6325 4.0325 1.6325 9 P 0 ;1
L 4.0325 1.8825 4.0325 1.8825 9 P 0 ;1
L 4.0325 1.9325 4.0325 1.9325 9 P 0 ;1
L 4.0325 1.9825 4.0325 1.9825 9 P 0 ;1
L 4.0325 2.0325 4.0325 2.0325 9 P 0 ;1
L 4.0325 2.0825 4.0325 2.0825 9 P 0 ;1
L 4.0325 2.1325 4.0325 2.1325 9 P 0 ;1
L 4.0325 2.1825 4.0325 2.1825 9 P 0 ;1
L 4.0325 2.2325 4.0325 2.2325 9 P 0 ;1
L 4.0325 2.2825 4.0325 2.2825 9 P 0 ;1
L 4.0325 2.3325 4.0325 2.3325 9 P 0 ;1
L 4.0325 2.3825 4.0325 2.3825 9 P 0 ;1
L 4.0325 2.4325 4.0325 2.4325 9 P 0 ;1
L 4.0325 2.6825 4.0325 2.6825 9 P 0 ;1
L 4.0325 2.7325 4.0325 2.7325 9 P 0 ;1
L 4.0325 2.7825 4.0325 2.7825 9 P 0 ;1
L 4.0325 2.8325 4.0325 2.8325 9 P 0 ;1
L 4.0325 2.8825 4.0325 2.8825 9 P 0 ;1
L 4.0325 2.9325 4.0325 2.9325 9 P 0 ;1
L 4.0325 2.9825 4.0325 2.9825 9 P 0 ;1
L 4.0325 3.0325 4.0325 3.0325 9 P 0 ;1
L 4.0325 3.0825 4.0325 3.0825 9 P 0 ;1
L 4.0325 3.1325 4.0325 3.1325 9 P 0 ;1
L 4.0325 3.1825 4.0325 3.1825 9 P 0 ;1
L 4.0325 3.2325 4.0325 3.2325 9 P 0 ;1
L 4.0325 3.2825 4.0325 3.2825 9 P 0 ;1
L 4.0325 3.3325 4.0325 3.3325 9 P 0 ;1
L 4.0325 3.3825 4.0325 3.3825 9 P 0 ;1
L 4.0325 3.4325 4.0325 3.4325 9 P 0 ;1
L 4.0325 3.4825 4.0325 3.4825 9 P 0 ;1
L 4.0325 3.5325 4.0325 3.5325 9 P 0 ;1
L 4.0325 3.5825 4.0325 3.5825 9 P 0 ;1
L 4.0325 3.6325 4.0325 3.6325 9 P 0 ;1
L 4.0325 3.6825 4.0325 3.6825 9 P 0 ;1
L 4.0325 3.7325 4.0325 3.7325 9 P 0 ;1
L 4.0325 3.7825 4.0325 3.7825 9 P 0 ;1
L 4.0325 3.8325 4.0325 3.8325 9 P 0 ;1
L 4.0325 3.8825 4.0325 3.8825 9 P 0 ;1
L 4.0325 3.9325 4.0325 3.9325 9 P 0 ;1
L 4.0325 4.2325 4.0325 4.2325 9 P 0 ;1
L 4.0325 4.5325 4.0325 4.5325 9 P 0 ;1
L 4.0325 5.0325 4.0325 5.0325 9 P 0 ;1
L 4.0325 5.0825 4.0325 5.0825 9 P 0 ;1
L 4.0325 5.1325 4.0325 5.1325 9 P 0 ;1
L 4.0325 5.1825 4.0325 5.1825 9 P 0 ;1
L 4.0325 5.4825 4.0325 5.4825 9 P 0 ;1
L 4.0325 5.5325 4.0325 5.5325 9 P 0 ;1
L 4.0325 5.5825 4.0325 5.5825 9 P 0 ;1
L 4.0325 5.6325 4.0325 5.6325 9 P 0 ;1
L 4.0325 5.6825 4.0325 5.6825 9 P 0 ;1
L 4.0325 5.7325 4.0325 5.7325 9 P 0 ;1
L 4.0325 5.7825 4.0325 5.7825 9 P 0 ;1
L 4.0325 5.8325 4.0325 5.8325 9 P 0 ;1
L 4.0325 5.8825 4.0325 5.8825 9 P 0 ;1
L 4.0825 0.1325 4.0825 0.1325 9 P 0 ;1
L 4.0825 0.1825 4.0825 0.1825 9 P 0 ;1
L 4.0825 0.2325 4.0825 0.2325 9 P 0 ;1
L 4.0825 0.2825 4.0825 0.2825 9 P 0 ;1
L 4.0825 0.3325 4.0825 0.3325 9 P 0 ;1
L 4.0825 0.3825 4.0825 0.3825 9 P 0 ;1
L 4.0825 0.4325 4.0825 0.4325 9 P 0 ;1
L 4.0825 0.4825 4.0825 0.4825 9 P 0 ;1
L 4.0825 0.5325 4.0825 0.5325 9 P 0 ;1
L 4.0825 0.5825 4.0825 0.5825 9 P 0 ;1
L 4.0825 0.7825 4.0825 0.7825 9 P 0 ;1
L 4.0825 0.8325 4.0825 0.8325 9 P 0 ;1
L 4.0825 0.8825 4.0825 0.8825 9 P 0 ;1
L 4.0825 0.9325 4.0825 0.9325 9 P 0 ;1
L 4.0825 0.9825 4.0825 0.9825 9 P 0 ;1
L 4.0825 1.0325 4.0825 1.0325 9 P 0 ;1
L 4.0825 1.5325 4.0825 1.5325 9 P 0 ;1
L 4.0825 1.5825 4.0825 1.5825 9 P 0 ;1
L 4.0825 1.6325 4.0825 1.6325 9 P 0 ;1
L 4.0825 1.8825 4.0825 1.8825 9 P 0 ;1
L 4.0825 1.9325 4.0825 1.9325 9 P 0 ;1
L 4.0825 1.9825 4.0825 1.9825 9 P 0 ;1
L 4.0825 2.0325 4.0825 2.0325 9 P 0 ;1
L 4.0825 2.0825 4.0825 2.0825 9 P 0 ;1
L 4.0825 2.1325 4.0825 2.1325 9 P 0 ;1
L 4.0825 2.1825 4.0825 2.1825 9 P 0 ;1
L 4.0825 2.2325 4.0825 2.2325 9 P 0 ;1
L 4.0825 2.2825 4.0825 2.2825 9 P 0 ;1
L 4.0825 2.3325 4.0825 2.3325 9 P 0 ;1
L 4.0825 2.3825 4.0825 2.3825 9 P 0 ;1
L 4.0825 2.4325 4.0825 2.4325 9 P 0 ;1
L 4.0825 2.8325 4.0825 2.8325 9 P 0 ;1
L 4.0825 2.8825 4.0825 2.8825 9 P 0 ;1
L 4.0825 2.9825 4.0825 2.9825 9 P 0 ;1
L 4.0825 3.0325 4.0825 3.0325 9 P 0 ;1
L 4.0825 3.0825 4.0825 3.0825 9 P 0 ;1
L 4.0825 3.1325 4.0825 3.1325 9 P 0 ;1
L 4.0825 3.1825 4.0825 3.1825 9 P 0 ;1
L 4.0825 3.2325 4.0825 3.2325 9 P 0 ;1
L 4.0825 3.2825 4.0825 3.2825 9 P 0 ;1
L 4.0825 3.3325 4.0825 3.3325 9 P 0 ;1
L 4.0825 3.3825 4.0825 3.3825 9 P 0 ;1
L 4.0825 3.4325 4.0825 3.4325 9 P 0 ;1
L 4.0825 3.4825 4.0825 3.4825 9 P 0 ;1
L 4.0825 3.5325 4.0825 3.5325 9 P 0 ;1
L 4.0825 3.5825 4.0825 3.5825 9 P 0 ;1
L 4.0825 3.6325 4.0825 3.6325 9 P 0 ;1
L 4.0825 3.6825 4.0825 3.6825 9 P 0 ;1
L 4.0825 3.7325 4.0825 3.7325 9 P 0 ;1
L 4.0825 3.7825 4.0825 3.7825 9 P 0 ;1
L 4.0825 3.8325 4.0825 3.8325 9 P 0 ;1
L 4.0825 3.8825 4.0825 3.8825 9 P 0 ;1
L 4.0825 3.9325 4.0825 3.9325 9 P 0 ;1
L 4.0825 4.2325 4.0825 4.2325 9 P 0 ;1
L 4.0825 4.2825 4.0825 4.2825 9 P 0 ;1
L 4.0825 4.4825 4.0825 4.4825 9 P 0 ;1
L 4.0825 4.5325 4.0825 4.5325 9 P 0 ;1
L 4.0825 5.0825 4.0825 5.0825 9 P 0 ;1
L 4.0825 5.1325 4.0825 5.1325 9 P 0 ;1
L 4.0825 5.1825 4.0825 5.1825 9 P 0 ;1
L 4.0825 5.2325 4.0825 5.2325 9 P 0 ;1
L 4.0825 5.2825 4.0825 5.2825 9 P 0 ;1
L 4.0825 5.4825 4.0825 5.4825 9 P 0 ;1
L 4.0825 5.5325 4.0825 5.5325 9 P 0 ;1
L 4.0825 5.5825 4.0825 5.5825 9 P 0 ;1
L 4.0825 5.6325 4.0825 5.6325 9 P 0 ;1
L 4.0825 5.6825 4.0825 5.6825 9 P 0 ;1
L 4.0825 5.7325 4.0825 5.7325 9 P 0 ;1
L 4.0825 5.7825 4.0825 5.7825 9 P 0 ;1
L 4.0825 5.8325 4.0825 5.8325 9 P 0 ;1
L 4.0825 5.8825 4.0825 5.8825 9 P 0 ;1
L 4.1325 0.1325 4.1325 0.1325 9 P 0 ;1
L 4.1325 0.1825 4.1325 0.1825 9 P 0 ;1
L 4.1325 0.2325 4.1325 0.2325 9 P 0 ;1
L 4.1325 0.2825 4.1325 0.2825 9 P 0 ;1
L 4.1325 0.3325 4.1325 0.3325 9 P 0 ;1
L 4.1325 0.3825 4.1325 0.3825 9 P 0 ;1
L 4.1325 0.4325 4.1325 0.4325 9 P 0 ;1
L 4.1325 0.4825 4.1325 0.4825 9 P 0 ;1
L 4.1325 0.5325 4.1325 0.5325 9 P 0 ;1
L 4.1325 0.5825 4.1325 0.5825 9 P 0 ;1
L 4.1325 0.6325 4.1325 0.6325 9 P 0 ;1
L 4.1325 0.8325 4.1325 0.8325 9 P 0 ;1
L 4.1325 0.8825 4.1325 0.8825 9 P 0 ;1
L 4.1325 0.9325 4.1325 0.9325 9 P 0 ;1
L 4.1325 0.9825 4.1325 0.9825 9 P 0 ;1
L 4.1325 1.0325 4.1325 1.0325 9 P 0 ;1
L 4.1325 1.4825 4.1325 1.4825 9 P 0 ;1
L 4.1325 1.5325 4.1325 1.5325 9 P 0 ;1
L 4.1325 1.5825 4.1325 1.5825 9 P 0 ;1
L 4.1325 1.6325 4.1325 1.6325 9 P 0 ;1
L 4.1325 1.9325 4.1325 1.9325 9 P 0 ;1
L 4.1325 1.9825 4.1325 1.9825 9 P 0 ;1
L 4.1325 2.0325 4.1325 2.0325 9 P 0 ;1
L 4.1325 2.0825 4.1325 2.0825 9 P 0 ;1
L 4.1325 2.1325 4.1325 2.1325 9 P 0 ;1
L 4.1325 2.1825 4.1325 2.1825 9 P 0 ;1
L 4.1325 2.2325 4.1325 2.2325 9 P 0 ;1
L 4.1325 2.2825 4.1325 2.2825 9 P 0 ;1
L 4.1325 2.3325 4.1325 2.3325 9 P 0 ;1
L 4.1325 2.3825 4.1325 2.3825 9 P 0 ;1
L 4.1325 2.4325 4.1325 2.4325 9 P 0 ;1
L 4.1325 2.4825 4.1325 2.4825 9 P 0 ;1
L 4.1325 2.8325 4.1325 2.8325 9 P 0 ;1
L 4.1325 3.0325 4.1325 3.0325 9 P 0 ;1
L 4.1325 3.0825 4.1325 3.0825 9 P 0 ;1
L 4.1325 3.1325 4.1325 3.1325 9 P 0 ;1
L 4.1325 3.1825 4.1325 3.1825 9 P 0 ;1
L 4.1325 3.2325 4.1325 3.2325 9 P 0 ;1
L 4.1325 3.2825 4.1325 3.2825 9 P 0 ;1
L 4.1325 3.3325 4.1325 3.3325 9 P 0 ;1
L 4.1325 3.3825 4.1325 3.3825 9 P 0 ;1
L 4.1325 3.4325 4.1325 3.4325 9 P 0 ;1
L 4.1325 3.4825 4.1325 3.4825 9 P 0 ;1
L 4.1325 3.5325 4.1325 3.5325 9 P 0 ;1
L 4.1325 3.5825 4.1325 3.5825 9 P 0 ;1
L 4.1325 3.6325 4.1325 3.6325 9 P 0 ;1
L 4.1325 3.6825 4.1325 3.6825 9 P 0 ;1
L 4.1325 3.7325 4.1325 3.7325 9 P 0 ;1
L 4.1325 3.7825 4.1325 3.7825 9 P 0 ;1
L 4.1325 3.8325 4.1325 3.8325 9 P 0 ;1
L 4.1325 3.8825 4.1325 3.8825 9 P 0 ;1
L 4.1325 4.2325 4.1325 4.2325 9 P 0 ;1
L 4.1325 4.2825 4.1325 4.2825 9 P 0 ;1
L 4.1325 4.3325 4.1325 4.3325 9 P 0 ;1
L 4.1325 4.3825 4.1325 4.3825 9 P 0 ;1
L 4.1325 4.4325 4.1325 4.4325 9 P 0 ;1
L 4.1325 4.4825 4.1325 4.4825 9 P 0 ;1
L 4.1325 4.5325 4.1325 4.5325 9 P 0 ;1
L 4.1325 5.0825 4.1325 5.0825 9 P 0 ;1
L 4.1325 5.1325 4.1325 5.1325 9 P 0 ;1
L 4.1325 5.1825 4.1325 5.1825 9 P 0 ;1
L 4.1325 5.2325 4.1325 5.2325 9 P 0 ;1
L 4.1325 5.2825 4.1325 5.2825 9 P 0 ;1
L 4.1325 5.3325 4.1325 5.3325 9 P 0 ;1
L 4.1325 5.4325 4.1325 5.4325 9 P 0 ;1
L 4.1325 5.4825 4.1325 5.4825 9 P 0 ;1
L 4.1325 5.5325 4.1325 5.5325 9 P 0 ;1
L 4.1325 5.5825 4.1325 5.5825 9 P 0 ;1
L 4.1325 5.6325 4.1325 5.6325 9 P 0 ;1
L 4.1325 5.6825 4.1325 5.6825 9 P 0 ;1
L 4.1325 5.7325 4.1325 5.7325 9 P 0 ;1
L 4.1325 5.7825 4.1325 5.7825 9 P 0 ;1
L 4.1325 5.8325 4.1325 5.8325 9 P 0 ;1
L 4.1325 5.8825 4.1325 5.8825 9 P 0 ;1
L 4.1825 0.1325 4.1825 0.1325 9 P 0 ;1
L 4.1825 0.1825 4.1825 0.1825 9 P 0 ;1
L 4.1825 0.2325 4.1825 0.2325 9 P 0 ;1
L 4.1825 0.2825 4.1825 0.2825 9 P 0 ;1
L 4.1825 0.3325 4.1825 0.3325 9 P 0 ;1
L 4.1825 0.3825 4.1825 0.3825 9 P 0 ;1
L 4.1825 0.4325 4.1825 0.4325 9 P 0 ;1
L 4.1825 0.4825 4.1825 0.4825 9 P 0 ;1
L 4.1825 0.5325 4.1825 0.5325 9 P 0 ;1
L 4.1825 0.5825 4.1825 0.5825 9 P 0 ;1
L 4.1825 0.6325 4.1825 0.6325 9 P 0 ;1
L 4.1825 0.8325 4.1825 0.8325 9 P 0 ;1
L 4.1825 0.8825 4.1825 0.8825 9 P 0 ;1
L 4.1825 0.9325 4.1825 0.9325 9 P 0 ;1
L 4.1825 0.9825 4.1825 0.9825 9 P 0 ;1
L 4.1825 1.4825 4.1825 1.4825 9 P 0 ;1
L 4.1825 1.5325 4.1825 1.5325 9 P 0 ;1
L 4.1825 1.5825 4.1825 1.5825 9 P 0 ;1
L 4.1825 1.6325 4.1825 1.6325 9 P 0 ;1
L 4.1825 1.9325 4.1825 1.9325 9 P 0 ;1
L 4.1825 1.9825 4.1825 1.9825 9 P 0 ;1
L 4.1825 2.0325 4.1825 2.0325 9 P 0 ;1
L 4.1825 2.0825 4.1825 2.0825 9 P 0 ;1
L 4.1825 2.1325 4.1825 2.1325 9 P 0 ;1
L 4.1825 2.1825 4.1825 2.1825 9 P 0 ;1
L 4.1825 2.2325 4.1825 2.2325 9 P 0 ;1
L 4.1825 2.2825 4.1825 2.2825 9 P 0 ;1
L 4.1825 2.3325 4.1825 2.3325 9 P 0 ;1
L 4.1825 2.3825 4.1825 2.3825 9 P 0 ;1
L 4.1825 2.4325 4.1825 2.4325 9 P 0 ;1
L 4.1825 2.4825 4.1825 2.4825 9 P 0 ;1
L 4.1825 2.5325 4.1825 2.5325 9 P 0 ;1
L 4.1825 2.5825 4.1825 2.5825 9 P 0 ;1
L 4.1825 2.7825 4.1825 2.7825 9 P 0 ;1
L 4.1825 2.8325 4.1825 2.8325 9 P 0 ;1
L 4.1825 3.0325 4.1825 3.0325 9 P 0 ;1
L 4.1825 3.0825 4.1825 3.0825 9 P 0 ;1
L 4.1825 3.1325 4.1825 3.1325 9 P 0 ;1
L 4.1825 3.1825 4.1825 3.1825 9 P 0 ;1
L 4.1825 3.2325 4.1825 3.2325 9 P 0 ;1
L 4.1825 3.2825 4.1825 3.2825 9 P 0 ;1
L 4.1825 3.3325 4.1825 3.3325 9 P 0 ;1
L 4.1825 3.3825 4.1825 3.3825 9 P 0 ;1
L 4.1825 3.4325 4.1825 3.4325 9 P 0 ;1
L 4.1825 3.4825 4.1825 3.4825 9 P 0 ;1
L 4.1825 3.5325 4.1825 3.5325 9 P 0 ;1
L 4.1825 3.5825 4.1825 3.5825 9 P 0 ;1
L 4.1825 3.6325 4.1825 3.6325 9 P 0 ;1
L 4.1825 3.6825 4.1825 3.6825 9 P 0 ;1
L 4.1825 3.7325 4.1825 3.7325 9 P 0 ;1
L 4.1825 3.7825 4.1825 3.7825 9 P 0 ;1
L 4.1825 3.8325 4.1825 3.8325 9 P 0 ;1
L 4.1825 3.8825 4.1825 3.8825 9 P 0 ;1
L 4.1825 4.2325 4.1825 4.2325 9 P 0 ;1
L 4.1825 4.2825 4.1825 4.2825 9 P 0 ;1
L 4.1825 4.3325 4.1825 4.3325 9 P 0 ;1
L 4.1825 4.3825 4.1825 4.3825 9 P 0 ;1
L 4.1825 4.4325 4.1825 4.4325 9 P 0 ;1
L 4.1825 4.4825 4.1825 4.4825 9 P 0 ;1
L 4.1825 4.5325 4.1825 4.5325 9 P 0 ;1
L 4.1825 4.5825 4.1825 4.5825 9 P 0 ;1
L 4.1825 4.8325 4.1825 4.8325 9 P 0 ;1
L 4.1825 4.8825 4.1825 4.8825 9 P 0 ;1
L 4.1825 4.9325 4.1825 4.9325 9 P 0 ;1
L 4.1825 5.0325 4.1825 5.0325 9 P 0 ;1
L 4.1825 5.0825 4.1825 5.0825 9 P 0 ;1
L 4.1825 5.1325 4.1825 5.1325 9 P 0 ;1
L 4.1825 5.1825 4.1825 5.1825 9 P 0 ;1
L 4.1825 5.2325 4.1825 5.2325 9 P 0 ;1
L 4.1825 5.2825 4.1825 5.2825 9 P 0 ;1
L 4.1825 5.3325 4.1825 5.3325 9 P 0 ;1
L 4.1825 5.3825 4.1825 5.3825 9 P 0 ;1
L 4.1825 5.4325 4.1825 5.4325 9 P 0 ;1
L 4.1825 5.4825 4.1825 5.4825 9 P 0 ;1
L 4.1825 5.5325 4.1825 5.5325 9 P 0 ;1
L 4.1825 5.5825 4.1825 5.5825 9 P 0 ;1
L 4.1825 5.6325 4.1825 5.6325 9 P 0 ;1
L 4.1825 5.6825 4.1825 5.6825 9 P 0 ;1
L 4.1825 5.7325 4.1825 5.7325 9 P 0 ;1
L 4.1825 5.7825 4.1825 5.7825 9 P 0 ;1
L 4.1825 5.8325 4.1825 5.8325 9 P 0 ;1
L 4.1825 5.8825 4.1825 5.8825 9 P 0 ;1
L 4.2325 0.1325 4.2325 0.1325 9 P 0 ;1
L 4.2325 0.1825 4.2325 0.1825 9 P 0 ;1
L 4.2325 0.2325 4.2325 0.2325 9 P 0 ;1
L 4.2325 0.2825 4.2325 0.2825 9 P 0 ;1
L 4.2325 0.3325 4.2325 0.3325 9 P 0 ;1
L 4.2325 0.3825 4.2325 0.3825 9 P 0 ;1
L 4.2325 0.4325 4.2325 0.4325 9 P 0 ;1
L 4.2325 0.4825 4.2325 0.4825 9 P 0 ;1
L 4.2325 0.5325 4.2325 0.5325 9 P 0 ;1
L 4.2325 0.5825 4.2325 0.5825 9 P 0 ;1
L 4.2325 0.6325 4.2325 0.6325 9 P 0 ;1
L 4.2325 0.8325 4.2325 0.8325 9 P 0 ;1
L 4.2325 0.8825 4.2325 0.8825 9 P 0 ;1
L 4.2325 0.9325 4.2325 0.9325 9 P 0 ;1
L 4.2325 0.9825 4.2325 0.9825 9 P 0 ;1
L 4.2325 1.4825 4.2325 1.4825 9 P 0 ;1
L 4.2325 1.5325 4.2325 1.5325 9 P 0 ;1
L 4.2325 1.5825 4.2325 1.5825 9 P 0 ;1
L 4.2325 1.6325 4.2325 1.6325 9 P 0 ;1
L 4.2325 1.9325 4.2325 1.9325 9 P 0 ;1
L 4.2325 1.9825 4.2325 1.9825 9 P 0 ;1
L 4.2325 2.0325 4.2325 2.0325 9 P 0 ;1
L 4.2325 2.0825 4.2325 2.0825 9 P 0 ;1
L 4.2325 2.1325 4.2325 2.1325 9 P 0 ;1
L 4.2325 2.1825 4.2325 2.1825 9 P 0 ;1
L 4.2325 2.2325 4.2325 2.2325 9 P 0 ;1
L 4.2325 2.2825 4.2325 2.2825 9 P 0 ;1
L 4.2325 2.3325 4.2325 2.3325 9 P 0 ;1
L 4.2325 2.3825 4.2325 2.3825 9 P 0 ;1
L 4.2325 2.4325 4.2325 2.4325 9 P 0 ;1
L 4.2325 2.4825 4.2325 2.4825 9 P 0 ;1
L 4.2325 2.5325 4.2325 2.5325 9 P 0 ;1
L 4.2325 2.5825 4.2325 2.5825 9 P 0 ;1
L 4.2325 2.6325 4.2325 2.6325 9 P 0 ;1
L 4.2325 2.6825 4.2325 2.6825 9 P 0 ;1
L 4.2325 2.7325 4.2325 2.7325 9 P 0 ;1
L 4.2325 2.7825 4.2325 2.7825 9 P 0 ;1
L 4.2325 2.8325 4.2325 2.8325 9 P 0 ;1
L 4.2325 2.8825 4.2325 2.8825 9 P 0 ;1
L 4.2325 2.9325 4.2325 2.9325 9 P 0 ;1
L 4.2325 2.9825 4.2325 2.9825 9 P 0 ;1
L 4.2325 3.0325 4.2325 3.0325 9 P 0 ;1
L 4.2325 3.0825 4.2325 3.0825 9 P 0 ;1
L 4.2325 3.1325 4.2325 3.1325 9 P 0 ;1
L 4.2325 3.1825 4.2325 3.1825 9 P 0 ;1
L 4.2325 3.2325 4.2325 3.2325 9 P 0 ;1
L 4.2325 3.2825 4.2325 3.2825 9 P 0 ;1
L 4.2325 3.3325 4.2325 3.3325 9 P 0 ;1
L 4.2325 3.3825 4.2325 3.3825 9 P 0 ;1
L 4.2325 3.4325 4.2325 3.4325 9 P 0 ;1
L 4.2325 3.4825 4.2325 3.4825 9 P 0 ;1
L 4.2325 3.5325 4.2325 3.5325 9 P 0 ;1
L 4.2325 3.5825 4.2325 3.5825 9 P 0 ;1
L 4.2325 3.6325 4.2325 3.6325 9 P 0 ;1
L 4.2325 3.6825 4.2325 3.6825 9 P 0 ;1
L 4.2325 3.7325 4.2325 3.7325 9 P 0 ;1
L 4.2325 3.7825 4.2325 3.7825 9 P 0 ;1
L 4.2325 3.8325 4.2325 3.8325 9 P 0 ;1
L 4.2325 3.8825 4.2325 3.8825 9 P 0 ;1
L 4.2325 4.2325 4.2325 4.2325 9 P 0 ;1
L 4.2325 4.2825 4.2325 4.2825 9 P 0 ;1
L 4.2325 4.3325 4.2325 4.3325 9 P 0 ;1
L 4.2325 4.3825 4.2325 4.3825 9 P 0 ;1
L 4.2325 4.4325 4.2325 4.4325 9 P 0 ;1
L 4.2325 4.4825 4.2325 4.4825 9 P 0 ;1
L 4.2325 4.5325 4.2325 4.5325 9 P 0 ;1
L 4.2325 4.5825 4.2325 4.5825 9 P 0 ;1
L 4.2325 5.2325 4.2325 5.2325 9 P 0 ;1
L 4.2325 5.2825 4.2325 5.2825 9 P 0 ;1
L 4.2325 5.3325 4.2325 5.3325 9 P 0 ;1
L 4.2325 5.3825 4.2325 5.3825 9 P 0 ;1
L 4.2325 5.4325 4.2325 5.4325 9 P 0 ;1
L 4.2325 5.4825 4.2325 5.4825 9 P 0 ;1
L 4.2325 5.5325 4.2325 5.5325 9 P 0 ;1
L 4.2325 5.5825 4.2325 5.5825 9 P 0 ;1
L 4.2325 5.6325 4.2325 5.6325 9 P 0 ;1
L 4.2325 5.6825 4.2325 5.6825 9 P 0 ;1
L 4.2325 5.7325 4.2325 5.7325 9 P 0 ;1
L 4.2325 5.7825 4.2325 5.7825 9 P 0 ;1
L 4.2325 5.8325 4.2325 5.8325 9 P 0 ;1
L 4.2325 5.8825 4.2325 5.8825 9 P 0 ;1
L 4.2825 0.1325 4.2825 0.1325 9 P 0 ;1
L 4.2825 0.1825 4.2825 0.1825 9 P 0 ;1
L 4.2825 0.2325 4.2825 0.2325 9 P 0 ;1
L 4.2825 0.2825 4.2825 0.2825 9 P 0 ;1
L 4.2825 0.3325 4.2825 0.3325 9 P 0 ;1
L 4.2825 0.3825 4.2825 0.3825 9 P 0 ;1
L 4.2825 0.4325 4.2825 0.4325 9 P 0 ;1
L 4.2825 0.4825 4.2825 0.4825 9 P 0 ;1
L 4.2825 0.5325 4.2825 0.5325 9 P 0 ;1
L 4.2825 0.5825 4.2825 0.5825 9 P 0 ;1
L 4.2825 0.6325 4.2825 0.6325 9 P 0 ;1
L 4.2825 0.8325 4.2825 0.8325 9 P 0 ;1
L 4.2825 0.8825 4.2825 0.8825 9 P 0 ;1
L 4.2825 0.9325 4.2825 0.9325 9 P 0 ;1
L 4.2825 0.9825 4.2825 0.9825 9 P 0 ;1
L 4.2825 1.4825 4.2825 1.4825 9 P 0 ;1
L 4.2825 1.5325 4.2825 1.5325 9 P 0 ;1
L 4.2825 1.5825 4.2825 1.5825 9 P 0 ;1
L 4.2825 1.6325 4.2825 1.6325 9 P 0 ;1
L 4.2825 1.9325 4.2825 1.9325 9 P 0 ;1
L 4.2825 1.9825 4.2825 1.9825 9 P 0 ;1
L 4.2825 2.0325 4.2825 2.0325 9 P 0 ;1
L 4.2825 2.0825 4.2825 2.0825 9 P 0 ;1
L 4.2825 2.1325 4.2825 2.1325 9 P 0 ;1
L 4.2825 2.1825 4.2825 2.1825 9 P 0 ;1
L 4.2825 2.2325 4.2825 2.2325 9 P 0 ;1
L 4.2825 2.2825 4.2825 2.2825 9 P 0 ;1
L 4.2825 2.3325 4.2825 2.3325 9 P 0 ;1
L 4.2825 2.3825 4.2825 2.3825 9 P 0 ;1
L 4.2825 2.4325 4.2825 2.4325 9 P 0 ;1
L 4.2825 2.4825 4.2825 2.4825 9 P 0 ;1
L 4.2825 2.5325 4.2825 2.5325 9 P 0 ;1
L 4.2825 2.5825 4.2825 2.5825 9 P 0 ;1
L 4.2825 2.6325 4.2825 2.6325 9 P 0 ;1
L 4.2825 2.6825 4.2825 2.6825 9 P 0 ;1
L 4.2825 2.7325 4.2825 2.7325 9 P 0 ;1
L 4.2825 2.7825 4.2825 2.7825 9 P 0 ;1
L 4.2825 2.8325 4.2825 2.8325 9 P 0 ;1
L 4.2825 2.8825 4.2825 2.8825 9 P 0 ;1
L 4.2825 2.9325 4.2825 2.9325 9 P 0 ;1
L 4.2825 2.9825 4.2825 2.9825 9 P 0 ;1
L 4.2825 3.0325 4.2825 3.0325 9 P 0 ;1
L 4.2825 3.0825 4.2825 3.0825 9 P 0 ;1
L 4.2825 3.1325 4.2825 3.1325 9 P 0 ;1
L 4.2825 3.1825 4.2825 3.1825 9 P 0 ;1
L 4.2825 3.2325 4.2825 3.2325 9 P 0 ;1
L 4.2825 3.2825 4.2825 3.2825 9 P 0 ;1
L 4.2825 3.3325 4.2825 3.3325 9 P 0 ;1
L 4.2825 3.3825 4.2825 3.3825 9 P 0 ;1
L 4.2825 3.4325 4.2825 3.4325 9 P 0 ;1
L 4.2825 3.4825 4.2825 3.4825 9 P 0 ;1
L 4.2825 3.5325 4.2825 3.5325 9 P 0 ;1
L 4.2825 3.5825 4.2825 3.5825 9 P 0 ;1
L 4.2825 3.6325 4.2825 3.6325 9 P 0 ;1
L 4.2825 3.6825 4.2825 3.6825 9 P 0 ;1
L 4.2825 3.7325 4.2825 3.7325 9 P 0 ;1
L 4.2825 3.7825 4.2825 3.7825 9 P 0 ;1
L 4.2825 3.8325 4.2825 3.8325 9 P 0 ;1
L 4.2825 3.8825 4.2825 3.8825 9 P 0 ;1
L 4.2825 4.1825 4.2825 4.1825 9 P 0 ;1
L 4.2825 4.2325 4.2825 4.2325 9 P 0 ;1
L 4.2825 4.2825 4.2825 4.2825 9 P 0 ;1
L 4.2825 4.3325 4.2825 4.3325 9 P 0 ;1
L 4.2825 4.3825 4.2825 4.3825 9 P 0 ;1
L 4.2825 4.4325 4.2825 4.4325 9 P 0 ;1
L 4.2825 4.4825 4.2825 4.4825 9 P 0 ;1
L 4.2825 4.5325 4.2825 4.5325 9 P 0 ;1
L 4.2825 4.5825 4.2825 4.5825 9 P 0 ;1
L 4.2825 5.2325 4.2825 5.2325 9 P 0 ;1
L 4.2825 5.2825 4.2825 5.2825 9 P 0 ;1
L 4.2825 5.3325 4.2825 5.3325 9 P 0 ;1
L 4.2825 5.3825 4.2825 5.3825 9 P 0 ;1
L 4.2825 5.4325 4.2825 5.4325 9 P 0 ;1
L 4.2825 5.4825 4.2825 5.4825 9 P 0 ;1
L 4.2825 5.5325 4.2825 5.5325 9 P 0 ;1
L 4.2825 5.5825 4.2825 5.5825 9 P 0 ;1
L 4.2825 5.6325 4.2825 5.6325 9 P 0 ;1
L 4.2825 5.6825 4.2825 5.6825 9 P 0 ;1
L 4.2825 5.7325 4.2825 5.7325 9 P 0 ;1
L 4.2825 5.7825 4.2825 5.7825 9 P 0 ;1
L 4.2825 5.8325 4.2825 5.8325 9 P 0 ;1
L 4.2825 5.8825 4.2825 5.8825 9 P 0 ;1
L 4.3325 0.1325 4.3325 0.1325 9 P 0 ;1
L 4.3325 0.1825 4.3325 0.1825 9 P 0 ;1
L 4.3325 0.2325 4.3325 0.2325 9 P 0 ;1
L 4.3325 0.2825 4.3325 0.2825 9 P 0 ;1
L 4.3325 0.3325 4.3325 0.3325 9 P 0 ;1
L 4.3325 0.3825 4.3325 0.3825 9 P 0 ;1
L 4.3325 0.4325 4.3325 0.4325 9 P 0 ;1
L 4.3325 0.4825 4.3325 0.4825 9 P 0 ;1
L 4.3325 0.5325 4.3325 0.5325 9 P 0 ;1
L 4.3325 0.5825 4.3325 0.5825 9 P 0 ;1
L 4.3325 0.6325 4.3325 0.6325 9 P 0 ;1
L 4.3325 0.8325 4.3325 0.8325 9 P 0 ;1
L 4.3325 0.8825 4.3325 0.8825 9 P 0 ;1
L 4.3325 0.9325 4.3325 0.9325 9 P 0 ;1
L 4.3325 0.9825 4.3325 0.9825 9 P 0 ;1
L 4.3325 1.4825 4.3325 1.4825 9 P 0 ;1
L 4.3325 1.5325 4.3325 1.5325 9 P 0 ;1
L 4.3325 1.5825 4.3325 1.5825 9 P 0 ;1
L 4.3325 1.6325 4.3325 1.6325 9 P 0 ;1
L 4.3325 1.6825 4.3325 1.6825 9 P 0 ;1
L 4.3325 1.9325 4.3325 1.9325 9 P 0 ;1
L 4.3325 1.9825 4.3325 1.9825 9 P 0 ;1
L 4.3325 2.0325 4.3325 2.0325 9 P 0 ;1
L 4.3325 2.0825 4.3325 2.0825 9 P 0 ;1
L 4.3325 2.1325 4.3325 2.1325 9 P 0 ;1
L 4.3325 2.1825 4.3325 2.1825 9 P 0 ;1
L 4.3325 2.2325 4.3325 2.2325 9 P 0 ;1
L 4.3325 2.2825 4.3325 2.2825 9 P 0 ;1
L 4.3325 2.3325 4.3325 2.3325 9 P 0 ;1
L 4.3325 2.3825 4.3325 2.3825 9 P 0 ;1
L 4.3325 2.4325 4.3325 2.4325 9 P 0 ;1
L 4.3325 2.4825 4.3325 2.4825 9 P 0 ;1
L 4.3325 2.5325 4.3325 2.5325 9 P 0 ;1
L 4.3325 2.5825 4.3325 2.5825 9 P 0 ;1
L 4.3325 2.6325 4.3325 2.6325 9 P 0 ;1
L 4.3325 2.6825 4.3325 2.6825 9 P 0 ;1
L 4.3325 2.7325 4.3325 2.7325 9 P 0 ;1
L 4.3325 2.7825 4.3325 2.7825 9 P 0 ;1
L 4.3325 2.8325 4.3325 2.8325 9 P 0 ;1
L 4.3325 2.8825 4.3325 2.8825 9 P 0 ;1
L 4.3325 2.9325 4.3325 2.9325 9 P 0 ;1
L 4.3325 2.9825 4.3325 2.9825 9 P 0 ;1
L 4.3325 3.0325 4.3325 3.0325 9 P 0 ;1
L 4.3325 3.0825 4.3325 3.0825 9 P 0 ;1
L 4.3325 3.1325 4.3325 3.1325 9 P 0 ;1
L 4.3325 3.1825 4.3325 3.1825 9 P 0 ;1
L 4.3325 3.2325 4.3325 3.2325 9 P 0 ;1
L 4.3325 3.2825 4.3325 3.2825 9 P 0 ;1
L 4.3325 3.3325 4.3325 3.3325 9 P 0 ;1
L 4.3325 3.3825 4.3325 3.3825 9 P 0 ;1
L 4.3325 3.4325 4.3325 3.4325 9 P 0 ;1
L 4.3325 3.4825 4.3325 3.4825 9 P 0 ;1
L 4.3325 3.5325 4.3325 3.5325 9 P 0 ;1
L 4.3325 3.5825 4.3325 3.5825 9 P 0 ;1
L 4.3325 3.6325 4.3325 3.6325 9 P 0 ;1
L 4.3325 3.6825 4.3325 3.6825 9 P 0 ;1
L 4.3325 3.7325 4.3325 3.7325 9 P 0 ;1
L 4.3325 3.7825 4.3325 3.7825 9 P 0 ;1
L 4.3325 3.8325 4.3325 3.8325 9 P 0 ;1
L 4.3325 3.8825 4.3325 3.8825 9 P 0 ;1
L 4.3325 4.1825 4.3325 4.1825 9 P 0 ;1
L 4.3325 4.2325 4.3325 4.2325 9 P 0 ;1
L 4.3325 4.2825 4.3325 4.2825 9 P 0 ;1
L 4.3325 4.3325 4.3325 4.3325 9 P 0 ;1
L 4.3325 4.3825 4.3325 4.3825 9 P 0 ;1
L 4.3325 4.4325 4.3325 4.4325 9 P 0 ;1
L 4.3325 4.4825 4.3325 4.4825 9 P 0 ;1
L 4.3325 4.5325 4.3325 4.5325 9 P 0 ;1
L 4.3325 5.2325 4.3325 5.2325 9 P 0 ;1
L 4.3325 5.2825 4.3325 5.2825 9 P 0 ;1
L 4.3325 5.3325 4.3325 5.3325 9 P 0 ;1
L 4.3325 5.3825 4.3325 5.3825 9 P 0 ;1
L 4.3325 5.4325 4.3325 5.4325 9 P 0 ;1
L 4.3325 5.4825 4.3325 5.4825 9 P 0 ;1
L 4.3325 5.5325 4.3325 5.5325 9 P 0 ;1
L 4.3325 5.5825 4.3325 5.5825 9 P 0 ;1
L 4.3325 5.6325 4.3325 5.6325 9 P 0 ;1
L 4.3325 5.6825 4.3325 5.6825 9 P 0 ;1
L 4.3325 5.7325 4.3325 5.7325 9 P 0 ;1
L 4.3325 5.7825 4.3325 5.7825 9 P 0 ;1
L 4.3325 5.8325 4.3325 5.8325 9 P 0 ;1
L 4.3325 5.8825 4.3325 5.8825 9 P 0 ;1
L 4.3825 0.1325 4.3825 0.1325 9 P 0 ;1
L 4.3825 0.1825 4.3825 0.1825 9 P 0 ;1
L 4.3825 0.2325 4.3825 0.2325 9 P 0 ;1
L 4.3825 0.2825 4.3825 0.2825 9 P 0 ;1
L 4.3825 0.3325 4.3825 0.3325 9 P 0 ;1
L 4.3825 0.3825 4.3825 0.3825 9 P 0 ;1
L 4.3825 0.4325 4.3825 0.4325 9 P 0 ;1
L 4.3825 0.4825 4.3825 0.4825 9 P 0 ;1
L 4.3825 0.5325 4.3825 0.5325 9 P 0 ;1
L 4.3825 0.5825 4.3825 0.5825 9 P 0 ;1
L 4.3825 0.6325 4.3825 0.6325 9 P 0 ;1
L 4.3825 0.8825 4.3825 0.8825 9 P 0 ;1
L 4.3825 0.9325 4.3825 0.9325 9 P 0 ;1
L 4.3825 0.9825 4.3825 0.9825 9 P 0 ;1
L 4.3825 1.4825 4.3825 1.4825 9 P 0 ;1
L 4.3825 1.5325 4.3825 1.5325 9 P 0 ;1
L 4.3825 1.5825 4.3825 1.5825 9 P 0 ;1
L 4.3825 1.6325 4.3825 1.6325 9 P 0 ;1
L 4.3825 1.6825 4.3825 1.6825 9 P 0 ;1
L 4.3825 1.9325 4.3825 1.9325 9 P 0 ;1
L 4.3825 1.9825 4.3825 1.9825 9 P 0 ;1
L 4.3825 2.0325 4.3825 2.0325 9 P 0 ;1
L 4.3825 2.0825 4.3825 2.0825 9 P 0 ;1
L 4.3825 2.1325 4.3825 2.1325 9 P 0 ;1
L 4.3825 2.1825 4.3825 2.1825 9 P 0 ;1
L 4.3825 2.2325 4.3825 2.2325 9 P 0 ;1
L 4.3825 2.2825 4.3825 2.2825 9 P 0 ;1
L 4.3825 2.3325 4.3825 2.3325 9 P 0 ;1
L 4.3825 2.3825 4.3825 2.3825 9 P 0 ;1
L 4.3825 2.4325 4.3825 2.4325 9 P 0 ;1
L 4.3825 2.4825 4.3825 2.4825 9 P 0 ;1
L 4.3825 2.5325 4.3825 2.5325 9 P 0 ;1
L 4.3825 2.5825 4.3825 2.5825 9 P 0 ;1
L 4.3825 2.6325 4.3825 2.6325 9 P 0 ;1
L 4.3825 2.6825 4.3825 2.6825 9 P 0 ;1
L 4.3825 2.7325 4.3825 2.7325 9 P 0 ;1
L 4.3825 2.7825 4.3825 2.7825 9 P 0 ;1
L 4.3825 2.8325 4.3825 2.8325 9 P 0 ;1
L 4.3825 2.8825 4.3825 2.8825 9 P 0 ;1
L 4.3825 2.9325 4.3825 2.9325 9 P 0 ;1
L 4.3825 2.9825 4.3825 2.9825 9 P 0 ;1
L 4.3825 3.0325 4.3825 3.0325 9 P 0 ;1
L 4.3825 3.0825 4.3825 3.0825 9 P 0 ;1
L 4.3825 3.1325 4.3825 3.1325 9 P 0 ;1
L 4.3825 3.1825 4.3825 3.1825 9 P 0 ;1
L 4.3825 3.2325 4.3825 3.2325 9 P 0 ;1
L 4.3825 3.2825 4.3825 3.2825 9 P 0 ;1
L 4.3825 3.3325 4.3825 3.3325 9 P 0 ;1
L 4.3825 3.3825 4.3825 3.3825 9 P 0 ;1
L 4.3825 3.4325 4.3825 3.4325 9 P 0 ;1
L 4.3825 3.4825 4.3825 3.4825 9 P 0 ;1
L 4.3825 3.5325 4.3825 3.5325 9 P 0 ;1
L 4.3825 3.5825 4.3825 3.5825 9 P 0 ;1
L 4.3825 3.6325 4.3825 3.6325 9 P 0 ;1
L 4.3825 3.6825 4.3825 3.6825 9 P 0 ;1
L 4.3825 3.7325 4.3825 3.7325 9 P 0 ;1
L 4.3825 3.7825 4.3825 3.7825 9 P 0 ;1
L 4.3825 3.8325 4.3825 3.8325 9 P 0 ;1
L 4.3825 3.8825 4.3825 3.8825 9 P 0 ;1
L 4.3825 4.1825 4.3825 4.1825 9 P 0 ;1
L 4.3825 4.2325 4.3825 4.2325 9 P 0 ;1
L 4.3825 4.2825 4.3825 4.2825 9 P 0 ;1
L 4.3825 4.3325 4.3825 4.3325 9 P 0 ;1
L 4.3825 4.3825 4.3825 4.3825 9 P 0 ;1
L 4.3825 4.4325 4.3825 4.4325 9 P 0 ;1
L 4.3825 4.4825 4.3825 4.4825 9 P 0 ;1
L 4.3825 4.5325 4.3825 4.5325 9 P 0 ;1
L 4.3825 5.2325 4.3825 5.2325 9 P 0 ;1
L 4.3825 5.2825 4.3825 5.2825 9 P 0 ;1
L 4.3825 5.3325 4.3825 5.3325 9 P 0 ;1
L 4.3825 5.3825 4.3825 5.3825 9 P 0 ;1
L 4.3825 5.4325 4.3825 5.4325 9 P 0 ;1
L 4.3825 5.4825 4.3825 5.4825 9 P 0 ;1
L 4.3825 5.5325 4.3825 5.5325 9 P 0 ;1
L 4.3825 5.5825 4.3825 5.5825 9 P 0 ;1
L 4.3825 5.6325 4.3825 5.6325 9 P 0 ;1
L 4.3825 5.6825 4.3825 5.6825 9 P 0 ;1
L 4.3825 5.7325 4.3825 5.7325 9 P 0 ;1
L 4.3825 5.7825 4.3825 5.7825 9 P 0 ;1
L 4.3825 5.8325 4.3825 5.8325 9 P 0 ;1
L 4.3825 5.8825 4.3825 5.8825 9 P 0 ;1
L 4.4325 0.1325 4.4325 0.1325 9 P 0 ;1
L 4.4325 0.1825 4.4325 0.1825 9 P 0 ;1
L 4.4325 0.2325 4.4325 0.2325 9 P 0 ;1
L 4.4325 0.2825 4.4325 0.2825 9 P 0 ;1
L 4.4325 0.3325 4.4325 0.3325 9 P 0 ;1
L 4.4325 0.3825 4.4325 0.3825 9 P 0 ;1
L 4.4325 0.4325 4.4325 0.4325 9 P 0 ;1
L 4.4325 0.4825 4.4325 0.4825 9 P 0 ;1
L 4.4325 0.5325 4.4325 0.5325 9 P 0 ;1
L 4.4325 0.5825 4.4325 0.5825 9 P 0 ;1
L 4.4325 0.6325 4.4325 0.6325 9 P 0 ;1
L 4.4325 0.6825 4.4325 0.6825 9 P 0 ;1
L 4.4325 0.8825 4.4325 0.8825 9 P 0 ;1
L 4.4325 0.9325 4.4325 0.9325 9 P 0 ;1
L 4.4325 1.4325 4.4325 1.4325 9 P 0 ;1
L 4.4325 1.4825 4.4325 1.4825 9 P 0 ;1
L 4.4325 1.5325 4.4325 1.5325 9 P 0 ;1
L 4.4325 1.5825 4.4325 1.5825 9 P 0 ;1
L 4.4325 1.6325 4.4325 1.6325 9 P 0 ;1
L 4.4325 1.9325 4.4325 1.9325 9 P 0 ;1
L 4.4325 1.9825 4.4325 1.9825 9 P 0 ;1
L 4.4325 2.0325 4.4325 2.0325 9 P 0 ;1
L 4.4325 2.0825 4.4325 2.0825 9 P 0 ;1
L 4.4325 2.1325 4.4325 2.1325 9 P 0 ;1
L 4.4325 2.1825 4.4325 2.1825 9 P 0 ;1
L 4.4325 2.2325 4.4325 2.2325 9 P 0 ;1
L 4.4325 2.2825 4.4325 2.2825 9 P 0 ;1
L 4.4325 2.3325 4.4325 2.3325 9 P 0 ;1
L 4.4325 2.3825 4.4325 2.3825 9 P 0 ;1
L 4.4325 2.4325 4.4325 2.4325 9 P 0 ;1
L 4.4325 2.4825 4.4325 2.4825 9 P 0 ;1
L 4.4325 2.5325 4.4325 2.5325 9 P 0 ;1
L 4.4325 2.5825 4.4325 2.5825 9 P 0 ;1
L 4.4325 2.6325 4.4325 2.6325 9 P 0 ;1
L 4.4325 2.6825 4.4325 2.6825 9 P 0 ;1
L 4.4325 2.7325 4.4325 2.7325 9 P 0 ;1
L 4.4325 2.7825 4.4325 2.7825 9 P 0 ;1
L 4.4325 2.8325 4.4325 2.8325 9 P 0 ;1
L 4.4325 2.8825 4.4325 2.8825 9 P 0 ;1
L 4.4325 2.9325 4.4325 2.9325 9 P 0 ;1
L 4.4325 2.9825 4.4325 2.9825 9 P 0 ;1
L 4.4325 3.0325 4.4325 3.0325 9 P 0 ;1
L 4.4325 3.0825 4.4325 3.0825 9 P 0 ;1
L 4.4325 3.1325 4.4325 3.1325 9 P 0 ;1
L 4.4325 3.1825 4.4325 3.1825 9 P 0 ;1
L 4.4325 3.2325 4.4325 3.2325 9 P 0 ;1
L 4.4325 3.2825 4.4325 3.2825 9 P 0 ;1
L 4.4325 3.3325 4.4325 3.3325 9 P 0 ;1
L 4.4325 3.3825 4.4325 3.3825 9 P 0 ;1
L 4.4325 3.4325 4.4325 3.4325 9 P 0 ;1
L 4.4325 3.4825 4.4325 3.4825 9 P 0 ;1
L 4.4325 3.5325 4.4325 3.5325 9 P 0 ;1
L 4.4325 3.5825 4.4325 3.5825 9 P 0 ;1
L 4.4325 3.6325 4.4325 3.6325 9 P 0 ;1
L 4.4325 3.6825 4.4325 3.6825 9 P 0 ;1
L 4.4325 3.7325 4.4325 3.7325 9 P 0 ;1
L 4.4325 3.7825 4.4325 3.7825 9 P 0 ;1
L 4.4325 3.8325 4.4325 3.8325 9 P 0 ;1
L 4.4325 4.1825 4.4325 4.1825 9 P 0 ;1
L 4.4325 4.2325 4.4325 4.2325 9 P 0 ;1
L 4.4325 4.2825 4.4325 4.2825 9 P 0 ;1
L 4.4325 4.3325 4.4325 4.3325 9 P 0 ;1
L 4.4325 4.3825 4.4325 4.3825 9 P 0 ;1
L 4.4325 4.4325 4.4325 4.4325 9 P 0 ;1
L 4.4325 4.4825 4.4325 4.4825 9 P 0 ;1
L 4.4325 4.5325 4.4325 4.5325 9 P 0 ;1
L 4.4325 5.2325 4.4325 5.2325 9 P 0 ;1
L 4.4325 5.2825 4.4325 5.2825 9 P 0 ;1
L 4.4325 5.3325 4.4325 5.3325 9 P 0 ;1
L 4.4325 5.3825 4.4325 5.3825 9 P 0 ;1
L 4.4325 5.4325 4.4325 5.4325 9 P 0 ;1
L 4.4325 5.4825 4.4325 5.4825 9 P 0 ;1
L 4.4325 5.5325 4.4325 5.5325 9 P 0 ;1
L 4.4325 5.5825 4.4325 5.5825 9 P 0 ;1
L 4.4325 5.6325 4.4325 5.6325 9 P 0 ;1
L 4.4325 5.6825 4.4325 5.6825 9 P 0 ;1
L 4.4325 5.7325 4.4325 5.7325 9 P 0 ;1
L 4.4325 5.7825 4.4325 5.7825 9 P 0 ;1
L 4.4325 5.8325 4.4325 5.8325 9 P 0 ;1
L 4.4325 5.8825 4.4325 5.8825 9 P 0 ;1
L 4.4825 0.1325 4.4825 0.1325 9 P 0 ;1
L 4.4825 0.1825 4.4825 0.1825 9 P 0 ;1
L 4.4825 0.2325 4.4825 0.2325 9 P 0 ;1
L 4.4825 0.2825 4.4825 0.2825 9 P 0 ;1
L 4.4825 0.3325 4.4825 0.3325 9 P 0 ;1
L 4.4825 0.3825 4.4825 0.3825 9 P 0 ;1
L 4.4825 0.4325 4.4825 0.4325 9 P 0 ;1
L 4.4825 0.4825 4.4825 0.4825 9 P 0 ;1
L 4.4825 0.5325 4.4825 0.5325 9 P 0 ;1
L 4.4825 0.5825 4.4825 0.5825 9 P 0 ;1
L 4.4825 0.6325 4.4825 0.6325 9 P 0 ;1
L 4.4825 0.6825 4.4825 0.6825 9 P 0 ;1
L 4.4825 0.8825 4.4825 0.8825 9 P 0 ;1
L 4.4825 0.9325 4.4825 0.9325 9 P 0 ;1
L 4.4825 1.4325 4.4825 1.4325 9 P 0 ;1
L 4.4825 1.4825 4.4825 1.4825 9 P 0 ;1
L 4.4825 1.5325 4.4825 1.5325 9 P 0 ;1
L 4.4825 1.5825 4.4825 1.5825 9 P 0 ;1
L 4.4825 1.6325 4.4825 1.6325 9 P 0 ;1
L 4.4825 1.9325 4.4825 1.9325 9 P 0 ;1
L 4.4825 1.9825 4.4825 1.9825 9 P 0 ;1
L 4.4825 2.0325 4.4825 2.0325 9 P 0 ;1
L 4.4825 2.0825 4.4825 2.0825 9 P 0 ;1
L 4.4825 2.1325 4.4825 2.1325 9 P 0 ;1
L 4.4825 2.1825 4.4825 2.1825 9 P 0 ;1
L 4.4825 2.2325 4.4825 2.2325 9 P 0 ;1
L 4.4825 2.2825 4.4825 2.2825 9 P 0 ;1
L 4.4825 2.3325 4.4825 2.3325 9 P 0 ;1
L 4.4825 2.3825 4.4825 2.3825 9 P 0 ;1
L 4.4825 2.4325 4.4825 2.4325 9 P 0 ;1
L 4.4825 2.4825 4.4825 2.4825 9 P 0 ;1
L 4.4825 2.5325 4.4825 2.5325 9 P 0 ;1
L 4.4825 2.5825 4.4825 2.5825 9 P 0 ;1
L 4.4825 2.6325 4.4825 2.6325 9 P 0 ;1
L 4.4825 2.6825 4.4825 2.6825 9 P 0 ;1
L 4.4825 2.7325 4.4825 2.7325 9 P 0 ;1
L 4.4825 2.7825 4.4825 2.7825 9 P 0 ;1
L 4.4825 2.8325 4.4825 2.8325 9 P 0 ;1
L 4.4825 2.8825 4.4825 2.8825 9 P 0 ;1
L 4.4825 2.9325 4.4825 2.9325 9 P 0 ;1
L 4.4825 2.9825 4.4825 2.9825 9 P 0 ;1
L 4.4825 3.0325 4.4825 3.0325 9 P 0 ;1
L 4.4825 3.0825 4.4825 3.0825 9 P 0 ;1
L 4.4825 3.1325 4.4825 3.1325 9 P 0 ;1
L 4.4825 3.1825 4.4825 3.1825 9 P 0 ;1
L 4.4825 3.2325 4.4825 3.2325 9 P 0 ;1
L 4.4825 3.2825 4.4825 3.2825 9 P 0 ;1
L 4.4825 3.3325 4.4825 3.3325 9 P 0 ;1
L 4.4825 3.3825 4.4825 3.3825 9 P 0 ;1
L 4.4825 3.4325 4.4825 3.4325 9 P 0 ;1
L 4.4825 3.4825 4.4825 3.4825 9 P 0 ;1
L 4.4825 3.5325 4.4825 3.5325 9 P 0 ;1
L 4.4825 3.5825 4.4825 3.5825 9 P 0 ;1
L 4.4825 3.6325 4.4825 3.6325 9 P 0 ;1
L 4.4825 3.6825 4.4825 3.6825 9 P 0 ;1
L 4.4825 3.7325 4.4825 3.7325 9 P 0 ;1
L 4.4825 3.7825 4.4825 3.7825 9 P 0 ;1
L 4.4825 3.8325 4.4825 3.8325 9 P 0 ;1
L 4.4825 4.1825 4.4825 4.1825 9 P 0 ;1
L 4.4825 4.2325 4.4825 4.2325 9 P 0 ;1
L 4.4825 4.2825 4.4825 4.2825 9 P 0 ;1
L 4.4825 4.3325 4.4825 4.3325 9 P 0 ;1
L 4.4825 4.3825 4.4825 4.3825 9 P 0 ;1
L 4.4825 4.4325 4.4825 4.4325 9 P 0 ;1
L 4.4825 4.4825 4.4825 4.4825 9 P 0 ;1
L 4.4825 4.5325 4.4825 4.5325 9 P 0 ;1
L 4.4825 4.5825 4.4825 4.5825 9 P 0 ;1
L 4.4825 5.2325 4.4825 5.2325 9 P 0 ;1
L 4.4825 5.2825 4.4825 5.2825 9 P 0 ;1
L 4.4825 5.3325 4.4825 5.3325 9 P 0 ;1
L 4.4825 5.3825 4.4825 5.3825 9 P 0 ;1
L 4.4825 5.4325 4.4825 5.4325 9 P 0 ;1
L 4.4825 5.4825 4.4825 5.4825 9 P 0 ;1
L 4.4825 5.5325 4.4825 5.5325 9 P 0 ;1
L 4.4825 5.5825 4.4825 5.5825 9 P 0 ;1
L 4.4825 5.6325 4.4825 5.6325 9 P 0 ;1
L 4.4825 5.6825 4.4825 5.6825 9 P 0 ;1
L 4.4825 5.7325 4.4825 5.7325 9 P 0 ;1
L 4.4825 5.7825 4.4825 5.7825 9 P 0 ;1
L 4.4825 5.8325 4.4825 5.8325 9 P 0 ;1
L 4.4825 5.8825 4.4825 5.8825 9 P 0 ;1
L 4.5325 0.1325 4.5325 0.1325 9 P 0 ;1
L 4.5325 0.1825 4.5325 0.1825 9 P 0 ;1
L 4.5325 0.2325 4.5325 0.2325 9 P 0 ;1
L 4.5325 0.2825 4.5325 0.2825 9 P 0 ;1
L 4.5325 0.3325 4.5325 0.3325 9 P 0 ;1
L 4.5325 0.3825 4.5325 0.3825 9 P 0 ;1
L 4.5325 0.4325 4.5325 0.4325 9 P 0 ;1
L 4.5325 0.4825 4.5325 0.4825 9 P 0 ;1
L 4.5325 0.5325 4.5325 0.5325 9 P 0 ;1
L 4.5325 0.5825 4.5325 0.5825 9 P 0 ;1
L 4.5325 0.6325 4.5325 0.6325 9 P 0 ;1
L 4.5325 0.6825 4.5325 0.6825 9 P 0 ;1
L 4.5325 0.8825 4.5325 0.8825 9 P 0 ;1
L 4.5325 0.9325 4.5325 0.9325 9 P 0 ;1
L 4.5325 1.4325 4.5325 1.4325 9 P 0 ;1
L 4.5325 1.4825 4.5325 1.4825 9 P 0 ;1
L 4.5325 1.5325 4.5325 1.5325 9 P 0 ;1
L 4.5325 1.5825 4.5325 1.5825 9 P 0 ;1
L 4.5325 1.6325 4.5325 1.6325 9 P 0 ;1
L 4.5325 4.1325 4.5325 4.1325 9 P 0 ;1
L 4.5325 4.1825 4.5325 4.1825 9 P 0 ;1
L 4.5325 4.2325 4.5325 4.2325 9 P 0 ;1
L 4.5325 4.2825 4.5325 4.2825 9 P 0 ;1
L 4.5325 4.3325 4.5325 4.3325 9 P 0 ;1
L 4.5325 4.3825 4.5325 4.3825 9 P 0 ;1
L 4.5325 4.4325 4.5325 4.4325 9 P 0 ;1
L 4.5325 4.4825 4.5325 4.4825 9 P 0 ;1
L 4.5325 4.5325 4.5325 4.5325 9 P 0 ;1
L 4.5325 4.5825 4.5325 4.5825 9 P 0 ;1
L 4.5325 5.1825 4.5325 5.1825 9 P 0 ;1
L 4.5325 5.2325 4.5325 5.2325 9 P 0 ;1
L 4.5325 5.2825 4.5325 5.2825 9 P 0 ;1
L 4.5325 5.3325 4.5325 5.3325 9 P 0 ;1
L 4.5325 5.3825 4.5325 5.3825 9 P 0 ;1
L 4.5325 5.4325 4.5325 5.4325 9 P 0 ;1
L 4.5325 5.4825 4.5325 5.4825 9 P 0 ;1
L 4.5325 5.5325 4.5325 5.5325 9 P 0 ;1
L 4.5325 5.5825 4.5325 5.5825 9 P 0 ;1
L 4.5325 5.6325 4.5325 5.6325 9 P 0 ;1
L 4.5325 5.6825 4.5325 5.6825 9 P 0 ;1
L 4.5325 5.7325 4.5325 5.7325 9 P 0 ;1
L 4.5325 5.7825 4.5325 5.7825 9 P 0 ;1
L 4.5325 5.8325 4.5325 5.8325 9 P 0 ;1
L 4.5325 5.8825 4.5325 5.8825 9 P 0 ;1
L 4.5825 0.1325 4.5825 0.1325 9 P 0 ;1
L 4.5825 0.1825 4.5825 0.1825 9 P 0 ;1
L 4.5825 0.2325 4.5825 0.2325 9 P 0 ;1
L 4.5825 0.2825 4.5825 0.2825 9 P 0 ;1
L 4.5825 0.3325 4.5825 0.3325 9 P 0 ;1
L 4.5825 0.3825 4.5825 0.3825 9 P 0 ;1
L 4.5825 0.4325 4.5825 0.4325 9 P 0 ;1
L 4.5825 0.4825 4.5825 0.4825 9 P 0 ;1
L 4.5825 0.5325 4.5825 0.5325 9 P 0 ;1
L 4.5825 0.5825 4.5825 0.5825 9 P 0 ;1
L 4.5825 0.6325 4.5825 0.6325 9 P 0 ;1
L 4.5825 0.6825 4.5825 0.6825 9 P 0 ;1
L 4.5825 0.8825 4.5825 0.8825 9 P 0 ;1
L 4.5825 0.9325 4.5825 0.9325 9 P 0 ;1
L 4.5825 1.4325 4.5825 1.4325 9 P 0 ;1
L 4.5825 1.4825 4.5825 1.4825 9 P 0 ;1
L 4.5825 1.5325 4.5825 1.5325 9 P 0 ;1
L 4.5825 1.5825 4.5825 1.5825 9 P 0 ;1
L 4.5825 1.6325 4.5825 1.6325 9 P 0 ;1
L 4.5825 4.1325 4.5825 4.1325 9 P 0 ;1
L 4.5825 4.1825 4.5825 4.1825 9 P 0 ;1
L 4.5825 4.2325 4.5825 4.2325 9 P 0 ;1
L 4.5825 4.2825 4.5825 4.2825 9 P 0 ;1
L 4.5825 4.3325 4.5825 4.3325 9 P 0 ;1
L 4.5825 4.3825 4.5825 4.3825 9 P 0 ;1
L 4.5825 4.4325 4.5825 4.4325 9 P 0 ;1
L 4.5825 4.4825 4.5825 4.4825 9 P 0 ;1
L 4.5825 4.5325 4.5825 4.5325 9 P 0 ;1
L 4.5825 4.5825 4.5825 4.5825 9 P 0 ;1
L 4.5825 4.8825 4.5825 4.8825 9 P 0 ;1
L 4.5825 5.1825 4.5825 5.1825 9 P 0 ;1
L 4.5825 5.2325 4.5825 5.2325 9 P 0 ;1
L 4.5825 5.2825 4.5825 5.2825 9 P 0 ;1
L 4.5825 5.3325 4.5825 5.3325 9 P 0 ;1
L 4.5825 5.3825 4.5825 5.3825 9 P 0 ;1
L 4.5825 5.4325 4.5825 5.4325 9 P 0 ;1
L 4.5825 5.4825 4.5825 5.4825 9 P 0 ;1
L 4.5825 5.5325 4.5825 5.5325 9 P 0 ;1
L 4.5825 5.5825 4.5825 5.5825 9 P 0 ;1
L 4.5825 5.6325 4.5825 5.6325 9 P 0 ;1
L 4.5825 5.6825 4.5825 5.6825 9 P 0 ;1
L 4.5825 5.7325 4.5825 5.7325 9 P 0 ;1
L 4.5825 5.7825 4.5825 5.7825 9 P 0 ;1
L 4.5825 5.8325 4.5825 5.8325 9 P 0 ;1
L 4.5825 5.8825 4.5825 5.8825 9 P 0 ;1
L 4.6325 0.1325 4.6325 0.1325 9 P 0 ;1
L 4.6325 0.1825 4.6325 0.1825 9 P 0 ;1
L 4.6325 0.2325 4.6325 0.2325 9 P 0 ;1
L 4.6325 0.2825 4.6325 0.2825 9 P 0 ;1
L 4.6325 0.3325 4.6325 0.3325 9 P 0 ;1
L 4.6325 0.3825 4.6325 0.3825 9 P 0 ;1
L 4.6325 0.4325 4.6325 0.4325 9 P 0 ;1
L 4.6325 0.4825 4.6325 0.4825 9 P 0 ;1
L 4.6325 0.5325 4.6325 0.5325 9 P 0 ;1
L 4.6325 0.5825 4.6325 0.5825 9 P 0 ;1
L 4.6325 0.6325 4.6325 0.6325 9 P 0 ;1
L 4.6325 0.6825 4.6325 0.6825 9 P 0 ;1
L 4.6325 0.8825 4.6325 0.8825 9 P 0 ;1
L 4.6325 0.9325 4.6325 0.9325 9 P 0 ;1
L 4.6325 1.4325 4.6325 1.4325 9 P 0 ;1
L 4.6325 1.5825 4.6325 1.5825 9 P 0 ;1
L 4.6325 1.6325 4.6325 1.6325 9 P 0 ;1
L 4.6325 4.1325 4.6325 4.1325 9 P 0 ;1
L 4.6325 4.1825 4.6325 4.1825 9 P 0 ;1
L 4.6325 4.2825 4.6325 4.2825 9 P 0 ;1
L 4.6325 4.3325 4.6325 4.3325 9 P 0 ;1
L 4.6325 4.3825 4.6325 4.3825 9 P 0 ;1
L 4.6325 4.4325 4.6325 4.4325 9 P 0 ;1
L 4.6325 4.4825 4.6325 4.4825 9 P 0 ;1
L 4.6325 4.5325 4.6325 4.5325 9 P 0 ;1
L 4.6325 4.5825 4.6325 4.5825 9 P 0 ;1
L 4.6325 5.2325 4.6325 5.2325 9 P 0 ;1
L 4.6325 5.2825 4.6325 5.2825 9 P 0 ;1
L 4.6325 5.3325 4.6325 5.3325 9 P 0 ;1
L 4.6325 5.3825 4.6325 5.3825 9 P 0 ;1
L 4.6325 5.4325 4.6325 5.4325 9 P 0 ;1
L 4.6325 5.4825 4.6325 5.4825 9 P 0 ;1
L 4.6325 5.6325 4.6325 5.6325 9 P 0 ;1
L 4.6325 5.6825 4.6325 5.6825 9 P 0 ;1
L 4.6325 5.7325 4.6325 5.7325 9 P 0 ;1
L 4.6325 5.7825 4.6325 5.7825 9 P 0 ;1
L 4.6325 5.8325 4.6325 5.8325 9 P 0 ;1
L 4.6325 5.8825 4.6325 5.8825 9 P 0 ;1
L 4.6825 0.1325 4.6825 0.1325 9 P 0 ;1
L 4.6825 0.1825 4.6825 0.1825 9 P 0 ;1
L 4.6825 0.2325 4.6825 0.2325 9 P 0 ;1
L 4.6825 0.2825 4.6825 0.2825 9 P 0 ;1
L 4.6825 0.3325 4.6825 0.3325 9 P 0 ;1
L 4.6825 0.3825 4.6825 0.3825 9 P 0 ;1
L 4.6825 0.4325 4.6825 0.4325 9 P 0 ;1
L 4.6825 0.4825 4.6825 0.4825 9 P 0 ;1
L 4.6825 0.5325 4.6825 0.5325 9 P 0 ;1
L 4.6825 0.5825 4.6825 0.5825 9 P 0 ;1
L 4.6825 0.6325 4.6825 0.6325 9 P 0 ;1
L 4.6825 0.6825 4.6825 0.6825 9 P 0 ;1
L 4.6825 0.9325 4.6825 0.9325 9 P 0 ;1
L 4.6825 4.3825 4.6825 4.3825 9 P 0 ;1
L 4.6825 4.4325 4.6825 4.4325 9 P 0 ;1
L 4.6825 4.4825 4.6825 4.4825 9 P 0 ;1
L 4.6825 4.5325 4.6825 4.5325 9 P 0 ;1
L 4.6825 5.2325 4.6825 5.2325 9 P 0 ;1
L 4.6825 5.2825 4.6825 5.2825 9 P 0 ;1
L 4.6825 5.3325 4.6825 5.3325 9 P 0 ;1
L 4.6825 5.4325 4.6825 5.4325 9 P 0 ;1
L 4.6825 5.6325 4.6825 5.6325 9 P 0 ;1
L 4.6825 5.6825 4.6825 5.6825 9 P 0 ;1
L 4.6825 5.7325 4.6825 5.7325 9 P 0 ;1
L 4.6825 5.7825 4.6825 5.7825 9 P 0 ;1
L 4.6825 5.8325 4.6825 5.8325 9 P 0 ;1
L 4.6825 5.8825 4.6825 5.8825 9 P 0 ;1
L 4.7325 0.1325 4.7325 0.1325 9 P 0 ;1
L 4.7325 0.1825 4.7325 0.1825 9 P 0 ;1
L 4.7325 0.2325 4.7325 0.2325 9 P 0 ;1
L 4.7325 0.2825 4.7325 0.2825 9 P 0 ;1
L 4.7325 0.3325 4.7325 0.3325 9 P 0 ;1
L 4.7325 0.3825 4.7325 0.3825 9 P 0 ;1
L 4.7325 0.4325 4.7325 0.4325 9 P 0 ;1
L 4.7325 0.4825 4.7325 0.4825 9 P 0 ;1
L 4.7325 0.5325 4.7325 0.5325 9 P 0 ;1
L 4.7325 0.5825 4.7325 0.5825 9 P 0 ;1
L 4.7325 0.6325 4.7325 0.6325 9 P 0 ;1
L 4.7325 0.6825 4.7325 0.6825 9 P 0 ;1
L 4.7325 0.7325 4.7325 0.7325 9 P 0 ;1
L 4.7325 0.9325 4.7325 0.9325 9 P 0 ;1
L 4.7325 0.9825 4.7325 0.9825 9 P 0 ;1
L 4.7325 4.4325 4.7325 4.4325 9 P 0 ;1
L 4.7325 4.4825 4.7325 4.4825 9 P 0 ;1
L 4.7325 4.5325 4.7325 4.5325 9 P 0 ;1
L 4.7325 5.2325 4.7325 5.2325 9 P 0 ;1
L 4.7325 5.2825 4.7325 5.2825 9 P 0 ;1
L 4.7325 5.6325 4.7325 5.6325 9 P 0 ;1
L 4.7325 5.6825 4.7325 5.6825 9 P 0 ;1
L 4.7325 5.7325 4.7325 5.7325 9 P 0 ;1
L 4.7325 5.7825 4.7325 5.7825 9 P 0 ;1
L 4.7325 5.8325 4.7325 5.8325 9 P 0 ;1
L 4.7325 5.8825 4.7325 5.8825 9 P 0 ;1
L 4.7825 0.4825 4.7825 0.4825 9 P 0 ;1
L 4.7825 0.5325 4.7825 0.5325 9 P 0 ;1
L 4.7825 0.5825 4.7825 0.5825 9 P 0 ;1
L 4.7825 0.6325 4.7825 0.6325 9 P 0 ;1
L 4.7825 0.6825 4.7825 0.6825 9 P 0 ;1
L 4.7825 0.7325 4.7825 0.7325 9 P 0 ;1
L 4.7825 0.9825 4.7825 0.9825 9 P 0 ;1
L 4.7825 4.4325 4.7825 4.4325 9 P 0 ;1
L 4.7825 4.4825 4.7825 4.4825 9 P 0 ;1
L 4.7825 4.5325 4.7825 4.5325 9 P 0 ;1
L 4.7825 5.2325 4.7825 5.2325 9 P 0 ;1
L 4.7825 5.2825 4.7825 5.2825 9 P 0 ;1
L 4.7825 5.4825 4.7825 5.4825 9 P 0 ;1
L 4.7825 5.5325 4.7825 5.5325 9 P 0 ;1
L 4.7825 5.5825 4.7825 5.5825 9 P 0 ;1
L 4.7825 5.6325 4.7825 5.6325 9 P 0 ;1
L 4.7825 5.6825 4.7825 5.6825 9 P 0 ;1
L 4.7825 5.7325 4.7825 5.7325 9 P 0 ;1
L 4.7825 5.7825 4.7825 5.7825 9 P 0 ;1
L 4.7825 5.8325 4.7825 5.8325 9 P 0 ;1
L 4.7825 5.8825 4.7825 5.8825 9 P 0 ;1
L 4.8325 0.5325 4.8325 0.5325 9 P 0 ;1
L 4.8325 0.5825 4.8325 0.5825 9 P 0 ;1
L 4.8325 0.6325 4.8325 0.6325 9 P 0 ;1
L 4.8325 0.6825 4.8325 0.6825 9 P 0 ;1
L 4.8325 0.7325 4.8325 0.7325 9 P 0 ;1
L 4.8325 0.7825 4.8325 0.7825 9 P 0 ;1
L 4.8325 4.4325 4.8325 4.4325 9 P 0 ;1
L 4.8325 4.4825 4.8325 4.4825 9 P 0 ;1
L 4.8325 4.5325 4.8325 4.5325 9 P 0 ;1
L 4.8325 4.5825 4.8325 4.5825 9 P 0 ;1
L 4.8325 5.2325 4.8325 5.2325 9 P 0 ;1
L 4.8325 5.2825 4.8325 5.2825 9 P 0 ;1
L 4.8325 5.4825 4.8325 5.4825 9 P 0 ;1
L 4.8325 5.5325 4.8325 5.5325 9 P 0 ;1
L 4.8325 5.5825 4.8325 5.5825 9 P 0 ;1
L 4.8325 5.6325 4.8325 5.6325 9 P 0 ;1
L 4.8325 5.6825 4.8325 5.6825 9 P 0 ;1
L 4.8325 5.8325 4.8325 5.8325 9 P 0 ;1
L 4.8325 5.8825 4.8325 5.8825 9 P 0 ;1
L 4.8825 0.5825 4.8825 0.5825 9 P 0 ;1
L 4.8825 0.6325 4.8825 0.6325 9 P 0 ;1
L 4.8825 0.6825 4.8825 0.6825 9 P 0 ;1
L 4.8825 0.7325 4.8825 0.7325 9 P 0 ;1
L 4.8825 0.7825 4.8825 0.7825 9 P 0 ;1
L 4.8825 0.8325 4.8825 0.8325 9 P 0 ;1
L 4.8825 4.4325 4.8825 4.4325 9 P 0 ;1
L 4.8825 4.4825 4.8825 4.4825 9 P 0 ;1
L 4.8825 4.5325 4.8825 4.5325 9 P 0 ;1
L 4.8825 4.5825 4.8825 4.5825 9 P 0 ;1
L 4.8825 5.2325 4.8825 5.2325 9 P 0 ;1
L 4.8825 5.2825 4.8825 5.2825 9 P 0 ;1
L 4.8825 5.4825 4.8825 5.4825 9 P 0 ;1
L 4.8825 5.5325 4.8825 5.5325 9 P 0 ;1
L 4.8825 5.5825 4.8825 5.5825 9 P 0 ;1
L 4.8825 5.8825 4.8825 5.8825 9 P 0 ;1
L 4.9325 0.5825 4.9325 0.5825 9 P 0 ;1
L 4.9325 0.6325 4.9325 0.6325 9 P 0 ;1
L 4.9325 0.6825 4.9325 0.6825 9 P 0 ;1
L 4.9325 0.7325 4.9325 0.7325 9 P 0 ;1
L 4.9325 0.7825 4.9325 0.7825 9 P 0 ;1
L 4.9325 0.8325 4.9325 0.8325 9 P 0 ;1
L 4.9325 4.4325 4.9325 4.4325 9 P 0 ;1
L 4.9325 4.4825 4.9325 4.4825 9 P 0 ;1
L 4.9325 4.5325 4.9325 4.5325 9 P 0 ;1
L 4.9325 4.5825 4.9325 4.5825 9 P 0 ;1
L 4.9325 4.6325 4.9325 4.6325 9 P 0 ;1
L 4.9325 5.2325 4.9325 5.2325 9 P 0 ;1
L 4.9325 5.2825 4.9325 5.2825 9 P 0 ;1
L 4.9325 5.5825 4.9325 5.5825 9 P 0 ;1
L 4.9325 5.8825 4.9325 5.8825 9 P 0 ;1
L 4.9825 0.5825 4.9825 0.5825 9 P 0 ;1
L 4.9825 0.6325 4.9825 0.6325 9 P 0 ;1
L 4.9825 0.6825 4.9825 0.6825 9 P 0 ;1
L 4.9825 0.7325 4.9825 0.7325 9 P 0 ;1
L 4.9825 0.7825 4.9825 0.7825 9 P 0 ;1
L 4.9825 0.8325 4.9825 0.8325 9 P 0 ;1
L 4.9825 0.8825 4.9825 0.8825 9 P 0 ;1
L 4.9825 4.3825 4.9825 4.3825 9 P 0 ;1
L 4.9825 4.4325 4.9825 4.4325 9 P 0 ;1
L 4.9825 4.4825 4.9825 4.4825 9 P 0 ;1
L 4.9825 4.5325 4.9825 4.5325 9 P 0 ;1
L 4.9825 4.5825 4.9825 4.5825 9 P 0 ;1
L 4.9825 5.2825 4.9825 5.2825 9 P 0 ;1
L 4.9825 5.7825 4.9825 5.7825 9 P 0 ;1
L 4.9825 5.8325 4.9825 5.8325 9 P 0 ;1
L 4.9825 5.8825 4.9825 5.8825 9 P 0 ;1
L 5.0325 0.5825 5.0325 0.5825 9 P 0 ;1
L 5.0325 0.6325 5.0325 0.6325 9 P 0 ;1
L 5.0325 0.6825 5.0325 0.6825 9 P 0 ;1
L 5.0325 0.7325 5.0325 0.7325 9 P 0 ;1
L 5.0325 0.7825 5.0325 0.7825 9 P 0 ;1
L 5.0325 0.8325 5.0325 0.8325 9 P 0 ;1
L 5.0325 0.8825 5.0325 0.8825 9 P 0 ;1
L 5.0325 0.9325 5.0325 0.9325 9 P 0 ;1
L 5.0325 1.5825 5.0325 1.5825 9 P 0 ;1
L 5.0325 1.6325 5.0325 1.6325 9 P 0 ;1
L 5.0325 4.0825 5.0325 4.0825 9 P 0 ;1
L 5.0325 4.1325 5.0325 4.1325 9 P 0 ;1
L 5.0325 4.1825 5.0325 4.1825 9 P 0 ;1
L 5.0325 4.2825 5.0325 4.2825 9 P 0 ;1
L 5.0325 4.3325 5.0325 4.3325 9 P 0 ;1
L 5.0325 4.3825 5.0325 4.3825 9 P 0 ;1
L 5.0325 4.4325 5.0325 4.4325 9 P 0 ;1
L 5.0325 4.4825 5.0325 4.4825 9 P 0 ;1
L 5.0325 4.5325 5.0325 4.5325 9 P 0 ;1
L 5.0325 4.5825 5.0325 4.5825 9 P 0 ;1
L 5.0325 5.2825 5.0325 5.2825 9 P 0 ;1
L 5.0325 5.6825 5.0325 5.6825 9 P 0 ;1
L 5.0325 5.8325 5.0325 5.8325 9 P 0 ;1
L 5.0325 5.8825 5.0325 5.8825 9 P 0 ;1
L 5.0825 0.5825 5.0825 0.5825 9 P 0 ;1
L 5.0825 0.6325 5.0825 0.6325 9 P 0 ;1
L 5.0825 0.6825 5.0825 0.6825 9 P 0 ;1
L 5.0825 0.7325 5.0825 0.7325 9 P 0 ;1
L 5.0825 0.7825 5.0825 0.7825 9 P 0 ;1
L 5.0825 0.8325 5.0825 0.8325 9 P 0 ;1
L 5.0825 0.8825 5.0825 0.8825 9 P 0 ;1
L 5.0825 0.9325 5.0825 0.9325 9 P 0 ;1
L 5.0825 0.9825 5.0825 0.9825 9 P 0 ;1
L 5.0825 4.0825 5.0825 4.0825 9 P 0 ;1
L 5.0825 4.1325 5.0825 4.1325 9 P 0 ;1
L 5.0825 4.1825 5.0825 4.1825 9 P 0 ;1
L 5.0825 4.2325 5.0825 4.2325 9 P 0 ;1
L 5.0825 4.2825 5.0825 4.2825 9 P 0 ;1
L 5.0825 4.3325 5.0825 4.3325 9 P 0 ;1
L 5.0825 4.3825 5.0825 4.3825 9 P 0 ;1
L 5.0825 4.4325 5.0825 4.4325 9 P 0 ;1
L 5.0825 4.4825 5.0825 4.4825 9 P 0 ;1
L 5.0825 4.5325 5.0825 4.5325 9 P 0 ;1
L 5.0825 4.5825 5.0825 4.5825 9 P 0 ;1
L 5.0825 5.2825 5.0825 5.2825 9 P 0 ;1
L 5.0825 5.4825 5.0825 5.4825 9 P 0 ;1
L 5.0825 5.5325 5.0825 5.5325 9 P 0 ;1
L 5.0825 5.6825 5.0825 5.6825 9 P 0 ;1
L 5.0825 5.8825 5.0825 5.8825 9 P 0 ;1
L 5.1325 0.5825 5.1325 0.5825 9 P 0 ;1
L 5.1325 0.6325 5.1325 0.6325 9 P 0 ;1
L 5.1325 0.6825 5.1325 0.6825 9 P 0 ;1
L 5.1325 0.7325 5.1325 0.7325 9 P 0 ;1
L 5.1325 0.7825 5.1325 0.7825 9 P 0 ;1
L 5.1325 0.8325 5.1325 0.8325 9 P 0 ;1
L 5.1325 0.8825 5.1325 0.8825 9 P 0 ;1
L 5.1325 0.9325 5.1325 0.9325 9 P 0 ;1
L 5.1325 0.9825 5.1325 0.9825 9 P 0 ;1
L 5.1325 4.0825 5.1325 4.0825 9 P 0 ;1
L 5.1325 4.1325 5.1325 4.1325 9 P 0 ;1
L 5.1325 4.1825 5.1325 4.1825 9 P 0 ;1
L 5.1325 4.2325 5.1325 4.2325 9 P 0 ;1
L 5.1325 4.2825 5.1325 4.2825 9 P 0 ;1
L 5.1325 4.3325 5.1325 4.3325 9 P 0 ;1
L 5.1325 4.3825 5.1325 4.3825 9 P 0 ;1
L 5.1325 4.4325 5.1325 4.4325 9 P 0 ;1
L 5.1325 4.4825 5.1325 4.4825 9 P 0 ;1
L 5.1325 4.5325 5.1325 4.5325 9 P 0 ;1
L 5.1325 4.5825 5.1325 4.5825 9 P 0 ;1
L 5.1325 5.2825 5.1325 5.2825 9 P 0 ;1
L 5.1325 5.8825 5.1325 5.8825 9 P 0 ;1
L 5.1825 0.5825 5.1825 0.5825 9 P 0 ;1
L 5.1825 0.6325 5.1825 0.6325 9 P 0 ;1
L 5.1825 0.6825 5.1825 0.6825 9 P 0 ;1
L 5.1825 0.7325 5.1825 0.7325 9 P 0 ;1
L 5.1825 0.7825 5.1825 0.7825 9 P 0 ;1
L 5.1825 0.8325 5.1825 0.8325 9 P 0 ;1
L 5.1825 0.8825 5.1825 0.8825 9 P 0 ;1
L 5.1825 0.9325 5.1825 0.9325 9 P 0 ;1
L 5.1825 0.9825 5.1825 0.9825 9 P 0 ;1
L 5.1825 1.0325 5.1825 1.0325 9 P 0 ;1
L 5.1825 2.3325 5.1825 2.3325 9 P 0 ;1
L 5.1825 2.3825 5.1825 2.3825 9 P 0 ;1
L 5.1825 2.4325 5.1825 2.4325 9 P 0 ;1
L 5.1825 2.4825 5.1825 2.4825 9 P 0 ;1
L 5.1825 2.5325 5.1825 2.5325 9 P 0 ;1
L 5.1825 2.5825 5.1825 2.5825 9 P 0 ;1
L 5.1825 4.0325 5.1825 4.0325 9 P 0 ;1
L 5.1825 4.0825 5.1825 4.0825 9 P 0 ;1
L 5.1825 4.1325 5.1825 4.1325 9 P 0 ;1
L 5.1825 4.1825 5.1825 4.1825 9 P 0 ;1
L 5.1825 4.2325 5.1825 4.2325 9 P 0 ;1
L 5.1825 4.2825 5.1825 4.2825 9 P 0 ;1
L 5.1825 4.3325 5.1825 4.3325 9 P 0 ;1
L 5.1825 4.3825 5.1825 4.3825 9 P 0 ;1
L 5.1825 4.4325 5.1825 4.4325 9 P 0 ;1
L 5.1825 4.4825 5.1825 4.4825 9 P 0 ;1
L 5.1825 4.5325 5.1825 4.5325 9 P 0 ;1
L 5.1825 4.5825 5.1825 4.5825 9 P 0 ;1
L 5.1825 5.2825 5.1825 5.2825 9 P 0 ;1
L 5.1825 5.3325 5.1825 5.3325 9 P 0 ;1
L 5.1825 5.7325 5.1825 5.7325 9 P 0 ;1
L 5.1825 5.7825 5.1825 5.7825 9 P 0 ;1
L 5.1825 5.8325 5.1825 5.8325 9 P 0 ;1
L 5.1825 5.8825 5.1825 5.8825 9 P 0 ;1
L 5.2325 0.5825 5.2325 0.5825 9 P 0 ;1
L 5.2325 0.6325 5.2325 0.6325 9 P 0 ;1
L 5.2325 0.6825 5.2325 0.6825 9 P 0 ;1
L 5.2325 0.7325 5.2325 0.7325 9 P 0 ;1
L 5.2325 0.7825 5.2325 0.7825 9 P 0 ;1
L 5.2325 0.8325 5.2325 0.8325 9 P 0 ;1
L 5.2325 0.8825 5.2325 0.8825 9 P 0 ;1
L 5.2325 0.9325 5.2325 0.9325 9 P 0 ;1
L 5.2325 0.9825 5.2325 0.9825 9 P 0 ;1
L 5.2325 1.0325 5.2325 1.0325 9 P 0 ;1
L 5.2325 1.0825 5.2325 1.0825 9 P 0 ;1
L 5.2325 2.4325 5.2325 2.4325 9 P 0 ;1
L 5.2325 2.4825 5.2325 2.4825 9 P 0 ;1
L 5.2325 4.0325 5.2325 4.0325 9 P 0 ;1
L 5.2325 4.0825 5.2325 4.0825 9 P 0 ;1
L 5.2325 4.1325 5.2325 4.1325 9 P 0 ;1
L 5.2325 4.1825 5.2325 4.1825 9 P 0 ;1
L 5.2325 4.2325 5.2325 4.2325 9 P 0 ;1
L 5.2325 4.2825 5.2325 4.2825 9 P 0 ;1
L 5.2325 4.3325 5.2325 4.3325 9 P 0 ;1
L 5.2325 4.3825 5.2325 4.3825 9 P 0 ;1
L 5.2325 4.4325 5.2325 4.4325 9 P 0 ;1
L 5.2325 4.4825 5.2325 4.4825 9 P 0 ;1
L 5.2325 4.5325 5.2325 4.5325 9 P 0 ;1
L 5.2325 4.5825 5.2325 4.5825 9 P 0 ;1
L 5.2325 5.2825 5.2325 5.2825 9 P 0 ;1
L 5.2325 5.3325 5.2325 5.3325 9 P 0 ;1
L 5.2325 5.3825 5.2325 5.3825 9 P 0 ;1
L 5.2325 5.4325 5.2325 5.4325 9 P 0 ;1
L 5.2325 5.4825 5.2325 5.4825 9 P 0 ;1
L 5.2325 5.6825 5.2325 5.6825 9 P 0 ;1
L 5.2325 5.7325 5.2325 5.7325 9 P 0 ;1
L 5.2325 5.7825 5.2325 5.7825 9 P 0 ;1
L 5.2325 5.8325 5.2325 5.8325 9 P 0 ;1
L 5.2325 5.8825 5.2325 5.8825 9 P 0 ;1
L 5.2825 0.5825 5.2825 0.5825 9 P 0 ;1
L 5.2825 0.6325 5.2825 0.6325 9 P 0 ;1
L 5.2825 0.6825 5.2825 0.6825 9 P 0 ;1
L 5.2825 0.7325 5.2825 0.7325 9 P 0 ;1
L 5.2825 0.7825 5.2825 0.7825 9 P 0 ;1
L 5.2825 0.8325 5.2825 0.8325 9 P 0 ;1
L 5.2825 0.8825 5.2825 0.8825 9 P 0 ;1
L 5.2825 0.9325 5.2825 0.9325 9 P 0 ;1
L 5.2825 0.9825 5.2825 0.9825 9 P 0 ;1
L 5.2825 1.0325 5.2825 1.0325 9 P 0 ;1
L 5.2825 1.0825 5.2825 1.0825 9 P 0 ;1
L 5.2825 3.3825 5.2825 3.3825 9 P 0 ;1
L 5.2825 3.9325 5.2825 3.9325 9 P 0 ;1
L 5.2825 3.9825 5.2825 3.9825 9 P 0 ;1
L 5.2825 4.0325 5.2825 4.0325 9 P 0 ;1
L 5.2825 4.0825 5.2825 4.0825 9 P 0 ;1
L 5.2825 4.1325 5.2825 4.1325 9 P 0 ;1
L 5.2825 4.1825 5.2825 4.1825 9 P 0 ;1
L 5.2825 4.2325 5.2825 4.2325 9 P 0 ;1
L 5.2825 4.2825 5.2825 4.2825 9 P 0 ;1
L 5.2825 4.3325 5.2825 4.3325 9 P 0 ;1
L 5.2825 4.3825 5.2825 4.3825 9 P 0 ;1
L 5.2825 4.4325 5.2825 4.4325 9 P 0 ;1
L 5.2825 4.4825 5.2825 4.4825 9 P 0 ;1
L 5.2825 4.5325 5.2825 4.5325 9 P 0 ;1
L 5.2825 4.5825 5.2825 4.5825 9 P 0 ;1
L 5.2825 4.6325 5.2825 4.6325 9 P 0 ;1
L 5.2825 4.6825 5.2825 4.6825 9 P 0 ;1
L 5.2825 4.7325 5.2825 4.7325 9 P 0 ;1
L 5.2825 4.7825 5.2825 4.7825 9 P 0 ;1
L 5.2825 4.8325 5.2825 4.8325 9 P 0 ;1
L 5.2825 5.2325 5.2825 5.2325 9 P 0 ;1
L 5.2825 5.2825 5.2825 5.2825 9 P 0 ;1
L 5.2825 5.3325 5.2825 5.3325 9 P 0 ;1
L 5.2825 5.3825 5.2825 5.3825 9 P 0 ;1
L 5.2825 5.4325 5.2825 5.4325 9 P 0 ;1
L 5.2825 5.4825 5.2825 5.4825 9 P 0 ;1
L 5.2825 5.5325 5.2825 5.5325 9 P 0 ;1
L 5.2825 5.5825 5.2825 5.5825 9 P 0 ;1
L 5.2825 5.6325 5.2825 5.6325 9 P 0 ;1
L 5.2825 5.6825 5.2825 5.6825 9 P 0 ;1
L 5.2825 5.7325 5.2825 5.7325 9 P 0 ;1
L 5.2825 5.7825 5.2825 5.7825 9 P 0 ;1
L 5.2825 5.8325 5.2825 5.8325 9 P 0 ;1
L 5.2825 5.8825 5.2825 5.8825 9 P 0 ;1
L 5.3325 0.5825 5.3325 0.5825 9 P 0 ;1
L 5.3325 0.6325 5.3325 0.6325 9 P 0 ;1
L 5.3325 0.6825 5.3325 0.6825 9 P 0 ;1
L 5.3325 0.7325 5.3325 0.7325 9 P 0 ;1
L 5.3325 0.7825 5.3325 0.7825 9 P 0 ;1
L 5.3325 0.8325 5.3325 0.8325 9 P 0 ;1
L 5.3325 0.8825 5.3325 0.8825 9 P 0 ;1
L 5.3325 0.9325 5.3325 0.9325 9 P 0 ;1
L 5.3325 0.9825 5.3325 0.9825 9 P 0 ;1
L 5.3325 1.0325 5.3325 1.0325 9 P 0 ;1
L 5.3325 1.0825 5.3325 1.0825 9 P 0 ;1
L 5.3325 1.1325 5.3325 1.1325 9 P 0 ;1
L 5.3325 3.3825 5.3325 3.3825 9 P 0 ;1
L 5.3325 3.4325 5.3325 3.4325 9 P 0 ;1
L 5.3325 3.4825 5.3325 3.4825 9 P 0 ;1
L 5.3325 3.5325 5.3325 3.5325 9 P 0 ;1
L 5.3325 3.5825 5.3325 3.5825 9 P 0 ;1
L 5.3325 3.6325 5.3325 3.6325 9 P 0 ;1
L 5.3325 3.6825 5.3325 3.6825 9 P 0 ;1
L 5.3325 3.7825 5.3325 3.7825 9 P 0 ;1
L 5.3325 3.8325 5.3325 3.8325 9 P 0 ;1
L 5.3325 3.8825 5.3325 3.8825 9 P 0 ;1
L 5.3325 3.9325 5.3325 3.9325 9 P 0 ;1
L 5.3325 3.9825 5.3325 3.9825 9 P 0 ;1
L 5.3325 4.0325 5.3325 4.0325 9 P 0 ;1
L 5.3325 4.0825 5.3325 4.0825 9 P 0 ;1
L 5.3325 4.1325 5.3325 4.1325 9 P 0 ;1
L 5.3325 4.1825 5.3325 4.1825 9 P 0 ;1
L 5.3325 4.2325 5.3325 4.2325 9 P 0 ;1
L 5.3325 4.2825 5.3325 4.2825 9 P 0 ;1
L 5.3325 4.3325 5.3325 4.3325 9 P 0 ;1
L 5.3325 4.3825 5.3325 4.3825 9 P 0 ;1
L 5.3325 4.4325 5.3325 4.4325 9 P 0 ;1
L 5.3325 4.4825 5.3325 4.4825 9 P 0 ;1
L 5.3325 4.5325 5.3325 4.5325 9 P 0 ;1
L 5.3325 4.5825 5.3325 4.5825 9 P 0 ;1
L 5.3325 4.6325 5.3325 4.6325 9 P 0 ;1
L 5.3325 4.6825 5.3325 4.6825 9 P 0 ;1
L 5.3325 4.7325 5.3325 4.7325 9 P 0 ;1
L 5.3325 4.7825 5.3325 4.7825 9 P 0 ;1
L 5.3325 4.8325 5.3325 4.8325 9 P 0 ;1
L 5.3325 4.8825 5.3325 4.8825 9 P 0 ;1
L 5.3325 4.9325 5.3325 4.9325 9 P 0 ;1
L 5.3325 4.9825 5.3325 4.9825 9 P 0 ;1
L 5.3325 5.0325 5.3325 5.0325 9 P 0 ;1
L 5.3325 5.0825 5.3325 5.0825 9 P 0 ;1
L 5.3325 5.1325 5.3325 5.1325 9 P 0 ;1
L 5.3325 5.1825 5.3325 5.1825 9 P 0 ;1
L 5.3325 5.2325 5.3325 5.2325 9 P 0 ;1
L 5.3325 5.2825 5.3325 5.2825 9 P 0 ;1
L 5.3325 5.3325 5.3325 5.3325 9 P 0 ;1
L 5.3325 5.3825 5.3325 5.3825 9 P 0 ;1
L 5.3325 5.4325 5.3325 5.4325 9 P 0 ;1
L 5.3325 5.4825 5.3325 5.4825 9 P 0 ;1
L 5.3325 5.5325 5.3325 5.5325 9 P 0 ;1
L 5.3325 5.5825 5.3325 5.5825 9 P 0 ;1
L 5.3325 5.6325 5.3325 5.6325 9 P 0 ;1
L 5.3325 5.6825 5.3325 5.6825 9 P 0 ;1
L 5.3325 5.7325 5.3325 5.7325 9 P 0 ;1
L 5.3325 5.7825 5.3325 5.7825 9 P 0 ;1
L 5.3325 5.8325 5.3325 5.8325 9 P 0 ;1
L 5.3325 5.8825 5.3325 5.8825 9 P 0 ;1
L 5.3825 0.5825 5.3825 0.5825 9 P 0 ;1
L 5.3825 0.6325 5.3825 0.6325 9 P 0 ;1
L 5.3825 0.6825 5.3825 0.6825 9 P 0 ;1
L 5.3825 0.7325 5.3825 0.7325 9 P 0 ;1
L 5.3825 0.7825 5.3825 0.7825 9 P 0 ;1
L 5.3825 0.8325 5.3825 0.8325 9 P 0 ;1
L 5.3825 0.8825 5.3825 0.8825 9 P 0 ;1
L 5.3825 0.9325 5.3825 0.9325 9 P 0 ;1
L 5.3825 0.9825 5.3825 0.9825 9 P 0 ;1
L 5.3825 1.0325 5.3825 1.0325 9 P 0 ;1
L 5.3825 1.0825 5.3825 1.0825 9 P 0 ;1
L 5.3825 1.1325 5.3825 1.1325 9 P 0 ;1
L 5.3825 1.1825 5.3825 1.1825 9 P 0 ;1
L 5.3825 2.8825 5.3825 2.8825 9 P 0 ;1
L 5.3825 3.3825 5.3825 3.3825 9 P 0 ;1
L 5.3825 3.4325 5.3825 3.4325 9 P 0 ;1
L 5.3825 3.4825 5.3825 3.4825 9 P 0 ;1
L 5.3825 3.5325 5.3825 3.5325 9 P 0 ;1
L 5.3825 3.5825 5.3825 3.5825 9 P 0 ;1
L 5.3825 3.6325 5.3825 3.6325 9 P 0 ;1
L 5.3825 3.6825 5.3825 3.6825 9 P 0 ;1
L 5.3825 3.7325 5.3825 3.7325 9 P 0 ;1
L 5.3825 3.7825 5.3825 3.7825 9 P 0 ;1
L 5.3825 3.8325 5.3825 3.8325 9 P 0 ;1
L 5.3825 3.8825 5.3825 3.8825 9 P 0 ;1
L 5.3825 3.9325 5.3825 3.9325 9 P 0 ;1
L 5.3825 3.9825 5.3825 3.9825 9 P 0 ;1
L 5.3825 4.0325 5.3825 4.0325 9 P 0 ;1
L 5.3825 4.0825 5.3825 4.0825 9 P 0 ;1
L 5.3825 4.1325 5.3825 4.1325 9 P 0 ;1
L 5.3825 4.1825 5.3825 4.1825 9 P 0 ;1
L 5.3825 4.2325 5.3825 4.2325 9 P 0 ;1
L 5.3825 4.2825 5.3825 4.2825 9 P 0 ;1
L 5.3825 4.3325 5.3825 4.3325 9 P 0 ;1
L 5.3825 4.3825 5.3825 4.3825 9 P 0 ;1
L 5.3825 4.4325 5.3825 4.4325 9 P 0 ;1
L 5.3825 4.4825 5.3825 4.4825 9 P 0 ;1
L 5.3825 4.5325 5.3825 4.5325 9 P 0 ;1
L 5.3825 4.5825 5.3825 4.5825 9 P 0 ;1
L 5.3825 4.6325 5.3825 4.6325 9 P 0 ;1
L 5.3825 4.6825 5.3825 4.6825 9 P 0 ;1
L 5.3825 4.7325 5.3825 4.7325 9 P 0 ;1
L 5.3825 4.7825 5.3825 4.7825 9 P 0 ;1
L 5.3825 4.8325 5.3825 4.8325 9 P 0 ;1
L 5.3825 4.8825 5.3825 4.8825 9 P 0 ;1
L 5.3825 4.9325 5.3825 4.9325 9 P 0 ;1
L 5.3825 4.9825 5.3825 4.9825 9 P 0 ;1
L 5.3825 5.0325 5.3825 5.0325 9 P 0 ;1
L 5.3825 5.0825 5.3825 5.0825 9 P 0 ;1
L 5.3825 5.1325 5.3825 5.1325 9 P 0 ;1
L 5.3825 5.1825 5.3825 5.1825 9 P 0 ;1
L 5.3825 5.2325 5.3825 5.2325 9 P 0 ;1
L 5.3825 5.2825 5.3825 5.2825 9 P 0 ;1
L 5.3825 5.3325 5.3825 5.3325 9 P 0 ;1
L 5.3825 5.3825 5.3825 5.3825 9 P 0 ;1
L 5.3825 5.4325 5.3825 5.4325 9 P 0 ;1
L 5.3825 5.4825 5.3825 5.4825 9 P 0 ;1
L 5.3825 5.5325 5.3825 5.5325 9 P 0 ;1
L 5.3825 5.5825 5.3825 5.5825 9 P 0 ;1
L 5.3825 5.6325 5.3825 5.6325 9 P 0 ;1
L 5.3825 5.6825 5.3825 5.6825 9 P 0 ;1
L 5.3825 5.7325 5.3825 5.7325 9 P 0 ;1
L 5.3825 5.7825 5.3825 5.7825 9 P 0 ;1
L 5.3825 5.8325 5.3825 5.8325 9 P 0 ;1
L 5.3825 5.8825 5.3825 5.8825 9 P 0 ;1
L 5.4325 0.5825 5.4325 0.5825 9 P 0 ;1
L 5.4325 0.6325 5.4325 0.6325 9 P 0 ;1
L 5.4325 0.6825 5.4325 0.6825 9 P 0 ;1
L 5.4325 0.7325 5.4325 0.7325 9 P 0 ;1
L 5.4325 0.7825 5.4325 0.7825 9 P 0 ;1
L 5.4325 0.8325 5.4325 0.8325 9 P 0 ;1
L 5.4325 0.8825 5.4325 0.8825 9 P 0 ;1
L 5.4325 0.9325 5.4325 0.9325 9 P 0 ;1
L 5.4325 0.9825 5.4325 0.9825 9 P 0 ;1
L 5.4325 1.0325 5.4325 1.0325 9 P 0 ;1
L 5.4325 1.0825 5.4325 1.0825 9 P 0 ;1
L 5.4325 1.1325 5.4325 1.1325 9 P 0 ;1
L 5.4325 1.1825 5.4325 1.1825 9 P 0 ;1
L 5.4325 3.3825 5.4325 3.3825 9 P 0 ;1
L 5.4325 3.4325 5.4325 3.4325 9 P 0 ;1
L 5.4325 3.4825 5.4325 3.4825 9 P 0 ;1
L 5.4325 3.5325 5.4325 3.5325 9 P 0 ;1
L 5.4325 3.5825 5.4325 3.5825 9 P 0 ;1
L 5.4325 3.6325 5.4325 3.6325 9 P 0 ;1
L 5.4325 3.6825 5.4325 3.6825 9 P 0 ;1
L 5.4325 3.7325 5.4325 3.7325 9 P 0 ;1
L 5.4325 3.7825 5.4325 3.7825 9 P 0 ;1
L 5.4325 3.8325 5.4325 3.8325 9 P 0 ;1
L 5.4325 3.8825 5.4325 3.8825 9 P 0 ;1
L 5.4325 3.9325 5.4325 3.9325 9 P 0 ;1
L 5.4325 3.9825 5.4325 3.9825 9 P 0 ;1
L 5.4325 4.0325 5.4325 4.0325 9 P 0 ;1
L 5.4325 4.0825 5.4325 4.0825 9 P 0 ;1
L 5.4325 4.1325 5.4325 4.1325 9 P 0 ;1
L 5.4325 4.1825 5.4325 4.1825 9 P 0 ;1
L 5.4325 4.2325 5.4325 4.2325 9 P 0 ;1
L 5.4325 4.2825 5.4325 4.2825 9 P 0 ;1
L 5.4325 4.3325 5.4325 4.3325 9 P 0 ;1
L 5.4325 4.3825 5.4325 4.3825 9 P 0 ;1
L 5.4325 4.4325 5.4325 4.4325 9 P 0 ;1
L 5.4325 4.4825 5.4325 4.4825 9 P 0 ;1
L 5.4325 4.5325 5.4325 4.5325 9 P 0 ;1
L 5.4325 4.5825 5.4325 4.5825 9 P 0 ;1
L 5.4325 4.6325 5.4325 4.6325 9 P 0 ;1
L 5.4325 4.6825 5.4325 4.6825 9 P 0 ;1
L 5.4325 4.7325 5.4325 4.7325 9 P 0 ;1
L 5.4325 4.7825 5.4325 4.7825 9 P 0 ;1
L 5.4325 4.8325 5.4325 4.8325 9 P 0 ;1
L 5.4325 4.8825 5.4325 4.8825 9 P 0 ;1
L 5.4325 4.9325 5.4325 4.9325 9 P 0 ;1
L 5.4325 4.9825 5.4325 4.9825 9 P 0 ;1
L 5.4325 5.0325 5.4325 5.0325 9 P 0 ;1
L 5.4325 5.0825 5.4325 5.0825 9 P 0 ;1
L 5.4325 5.1325 5.4325 5.1325 9 P 0 ;1
L 5.4325 5.1825 5.4325 5.1825 9 P 0 ;1
L 5.4325 5.2325 5.4325 5.2325 9 P 0 ;1
L 5.4325 5.2825 5.4325 5.2825 9 P 0 ;1
L 5.4325 5.3325 5.4325 5.3325 9 P 0 ;1
L 5.4325 5.3825 5.4325 5.3825 9 P 0 ;1
L 5.4325 5.4325 5.4325 5.4325 9 P 0 ;1
L 5.4325 5.4825 5.4325 5.4825 9 P 0 ;1
L 5.4325 5.5325 5.4325 5.5325 9 P 0 ;1
L 5.4325 5.5825 5.4325 5.5825 9 P 0 ;1
L 5.4325 5.6325 5.4325 5.6325 9 P 0 ;1
L 5.4325 5.6825 5.4325 5.6825 9 P 0 ;1
L 5.4325 5.7325 5.4325 5.7325 9 P 0 ;1
L 5.4325 5.7825 5.4325 5.7825 9 P 0 ;1
L 5.4325 5.8325 5.4325 5.8325 9 P 0 ;1
L 5.4325 5.8825 5.4325 5.8825 9 P 0 ;1
L 5.4825 0.5825 5.4825 0.5825 9 P 0 ;1
L 5.4825 0.6325 5.4825 0.6325 9 P 0 ;1
L 5.4825 0.6825 5.4825 0.6825 9 P 0 ;1
L 5.4825 0.7325 5.4825 0.7325 9 P 0 ;1
L 5.4825 0.7825 5.4825 0.7825 9 P 0 ;1
L 5.4825 0.8325 5.4825 0.8325 9 P 0 ;1
L 5.4825 0.8825 5.4825 0.8825 9 P 0 ;1
L 5.4825 0.9325 5.4825 0.9325 9 P 0 ;1
L 5.4825 0.9825 5.4825 0.9825 9 P 0 ;1
L 5.4825 1.0325 5.4825 1.0325 9 P 0 ;1
L 5.4825 1.0825 5.4825 1.0825 9 P 0 ;1
L 5.4825 1.1325 5.4825 1.1325 9 P 0 ;1
L 5.4825 1.1825 5.4825 1.1825 9 P 0 ;1
L 5.4825 1.2325 5.4825 1.2325 9 P 0 ;1
L 5.4825 2.8325 5.4825 2.8325 9 P 0 ;1
L 5.4825 3.3825 5.4825 3.3825 9 P 0 ;1
L 5.4825 3.4325 5.4825 3.4325 9 P 0 ;1
L 5.4825 3.4825 5.4825 3.4825 9 P 0 ;1
L 5.4825 3.5325 5.4825 3.5325 9 P 0 ;1
L 5.4825 3.5825 5.4825 3.5825 9 P 0 ;1
L 5.4825 3.6325 5.4825 3.6325 9 P 0 ;1
L 5.4825 3.6825 5.4825 3.6825 9 P 0 ;1
L 5.4825 3.7325 5.4825 3.7325 9 P 0 ;1
L 5.4825 3.7825 5.4825 3.7825 9 P 0 ;1
L 5.4825 3.8325 5.4825 3.8325 9 P 0 ;1
L 5.4825 3.8825 5.4825 3.8825 9 P 0 ;1
L 5.4825 3.9325 5.4825 3.9325 9 P 0 ;1
L 5.4825 3.9825 5.4825 3.9825 9 P 0 ;1
L 5.4825 4.0325 5.4825 4.0325 9 P 0 ;1
L 5.4825 4.0825 5.4825 4.0825 9 P 0 ;1
L 5.4825 4.1325 5.4825 4.1325 9 P 0 ;1
L 5.4825 4.1825 5.4825 4.1825 9 P 0 ;1
L 5.4825 4.2325 5.4825 4.2325 9 P 0 ;1
L 5.4825 4.2825 5.4825 4.2825 9 P 0 ;1
L 5.4825 4.3325 5.4825 4.3325 9 P 0 ;1
L 5.4825 4.3825 5.4825 4.3825 9 P 0 ;1
L 5.4825 4.4325 5.4825 4.4325 9 P 0 ;1
L 5.4825 4.4825 5.4825 4.4825 9 P 0 ;1
L 5.4825 4.6325 5.4825 4.6325 9 P 0 ;1
L 5.4825 4.6825 5.4825 4.6825 9 P 0 ;1
L 5.4825 4.7325 5.4825 4.7325 9 P 0 ;1
L 5.4825 4.7825 5.4825 4.7825 9 P 0 ;1
L 5.4825 4.8325 5.4825 4.8325 9 P 0 ;1
L 5.4825 4.8825 5.4825 4.8825 9 P 0 ;1
L 5.4825 4.9325 5.4825 4.9325 9 P 0 ;1
L 5.4825 4.9825 5.4825 4.9825 9 P 0 ;1
L 5.4825 5.0325 5.4825 5.0325 9 P 0 ;1
L 5.4825 5.0825 5.4825 5.0825 9 P 0 ;1
L 5.4825 5.1325 5.4825 5.1325 9 P 0 ;1
L 5.4825 5.1825 5.4825 5.1825 9 P 0 ;1
L 5.4825 5.2325 5.4825 5.2325 9 P 0 ;1
L 5.4825 5.2825 5.4825 5.2825 9 P 0 ;1
L 5.4825 5.3325 5.4825 5.3325 9 P 0 ;1
L 5.4825 5.3825 5.4825 5.3825 9 P 0 ;1
L 5.4825 5.4325 5.4825 5.4325 9 P 0 ;1
L 5.4825 5.4825 5.4825 5.4825 9 P 0 ;1
L 5.4825 5.5325 5.4825 5.5325 9 P 0 ;1
L 5.4825 5.5825 5.4825 5.5825 9 P 0 ;1
L 5.4825 5.6325 5.4825 5.6325 9 P 0 ;1
L 5.4825 5.6825 5.4825 5.6825 9 P 0 ;1
L 5.4825 5.7325 5.4825 5.7325 9 P 0 ;1
L 5.4825 5.7825 5.4825 5.7825 9 P 0 ;1
L 5.4825 5.8325 5.4825 5.8325 9 P 0 ;1
L 5.4825 5.8825 5.4825 5.8825 9 P 0 ;1
L 5.5325 0.5825 5.5325 0.5825 9 P 0 ;1
L 5.5325 0.6325 5.5325 0.6325 9 P 0 ;1
L 5.5325 0.6825 5.5325 0.6825 9 P 0 ;1
L 5.5325 0.7325 5.5325 0.7325 9 P 0 ;1
L 5.5325 0.7825 5.5325 0.7825 9 P 0 ;1
L 5.5325 0.8325 5.5325 0.8325 9 P 0 ;1
L 5.5325 0.8825 5.5325 0.8825 9 P 0 ;1
L 5.5325 0.9325 5.5325 0.9325 9 P 0 ;1
L 5.5325 0.9825 5.5325 0.9825 9 P 0 ;1
L 5.5325 1.0325 5.5325 1.0325 9 P 0 ;1
L 5.5325 1.0825 5.5325 1.0825 9 P 0 ;1
L 5.5325 1.1325 5.5325 1.1325 9 P 0 ;1
L 5.5325 1.1825 5.5325 1.1825 9 P 0 ;1
L 5.5325 1.2325 5.5325 1.2325 9 P 0 ;1
L 5.5325 1.2825 5.5325 1.2825 9 P 0 ;1
L 5.5325 3.0825 5.5325 3.0825 9 P 0 ;1
L 5.5325 3.1325 5.5325 3.1325 9 P 0 ;1
L 5.5325 3.1825 5.5325 3.1825 9 P 0 ;1
L 5.5325 3.2325 5.5325 3.2325 9 P 0 ;1
L 5.5325 3.2825 5.5325 3.2825 9 P 0 ;1
L 5.5325 3.3325 5.5325 3.3325 9 P 0 ;1
L 5.5325 3.3825 5.5325 3.3825 9 P 0 ;1
L 5.5325 3.4325 5.5325 3.4325 9 P 0 ;1
L 5.5325 3.4825 5.5325 3.4825 9 P 0 ;1
L 5.5325 3.5325 5.5325 3.5325 9 P 0 ;1
L 5.5325 3.5825 5.5325 3.5825 9 P 0 ;1
L 5.5325 3.6325 5.5325 3.6325 9 P 0 ;1
L 5.5325 3.6825 5.5325 3.6825 9 P 0 ;1
L 5.5325 3.7325 5.5325 3.7325 9 P 0 ;1
L 5.5325 3.7825 5.5325 3.7825 9 P 0 ;1
L 5.5325 3.8325 5.5325 3.8325 9 P 0 ;1
L 5.5325 3.8825 5.5325 3.8825 9 P 0 ;1
L 5.5325 3.9325 5.5325 3.9325 9 P 0 ;1
L 5.5325 3.9825 5.5325 3.9825 9 P 0 ;1
L 5.5325 4.0325 5.5325 4.0325 9 P 0 ;1
L 5.5325 4.0825 5.5325 4.0825 9 P 0 ;1
L 5.5325 4.1325 5.5325 4.1325 9 P 0 ;1
L 5.5325 4.1825 5.5325 4.1825 9 P 0 ;1
L 5.5325 4.2325 5.5325 4.2325 9 P 0 ;1
L 5.5325 4.2825 5.5325 4.2825 9 P 0 ;1
L 5.5325 4.3325 5.5325 4.3325 9 P 0 ;1
L 5.5325 4.3825 5.5325 4.3825 9 P 0 ;1
L 5.5325 4.4325 5.5325 4.4325 9 P 0 ;1
L 5.5325 4.8825 5.5325 4.8825 9 P 0 ;1
L 5.5325 4.9325 5.5325 4.9325 9 P 0 ;1
L 5.5325 4.9825 5.5325 4.9825 9 P 0 ;1
L 5.5325 5.0325 5.5325 5.0325 9 P 0 ;1
L 5.5325 5.0825 5.5325 5.0825 9 P 0 ;1
L 5.5325 5.1325 5.5325 5.1325 9 P 0 ;1
L 5.5325 5.1825 5.5325 5.1825 9 P 0 ;1
L 5.5325 5.2325 5.5325 5.2325 9 P 0 ;1
L 5.5325 5.2825 5.5325 5.2825 9 P 0 ;1
L 5.5325 5.3325 5.5325 5.3325 9 P 0 ;1
L 5.5325 5.5825 5.5325 5.5825 9 P 0 ;1
L 5.5325 5.6325 5.5325 5.6325 9 P 0 ;1
L 5.5325 5.6825 5.5325 5.6825 9 P 0 ;1
L 5.5325 5.7325 5.5325 5.7325 9 P 0 ;1
L 5.5325 5.7825 5.5325 5.7825 9 P 0 ;1
L 5.5325 5.8325 5.5325 5.8325 9 P 0 ;1
L 5.5325 5.8825 5.5325 5.8825 9 P 0 ;1
L 5.5825 0.5825 5.5825 0.5825 9 P 0 ;1
L 5.5825 0.6325 5.5825 0.6325 9 P 0 ;1
L 5.5825 0.6825 5.5825 0.6825 9 P 0 ;1
L 5.5825 0.7325 5.5825 0.7325 9 P 0 ;1
L 5.5825 0.7825 5.5825 0.7825 9 P 0 ;1
L 5.5825 0.8325 5.5825 0.8325 9 P 0 ;1
L 5.5825 0.8825 5.5825 0.8825 9 P 0 ;1
L 5.5825 0.9325 5.5825 0.9325 9 P 0 ;1
L 5.5825 0.9825 5.5825 0.9825 9 P 0 ;1
L 5.5825 1.0325 5.5825 1.0325 9 P 0 ;1
L 5.5825 1.0825 5.5825 1.0825 9 P 0 ;1
L 5.5825 1.1325 5.5825 1.1325 9 P 0 ;1
L 5.5825 1.1825 5.5825 1.1825 9 P 0 ;1
L 5.5825 1.2325 5.5825 1.2325 9 P 0 ;1
L 5.5825 1.2825 5.5825 1.2825 9 P 0 ;1
L 5.5825 1.3325 5.5825 1.3325 9 P 0 ;1
L 5.5825 3.0825 5.5825 3.0825 9 P 0 ;1
L 5.5825 3.1325 5.5825 3.1325 9 P 0 ;1
L 5.5825 3.1825 5.5825 3.1825 9 P 0 ;1
L 5.5825 3.2325 5.5825 3.2325 9 P 0 ;1
L 5.5825 3.2825 5.5825 3.2825 9 P 0 ;1
L 5.5825 3.3325 5.5825 3.3325 9 P 0 ;1
L 5.5825 3.3825 5.5825 3.3825 9 P 0 ;1
L 5.5825 3.4325 5.5825 3.4325 9 P 0 ;1
L 5.5825 3.4825 5.5825 3.4825 9 P 0 ;1
L 5.5825 3.5325 5.5825 3.5325 9 P 0 ;1
L 5.5825 3.5825 5.5825 3.5825 9 P 0 ;1
L 5.5825 3.6325 5.5825 3.6325 9 P 0 ;1
L 5.5825 3.6825 5.5825 3.6825 9 P 0 ;1
L 5.5825 3.7325 5.5825 3.7325 9 P 0 ;1
L 5.5825 3.7825 5.5825 3.7825 9 P 0 ;1
L 5.5825 3.8325 5.5825 3.8325 9 P 0 ;1
L 5.5825 3.8825 5.5825 3.8825 9 P 0 ;1
L 5.5825 3.9325 5.5825 3.9325 9 P 0 ;1
L 5.5825 3.9825 5.5825 3.9825 9 P 0 ;1
L 5.5825 4.0325 5.5825 4.0325 9 P 0 ;1
L 5.5825 4.0825 5.5825 4.0825 9 P 0 ;1
L 5.5825 4.1325 5.5825 4.1325 9 P 0 ;1
L 5.5825 4.1825 5.5825 4.1825 9 P 0 ;1
L 5.5825 4.2325 5.5825 4.2325 9 P 0 ;1
L 5.5825 4.2825 5.5825 4.2825 9 P 0 ;1
L 5.5825 4.3325 5.5825 4.3325 9 P 0 ;1
L 5.5825 4.3825 5.5825 4.3825 9 P 0 ;1
L 5.5825 4.4325 5.5825 4.4325 9 P 0 ;1
L 5.5825 4.9325 5.5825 4.9325 9 P 0 ;1
L 5.5825 4.9825 5.5825 4.9825 9 P 0 ;1
L 5.5825 5.0325 5.5825 5.0325 9 P 0 ;1
L 5.5825 5.0825 5.5825 5.0825 9 P 0 ;1
L 5.5825 5.1325 5.5825 5.1325 9 P 0 ;1
L 5.5825 5.1825 5.5825 5.1825 9 P 0 ;1
L 5.5825 5.2325 5.5825 5.2325 9 P 0 ;1
L 5.5825 5.6325 5.5825 5.6325 9 P 0 ;1
L 5.5825 5.6825 5.5825 5.6825 9 P 0 ;1
L 5.5825 5.7325 5.5825 5.7325 9 P 0 ;1
L 5.5825 5.7825 5.5825 5.7825 9 P 0 ;1
L 5.5825 5.8325 5.5825 5.8325 9 P 0 ;1
L 5.5825 5.8825 5.5825 5.8825 9 P 0 ;1
L 5.6325 0.5825 5.6325 0.5825 9 P 0 ;1
L 5.6325 0.6325 5.6325 0.6325 9 P 0 ;1
L 5.6325 0.6825 5.6325 0.6825 9 P 0 ;1
L 5.6325 0.7325 5.6325 0.7325 9 P 0 ;1
L 5.6325 0.7825 5.6325 0.7825 9 P 0 ;1
L 5.6325 0.8325 5.6325 0.8325 9 P 0 ;1
L 5.6325 0.8825 5.6325 0.8825 9 P 0 ;1
L 5.6325 0.9325 5.6325 0.9325 9 P 0 ;1
L 5.6325 0.9825 5.6325 0.9825 9 P 0 ;1
L 5.6325 1.0325 5.6325 1.0325 9 P 0 ;1
L 5.6325 1.0825 5.6325 1.0825 9 P 0 ;1
L 5.6325 1.1325 5.6325 1.1325 9 P 0 ;1
L 5.6325 1.1825 5.6325 1.1825 9 P 0 ;1
L 5.6325 1.2325 5.6325 1.2325 9 P 0 ;1
L 5.6325 1.2825 5.6325 1.2825 9 P 0 ;1
L 5.6325 1.3325 5.6325 1.3325 9 P 0 ;1
L 5.6325 1.3825 5.6325 1.3825 9 P 0 ;1
L 5.6325 3.0825 5.6325 3.0825 9 P 0 ;1
L 5.6325 3.1325 5.6325 3.1325 9 P 0 ;1
L 5.6325 3.1825 5.6325 3.1825 9 P 0 ;1
L 5.6325 3.2325 5.6325 3.2325 9 P 0 ;1
L 5.6325 3.2825 5.6325 3.2825 9 P 0 ;1
L 5.6325 3.3325 5.6325 3.3325 9 P 0 ;1
L 5.6325 3.3825 5.6325 3.3825 9 P 0 ;1
L 5.6325 3.4325 5.6325 3.4325 9 P 0 ;1
L 5.6325 3.4825 5.6325 3.4825 9 P 0 ;1
L 5.6325 3.5325 5.6325 3.5325 9 P 0 ;1
L 5.6325 3.5825 5.6325 3.5825 9 P 0 ;1
L 5.6325 3.6325 5.6325 3.6325 9 P 0 ;1
L 5.6325 3.6825 5.6325 3.6825 9 P 0 ;1
L 5.6325 3.7325 5.6325 3.7325 9 P 0 ;1
L 5.6325 3.7825 5.6325 3.7825 9 P 0 ;1
L 5.6325 3.8325 5.6325 3.8325 9 P 0 ;1
L 5.6325 3.8825 5.6325 3.8825 9 P 0 ;1
L 5.6325 3.9325 5.6325 3.9325 9 P 0 ;1
L 5.6325 3.9825 5.6325 3.9825 9 P 0 ;1
L 5.6325 4.0325 5.6325 4.0325 9 P 0 ;1
L 5.6325 4.0825 5.6325 4.0825 9 P 0 ;1
L 5.6325 4.1325 5.6325 4.1325 9 P 0 ;1
L 5.6325 4.1825 5.6325 4.1825 9 P 0 ;1
L 5.6325 4.2325 5.6325 4.2325 9 P 0 ;1
L 5.6325 4.2825 5.6325 4.2825 9 P 0 ;1
L 5.6325 4.3325 5.6325 4.3325 9 P 0 ;1
L 5.6325 4.3825 5.6325 4.3825 9 P 0 ;1
L 5.6325 4.4325 5.6325 4.4325 9 P 0 ;1
L 5.6325 4.8825 5.6325 4.8825 9 P 0 ;1
L 5.6325 4.9325 5.6325 4.9325 9 P 0 ;1
L 5.6325 4.9825 5.6325 4.9825 9 P 0 ;1
L 5.6325 5.0325 5.6325 5.0325 9 P 0 ;1
L 5.6325 5.0825 5.6325 5.0825 9 P 0 ;1
L 5.6325 5.1325 5.6325 5.1325 9 P 0 ;1
L 5.6325 5.1825 5.6325 5.1825 9 P 0 ;1
L 5.6325 5.6825 5.6325 5.6825 9 P 0 ;1
L 5.6325 5.7325 5.6325 5.7325 9 P 0 ;1
L 5.6325 5.7825 5.6325 5.7825 9 P 0 ;1
L 5.6325 5.8325 5.6325 5.8325 9 P 0 ;1
L 5.6325 5.8825 5.6325 5.8825 9 P 0 ;1
L 5.6825 0.5825 5.6825 0.5825 9 P 0 ;1
L 5.6825 0.6325 5.6825 0.6325 9 P 0 ;1
L 5.6825 0.6825 5.6825 0.6825 9 P 0 ;1
L 5.6825 0.7325 5.6825 0.7325 9 P 0 ;1
L 5.6825 0.7825 5.6825 0.7825 9 P 0 ;1
L 5.6825 0.8325 5.6825 0.8325 9 P 0 ;1
L 5.6825 0.8825 5.6825 0.8825 9 P 0 ;1
L 5.6825 0.9325 5.6825 0.9325 9 P 0 ;1
L 5.6825 0.9825 5.6825 0.9825 9 P 0 ;1
L 5.6825 1.0325 5.6825 1.0325 9 P 0 ;1
L 5.6825 1.0825 5.6825 1.0825 9 P 0 ;1
L 5.6825 1.1325 5.6825 1.1325 9 P 0 ;1
L 5.6825 1.1825 5.6825 1.1825 9 P 0 ;1
L 5.6825 1.2325 5.6825 1.2325 9 P 0 ;1
L 5.6825 1.2825 5.6825 1.2825 9 P 0 ;1
L 5.6825 1.3325 5.6825 1.3325 9 P 0 ;1
L 5.6825 1.3825 5.6825 1.3825 9 P 0 ;1
L 5.6825 1.4325 5.6825 1.4325 9 P 0 ;1
L 5.6825 1.9325 5.6825 1.9325 9 P 0 ;1
L 5.6825 1.9825 5.6825 1.9825 9 P 0 ;1
L 5.6825 2.0325 5.6825 2.0325 9 P 0 ;1
L 5.6825 2.0825 5.6825 2.0825 9 P 0 ;1
L 5.6825 2.1325 5.6825 2.1325 9 P 0 ;1
L 5.6825 2.1825 5.6825 2.1825 9 P 0 ;1
L 5.6825 2.2325 5.6825 2.2325 9 P 0 ;1
L 5.6825 2.2825 5.6825 2.2825 9 P 0 ;1
L 5.6825 2.3325 5.6825 2.3325 9 P 0 ;1
L 5.6825 2.3825 5.6825 2.3825 9 P 0 ;1
L 5.6825 2.4325 5.6825 2.4325 9 P 0 ;1
L 5.6825 2.4825 5.6825 2.4825 9 P 0 ;1
L 5.6825 2.5325 5.6825 2.5325 9 P 0 ;1
L 5.6825 2.5825 5.6825 2.5825 9 P 0 ;1
L 5.6825 2.7325 5.6825 2.7325 9 P 0 ;1
L 5.6825 2.9325 5.6825 2.9325 9 P 0 ;1
L 5.6825 2.9825 5.6825 2.9825 9 P 0 ;1
L 5.6825 3.0825 5.6825 3.0825 9 P 0 ;1
L 5.6825 3.1325 5.6825 3.1325 9 P 0 ;1
L 5.6825 3.1825 5.6825 3.1825 9 P 0 ;1
L 5.6825 3.2325 5.6825 3.2325 9 P 0 ;1
L 5.6825 3.2825 5.6825 3.2825 9 P 0 ;1
L 5.6825 3.3325 5.6825 3.3325 9 P 0 ;1
L 5.6825 3.3825 5.6825 3.3825 9 P 0 ;1
L 5.6825 3.4325 5.6825 3.4325 9 P 0 ;1
L 5.6825 3.4825 5.6825 3.4825 9 P 0 ;1
L 5.6825 3.5325 5.6825 3.5325 9 P 0 ;1
L 5.6825 3.5825 5.6825 3.5825 9 P 0 ;1
L 5.6825 3.6325 5.6825 3.6325 9 P 0 ;1
L 5.6825 3.6825 5.6825 3.6825 9 P 0 ;1
L 5.6825 3.7325 5.6825 3.7325 9 P 0 ;1
L 5.6825 3.7825 5.6825 3.7825 9 P 0 ;1
L 5.6825 3.8325 5.6825 3.8325 9 P 0 ;1
L 5.6825 3.8825 5.6825 3.8825 9 P 0 ;1
L 5.6825 3.9325 5.6825 3.9325 9 P 0 ;1
L 5.6825 3.9825 5.6825 3.9825 9 P 0 ;1
L 5.6825 4.0325 5.6825 4.0325 9 P 0 ;1
L 5.6825 4.0825 5.6825 4.0825 9 P 0 ;1
L 5.6825 4.1325 5.6825 4.1325 9 P 0 ;1
L 5.6825 4.1825 5.6825 4.1825 9 P 0 ;1
L 5.6825 4.2325 5.6825 4.2325 9 P 0 ;1
L 5.6825 4.2825 5.6825 4.2825 9 P 0 ;1
L 5.6825 4.3325 5.6825 4.3325 9 P 0 ;1
L 5.6825 4.3825 5.6825 4.3825 9 P 0 ;1
L 5.6825 4.4325 5.6825 4.4325 9 P 0 ;1
L 5.6825 4.9325 5.6825 4.9325 9 P 0 ;1
L 5.6825 4.9825 5.6825 4.9825 9 P 0 ;1
L 5.6825 5.0325 5.6825 5.0325 9 P 0 ;1
L 5.6825 5.0825 5.6825 5.0825 9 P 0 ;1
L 5.6825 5.1325 5.6825 5.1325 9 P 0 ;1
L 5.6825 5.1825 5.6825 5.1825 9 P 0 ;1
L 5.6825 5.7325 5.6825 5.7325 9 P 0 ;1
L 5.6825 5.7825 5.6825 5.7825 9 P 0 ;1
L 5.6825 5.8325 5.6825 5.8325 9 P 0 ;1
L 5.6825 5.8825 5.6825 5.8825 9 P 0 ;1
L 5.7325 0.5825 5.7325 0.5825 9 P 0 ;1
L 5.7325 0.6325 5.7325 0.6325 9 P 0 ;1
L 5.7325 0.6825 5.7325 0.6825 9 P 0 ;1
L 5.7325 0.7325 5.7325 0.7325 9 P 0 ;1
L 5.7325 0.7825 5.7325 0.7825 9 P 0 ;1
L 5.7325 0.8325 5.7325 0.8325 9 P 0 ;1
L 5.7325 0.8825 5.7325 0.8825 9 P 0 ;1
L 5.7325 0.9325 5.7325 0.9325 9 P 0 ;1
L 5.7325 0.9825 5.7325 0.9825 9 P 0 ;1
L 5.7325 1.0325 5.7325 1.0325 9 P 0 ;1
L 5.7325 1.0825 5.7325 1.0825 9 P 0 ;1
L 5.7325 1.1325 5.7325 1.1325 9 P 0 ;1
L 5.7325 1.1825 5.7325 1.1825 9 P 0 ;1
L 5.7325 1.2325 5.7325 1.2325 9 P 0 ;1
L 5.7325 1.2825 5.7325 1.2825 9 P 0 ;1
L 5.7325 1.3325 5.7325 1.3325 9 P 0 ;1
L 5.7325 1.3825 5.7325 1.3825 9 P 0 ;1
L 5.7325 1.4325 5.7325 1.4325 9 P 0 ;1
L 5.7325 1.4825 5.7325 1.4825 9 P 0 ;1
L 5.7325 1.5325 5.7325 1.5325 9 P 0 ;1
L 5.7325 2.7825 5.7325 2.7825 9 P 0 ;1
L 5.7325 2.9325 5.7325 2.9325 9 P 0 ;1
L 5.7325 3.1325 5.7325 3.1325 9 P 0 ;1
L 5.7325 3.1825 5.7325 3.1825 9 P 0 ;1
L 5.7325 3.2325 5.7325 3.2325 9 P 0 ;1
L 5.7325 3.2825 5.7325 3.2825 9 P 0 ;1
L 5.7325 3.3325 5.7325 3.3325 9 P 0 ;1
L 5.7325 3.3825 5.7325 3.3825 9 P 0 ;1
L 5.7325 3.4325 5.7325 3.4325 9 P 0 ;1
L 5.7325 3.4825 5.7325 3.4825 9 P 0 ;1
L 5.7325 3.5325 5.7325 3.5325 9 P 0 ;1
L 5.7325 3.5825 5.7325 3.5825 9 P 0 ;1
L 5.7325 3.6325 5.7325 3.6325 9 P 0 ;1
L 5.7325 3.6825 5.7325 3.6825 9 P 0 ;1
L 5.7325 3.7325 5.7325 3.7325 9 P 0 ;1
L 5.7325 3.7825 5.7325 3.7825 9 P 0 ;1
L 5.7325 3.8325 5.7325 3.8325 9 P 0 ;1
L 5.7325 3.8825 5.7325 3.8825 9 P 0 ;1
L 5.7325 3.9325 5.7325 3.9325 9 P 0 ;1
L 5.7325 3.9825 5.7325 3.9825 9 P 0 ;1
L 5.7325 4.0325 5.7325 4.0325 9 P 0 ;1
L 5.7325 4.0825 5.7325 4.0825 9 P 0 ;1
L 5.7325 4.1325 5.7325 4.1325 9 P 0 ;1
L 5.7325 4.1825 5.7325 4.1825 9 P 0 ;1
L 5.7325 4.2325 5.7325 4.2325 9 P 0 ;1
L 5.7325 4.2825 5.7325 4.2825 9 P 0 ;1
L 5.7325 4.3325 5.7325 4.3325 9 P 0 ;1
L 5.7325 4.3825 5.7325 4.3825 9 P 0 ;1
L 5.7325 4.4325 5.7325 4.4325 9 P 0 ;1
L 5.7325 4.9325 5.7325 4.9325 9 P 0 ;1
L 5.7325 4.9825 5.7325 4.9825 9 P 0 ;1
L 5.7325 5.0325 5.7325 5.0325 9 P 0 ;1
L 5.7325 5.0825 5.7325 5.0825 9 P 0 ;1
L 5.7325 5.1325 5.7325 5.1325 9 P 0 ;1
L 5.7325 5.7325 5.7325 5.7325 9 P 0 ;1
L 5.7325 5.7825 5.7325 5.7825 9 P 0 ;1
L 5.7325 5.8325 5.7325 5.8325 9 P 0 ;1
L 5.7325 5.8825 5.7325 5.8825 9 P 0 ;1
L 5.7825 0.5825 5.7825 0.5825 9 P 0 ;1
L 5.7825 0.6325 5.7825 0.6325 9 P 0 ;1
L 5.7825 0.6825 5.7825 0.6825 9 P 0 ;1
L 5.7825 0.7325 5.7825 0.7325 9 P 0 ;1
L 5.7825 0.7825 5.7825 0.7825 9 P 0 ;1
L 5.7825 0.8325 5.7825 0.8325 9 P 0 ;1
L 5.7825 1.0325 5.7825 1.0325 9 P 0 ;1
L 5.7825 1.0825 5.7825 1.0825 9 P 0 ;1
L 5.7825 1.1325 5.7825 1.1325 9 P 0 ;1
L 5.7825 1.1825 5.7825 1.1825 9 P 0 ;1
L 5.7825 1.2325 5.7825 1.2325 9 P 0 ;1
L 5.7825 1.2825 5.7825 1.2825 9 P 0 ;1
L 5.7825 1.3325 5.7825 1.3325 9 P 0 ;1
L 5.7825 1.3825 5.7825 1.3825 9 P 0 ;1
L 5.7825 1.4325 5.7825 1.4325 9 P 0 ;1
L 5.7825 1.4825 5.7825 1.4825 9 P 0 ;1
L 5.7825 1.5325 5.7825 1.5325 9 P 0 ;1
L 5.7825 1.5825 5.7825 1.5825 9 P 0 ;1
L 5.7825 2.7825 5.7825 2.7825 9 P 0 ;1
L 5.7825 3.1325 5.7825 3.1325 9 P 0 ;1
L 5.7825 3.1825 5.7825 3.1825 9 P 0 ;1
L 5.7825 3.2325 5.7825 3.2325 9 P 0 ;1
L 5.7825 3.2825 5.7825 3.2825 9 P 0 ;1
L 5.7825 3.3325 5.7825 3.3325 9 P 0 ;1
L 5.7825 3.3825 5.7825 3.3825 9 P 0 ;1
L 5.7825 3.4325 5.7825 3.4325 9 P 0 ;1
L 5.7825 3.4825 5.7825 3.4825 9 P 0 ;1
L 5.7825 3.5325 5.7825 3.5325 9 P 0 ;1
L 5.7825 3.5825 5.7825 3.5825 9 P 0 ;1
L 5.7825 3.6325 5.7825 3.6325 9 P 0 ;1
L 5.7825 3.6825 5.7825 3.6825 9 P 0 ;1
L 5.7825 3.7325 5.7825 3.7325 9 P 0 ;1
L 5.7825 3.7825 5.7825 3.7825 9 P 0 ;1
L 5.7825 3.8325 5.7825 3.8325 9 P 0 ;1
L 5.7825 3.8825 5.7825 3.8825 9 P 0 ;1
L 5.7825 3.9325 5.7825 3.9325 9 P 0 ;1
L 5.7825 3.9825 5.7825 3.9825 9 P 0 ;1
L 5.7825 4.0325 5.7825 4.0325 9 P 0 ;1
L 5.7825 4.0825 5.7825 4.0825 9 P 0 ;1
L 5.7825 4.1325 5.7825 4.1325 9 P 0 ;1
L 5.7825 4.1825 5.7825 4.1825 9 P 0 ;1
L 5.7825 4.2325 5.7825 4.2325 9 P 0 ;1
L 5.7825 4.2825 5.7825 4.2825 9 P 0 ;1
L 5.7825 4.3325 5.7825 4.3325 9 P 0 ;1
L 5.7825 4.3825 5.7825 4.3825 9 P 0 ;1
L 5.7825 4.4325 5.7825 4.4325 9 P 0 ;1
L 5.7825 4.9325 5.7825 4.9325 9 P 0 ;1
L 5.7825 4.9825 5.7825 4.9825 9 P 0 ;1
L 5.7825 5.0325 5.7825 5.0325 9 P 0 ;1
L 5.7825 5.0825 5.7825 5.0825 9 P 0 ;1
L 5.7825 5.1325 5.7825 5.1325 9 P 0 ;1
L 5.7825 5.7325 5.7825 5.7325 9 P 0 ;1
L 5.7825 5.7825 5.7825 5.7825 9 P 0 ;1
L 5.7825 5.8325 5.7825 5.8325 9 P 0 ;1
L 5.7825 5.8825 5.7825 5.8825 9 P 0 ;1
L 5.8325 0.5825 5.8325 0.5825 9 P 0 ;1
L 5.8325 0.6325 5.8325 0.6325 9 P 0 ;1
L 5.8325 0.6825 5.8325 0.6825 9 P 0 ;1
L 5.8325 0.7325 5.8325 0.7325 9 P 0 ;1
L 5.8325 0.7825 5.8325 0.7825 9 P 0 ;1
L 5.8325 0.8325 5.8325 0.8325 9 P 0 ;1
L 5.8325 1.0325 5.8325 1.0325 9 P 0 ;1
L 5.8325 1.0825 5.8325 1.0825 9 P 0 ;1
L 5.8325 1.1325 5.8325 1.1325 9 P 0 ;1
L 5.8325 1.1825 5.8325 1.1825 9 P 0 ;1
L 5.8325 1.2325 5.8325 1.2325 9 P 0 ;1
L 5.8325 1.2825 5.8325 1.2825 9 P 0 ;1
L 5.8325 1.3325 5.8325 1.3325 9 P 0 ;1
L 5.8325 1.3825 5.8325 1.3825 9 P 0 ;1
L 5.8325 1.4325 5.8325 1.4325 9 P 0 ;1
L 5.8325 1.4825 5.8325 1.4825 9 P 0 ;1
L 5.8325 1.5325 5.8325 1.5325 9 P 0 ;1
L 5.8325 1.5825 5.8325 1.5825 9 P 0 ;1
L 5.8325 1.6325 5.8325 1.6325 9 P 0 ;1
L 5.8325 1.6825 5.8325 1.6825 9 P 0 ;1
L 5.8325 1.7325 5.8325 1.7325 9 P 0 ;1
L 5.8325 1.7825 5.8325 1.7825 9 P 0 ;1
L 5.8325 1.8325 5.8325 1.8325 9 P 0 ;1
L 5.8325 1.8825 5.8325 1.8825 9 P 0 ;1
L 5.8325 2.7325 5.8325 2.7325 9 P 0 ;1
L 5.8325 3.1825 5.8325 3.1825 9 P 0 ;1
L 5.8325 3.2325 5.8325 3.2325 9 P 0 ;1
L 5.8325 3.2825 5.8325 3.2825 9 P 0 ;1
L 5.8325 3.3325 5.8325 3.3325 9 P 0 ;1
L 5.8325 3.3825 5.8325 3.3825 9 P 0 ;1
L 5.8325 3.4325 5.8325 3.4325 9 P 0 ;1
L 5.8325 3.4825 5.8325 3.4825 9 P 0 ;1
L 5.8325 3.5325 5.8325 3.5325 9 P 0 ;1
L 5.8325 3.5825 5.8325 3.5825 9 P 0 ;1
L 5.8325 3.6325 5.8325 3.6325 9 P 0 ;1
L 5.8325 3.6825 5.8325 3.6825 9 P 0 ;1
L 5.8325 3.7325 5.8325 3.7325 9 P 0 ;1
L 5.8325 3.7825 5.8325 3.7825 9 P 0 ;1
L 5.8325 3.8325 5.8325 3.8325 9 P 0 ;1
L 5.8325 3.8825 5.8325 3.8825 9 P 0 ;1
L 5.8325 3.9325 5.8325 3.9325 9 P 0 ;1
L 5.8325 3.9825 5.8325 3.9825 9 P 0 ;1
L 5.8325 4.0325 5.8325 4.0325 9 P 0 ;1
L 5.8325 4.0825 5.8325 4.0825 9 P 0 ;1
L 5.8325 4.1325 5.8325 4.1325 9 P 0 ;1
L 5.8325 4.1825 5.8325 4.1825 9 P 0 ;1
L 5.8325 4.2325 5.8325 4.2325 9 P 0 ;1
L 5.8325 4.2825 5.8325 4.2825 9 P 0 ;1
L 5.8325 4.3325 5.8325 4.3325 9 P 0 ;1
L 5.8325 4.3825 5.8325 4.3825 9 P 0 ;1
L 5.8325 4.4325 5.8325 4.4325 9 P 0 ;1
L 5.8325 4.9325 5.8325 4.9325 9 P 0 ;1
L 5.8325 4.9825 5.8325 4.9825 9 P 0 ;1
L 5.8325 5.0325 5.8325 5.0325 9 P 0 ;1
L 5.8325 5.0825 5.8325 5.0825 9 P 0 ;1
L 5.8325 5.1325 5.8325 5.1325 9 P 0 ;1
L 5.8325 5.7325 5.8325 5.7325 9 P 0 ;1
L 5.8325 5.7825 5.8325 5.7825 9 P 0 ;1
L 5.8325 5.8325 5.8325 5.8325 9 P 0 ;1
L 5.8325 5.8825 5.8325 5.8825 9 P 0 ;1
L 5.8825 0.5825 5.8825 0.5825 9 P 0 ;1
L 5.8825 0.6325 5.8825 0.6325 9 P 0 ;1
L 5.8825 0.6825 5.8825 0.6825 9 P 0 ;1
L 5.8825 0.7325 5.8825 0.7325 9 P 0 ;1
L 5.8825 0.7825 5.8825 0.7825 9 P 0 ;1
L 5.8825 0.8325 5.8825 0.8325 9 P 0 ;1
L 5.8825 1.0325 5.8825 1.0325 9 P 0 ;1
L 5.8825 1.0825 5.8825 1.0825 9 P 0 ;1
L 5.8825 1.1325 5.8825 1.1325 9 P 0 ;1
L 5.8825 1.1825 5.8825 1.1825 9 P 0 ;1
L 5.8825 1.2325 5.8825 1.2325 9 P 0 ;1
L 5.8825 1.2825 5.8825 1.2825 9 P 0 ;1
L 5.8825 1.3325 5.8825 1.3325 9 P 0 ;1
L 5.8825 1.3825 5.8825 1.3825 9 P 0 ;1
L 5.8825 1.4325 5.8825 1.4325 9 P 0 ;1
L 5.8825 1.4825 5.8825 1.4825 9 P 0 ;1
L 5.8825 1.5325 5.8825 1.5325 9 P 0 ;1
L 5.8825 1.5825 5.8825 1.5825 9 P 0 ;1
L 5.8825 1.6325 5.8825 1.6325 9 P 0 ;1
L 5.8825 1.6825 5.8825 1.6825 9 P 0 ;1
L 5.8825 1.7325 5.8825 1.7325 9 P 0 ;1
L 5.8825 1.7825 5.8825 1.7825 9 P 0 ;1
L 5.8825 1.8325 5.8825 1.8325 9 P 0 ;1
L 5.8825 1.8825 5.8825 1.8825 9 P 0 ;1
L 5.8825 1.9325 5.8825 1.9325 9 P 0 ;1
L 5.8825 1.9825 5.8825 1.9825 9 P 0 ;1
L 5.8825 2.0325 5.8825 2.0325 9 P 0 ;1
L 5.8825 2.0825 5.8825 2.0825 9 P 0 ;1
L 5.8825 2.1325 5.8825 2.1325 9 P 0 ;1
L 5.8825 2.1825 5.8825 2.1825 9 P 0 ;1
L 5.8825 2.2325 5.8825 2.2325 9 P 0 ;1
L 5.8825 2.2825 5.8825 2.2825 9 P 0 ;1
L 5.8825 2.3325 5.8825 2.3325 9 P 0 ;1
L 5.8825 2.3825 5.8825 2.3825 9 P 0 ;1
L 5.8825 2.4325 5.8825 2.4325 9 P 0 ;1
L 5.8825 2.4825 5.8825 2.4825 9 P 0 ;1
L 5.8825 2.5325 5.8825 2.5325 9 P 0 ;1
L 5.8825 2.5825 5.8825 2.5825 9 P 0 ;1
L 5.8825 2.6325 5.8825 2.6325 9 P 0 ;1
L 5.8825 2.6825 5.8825 2.6825 9 P 0 ;1
L 5.8825 2.7325 5.8825 2.7325 9 P 0 ;1
L 5.8825 3.1825 5.8825 3.1825 9 P 0 ;1
L 5.8825 3.2325 5.8825 3.2325 9 P 0 ;1
L 5.8825 3.2825 5.8825 3.2825 9 P 0 ;1
L 5.8825 3.3325 5.8825 3.3325 9 P 0 ;1
L 5.8825 3.3825 5.8825 3.3825 9 P 0 ;1
L 5.8825 3.4325 5.8825 3.4325 9 P 0 ;1
L 5.8825 3.4825 5.8825 3.4825 9 P 0 ;1
L 5.8825 3.5325 5.8825 3.5325 9 P 0 ;1
L 5.8825 3.5825 5.8825 3.5825 9 P 0 ;1
L 5.8825 3.6325 5.8825 3.6325 9 P 0 ;1
L 5.8825 3.6825 5.8825 3.6825 9 P 0 ;1
L 5.8825 3.7325 5.8825 3.7325 9 P 0 ;1
L 5.8825 3.7825 5.8825 3.7825 9 P 0 ;1
L 5.8825 3.8325 5.8825 3.8325 9 P 0 ;1
L 5.8825 3.8825 5.8825 3.8825 9 P 0 ;1
L 5.8825 3.9325 5.8825 3.9325 9 P 0 ;1
L 5.8825 3.9825 5.8825 3.9825 9 P 0 ;1
L 5.8825 4.0325 5.8825 4.0325 9 P 0 ;1
L 5.8825 4.0825 5.8825 4.0825 9 P 0 ;1
L 5.8825 4.1325 5.8825 4.1325 9 P 0 ;1
L 5.8825 4.1825 5.8825 4.1825 9 P 0 ;1
L 5.8825 4.2325 5.8825 4.2325 9 P 0 ;1
L 5.8825 4.2825 5.8825 4.2825 9 P 0 ;1
L 5.8825 4.3325 5.8825 4.3325 9 P 0 ;1
L 5.8825 4.3825 5.8825 4.3825 9 P 0 ;1
L 5.8825 4.4325 5.8825 4.4325 9 P 0 ;1
L 5.8825 4.8825 5.8825 4.8825 9 P 0 ;1
L 5.8825 4.9325 5.8825 4.9325 9 P 0 ;1
L 5.8825 4.9825 5.8825 4.9825 9 P 0 ;1
L 5.8825 5.0325 5.8825 5.0325 9 P 0 ;1
L 5.8825 5.0825 5.8825 5.0825 9 P 0 ;1
L 5.8825 5.1325 5.8825 5.1325 9 P 0 ;1
L 5.8825 5.1825 5.8825 5.1825 9 P 0 ;1
L 5.8825 5.7325 5.8825 5.7325 9 P 0 ;1
L 5.8825 5.7825 5.8825 5.7825 9 P 0 ;1
L 5.8825 5.8325 5.8825 5.8325 9 P 0 ;1
L 5.8825 5.8825 5.8825 5.8825 9 P 0 ;1
L 5.9325 0.5825 5.9325 0.5825 9 P 0 ;1
L 5.9325 0.6325 5.9325 0.6325 9 P 0 ;1
L 5.9325 0.6825 5.9325 0.6825 9 P 0 ;1
L 5.9325 0.7325 5.9325 0.7325 9 P 0 ;1
L 5.9325 0.7825 5.9325 0.7825 9 P 0 ;1
L 5.9325 0.8325 5.9325 0.8325 9 P 0 ;1
L 5.9325 0.8825 5.9325 0.8825 9 P 0 ;1
L 5.9325 0.9825 5.9325 0.9825 9 P 0 ;1
L 5.9325 1.0325 5.9325 1.0325 9 P 0 ;1
L 5.9325 1.0825 5.9325 1.0825 9 P 0 ;1
L 5.9325 1.1325 5.9325 1.1325 9 P 0 ;1
L 5.9325 1.1825 5.9325 1.1825 9 P 0 ;1
L 5.9325 1.2325 5.9325 1.2325 9 P 0 ;1
L 5.9325 1.2825 5.9325 1.2825 9 P 0 ;1
L 5.9325 1.3325 5.9325 1.3325 9 P 0 ;1
L 5.9325 1.3825 5.9325 1.3825 9 P 0 ;1
L 5.9325 1.4325 5.9325 1.4325 9 P 0 ;1
L 5.9325 1.6325 5.9325 1.6325 9 P 0 ;1
L 5.9325 1.6825 5.9325 1.6825 9 P 0 ;1
L 5.9325 1.7325 5.9325 1.7325 9 P 0 ;1
L 5.9325 1.7825 5.9325 1.7825 9 P 0 ;1
L 5.9325 1.8325 5.9325 1.8325 9 P 0 ;1
L 5.9325 1.8825 5.9325 1.8825 9 P 0 ;1
L 5.9325 1.9325 5.9325 1.9325 9 P 0 ;1
L 5.9325 1.9825 5.9325 1.9825 9 P 0 ;1
L 5.9325 2.0325 5.9325 2.0325 9 P 0 ;1
L 5.9325 2.0825 5.9325 2.0825 9 P 0 ;1
L 5.9325 2.1325 5.9325 2.1325 9 P 0 ;1
L 5.9325 2.1825 5.9325 2.1825 9 P 0 ;1
L 5.9325 2.2325 5.9325 2.2325 9 P 0 ;1
L 5.9325 2.2825 5.9325 2.2825 9 P 0 ;1
L 5.9325 2.3325 5.9325 2.3325 9 P 0 ;1
L 5.9325 2.3825 5.9325 2.3825 9 P 0 ;1
L 5.9325 2.4325 5.9325 2.4325 9 P 0 ;1
L 5.9325 2.4825 5.9325 2.4825 9 P 0 ;1
L 5.9325 2.6825 5.9325 2.6825 9 P 0 ;1
L 5.9325 2.7325 5.9325 2.7325 9 P 0 ;1
L 5.9325 2.7825 5.9325 2.7825 9 P 0 ;1
L 5.9325 2.8325 5.9325 2.8325 9 P 0 ;1
L 5.9325 3.0325 5.9325 3.0325 9 P 0 ;1
L 5.9325 3.0825 5.9325 3.0825 9 P 0 ;1
L 5.9325 3.1325 5.9325 3.1325 9 P 0 ;1
L 5.9325 3.1825 5.9325 3.1825 9 P 0 ;1
L 5.9325 3.2325 5.9325 3.2325 9 P 0 ;1
L 5.9325 3.2825 5.9325 3.2825 9 P 0 ;1
L 5.9325 3.3325 5.9325 3.3325 9 P 0 ;1
L 5.9325 3.3825 5.9325 3.3825 9 P 0 ;1
L 5.9325 3.4325 5.9325 3.4325 9 P 0 ;1
L 5.9325 3.4825 5.9325 3.4825 9 P 0 ;1
L 5.9325 3.5325 5.9325 3.5325 9 P 0 ;1
L 5.9325 3.5825 5.9325 3.5825 9 P 0 ;1
L 5.9325 3.6325 5.9325 3.6325 9 P 0 ;1
L 5.9325 3.6825 5.9325 3.6825 9 P 0 ;1
L 5.9325 3.7325 5.9325 3.7325 9 P 0 ;1
L 5.9325 3.7825 5.9325 3.7825 9 P 0 ;1
L 5.9325 3.8325 5.9325 3.8325 9 P 0 ;1
L 5.9325 3.8825 5.9325 3.8825 9 P 0 ;1
L 5.9325 3.9325 5.9325 3.9325 9 P 0 ;1
L 5.9325 3.9825 5.9325 3.9825 9 P 0 ;1
L 5.9325 4.0325 5.9325 4.0325 9 P 0 ;1
L 5.9325 4.0825 5.9325 4.0825 9 P 0 ;1
L 5.9325 4.1325 5.9325 4.1325 9 P 0 ;1
L 5.9325 4.2825 5.9325 4.2825 9 P 0 ;1
L 5.9325 4.3325 5.9325 4.3325 9 P 0 ;1
L 5.9325 4.3825 5.9325 4.3825 9 P 0 ;1
L 5.9325 4.4325 5.9325 4.4325 9 P 0 ;1
L 5.9325 4.9325 5.9325 4.9325 9 P 0 ;1
L 5.9325 4.9825 5.9325 4.9825 9 P 0 ;1
L 5.9325 5.0325 5.9325 5.0325 9 P 0 ;1
L 5.9325 5.0825 5.9325 5.0825 9 P 0 ;1
L 5.9325 5.1325 5.9325 5.1325 9 P 0 ;1
L 5.9325 5.1825 5.9325 5.1825 9 P 0 ;1
L 5.9325 5.6825 5.9325 5.6825 9 P 0 ;1
L 5.9325 5.7325 5.9325 5.7325 9 P 0 ;1
L 5.9325 5.7825 5.9325 5.7825 9 P 0 ;1
L 5.9325 5.8325 5.9325 5.8325 9 P 0 ;1
L 5.9325 5.8825 5.9325 5.8825 9 P 0 ;1
L 5.9825 0.5825 5.9825 0.5825 9 P 0 ;1
L 5.9825 0.6325 5.9825 0.6325 9 P 0 ;1
L 5.9825 0.6825 5.9825 0.6825 9 P 0 ;1
L 5.9825 0.7325 5.9825 0.7325 9 P 0 ;1
L 5.9825 0.7825 5.9825 0.7825 9 P 0 ;1
L 5.9825 0.8325 5.9825 0.8325 9 P 0 ;1
L 5.9825 0.8825 5.9825 0.8825 9 P 0 ;1
L 5.9825 0.9325 5.9825 0.9325 9 P 0 ;1
L 5.9825 0.9825 5.9825 0.9825 9 P 0 ;1
L 5.9825 1.0325 5.9825 1.0325 9 P 0 ;1
L 5.9825 1.0825 5.9825 1.0825 9 P 0 ;1
L 5.9825 1.1325 5.9825 1.1325 9 P 0 ;1
L 5.9825 1.1825 5.9825 1.1825 9 P 0 ;1
L 5.9825 1.2325 5.9825 1.2325 9 P 0 ;1
L 5.9825 1.2825 5.9825 1.2825 9 P 0 ;1
L 5.9825 1.3325 5.9825 1.3325 9 P 0 ;1
L 5.9825 1.7325 5.9825 1.7325 9 P 0 ;1
L 5.9825 1.7825 5.9825 1.7825 9 P 0 ;1
L 5.9825 1.8325 5.9825 1.8325 9 P 0 ;1
L 5.9825 1.8825 5.9825 1.8825 9 P 0 ;1
L 5.9825 1.9325 5.9825 1.9325 9 P 0 ;1
L 5.9825 1.9825 5.9825 1.9825 9 P 0 ;1
L 5.9825 2.0325 5.9825 2.0325 9 P 0 ;1
L 5.9825 2.0825 5.9825 2.0825 9 P 0 ;1
L 5.9825 2.1325 5.9825 2.1325 9 P 0 ;1
L 5.9825 2.1825 5.9825 2.1825 9 P 0 ;1
L 5.9825 2.2325 5.9825 2.2325 9 P 0 ;1
L 5.9825 2.2825 5.9825 2.2825 9 P 0 ;1
L 5.9825 2.3325 5.9825 2.3325 9 P 0 ;1
L 5.9825 2.3825 5.9825 2.3825 9 P 0 ;1
L 5.9825 2.4325 5.9825 2.4325 9 P 0 ;1
L 5.9825 2.7325 5.9825 2.7325 9 P 0 ;1
L 5.9825 2.7825 5.9825 2.7825 9 P 0 ;1
L 5.9825 2.8325 5.9825 2.8325 9 P 0 ;1
L 5.9825 2.8825 5.9825 2.8825 9 P 0 ;1
L 5.9825 3.0325 5.9825 3.0325 9 P 0 ;1
L 5.9825 3.0825 5.9825 3.0825 9 P 0 ;1
L 5.9825 3.1325 5.9825 3.1325 9 P 0 ;1
L 5.9825 3.1825 5.9825 3.1825 9 P 0 ;1
L 5.9825 3.2325 5.9825 3.2325 9 P 0 ;1
L 5.9825 3.2825 5.9825 3.2825 9 P 0 ;1
L 5.9825 3.3325 5.9825 3.3325 9 P 0 ;1
L 5.9825 3.3825 5.9825 3.3825 9 P 0 ;1
L 5.9825 3.4325 5.9825 3.4325 9 P 0 ;1
L 5.9825 3.4825 5.9825 3.4825 9 P 0 ;1
L 5.9825 3.5325 5.9825 3.5325 9 P 0 ;1
L 5.9825 3.5825 5.9825 3.5825 9 P 0 ;1
L 5.9825 3.6325 5.9825 3.6325 9 P 0 ;1
L 5.9825 3.6825 5.9825 3.6825 9 P 0 ;1
L 5.9825 3.7325 5.9825 3.7325 9 P 0 ;1
L 5.9825 3.7825 5.9825 3.7825 9 P 0 ;1
L 5.9825 3.8325 5.9825 3.8325 9 P 0 ;1
L 5.9825 3.8825 5.9825 3.8825 9 P 0 ;1
L 5.9825 3.9325 5.9825 3.9325 9 P 0 ;1
L 5.9825 3.9825 5.9825 3.9825 9 P 0 ;1
L 5.9825 4.0325 5.9825 4.0325 9 P 0 ;1
L 5.9825 4.3825 5.9825 4.3825 9 P 0 ;1
L 5.9825 4.4325 5.9825 4.4325 9 P 0 ;1
L 5.9825 4.9325 5.9825 4.9325 9 P 0 ;1
L 5.9825 4.9825 5.9825 4.9825 9 P 0 ;1
L 5.9825 5.0325 5.9825 5.0325 9 P 0 ;1
L 5.9825 5.0825 5.9825 5.0825 9 P 0 ;1
L 5.9825 5.1325 5.9825 5.1325 9 P 0 ;1
L 5.9825 5.1825 5.9825 5.1825 9 P 0 ;1
L 5.9825 5.2325 5.9825 5.2325 9 P 0 ;1
L 5.9825 5.6325 5.9825 5.6325 9 P 0 ;1
L 5.9825 5.6825 5.9825 5.6825 9 P 0 ;1
L 5.9825 5.7325 5.9825 5.7325 9 P 0 ;1
L 5.9825 5.7825 5.9825 5.7825 9 P 0 ;1
L 5.9825 5.8325 5.9825 5.8325 9 P 0 ;1
L 5.9825 5.8825 5.9825 5.8825 9 P 0 ;1
L 6.0325 0.5825 6.0325 0.5825 9 P 0 ;1
L 6.0325 0.6325 6.0325 0.6325 9 P 0 ;1
L 6.0325 0.6825 6.0325 0.6825 9 P 0 ;1
L 6.0325 0.7325 6.0325 0.7325 9 P 0 ;1
L 6.0325 0.7825 6.0325 0.7825 9 P 0 ;1
L 6.0325 0.8325 6.0325 0.8325 9 P 0 ;1
L 6.0325 0.8825 6.0325 0.8825 9 P 0 ;1
L 6.0325 0.9325 6.0325 0.9325 9 P 0 ;1
L 6.0325 0.9825 6.0325 0.9825 9 P 0 ;1
L 6.0325 1.0325 6.0325 1.0325 9 P 0 ;1
L 6.0325 1.0825 6.0325 1.0825 9 P 0 ;1
L 6.0325 1.1325 6.0325 1.1325 9 P 0 ;1
L 6.0325 1.1825 6.0325 1.1825 9 P 0 ;1
L 6.0325 1.2325 6.0325 1.2325 9 P 0 ;1
L 6.0325 1.2825 6.0325 1.2825 9 P 0 ;1
L 6.0325 1.3325 6.0325 1.3325 9 P 0 ;1
L 6.0325 1.7325 6.0325 1.7325 9 P 0 ;1
L 6.0325 1.7825 6.0325 1.7825 9 P 0 ;1
L 6.0325 1.8325 6.0325 1.8325 9 P 0 ;1
L 6.0325 1.8825 6.0325 1.8825 9 P 0 ;1
L 6.0325 1.9325 6.0325 1.9325 9 P 0 ;1
L 6.0325 1.9825 6.0325 1.9825 9 P 0 ;1
L 6.0325 2.0325 6.0325 2.0325 9 P 0 ;1
L 6.0325 2.0825 6.0325 2.0825 9 P 0 ;1
L 6.0325 2.1325 6.0325 2.1325 9 P 0 ;1
L 6.0325 2.1825 6.0325 2.1825 9 P 0 ;1
L 6.0325 2.2325 6.0325 2.2325 9 P 0 ;1
L 6.0325 2.2825 6.0325 2.2825 9 P 0 ;1
L 6.0325 2.3325 6.0325 2.3325 9 P 0 ;1
L 6.0325 2.3825 6.0325 2.3825 9 P 0 ;1
L 6.0325 2.4325 6.0325 2.4325 9 P 0 ;1
L 6.0325 2.7325 6.0325 2.7325 9 P 0 ;1
L 6.0325 2.7825 6.0325 2.7825 9 P 0 ;1
L 6.0325 2.8325 6.0325 2.8325 9 P 0 ;1
L 6.0325 2.8825 6.0325 2.8825 9 P 0 ;1
L 6.0325 2.9325 6.0325 2.9325 9 P 0 ;1
L 6.0325 2.9825 6.0325 2.9825 9 P 0 ;1
L 6.0325 3.0325 6.0325 3.0325 9 P 0 ;1
L 6.0325 3.0825 6.0325 3.0825 9 P 0 ;1
L 6.0325 3.1325 6.0325 3.1325 9 P 0 ;1
L 6.0325 3.1825 6.0325 3.1825 9 P 0 ;1
L 6.0325 3.2325 6.0325 3.2325 9 P 0 ;1
L 6.0325 3.2825 6.0325 3.2825 9 P 0 ;1
L 6.0325 3.3325 6.0325 3.3325 9 P 0 ;1
L 6.0325 3.3825 6.0325 3.3825 9 P 0 ;1
L 6.0325 3.4325 6.0325 3.4325 9 P 0 ;1
L 6.0325 3.4825 6.0325 3.4825 9 P 0 ;1
L 6.0325 3.5325 6.0325 3.5325 9 P 0 ;1
L 6.0325 3.5825 6.0325 3.5825 9 P 0 ;1
L 6.0325 3.6325 6.0325 3.6325 9 P 0 ;1
L 6.0325 3.6825 6.0325 3.6825 9 P 0 ;1
L 6.0325 3.7325 6.0325 3.7325 9 P 0 ;1
L 6.0325 3.7825 6.0325 3.7825 9 P 0 ;1
L 6.0325 3.8325 6.0325 3.8325 9 P 0 ;1
L 6.0325 3.8825 6.0325 3.8825 9 P 0 ;1
L 6.0325 3.9325 6.0325 3.9325 9 P 0 ;1
L 6.0325 3.9825 6.0325 3.9825 9 P 0 ;1
L 6.0325 4.0325 6.0325 4.0325 9 P 0 ;1
L 6.0325 4.3825 6.0325 4.3825 9 P 0 ;1
L 6.0325 4.4325 6.0325 4.4325 9 P 0 ;1
L 6.0325 4.8825 6.0325 4.8825 9 P 0 ;1
L 6.0325 4.9325 6.0325 4.9325 9 P 0 ;1
L 6.0325 4.9825 6.0325 4.9825 9 P 0 ;1
L 6.0325 5.0325 6.0325 5.0325 9 P 0 ;1
L 6.0325 5.0825 6.0325 5.0825 9 P 0 ;1
L 6.0325 5.1325 6.0325 5.1325 9 P 0 ;1
L 6.0325 5.1825 6.0325 5.1825 9 P 0 ;1
L 6.0325 5.2325 6.0325 5.2325 9 P 0 ;1
L 6.0325 5.2825 6.0325 5.2825 9 P 0 ;1
L 6.0325 5.3325 6.0325 5.3325 9 P 0 ;1
L 6.0325 5.5825 6.0325 5.5825 9 P 0 ;1
L 6.0325 5.6325 6.0325 5.6325 9 P 0 ;1
L 6.0325 5.6825 6.0325 5.6825 9 P 0 ;1
L 6.0325 5.7325 6.0325 5.7325 9 P 0 ;1
L 6.0325 5.7825 6.0325 5.7825 9 P 0 ;1
L 6.0325 5.8325 6.0325 5.8325 9 P 0 ;1
L 6.0325 5.8825 6.0325 5.8825 9 P 0 ;1
L 6.0825 0.5825 6.0825 0.5825 9 P 0 ;1
L 6.0825 0.6325 6.0825 0.6325 9 P 0 ;1
L 6.0825 0.6825 6.0825 0.6825 9 P 0 ;1
L 6.0825 0.7325 6.0825 0.7325 9 P 0 ;1
L 6.0825 0.7825 6.0825 0.7825 9 P 0 ;1
L 6.0825 0.8325 6.0825 0.8325 9 P 0 ;1
L 6.0825 0.8825 6.0825 0.8825 9 P 0 ;1
L 6.0825 0.9325 6.0825 0.9325 9 P 0 ;1
L 6.0825 0.9825 6.0825 0.9825 9 P 0 ;1
L 6.0825 1.0325 6.0825 1.0325 9 P 0 ;1
L 6.0825 1.0825 6.0825 1.0825 9 P 0 ;1
L 6.0825 1.1325 6.0825 1.1325 9 P 0 ;1
L 6.0825 1.1825 6.0825 1.1825 9 P 0 ;1
L 6.0825 1.2325 6.0825 1.2325 9 P 0 ;1
L 6.0825 1.2825 6.0825 1.2825 9 P 0 ;1
L 6.0825 1.7325 6.0825 1.7325 9 P 0 ;1
L 6.0825 1.7825 6.0825 1.7825 9 P 0 ;1
L 6.0825 1.8325 6.0825 1.8325 9 P 0 ;1
L 6.0825 1.8825 6.0825 1.8825 9 P 0 ;1
L 6.0825 1.9325 6.0825 1.9325 9 P 0 ;1
L 6.0825 1.9825 6.0825 1.9825 9 P 0 ;1
L 6.0825 2.0325 6.0825 2.0325 9 P 0 ;1
L 6.0825 2.0825 6.0825 2.0825 9 P 0 ;1
L 6.0825 2.1325 6.0825 2.1325 9 P 0 ;1
L 6.0825 2.1825 6.0825 2.1825 9 P 0 ;1
L 6.0825 2.2325 6.0825 2.2325 9 P 0 ;1
L 6.0825 2.2825 6.0825 2.2825 9 P 0 ;1
L 6.0825 2.3325 6.0825 2.3325 9 P 0 ;1
L 6.0825 2.3825 6.0825 2.3825 9 P 0 ;1
L 6.0825 2.4325 6.0825 2.4325 9 P 0 ;1
L 6.0825 2.7325 6.0825 2.7325 9 P 0 ;1
L 6.0825 2.7825 6.0825 2.7825 9 P 0 ;1
L 6.0825 2.8325 6.0825 2.8325 9 P 0 ;1
L 6.0825 2.8825 6.0825 2.8825 9 P 0 ;1
L 6.0825 2.9325 6.0825 2.9325 9 P 0 ;1
L 6.0825 2.9825 6.0825 2.9825 9 P 0 ;1
L 6.0825 3.0325 6.0825 3.0325 9 P 0 ;1
L 6.0825 3.0825 6.0825 3.0825 9 P 0 ;1
L 6.0825 3.1325 6.0825 3.1325 9 P 0 ;1
L 6.0825 3.1825 6.0825 3.1825 9 P 0 ;1
L 6.0825 3.2325 6.0825 3.2325 9 P 0 ;1
L 6.0825 3.2825 6.0825 3.2825 9 P 0 ;1
L 6.0825 3.3325 6.0825 3.3325 9 P 0 ;1
L 6.0825 3.3825 6.0825 3.3825 9 P 0 ;1
L 6.0825 3.4325 6.0825 3.4325 9 P 0 ;1
L 6.0825 3.4825 6.0825 3.4825 9 P 0 ;1
L 6.0825 3.5325 6.0825 3.5325 9 P 0 ;1
L 6.0825 3.5825 6.0825 3.5825 9 P 0 ;1
L 6.0825 3.6325 6.0825 3.6325 9 P 0 ;1
L 6.0825 3.6825 6.0825 3.6825 9 P 0 ;1
L 6.0825 3.7325 6.0825 3.7325 9 P 0 ;1
L 6.0825 3.7825 6.0825 3.7825 9 P 0 ;1
L 6.0825 3.8325 6.0825 3.8325 9 P 0 ;1
L 6.0825 3.8825 6.0825 3.8825 9 P 0 ;1
L 6.0825 3.9325 6.0825 3.9325 9 P 0 ;1
L 6.0825 3.9825 6.0825 3.9825 9 P 0 ;1
L 6.0825 4.4325 6.0825 4.4325 9 P 0 ;1
L 6.0825 5.0325 6.0825 5.0325 9 P 0 ;1
L 6.0825 5.0825 6.0825 5.0825 9 P 0 ;1
L 6.0825 5.1325 6.0825 5.1325 9 P 0 ;1
L 6.0825 5.1825 6.0825 5.1825 9 P 0 ;1
L 6.0825 5.2325 6.0825 5.2325 9 P 0 ;1
L 6.0825 5.2825 6.0825 5.2825 9 P 0 ;1
L 6.0825 5.3325 6.0825 5.3325 9 P 0 ;1
L 6.0825 5.3825 6.0825 5.3825 9 P 0 ;1
L 6.0825 5.4325 6.0825 5.4325 9 P 0 ;1
L 6.0825 5.4825 6.0825 5.4825 9 P 0 ;1
L 6.0825 5.5325 6.0825 5.5325 9 P 0 ;1
L 6.0825 5.5825 6.0825 5.5825 9 P 0 ;1
L 6.0825 5.6325 6.0825 5.6325 9 P 0 ;1
L 6.0825 5.6825 6.0825 5.6825 9 P 0 ;1
L 6.0825 5.7325 6.0825 5.7325 9 P 0 ;1
L 6.0825 5.7825 6.0825 5.7825 9 P 0 ;1
L 6.0825 5.8325 6.0825 5.8325 9 P 0 ;1
L 6.0825 5.8825 6.0825 5.8825 9 P 0 ;1
L 6.1325 0.5825 6.1325 0.5825 9 P 0 ;1
L 6.1325 0.6325 6.1325 0.6325 9 P 0 ;1
L 6.1325 0.6825 6.1325 0.6825 9 P 0 ;1
L 6.1325 0.7325 6.1325 0.7325 9 P 0 ;1
L 6.1325 0.7825 6.1325 0.7825 9 P 0 ;1
L 6.1325 0.8325 6.1325 0.8325 9 P 0 ;1
L 6.1325 0.8825 6.1325 0.8825 9 P 0 ;1
L 6.1325 0.9325 6.1325 0.9325 9 P 0 ;1
L 6.1325 0.9825 6.1325 0.9825 9 P 0 ;1
L 6.1325 1.0325 6.1325 1.0325 9 P 0 ;1
L 6.1325 1.0825 6.1325 1.0825 9 P 0 ;1
L 6.1325 1.1325 6.1325 1.1325 9 P 0 ;1
L 6.1325 1.1825 6.1325 1.1825 9 P 0 ;1
L 6.1325 1.2325 6.1325 1.2325 9 P 0 ;1
L 6.1325 1.2825 6.1325 1.2825 9 P 0 ;1
L 6.1325 1.7825 6.1325 1.7825 9 P 0 ;1
L 6.1325 1.8325 6.1325 1.8325 9 P 0 ;1
L 6.1325 1.8825 6.1325 1.8825 9 P 0 ;1
L 6.1325 1.9325 6.1325 1.9325 9 P 0 ;1
L 6.1325 1.9825 6.1325 1.9825 9 P 0 ;1
L 6.1325 2.0325 6.1325 2.0325 9 P 0 ;1
L 6.1325 2.0825 6.1325 2.0825 9 P 0 ;1
L 6.1325 2.1325 6.1325 2.1325 9 P 0 ;1
L 6.1325 2.1825 6.1325 2.1825 9 P 0 ;1
L 6.1325 2.2325 6.1325 2.2325 9 P 0 ;1
L 6.1325 2.2825 6.1325 2.2825 9 P 0 ;1
L 6.1325 2.3325 6.1325 2.3325 9 P 0 ;1
L 6.1325 2.3825 6.1325 2.3825 9 P 0 ;1
L 6.1325 2.4325 6.1325 2.4325 9 P 0 ;1
L 6.1325 2.7325 6.1325 2.7325 9 P 0 ;1
L 6.1325 2.7825 6.1325 2.7825 9 P 0 ;1
L 6.1325 2.8325 6.1325 2.8325 9 P 0 ;1
L 6.1325 2.8825 6.1325 2.8825 9 P 0 ;1
L 6.1325 2.9325 6.1325 2.9325 9 P 0 ;1
L 6.1325 2.9825 6.1325 2.9825 9 P 0 ;1
L 6.1325 3.0325 6.1325 3.0325 9 P 0 ;1
L 6.1325 3.0825 6.1325 3.0825 9 P 0 ;1
L 6.1325 3.1325 6.1325 3.1325 9 P 0 ;1
L 6.1325 3.1825 6.1325 3.1825 9 P 0 ;1
L 6.1325 3.2325 6.1325 3.2325 9 P 0 ;1
L 6.1325 3.2825 6.1325 3.2825 9 P 0 ;1
L 6.1325 3.3325 6.1325 3.3325 9 P 0 ;1
L 6.1325 3.3825 6.1325 3.3825 9 P 0 ;1
L 6.1325 3.4325 6.1325 3.4325 9 P 0 ;1
L 6.1325 3.4825 6.1325 3.4825 9 P 0 ;1
L 6.1325 3.5325 6.1325 3.5325 9 P 0 ;1
L 6.1325 3.5825 6.1325 3.5825 9 P 0 ;1
L 6.1325 3.6325 6.1325 3.6325 9 P 0 ;1
L 6.1325 3.6825 6.1325 3.6825 9 P 0 ;1
L 6.1325 3.7325 6.1325 3.7325 9 P 0 ;1
L 6.1325 3.7825 6.1325 3.7825 9 P 0 ;1
L 6.1325 3.8325 6.1325 3.8325 9 P 0 ;1
L 6.1325 3.8825 6.1325 3.8825 9 P 0 ;1
L 6.1325 3.9325 6.1325 3.9325 9 P 0 ;1
L 6.1325 3.9825 6.1325 3.9825 9 P 0 ;1
L 6.1325 4.4325 6.1325 4.4325 9 P 0 ;1
L 6.1325 5.0325 6.1325 5.0325 9 P 0 ;1
L 6.1325 5.0825 6.1325 5.0825 9 P 0 ;1
L 6.1325 5.1325 6.1325 5.1325 9 P 0 ;1
L 6.1325 5.1825 6.1325 5.1825 9 P 0 ;1
L 6.1325 5.2325 6.1325 5.2325 9 P 0 ;1
L 6.1325 5.2825 6.1325 5.2825 9 P 0 ;1
L 6.1325 5.3325 6.1325 5.3325 9 P 0 ;1
L 6.1325 5.3825 6.1325 5.3825 9 P 0 ;1
L 6.1325 5.4325 6.1325 5.4325 9 P 0 ;1
L 6.1325 5.4825 6.1325 5.4825 9 P 0 ;1
L 6.1325 5.5325 6.1325 5.5325 9 P 0 ;1
L 6.1325 5.5825 6.1325 5.5825 9 P 0 ;1
L 6.1325 5.6325 6.1325 5.6325 9 P 0 ;1
L 6.1325 5.6825 6.1325 5.6825 9 P 0 ;1
L 6.1325 5.7325 6.1325 5.7325 9 P 0 ;1
L 6.1325 5.7825 6.1325 5.7825 9 P 0 ;1
L 6.1325 5.8325 6.1325 5.8325 9 P 0 ;1
L 6.1325 5.8825 6.1325 5.8825 9 P 0 ;1
L 6.1825 0.5825 6.1825 0.5825 9 P 0 ;1
L 6.1825 0.6325 6.1825 0.6325 9 P 0 ;1
L 6.1825 0.6825 6.1825 0.6825 9 P 0 ;1
L 6.1825 0.7325 6.1825 0.7325 9 P 0 ;1
L 6.1825 0.7825 6.1825 0.7825 9 P 0 ;1
L 6.1825 0.8325 6.1825 0.8325 9 P 0 ;1
L 6.1825 0.8825 6.1825 0.8825 9 P 0 ;1
L 6.1825 0.9325 6.1825 0.9325 9 P 0 ;1
L 6.1825 0.9825 6.1825 0.9825 9 P 0 ;1
L 6.1825 1.0325 6.1825 1.0325 9 P 0 ;1
L 6.1825 1.0825 6.1825 1.0825 9 P 0 ;1
L 6.1825 1.1325 6.1825 1.1325 9 P 0 ;1
L 6.1825 1.1825 6.1825 1.1825 9 P 0 ;1
L 6.1825 1.2325 6.1825 1.2325 9 P 0 ;1
L 6.1825 1.2825 6.1825 1.2825 9 P 0 ;1
L 6.1825 1.3325 6.1825 1.3325 9 P 0 ;1
L 6.1825 1.7325 6.1825 1.7325 9 P 0 ;1
L 6.1825 1.7825 6.1825 1.7825 9 P 0 ;1
L 6.1825 1.8325 6.1825 1.8325 9 P 0 ;1
L 6.1825 1.8825 6.1825 1.8825 9 P 0 ;1
L 6.1825 1.9325 6.1825 1.9325 9 P 0 ;1
L 6.1825 1.9825 6.1825 1.9825 9 P 0 ;1
L 6.1825 2.0325 6.1825 2.0325 9 P 0 ;1
L 6.1825 2.0825 6.1825 2.0825 9 P 0 ;1
L 6.1825 2.1325 6.1825 2.1325 9 P 0 ;1
L 6.1825 2.1825 6.1825 2.1825 9 P 0 ;1
L 6.1825 2.2325 6.1825 2.2325 9 P 0 ;1
L 6.1825 2.2825 6.1825 2.2825 9 P 0 ;1
L 6.1825 2.3325 6.1825 2.3325 9 P 0 ;1
L 6.1825 2.3825 6.1825 2.3825 9 P 0 ;1
L 6.1825 2.4325 6.1825 2.4325 9 P 0 ;1
L 6.1825 2.4825 6.1825 2.4825 9 P 0 ;1
L 6.1825 2.6825 6.1825 2.6825 9 P 0 ;1
L 6.1825 2.7325 6.1825 2.7325 9 P 0 ;1
L 6.1825 2.7825 6.1825 2.7825 9 P 0 ;1
L 6.1825 2.8325 6.1825 2.8325 9 P 0 ;1
L 6.1825 2.8825 6.1825 2.8825 9 P 0 ;1
L 6.1825 2.9325 6.1825 2.9325 9 P 0 ;1
L 6.1825 2.9825 6.1825 2.9825 9 P 0 ;1
L 6.1825 3.0325 6.1825 3.0325 9 P 0 ;1
L 6.1825 3.0825 6.1825 3.0825 9 P 0 ;1
L 6.1825 3.1325 6.1825 3.1325 9 P 0 ;1
L 6.1825 3.1825 6.1825 3.1825 9 P 0 ;1
L 6.1825 3.2325 6.1825 3.2325 9 P 0 ;1
L 6.1825 3.2825 6.1825 3.2825 9 P 0 ;1
L 6.1825 3.3325 6.1825 3.3325 9 P 0 ;1
L 6.1825 3.3825 6.1825 3.3825 9 P 0 ;1
L 6.1825 3.4325 6.1825 3.4325 9 P 0 ;1
L 6.1825 3.4825 6.1825 3.4825 9 P 0 ;1
L 6.1825 3.5325 6.1825 3.5325 9 P 0 ;1
L 6.1825 3.5825 6.1825 3.5825 9 P 0 ;1
L 6.1825 3.6325 6.1825 3.6325 9 P 0 ;1
L 6.1825 3.6825 6.1825 3.6825 9 P 0 ;1
L 6.1825 3.7325 6.1825 3.7325 9 P 0 ;1
L 6.1825 3.7825 6.1825 3.7825 9 P 0 ;1
L 6.1825 3.8325 6.1825 3.8325 9 P 0 ;1
L 6.1825 3.8825 6.1825 3.8825 9 P 0 ;1
L 6.1825 3.9325 6.1825 3.9325 9 P 0 ;1
L 6.1825 3.9825 6.1825 3.9825 9 P 0 ;1
L 6.1825 4.4325 6.1825 4.4325 9 P 0 ;1
L 6.1825 4.4825 6.1825 4.4825 9 P 0 ;1
L 6.1825 4.5325 6.1825 4.5325 9 P 0 ;1
L 6.1825 5.0325 6.1825 5.0325 9 P 0 ;1
L 6.1825 5.0825 6.1825 5.0825 9 P 0 ;1
L 6.1825 5.1325 6.1825 5.1325 9 P 0 ;1
L 6.1825 5.1825 6.1825 5.1825 9 P 0 ;1
L 6.1825 5.2325 6.1825 5.2325 9 P 0 ;1
L 6.1825 5.2825 6.1825 5.2825 9 P 0 ;1
L 6.1825 5.3325 6.1825 5.3325 9 P 0 ;1
L 6.1825 5.3825 6.1825 5.3825 9 P 0 ;1
L 6.1825 5.4325 6.1825 5.4325 9 P 0 ;1
L 6.1825 5.4825 6.1825 5.4825 9 P 0 ;1
L 6.1825 5.5325 6.1825 5.5325 9 P 0 ;1
L 6.1825 5.5825 6.1825 5.5825 9 P 0 ;1
L 6.1825 5.6325 6.1825 5.6325 9 P 0 ;1
L 6.1825 5.6825 6.1825 5.6825 9 P 0 ;1
L 6.1825 5.7325 6.1825 5.7325 9 P 0 ;1
L 6.1825 5.7825 6.1825 5.7825 9 P 0 ;1
L 6.1825 5.8325 6.1825 5.8325 9 P 0 ;1
L 6.1825 5.8825 6.1825 5.8825 9 P 0 ;1
L 6.2325 0.5825 6.2325 0.5825 9 P 0 ;1
L 6.2325 0.6325 6.2325 0.6325 9 P 0 ;1
L 6.2325 0.6825 6.2325 0.6825 9 P 0 ;1
L 6.2325 0.7325 6.2325 0.7325 9 P 0 ;1
L 6.2325 0.7825 6.2325 0.7825 9 P 0 ;1
L 6.2325 0.8325 6.2325 0.8325 9 P 0 ;1
L 6.2325 0.8825 6.2325 0.8825 9 P 0 ;1
L 6.2325 0.9325 6.2325 0.9325 9 P 0 ;1
L 6.2325 0.9825 6.2325 0.9825 9 P 0 ;1
L 6.2325 1.0325 6.2325 1.0325 9 P 0 ;1
L 6.2325 1.0825 6.2325 1.0825 9 P 0 ;1
L 6.2325 1.1325 6.2325 1.1325 9 P 0 ;1
L 6.2325 1.1825 6.2325 1.1825 9 P 0 ;1
L 6.2325 1.2325 6.2325 1.2325 9 P 0 ;1
L 6.2325 1.2825 6.2325 1.2825 9 P 0 ;1
L 6.2325 1.3325 6.2325 1.3325 9 P 0 ;1
L 6.2325 1.7325 6.2325 1.7325 9 P 0 ;1
L 6.2325 1.7825 6.2325 1.7825 9 P 0 ;1
L 6.2325 1.8325 6.2325 1.8325 9 P 0 ;1
L 6.2325 1.8825 6.2325 1.8825 9 P 0 ;1
L 6.2325 1.9325 6.2325 1.9325 9 P 0 ;1
L 6.2325 1.9825 6.2325 1.9825 9 P 0 ;1
L 6.2325 2.0325 6.2325 2.0325 9 P 0 ;1
L 6.2325 2.0825 6.2325 2.0825 9 P 0 ;1
L 6.2325 2.1325 6.2325 2.1325 9 P 0 ;1
L 6.2325 2.1825 6.2325 2.1825 9 P 0 ;1
L 6.2325 2.2325 6.2325 2.2325 9 P 0 ;1
L 6.2325 2.2825 6.2325 2.2825 9 P 0 ;1
L 6.2325 2.3325 6.2325 2.3325 9 P 0 ;1
L 6.2325 2.3825 6.2325 2.3825 9 P 0 ;1
L 6.2325 2.4325 6.2325 2.4325 9 P 0 ;1
L 6.2325 2.4825 6.2325 2.4825 9 P 0 ;1
L 6.2325 2.5325 6.2325 2.5325 9 P 0 ;1
L 6.2325 2.5825 6.2325 2.5825 9 P 0 ;1
L 6.2325 2.6325 6.2325 2.6325 9 P 0 ;1
L 6.2325 2.6825 6.2325 2.6825 9 P 0 ;1
L 6.2325 2.7325 6.2325 2.7325 9 P 0 ;1
L 6.2325 2.7825 6.2325 2.7825 9 P 0 ;1
L 6.2325 2.8325 6.2325 2.8325 9 P 0 ;1
L 6.2325 2.8825 6.2325 2.8825 9 P 0 ;1
L 6.2325 2.9325 6.2325 2.9325 9 P 0 ;1
L 6.2325 2.9825 6.2325 2.9825 9 P 0 ;1
L 6.2325 3.0325 6.2325 3.0325 9 P 0 ;1
L 6.2325 3.0825 6.2325 3.0825 9 P 0 ;1
L 6.2325 3.1325 6.2325 3.1325 9 P 0 ;1
L 6.2325 3.1825 6.2325 3.1825 9 P 0 ;1
L 6.2325 3.2325 6.2325 3.2325 9 P 0 ;1
L 6.2325 3.2825 6.2325 3.2825 9 P 0 ;1
L 6.2325 3.3325 6.2325 3.3325 9 P 0 ;1
L 6.2325 3.3825 6.2325 3.3825 9 P 0 ;1
L 6.2325 3.4325 6.2325 3.4325 9 P 0 ;1
L 6.2325 3.4825 6.2325 3.4825 9 P 0 ;1
L 6.2325 3.5325 6.2325 3.5325 9 P 0 ;1
L 6.2325 3.5825 6.2325 3.5825 9 P 0 ;1
L 6.2325 3.6325 6.2325 3.6325 9 P 0 ;1
L 6.2325 3.6825 6.2325 3.6825 9 P 0 ;1
L 6.2325 3.7325 6.2325 3.7325 9 P 0 ;1
L 6.2325 3.7825 6.2325 3.7825 9 P 0 ;1
L 6.2325 3.8325 6.2325 3.8325 9 P 0 ;1
L 6.2325 3.8825 6.2325 3.8825 9 P 0 ;1
L 6.2325 3.9325 6.2325 3.9325 9 P 0 ;1
L 6.2325 3.9825 6.2325 3.9825 9 P 0 ;1
L 6.2325 4.0325 6.2325 4.0325 9 P 0 ;1
L 6.2325 4.3825 6.2325 4.3825 9 P 0 ;1
L 6.2325 4.4325 6.2325 4.4325 9 P 0 ;1
L 6.2325 4.4825 6.2325 4.4825 9 P 0 ;1
L 6.2325 4.5325 6.2325 4.5325 9 P 0 ;1
L 6.2325 4.5825 6.2325 4.5825 9 P 0 ;1
L 6.2325 4.6325 6.2325 4.6325 9 P 0 ;1
L 6.2325 4.6825 6.2325 4.6825 9 P 0 ;1
L 6.2325 4.7325 6.2325 4.7325 9 P 0 ;1
L 6.2325 4.7825 6.2325 4.7825 9 P 0 ;1
L 6.2325 4.8325 6.2325 4.8325 9 P 0 ;1
L 6.2325 4.8825 6.2325 4.8825 9 P 0 ;1
L 6.2325 4.9325 6.2325 4.9325 9 P 0 ;1
L 6.2325 4.9825 6.2325 4.9825 9 P 0 ;1
L 6.2325 5.0325 6.2325 5.0325 9 P 0 ;1
L 6.2325 5.0825 6.2325 5.0825 9 P 0 ;1
L 6.2325 5.1325 6.2325 5.1325 9 P 0 ;1
L 6.2325 5.1825 6.2325 5.1825 9 P 0 ;1
L 6.2325 5.2325 6.2325 5.2325 9 P 0 ;1
L 6.2325 5.2825 6.2325 5.2825 9 P 0 ;1
L 6.2325 5.3325 6.2325 5.3325 9 P 0 ;1
L 6.2325 5.3825 6.2325 5.3825 9 P 0 ;1
L 6.2325 5.4325 6.2325 5.4325 9 P 0 ;1
L 6.2325 5.4825 6.2325 5.4825 9 P 0 ;1
L 6.2325 5.5325 6.2325 5.5325 9 P 0 ;1
L 6.2325 5.5825 6.2325 5.5825 9 P 0 ;1
L 6.2325 5.6325 6.2325 5.6325 9 P 0 ;1
L 6.2325 5.6825 6.2325 5.6825 9 P 0 ;1
L 6.2325 5.7325 6.2325 5.7325 9 P 0 ;1
L 6.2325 5.7825 6.2325 5.7825 9 P 0 ;1
L 6.2325 5.8325 6.2325 5.8325 9 P 0 ;1
L 6.2325 5.8825 6.2325 5.8825 9 P 0 ;1
L 6.2825 0.5825 6.2825 0.5825 9 P 0 ;1
L 6.2825 0.6325 6.2825 0.6325 9 P 0 ;1
L 6.2825 0.6825 6.2825 0.6825 9 P 0 ;1
L 6.2825 0.7325 6.2825 0.7325 9 P 0 ;1
L 6.2825 0.7825 6.2825 0.7825 9 P 0 ;1
L 6.2825 0.8325 6.2825 0.8325 9 P 0 ;1
L 6.2825 0.8825 6.2825 0.8825 9 P 0 ;1
L 6.2825 0.9325 6.2825 0.9325 9 P 0 ;1
L 6.2825 0.9825 6.2825 0.9825 9 P 0 ;1
L 6.2825 1.0325 6.2825 1.0325 9 P 0 ;1
L 6.2825 1.0825 6.2825 1.0825 9 P 0 ;1
L 6.2825 1.1325 6.2825 1.1325 9 P 0 ;1
L 6.2825 1.1825 6.2825 1.1825 9 P 0 ;1
L 6.2825 1.2325 6.2825 1.2325 9 P 0 ;1
L 6.2825 1.2825 6.2825 1.2825 9 P 0 ;1
L 6.2825 1.3325 6.2825 1.3325 9 P 0 ;1
L 6.2825 1.3825 6.2825 1.3825 9 P 0 ;1
L 6.2825 1.6825 6.2825 1.6825 9 P 0 ;1
L 6.2825 1.7325 6.2825 1.7325 9 P 0 ;1
L 6.2825 1.7825 6.2825 1.7825 9 P 0 ;1
L 6.2825 1.8325 6.2825 1.8325 9 P 0 ;1
L 6.2825 1.8825 6.2825 1.8825 9 P 0 ;1
L 6.2825 1.9325 6.2825 1.9325 9 P 0 ;1
L 6.2825 1.9825 6.2825 1.9825 9 P 0 ;1
L 6.2825 2.0325 6.2825 2.0325 9 P 0 ;1
L 6.2825 2.0825 6.2825 2.0825 9 P 0 ;1
L 6.2825 2.1325 6.2825 2.1325 9 P 0 ;1
L 6.2825 2.1825 6.2825 2.1825 9 P 0 ;1
L 6.2825 2.2325 6.2825 2.2325 9 P 0 ;1
L 6.2825 2.2825 6.2825 2.2825 9 P 0 ;1
L 6.2825 2.3325 6.2825 2.3325 9 P 0 ;1
L 6.2825 2.3825 6.2825 2.3825 9 P 0 ;1
L 6.2825 2.4325 6.2825 2.4325 9 P 0 ;1
L 6.2825 2.4825 6.2825 2.4825 9 P 0 ;1
L 6.2825 2.5325 6.2825 2.5325 9 P 0 ;1
L 6.2825 2.5825 6.2825 2.5825 9 P 0 ;1
L 6.2825 2.6325 6.2825 2.6325 9 P 0 ;1
L 6.2825 2.6825 6.2825 2.6825 9 P 0 ;1
L 6.2825 2.7325 6.2825 2.7325 9 P 0 ;1
L 6.2825 2.7825 6.2825 2.7825 9 P 0 ;1
L 6.2825 2.8325 6.2825 2.8325 9 P 0 ;1
L 6.2825 2.8825 6.2825 2.8825 9 P 0 ;1
L 6.2825 2.9325 6.2825 2.9325 9 P 0 ;1
L 6.2825 2.9825 6.2825 2.9825 9 P 0 ;1
L 6.2825 3.0325 6.2825 3.0325 9 P 0 ;1
L 6.2825 3.0825 6.2825 3.0825 9 P 0 ;1
L 6.2825 3.1325 6.2825 3.1325 9 P 0 ;1
L 6.2825 3.1825 6.2825 3.1825 9 P 0 ;1
L 6.2825 3.2325 6.2825 3.2325 9 P 0 ;1
L 6.2825 3.2825 6.2825 3.2825 9 P 0 ;1
L 6.2825 3.3325 6.2825 3.3325 9 P 0 ;1
L 6.2825 3.3825 6.2825 3.3825 9 P 0 ;1
L 6.2825 3.4325 6.2825 3.4325 9 P 0 ;1
L 6.2825 3.4825 6.2825 3.4825 9 P 0 ;1
L 6.2825 3.5325 6.2825 3.5325 9 P 0 ;1
L 6.2825 3.5825 6.2825 3.5825 9 P 0 ;1
L 6.2825 3.6325 6.2825 3.6325 9 P 0 ;1
L 6.2825 3.6825 6.2825 3.6825 9 P 0 ;1
L 6.2825 3.7325 6.2825 3.7325 9 P 0 ;1
L 6.2825 3.7825 6.2825 3.7825 9 P 0 ;1
L 6.2825 3.8325 6.2825 3.8325 9 P 0 ;1
L 6.2825 3.8825 6.2825 3.8825 9 P 0 ;1
L 6.2825 3.9325 6.2825 3.9325 9 P 0 ;1
L 6.2825 3.9825 6.2825 3.9825 9 P 0 ;1
L 6.2825 4.0325 6.2825 4.0325 9 P 0 ;1
L 6.2825 4.3325 6.2825 4.3325 9 P 0 ;1
L 6.2825 4.3825 6.2825 4.3825 9 P 0 ;1
L 6.2825 4.4325 6.2825 4.4325 9 P 0 ;1
L 6.2825 4.4825 6.2825 4.4825 9 P 0 ;1
L 6.2825 4.5325 6.2825 4.5325 9 P 0 ;1
L 6.2825 5.0825 6.2825 5.0825 9 P 0 ;1
L 6.2825 5.1325 6.2825 5.1325 9 P 0 ;1
L 6.2825 5.1825 6.2825 5.1825 9 P 0 ;1
L 6.2825 5.2325 6.2825 5.2325 9 P 0 ;1
L 6.2825 5.2825 6.2825 5.2825 9 P 0 ;1
L 6.2825 5.3325 6.2825 5.3325 9 P 0 ;1
L 6.2825 5.3825 6.2825 5.3825 9 P 0 ;1
L 6.2825 5.4325 6.2825 5.4325 9 P 0 ;1
L 6.2825 5.4825 6.2825 5.4825 9 P 0 ;1
L 6.2825 5.5325 6.2825 5.5325 9 P 0 ;1
L 6.2825 5.5825 6.2825 5.5825 9 P 0 ;1
L 6.2825 5.6325 6.2825 5.6325 9 P 0 ;1
L 6.2825 5.6825 6.2825 5.6825 9 P 0 ;1
L 6.2825 5.7325 6.2825 5.7325 9 P 0 ;1
L 6.2825 5.7825 6.2825 5.7825 9 P 0 ;1
L 6.2825 5.8325 6.2825 5.8325 9 P 0 ;1
L 6.2825 5.8825 6.2825 5.8825 9 P 0 ;1
L 6.3325 0.5825 6.3325 0.5825 9 P 0 ;1
L 6.3325 0.6325 6.3325 0.6325 9 P 0 ;1
L 6.3325 0.6825 6.3325 0.6825 9 P 0 ;1
L 6.3325 0.7325 6.3325 0.7325 9 P 0 ;1
L 6.3325 0.7825 6.3325 0.7825 9 P 0 ;1
L 6.3325 0.8325 6.3325 0.8325 9 P 0 ;1
L 6.3325 0.8825 6.3325 0.8825 9 P 0 ;1
L 6.3325 0.9325 6.3325 0.9325 9 P 0 ;1
L 6.3325 0.9825 6.3325 0.9825 9 P 0 ;1
L 6.3325 1.0325 6.3325 1.0325 9 P 0 ;1
L 6.3325 1.0825 6.3325 1.0825 9 P 0 ;1
L 6.3325 1.1325 6.3325 1.1325 9 P 0 ;1
L 6.3325 1.1825 6.3325 1.1825 9 P 0 ;1
L 6.3325 1.2325 6.3325 1.2325 9 P 0 ;1
L 6.3325 1.2825 6.3325 1.2825 9 P 0 ;1
L 6.3325 1.3325 6.3325 1.3325 9 P 0 ;1
L 6.3325 1.3825 6.3325 1.3825 9 P 0 ;1
L 6.3325 1.4325 6.3325 1.4325 9 P 0 ;1
L 6.3325 1.4825 6.3325 1.4825 9 P 0 ;1
L 6.3325 1.5325 6.3325 1.5325 9 P 0 ;1
L 6.3325 1.5825 6.3325 1.5825 9 P 0 ;1
L 6.3325 1.6325 6.3325 1.6325 9 P 0 ;1
L 6.3325 1.6825 6.3325 1.6825 9 P 0 ;1
L 6.3325 1.7325 6.3325 1.7325 9 P 0 ;1
L 6.3325 1.7825 6.3325 1.7825 9 P 0 ;1
L 6.3325 1.8325 6.3325 1.8325 9 P 0 ;1
L 6.3325 1.8825 6.3325 1.8825 9 P 0 ;1
L 6.3325 1.9325 6.3325 1.9325 9 P 0 ;1
L 6.3325 1.9825 6.3325 1.9825 9 P 0 ;1
L 6.3325 2.0325 6.3325 2.0325 9 P 0 ;1
L 6.3325 2.0825 6.3325 2.0825 9 P 0 ;1
L 6.3325 2.1325 6.3325 2.1325 9 P 0 ;1
L 6.3325 2.1825 6.3325 2.1825 9 P 0 ;1
L 6.3325 2.2325 6.3325 2.2325 9 P 0 ;1
L 6.3325 2.2825 6.3325 2.2825 9 P 0 ;1
L 6.3325 2.3325 6.3325 2.3325 9 P 0 ;1
L 6.3325 2.3825 6.3325 2.3825 9 P 0 ;1
L 6.3325 2.4325 6.3325 2.4325 9 P 0 ;1
L 6.3325 2.4825 6.3325 2.4825 9 P 0 ;1
L 6.3325 2.5325 6.3325 2.5325 9 P 0 ;1
L 6.3325 2.5825 6.3325 2.5825 9 P 0 ;1
L 6.3325 2.6325 6.3325 2.6325 9 P 0 ;1
L 6.3325 2.6825 6.3325 2.6825 9 P 0 ;1
L 6.3325 2.7325 6.3325 2.7325 9 P 0 ;1
L 6.3325 2.7825 6.3325 2.7825 9 P 0 ;1
L 6.3325 2.8325 6.3325 2.8325 9 P 0 ;1
L 6.3325 2.8825 6.3325 2.8825 9 P 0 ;1
L 6.3325 2.9325 6.3325 2.9325 9 P 0 ;1
L 6.3325 2.9825 6.3325 2.9825 9 P 0 ;1
L 6.3325 3.0325 6.3325 3.0325 9 P 0 ;1
L 6.3325 3.0825 6.3325 3.0825 9 P 0 ;1
L 6.3325 3.1325 6.3325 3.1325 9 P 0 ;1
L 6.3325 3.1825 6.3325 3.1825 9 P 0 ;1
L 6.3325 3.2325 6.3325 3.2325 9 P 0 ;1
L 6.3325 3.2825 6.3325 3.2825 9 P 0 ;1
L 6.3325 3.3325 6.3325 3.3325 9 P 0 ;1
L 6.3325 3.3825 6.3325 3.3825 9 P 0 ;1
L 6.3325 3.4325 6.3325 3.4325 9 P 0 ;1
L 6.3325 3.4825 6.3325 3.4825 9 P 0 ;1
L 6.3325 3.5325 6.3325 3.5325 9 P 0 ;1
L 6.3325 3.5825 6.3325 3.5825 9 P 0 ;1
L 6.3325 3.6325 6.3325 3.6325 9 P 0 ;1
L 6.3325 3.6825 6.3325 3.6825 9 P 0 ;1
L 6.3325 3.7325 6.3325 3.7325 9 P 0 ;1
L 6.3325 3.7825 6.3325 3.7825 9 P 0 ;1
L 6.3325 3.8325 6.3325 3.8325 9 P 0 ;1
L 6.3325 3.8825 6.3325 3.8825 9 P 0 ;1
L 6.3325 3.9325 6.3325 3.9325 9 P 0 ;1
L 6.3325 3.9825 6.3325 3.9825 9 P 0 ;1
L 6.3325 4.0325 6.3325 4.0325 9 P 0 ;1
L 6.3325 4.0825 6.3325 4.0825 9 P 0 ;1
L 6.3325 4.1325 6.3325 4.1325 9 P 0 ;1
L 6.3325 4.1825 6.3325 4.1825 9 P 0 ;1
L 6.3325 4.2325 6.3325 4.2325 9 P 0 ;1
L 6.3325 4.2825 6.3325 4.2825 9 P 0 ;1
L 6.3325 4.3325 6.3325 4.3325 9 P 0 ;1
L 6.3325 4.3825 6.3325 4.3825 9 P 0 ;1
L 6.3325 4.4325 6.3325 4.4325 9 P 0 ;1
L 6.3325 4.4825 6.3325 4.4825 9 P 0 ;1
L 6.3325 4.5325 6.3325 4.5325 9 P 0 ;1
L 6.3325 5.1325 6.3325 5.1325 9 P 0 ;1
L 6.3325 5.1825 6.3325 5.1825 9 P 0 ;1
L 6.3325 5.2325 6.3325 5.2325 9 P 0 ;1
L 6.3325 5.2825 6.3325 5.2825 9 P 0 ;1
L 6.3325 5.3325 6.3325 5.3325 9 P 0 ;1
L 6.3325 5.3825 6.3325 5.3825 9 P 0 ;1
L 6.3325 5.4325 6.3325 5.4325 9 P 0 ;1
L 6.3325 5.4825 6.3325 5.4825 9 P 0 ;1
L 6.3325 5.5325 6.3325 5.5325 9 P 0 ;1
L 6.3325 5.5825 6.3325 5.5825 9 P 0 ;1
L 6.3325 5.6325 6.3325 5.6325 9 P 0 ;1
L 6.3325 5.6825 6.3325 5.6825 9 P 0 ;1
L 6.3325 5.7325 6.3325 5.7325 9 P 0 ;1
L 6.3325 5.7825 6.3325 5.7825 9 P 0 ;1
L 6.3325 5.8325 6.3325 5.8325 9 P 0 ;1
L 6.3325 5.8825 6.3325 5.8825 9 P 0 ;1
L 6.3825 0.5825 6.3825 0.5825 9 P 0 ;1
L 6.3825 0.6325 6.3825 0.6325 9 P 0 ;1
L 6.3825 0.6825 6.3825 0.6825 9 P 0 ;1
L 6.3825 0.7325 6.3825 0.7325 9 P 0 ;1
L 6.3825 0.7825 6.3825 0.7825 9 P 0 ;1
L 6.3825 0.8325 6.3825 0.8325 9 P 0 ;1
L 6.3825 0.8825 6.3825 0.8825 9 P 0 ;1
L 6.3825 0.9325 6.3825 0.9325 9 P 0 ;1
L 6.3825 0.9825 6.3825 0.9825 9 P 0 ;1
L 6.3825 1.0325 6.3825 1.0325 9 P 0 ;1
L 6.3825 1.0825 6.3825 1.0825 9 P 0 ;1
L 6.3825 1.1325 6.3825 1.1325 9 P 0 ;1
L 6.3825 1.1825 6.3825 1.1825 9 P 0 ;1
L 6.3825 1.2325 6.3825 1.2325 9 P 0 ;1
L 6.3825 1.2825 6.3825 1.2825 9 P 0 ;1
L 6.3825 1.3325 6.3825 1.3325 9 P 0 ;1
L 6.3825 1.3825 6.3825 1.3825 9 P 0 ;1
L 6.3825 1.4325 6.3825 1.4325 9 P 0 ;1
L 6.3825 1.4825 6.3825 1.4825 9 P 0 ;1
L 6.3825 1.5325 6.3825 1.5325 9 P 0 ;1
L 6.3825 1.5825 6.3825 1.5825 9 P 0 ;1
L 6.3825 1.6325 6.3825 1.6325 9 P 0 ;1
L 6.3825 1.6825 6.3825 1.6825 9 P 0 ;1
L 6.3825 1.7325 6.3825 1.7325 9 P 0 ;1
L 6.3825 1.7825 6.3825 1.7825 9 P 0 ;1
L 6.3825 1.8325 6.3825 1.8325 9 P 0 ;1
L 6.3825 1.8825 6.3825 1.8825 9 P 0 ;1
L 6.3825 1.9325 6.3825 1.9325 9 P 0 ;1
L 6.3825 1.9825 6.3825 1.9825 9 P 0 ;1
L 6.3825 2.0325 6.3825 2.0325 9 P 0 ;1
L 6.3825 2.0825 6.3825 2.0825 9 P 0 ;1
L 6.3825 2.1325 6.3825 2.1325 9 P 0 ;1
L 6.3825 2.1825 6.3825 2.1825 9 P 0 ;1
L 6.3825 2.2325 6.3825 2.2325 9 P 0 ;1
L 6.3825 2.2825 6.3825 2.2825 9 P 0 ;1
L 6.3825 2.3325 6.3825 2.3325 9 P 0 ;1
L 6.3825 2.3825 6.3825 2.3825 9 P 0 ;1
L 6.3825 2.4325 6.3825 2.4325 9 P 0 ;1
L 6.3825 2.4825 6.3825 2.4825 9 P 0 ;1
L 6.3825 2.5325 6.3825 2.5325 9 P 0 ;1
L 6.3825 2.5825 6.3825 2.5825 9 P 0 ;1
L 6.3825 2.6325 6.3825 2.6325 9 P 0 ;1
L 6.3825 2.6825 6.3825 2.6825 9 P 0 ;1
L 6.3825 2.7325 6.3825 2.7325 9 P 0 ;1
L 6.3825 2.7825 6.3825 2.7825 9 P 0 ;1
L 6.3825 2.8325 6.3825 2.8325 9 P 0 ;1
L 6.3825 2.8825 6.3825 2.8825 9 P 0 ;1
L 6.3825 2.9325 6.3825 2.9325 9 P 0 ;1
L 6.3825 2.9825 6.3825 2.9825 9 P 0 ;1
L 6.3825 3.0325 6.3825 3.0325 9 P 0 ;1
L 6.3825 3.0825 6.3825 3.0825 9 P 0 ;1
L 6.3825 3.1325 6.3825 3.1325 9 P 0 ;1
L 6.3825 3.1825 6.3825 3.1825 9 P 0 ;1
L 6.3825 3.2325 6.3825 3.2325 9 P 0 ;1
L 6.3825 3.2825 6.3825 3.2825 9 P 0 ;1
L 6.3825 3.3325 6.3825 3.3325 9 P 0 ;1
L 6.3825 3.3825 6.3825 3.3825 9 P 0 ;1
L 6.3825 3.4325 6.3825 3.4325 9 P 0 ;1
L 6.3825 3.4825 6.3825 3.4825 9 P 0 ;1
L 6.3825 3.5325 6.3825 3.5325 9 P 0 ;1
L 6.3825 3.5825 6.3825 3.5825 9 P 0 ;1
L 6.3825 3.6325 6.3825 3.6325 9 P 0 ;1
L 6.3825 3.6825 6.3825 3.6825 9 P 0 ;1
L 6.3825 3.7325 6.3825 3.7325 9 P 0 ;1
L 6.3825 3.7825 6.3825 3.7825 9 P 0 ;1
L 6.3825 3.8325 6.3825 3.8325 9 P 0 ;1
L 6.3825 3.8825 6.3825 3.8825 9 P 0 ;1
L 6.3825 3.9325 6.3825 3.9325 9 P 0 ;1
L 6.3825 3.9825 6.3825 3.9825 9 P 0 ;1
L 6.3825 4.0325 6.3825 4.0325 9 P 0 ;1
L 6.3825 4.0825 6.3825 4.0825 9 P 0 ;1
L 6.3825 4.1325 6.3825 4.1325 9 P 0 ;1
L 6.3825 4.1825 6.3825 4.1825 9 P 0 ;1
L 6.3825 4.2325 6.3825 4.2325 9 P 0 ;1
L 6.3825 4.2825 6.3825 4.2825 9 P 0 ;1
L 6.3825 4.3325 6.3825 4.3325 9 P 0 ;1
L 6.3825 4.3825 6.3825 4.3825 9 P 0 ;1
L 6.3825 4.4325 6.3825 4.4325 9 P 0 ;1
L 6.3825 4.4825 6.3825 4.4825 9 P 0 ;1
L 6.3825 4.5325 6.3825 4.5325 9 P 0 ;1
L 6.3825 5.1825 6.3825 5.1825 9 P 0 ;1
L 6.3825 5.2325 6.3825 5.2325 9 P 0 ;1
L 6.3825 5.2825 6.3825 5.2825 9 P 0 ;1
L 6.3825 5.3325 6.3825 5.3325 9 P 0 ;1
L 6.3825 5.3825 6.3825 5.3825 9 P 0 ;1
L 6.3825 5.4325 6.3825 5.4325 9 P 0 ;1
L 6.3825 5.4825 6.3825 5.4825 9 P 0 ;1
L 6.3825 5.5325 6.3825 5.5325 9 P 0 ;1
L 6.3825 5.5825 6.3825 5.5825 9 P 0 ;1
L 6.3825 5.6325 6.3825 5.6325 9 P 0 ;1
L 6.3825 5.6825 6.3825 5.6825 9 P 0 ;1
L 6.3825 5.7325 6.3825 5.7325 9 P 0 ;1
L 6.3825 5.7825 6.3825 5.7825 9 P 0 ;1
L 6.3825 5.8325 6.3825 5.8325 9 P 0 ;1
L 6.3825 5.8825 6.3825 5.8825 9 P 0 ;1
L 6.4325 0.5825 6.4325 0.5825 9 P 0 ;1
L 6.4325 0.6325 6.4325 0.6325 9 P 0 ;1
L 6.4325 0.6825 6.4325 0.6825 9 P 0 ;1
L 6.4325 0.7325 6.4325 0.7325 9 P 0 ;1
L 6.4325 0.7825 6.4325 0.7825 9 P 0 ;1
L 6.4325 0.8325 6.4325 0.8325 9 P 0 ;1
L 6.4325 0.8825 6.4325 0.8825 9 P 0 ;1
L 6.4325 0.9325 6.4325 0.9325 9 P 0 ;1
L 6.4325 0.9825 6.4325 0.9825 9 P 0 ;1
L 6.4325 1.0325 6.4325 1.0325 9 P 0 ;1
L 6.4325 1.0825 6.4325 1.0825 9 P 0 ;1
L 6.4325 1.1325 6.4325 1.1325 9 P 0 ;1
L 6.4325 1.1825 6.4325 1.1825 9 P 0 ;1
L 6.4325 1.2325 6.4325 1.2325 9 P 0 ;1
L 6.4325 1.2825 6.4325 1.2825 9 P 0 ;1
L 6.4325 1.3325 6.4325 1.3325 9 P 0 ;1
L 6.4325 1.3825 6.4325 1.3825 9 P 0 ;1
L 6.4325 1.4325 6.4325 1.4325 9 P 0 ;1
L 6.4325 1.4825 6.4325 1.4825 9 P 0 ;1
L 6.4325 1.5325 6.4325 1.5325 9 P 0 ;1
L 6.4325 1.5825 6.4325 1.5825 9 P 0 ;1
L 6.4325 1.6325 6.4325 1.6325 9 P 0 ;1
L 6.4325 1.6825 6.4325 1.6825 9 P 0 ;1
L 6.4325 1.7325 6.4325 1.7325 9 P 0 ;1
L 6.4325 1.7825 6.4325 1.7825 9 P 0 ;1
L 6.4325 1.8325 6.4325 1.8325 9 P 0 ;1
L 6.4325 1.8825 6.4325 1.8825 9 P 0 ;1
L 6.4325 1.9325 6.4325 1.9325 9 P 0 ;1
L 6.4325 1.9825 6.4325 1.9825 9 P 0 ;1
L 6.4325 2.0325 6.4325 2.0325 9 P 0 ;1
L 6.4325 2.0825 6.4325 2.0825 9 P 0 ;1
L 6.4325 2.1325 6.4325 2.1325 9 P 0 ;1
L 6.4325 2.1825 6.4325 2.1825 9 P 0 ;1
L 6.4325 2.2325 6.4325 2.2325 9 P 0 ;1
L 6.4325 2.2825 6.4325 2.2825 9 P 0 ;1
L 6.4325 2.3325 6.4325 2.3325 9 P 0 ;1
L 6.4325 2.3825 6.4325 2.3825 9 P 0 ;1
L 6.4325 2.4325 6.4325 2.4325 9 P 0 ;1
L 6.4325 2.4825 6.4325 2.4825 9 P 0 ;1
L 6.4325 2.5325 6.4325 2.5325 9 P 0 ;1
L 6.4325 2.5825 6.4325 2.5825 9 P 0 ;1
L 6.4325 2.6325 6.4325 2.6325 9 P 0 ;1
L 6.4325 2.6825 6.4325 2.6825 9 P 0 ;1
L 6.4325 2.7325 6.4325 2.7325 9 P 0 ;1
L 6.4325 2.7825 6.4325 2.7825 9 P 0 ;1
L 6.4325 2.8325 6.4325 2.8325 9 P 0 ;1
L 6.4325 2.8825 6.4325 2.8825 9 P 0 ;1
L 6.4325 2.9325 6.4325 2.9325 9 P 0 ;1
L 6.4325 2.9825 6.4325 2.9825 9 P 0 ;1
L 6.4325 3.0325 6.4325 3.0325 9 P 0 ;1
L 6.4325 3.0825 6.4325 3.0825 9 P 0 ;1
L 6.4325 3.1325 6.4325 3.1325 9 P 0 ;1
L 6.4325 3.1825 6.4325 3.1825 9 P 0 ;1
L 6.4325 3.2325 6.4325 3.2325 9 P 0 ;1
L 6.4325 3.2825 6.4325 3.2825 9 P 0 ;1
L 6.4325 3.3325 6.4325 3.3325 9 P 0 ;1
L 6.4325 3.3825 6.4325 3.3825 9 P 0 ;1
L 6.4325 3.4325 6.4325 3.4325 9 P 0 ;1
L 6.4325 3.4825 6.4325 3.4825 9 P 0 ;1
L 6.4325 3.5325 6.4325 3.5325 9 P 0 ;1
L 6.4325 3.5825 6.4325 3.5825 9 P 0 ;1
L 6.4325 3.6325 6.4325 3.6325 9 P 0 ;1
L 6.4325 3.6825 6.4325 3.6825 9 P 0 ;1
L 6.4325 3.7325 6.4325 3.7325 9 P 0 ;1
L 6.4325 3.7825 6.4325 3.7825 9 P 0 ;1
L 6.4325 3.8325 6.4325 3.8325 9 P 0 ;1
L 6.4325 3.8825 6.4325 3.8825 9 P 0 ;1
L 6.4325 3.9325 6.4325 3.9325 9 P 0 ;1
L 6.4325 3.9825 6.4325 3.9825 9 P 0 ;1
L 6.4325 4.0325 6.4325 4.0325 9 P 0 ;1
L 6.4325 4.0825 6.4325 4.0825 9 P 0 ;1
L 6.4325 4.1325 6.4325 4.1325 9 P 0 ;1
L 6.4325 4.1825 6.4325 4.1825 9 P 0 ;1
L 6.4325 4.2325 6.4325 4.2325 9 P 0 ;1
L 6.4325 4.2825 6.4325 4.2825 9 P 0 ;1
L 6.4325 4.3325 6.4325 4.3325 9 P 0 ;1
L 6.4325 4.3825 6.4325 4.3825 9 P 0 ;1
L 6.4325 4.4325 6.4325 4.4325 9 P 0 ;1
L 6.4325 4.4825 6.4325 4.4825 9 P 0 ;1
L 6.4325 4.5325 6.4325 4.5325 9 P 0 ;1
L 6.4325 4.5825 6.4325 4.5825 9 P 0 ;1
L 6.4325 4.6325 6.4325 4.6325 9 P 0 ;1
L 6.4325 4.6825 6.4325 4.6825 9 P 0 ;1
L 6.4325 4.7325 6.4325 4.7325 9 P 0 ;1
L 6.4325 4.7825 6.4325 4.7825 9 P 0 ;1
L 6.4325 4.8325 6.4325 4.8325 9 P 0 ;1
L 6.4325 5.1825 6.4325 5.1825 9 P 0 ;1
L 6.4325 5.2325 6.4325 5.2325 9 P 0 ;1
L 6.4325 5.2825 6.4325 5.2825 9 P 0 ;1
L 6.4325 5.3325 6.4325 5.3325 9 P 0 ;1
L 6.4325 5.3825 6.4325 5.3825 9 P 0 ;1
L 6.4325 5.4325 6.4325 5.4325 9 P 0 ;1
L 6.4325 5.4825 6.4325 5.4825 9 P 0 ;1
L 6.4325 5.5325 6.4325 5.5325 9 P 0 ;1
L 6.4325 5.5825 6.4325 5.5825 9 P 0 ;1
L 6.4325 5.6325 6.4325 5.6325 9 P 0 ;1
L 6.4325 5.6825 6.4325 5.6825 9 P 0 ;1
L 6.4325 5.7325 6.4325 5.7325 9 P 0 ;1
L 6.4325 5.7825 6.4325 5.7825 9 P 0 ;1
L 6.4325 5.8325 6.4325 5.8325 9 P 0 ;1
L 6.4325 5.8825 6.4325 5.8825 9 P 0 ;1
L 6.4825 0.5825 6.4825 0.5825 9 P 0 ;1
L 6.4825 0.6325 6.4825 0.6325 9 P 0 ;1
L 6.4825 0.6825 6.4825 0.6825 9 P 0 ;1
L 6.4825 0.7325 6.4825 0.7325 9 P 0 ;1
L 6.4825 0.7825 6.4825 0.7825 9 P 0 ;1
L 6.4825 0.8325 6.4825 0.8325 9 P 0 ;1
L 6.4825 0.8825 6.4825 0.8825 9 P 0 ;1
L 6.4825 0.9325 6.4825 0.9325 9 P 0 ;1
L 6.4825 0.9825 6.4825 0.9825 9 P 0 ;1
L 6.4825 1.0325 6.4825 1.0325 9 P 0 ;1
L 6.4825 1.0825 6.4825 1.0825 9 P 0 ;1
L 6.4825 1.1325 6.4825 1.1325 9 P 0 ;1
L 6.4825 1.1825 6.4825 1.1825 9 P 0 ;1
L 6.4825 1.2325 6.4825 1.2325 9 P 0 ;1
L 6.4825 1.2825 6.4825 1.2825 9 P 0 ;1
L 6.4825 1.3325 6.4825 1.3325 9 P 0 ;1
L 6.4825 1.3825 6.4825 1.3825 9 P 0 ;1
L 6.4825 1.4325 6.4825 1.4325 9 P 0 ;1
L 6.4825 1.4825 6.4825 1.4825 9 P 0 ;1
L 6.4825 1.5325 6.4825 1.5325 9 P 0 ;1
L 6.4825 1.5825 6.4825 1.5825 9 P 0 ;1
L 6.4825 1.6325 6.4825 1.6325 9 P 0 ;1
L 6.4825 1.6825 6.4825 1.6825 9 P 0 ;1
L 6.4825 1.7325 6.4825 1.7325 9 P 0 ;1
L 6.4825 1.7825 6.4825 1.7825 9 P 0 ;1
L 6.4825 1.8325 6.4825 1.8325 9 P 0 ;1
L 6.4825 1.8825 6.4825 1.8825 9 P 0 ;1
L 6.4825 1.9325 6.4825 1.9325 9 P 0 ;1
L 6.4825 1.9825 6.4825 1.9825 9 P 0 ;1
L 6.4825 2.0325 6.4825 2.0325 9 P 0 ;1
L 6.4825 2.0825 6.4825 2.0825 9 P 0 ;1
L 6.4825 2.1325 6.4825 2.1325 9 P 0 ;1
L 6.4825 2.1825 6.4825 2.1825 9 P 0 ;1
L 6.4825 2.2325 6.4825 2.2325 9 P 0 ;1
L 6.4825 2.2825 6.4825 2.2825 9 P 0 ;1
L 6.4825 2.3325 6.4825 2.3325 9 P 0 ;1
L 6.4825 2.3825 6.4825 2.3825 9 P 0 ;1
L 6.4825 2.4325 6.4825 2.4325 9 P 0 ;1
L 6.4825 2.4825 6.4825 2.4825 9 P 0 ;1
L 6.4825 2.5325 6.4825 2.5325 9 P 0 ;1
L 6.4825 2.5825 6.4825 2.5825 9 P 0 ;1
L 6.4825 2.6325 6.4825 2.6325 9 P 0 ;1
L 6.4825 2.6825 6.4825 2.6825 9 P 0 ;1
L 6.4825 2.7325 6.4825 2.7325 9 P 0 ;1
L 6.4825 2.7825 6.4825 2.7825 9 P 0 ;1
L 6.4825 2.8325 6.4825 2.8325 9 P 0 ;1
L 6.4825 2.8825 6.4825 2.8825 9 P 0 ;1
L 6.4825 2.9325 6.4825 2.9325 9 P 0 ;1
L 6.4825 2.9825 6.4825 2.9825 9 P 0 ;1
L 6.4825 3.0325 6.4825 3.0325 9 P 0 ;1
L 6.4825 3.0825 6.4825 3.0825 9 P 0 ;1
L 6.4825 3.1325 6.4825 3.1325 9 P 0 ;1
L 6.4825 3.1825 6.4825 3.1825 9 P 0 ;1
L 6.4825 3.2325 6.4825 3.2325 9 P 0 ;1
L 6.4825 3.2825 6.4825 3.2825 9 P 0 ;1
L 6.4825 3.3325 6.4825 3.3325 9 P 0 ;1
L 6.4825 3.3825 6.4825 3.3825 9 P 0 ;1
L 6.4825 3.4325 6.4825 3.4325 9 P 0 ;1
L 6.4825 3.4825 6.4825 3.4825 9 P 0 ;1
L 6.4825 3.5325 6.4825 3.5325 9 P 0 ;1
L 6.4825 3.5825 6.4825 3.5825 9 P 0 ;1
L 6.4825 3.6325 6.4825 3.6325 9 P 0 ;1
L 6.4825 3.6825 6.4825 3.6825 9 P 0 ;1
L 6.4825 3.7325 6.4825 3.7325 9 P 0 ;1
L 6.4825 3.7825 6.4825 3.7825 9 P 0 ;1
L 6.4825 3.8325 6.4825 3.8325 9 P 0 ;1
L 6.4825 3.8825 6.4825 3.8825 9 P 0 ;1
L 6.4825 3.9325 6.4825 3.9325 9 P 0 ;1
L 6.4825 3.9825 6.4825 3.9825 9 P 0 ;1
L 6.4825 4.0325 6.4825 4.0325 9 P 0 ;1
L 6.4825 4.0825 6.4825 4.0825 9 P 0 ;1
L 6.4825 4.1325 6.4825 4.1325 9 P 0 ;1
L 6.4825 4.1825 6.4825 4.1825 9 P 0 ;1
L 6.4825 4.2325 6.4825 4.2325 9 P 0 ;1
L 6.4825 4.2825 6.4825 4.2825 9 P 0 ;1
L 6.4825 4.3325 6.4825 4.3325 9 P 0 ;1
L 6.4825 4.3825 6.4825 4.3825 9 P 0 ;1
L 6.4825 4.4325 6.4825 4.4325 9 P 0 ;1
L 6.4825 4.4825 6.4825 4.4825 9 P 0 ;1
L 6.4825 4.5325 6.4825 4.5325 9 P 0 ;1
L 6.4825 4.5825 6.4825 4.5825 9 P 0 ;1
L 6.4825 4.6325 6.4825 4.6325 9 P 0 ;1
L 6.4825 4.6825 6.4825 4.6825 9 P 0 ;1
L 6.4825 4.7325 6.4825 4.7325 9 P 0 ;1
L 6.4825 4.7825 6.4825 4.7825 9 P 0 ;1
L 6.4825 4.8325 6.4825 4.8325 9 P 0 ;1
L 6.4825 5.1825 6.4825 5.1825 9 P 0 ;1
L 6.4825 5.2325 6.4825 5.2325 9 P 0 ;1
L 6.4825 5.2825 6.4825 5.2825 9 P 0 ;1
L 6.4825 5.3325 6.4825 5.3325 9 P 0 ;1
L 6.4825 5.3825 6.4825 5.3825 9 P 0 ;1
L 6.4825 5.4325 6.4825 5.4325 9 P 0 ;1
L 6.4825 5.4825 6.4825 5.4825 9 P 0 ;1
L 6.4825 5.5325 6.4825 5.5325 9 P 0 ;1
L 6.4825 5.5825 6.4825 5.5825 9 P 0 ;1
L 6.4825 5.6325 6.4825 5.6325 9 P 0 ;1
L 6.4825 5.6825 6.4825 5.6825 9 P 0 ;1
L 6.4825 5.7325 6.4825 5.7325 9 P 0 ;1
L 6.4825 5.7825 6.4825 5.7825 9 P 0 ;1
L 6.4825 5.8325 6.4825 5.8325 9 P 0 ;1
L 6.4825 5.8825 6.4825 5.8825 9 P 0 ;1
L 6.5325 0.5825 6.5325 0.5825 9 P 0 ;1
L 6.5325 0.6325 6.5325 0.6325 9 P 0 ;1
L 6.5325 0.6825 6.5325 0.6825 9 P 0 ;1
L 6.5325 0.7325 6.5325 0.7325 9 P 0 ;1
L 6.5325 0.7825 6.5325 0.7825 9 P 0 ;1
L 6.5325 0.8325 6.5325 0.8325 9 P 0 ;1
L 6.5325 0.8825 6.5325 0.8825 9 P 0 ;1
L 6.5325 0.9325 6.5325 0.9325 9 P 0 ;1
L 6.5325 0.9825 6.5325 0.9825 9 P 0 ;1
L 6.5325 1.0325 6.5325 1.0325 9 P 0 ;1
L 6.5325 1.0825 6.5325 1.0825 9 P 0 ;1
L 6.5325 1.1325 6.5325 1.1325 9 P 0 ;1
L 6.5325 1.1825 6.5325 1.1825 9 P 0 ;1
L 6.5325 1.2325 6.5325 1.2325 9 P 0 ;1
L 6.5325 1.2825 6.5325 1.2825 9 P 0 ;1
L 6.5325 1.3325 6.5325 1.3325 9 P 0 ;1
L 6.5325 1.3825 6.5325 1.3825 9 P 0 ;1
L 6.5325 1.4325 6.5325 1.4325 9 P 0 ;1
L 6.5325 1.4825 6.5325 1.4825 9 P 0 ;1
L 6.5325 1.5325 6.5325 1.5325 9 P 0 ;1
L 6.5325 1.5825 6.5325 1.5825 9 P 0 ;1
L 6.5325 1.6325 6.5325 1.6325 9 P 0 ;1
L 6.5325 1.6825 6.5325 1.6825 9 P 0 ;1
L 6.5325 1.7325 6.5325 1.7325 9 P 0 ;1
L 6.5325 1.7825 6.5325 1.7825 9 P 0 ;1
L 6.5325 1.8325 6.5325 1.8325 9 P 0 ;1
L 6.5325 1.8825 6.5325 1.8825 9 P 0 ;1
L 6.5325 1.9325 6.5325 1.9325 9 P 0 ;1
L 6.5325 1.9825 6.5325 1.9825 9 P 0 ;1
L 6.5325 2.0325 6.5325 2.0325 9 P 0 ;1
L 6.5325 2.0825 6.5325 2.0825 9 P 0 ;1
L 6.5325 2.1325 6.5325 2.1325 9 P 0 ;1
L 6.5325 2.1825 6.5325 2.1825 9 P 0 ;1
L 6.5325 2.2325 6.5325 2.2325 9 P 0 ;1
L 6.5325 2.2825 6.5325 2.2825 9 P 0 ;1
L 6.5325 2.3325 6.5325 2.3325 9 P 0 ;1
L 6.5325 2.3825 6.5325 2.3825 9 P 0 ;1
L 6.5325 2.4325 6.5325 2.4325 9 P 0 ;1
L 6.5325 2.4825 6.5325 2.4825 9 P 0 ;1
L 6.5325 2.5325 6.5325 2.5325 9 P 0 ;1
L 6.5325 2.5825 6.5325 2.5825 9 P 0 ;1
L 6.5325 2.6325 6.5325 2.6325 9 P 0 ;1
L 6.5325 2.6825 6.5325 2.6825 9 P 0 ;1
L 6.5325 2.7325 6.5325 2.7325 9 P 0 ;1
L 6.5325 2.7825 6.5325 2.7825 9 P 0 ;1
L 6.5325 2.8325 6.5325 2.8325 9 P 0 ;1
L 6.5325 2.8825 6.5325 2.8825 9 P 0 ;1
L 6.5325 2.9325 6.5325 2.9325 9 P 0 ;1
L 6.5325 2.9825 6.5325 2.9825 9 P 0 ;1
L 6.5325 3.0325 6.5325 3.0325 9 P 0 ;1
L 6.5325 3.0825 6.5325 3.0825 9 P 0 ;1
L 6.5325 3.1325 6.5325 3.1325 9 P 0 ;1
L 6.5325 3.1825 6.5325 3.1825 9 P 0 ;1
L 6.5325 3.2325 6.5325 3.2325 9 P 0 ;1
L 6.5325 3.2825 6.5325 3.2825 9 P 0 ;1
L 6.5325 3.3325 6.5325 3.3325 9 P 0 ;1
L 6.5325 3.3825 6.5325 3.3825 9 P 0 ;1
L 6.5325 3.4325 6.5325 3.4325 9 P 0 ;1
L 6.5325 3.4825 6.5325 3.4825 9 P 0 ;1
L 6.5325 3.5325 6.5325 3.5325 9 P 0 ;1
L 6.5325 3.5825 6.5325 3.5825 9 P 0 ;1
L 6.5325 3.6325 6.5325 3.6325 9 P 0 ;1
L 6.5325 3.6825 6.5325 3.6825 9 P 0 ;1
L 6.5325 3.7325 6.5325 3.7325 9 P 0 ;1
L 6.5325 3.7825 6.5325 3.7825 9 P 0 ;1
L 6.5325 3.8325 6.5325 3.8325 9 P 0 ;1
L 6.5325 3.8825 6.5325 3.8825 9 P 0 ;1
L 6.5325 3.9325 6.5325 3.9325 9 P 0 ;1
L 6.5325 3.9825 6.5325 3.9825 9 P 0 ;1
L 6.5325 4.0325 6.5325 4.0325 9 P 0 ;1
L 6.5325 4.0825 6.5325 4.0825 9 P 0 ;1
L 6.5325 4.1325 6.5325 4.1325 9 P 0 ;1
L 6.5325 4.1825 6.5325 4.1825 9 P 0 ;1
L 6.5325 4.2325 6.5325 4.2325 9 P 0 ;1
L 6.5325 4.2825 6.5325 4.2825 9 P 0 ;1
L 6.5325 4.3325 6.5325 4.3325 9 P 0 ;1
L 6.5325 4.3825 6.5325 4.3825 9 P 0 ;1
L 6.5325 4.4325 6.5325 4.4325 9 P 0 ;1
L 6.5325 4.4825 6.5325 4.4825 9 P 0 ;1
L 6.5325 4.5325 6.5325 4.5325 9 P 0 ;1
L 6.5325 4.5825 6.5325 4.5825 9 P 0 ;1
L 6.5325 4.6325 6.5325 4.6325 9 P 0 ;1
L 6.5325 4.6825 6.5325 4.6825 9 P 0 ;1
L 6.5325 4.7325 6.5325 4.7325 9 P 0 ;1
L 6.5325 4.8325 6.5325 4.8325 9 P 0 ;1
L 6.5325 5.1825 6.5325 5.1825 9 P 0 ;1
L 6.5325 5.2325 6.5325 5.2325 9 P 0 ;1
L 6.5325 5.2825 6.5325 5.2825 9 P 0 ;1
L 6.5325 5.3325 6.5325 5.3325 9 P 0 ;1
L 6.5325 5.3825 6.5325 5.3825 9 P 0 ;1
L 6.5325 5.4325 6.5325 5.4325 9 P 0 ;1
L 6.5325 5.4825 6.5325 5.4825 9 P 0 ;1
L 6.5325 5.5325 6.5325 5.5325 9 P 0 ;1
L 6.5325 5.5825 6.5325 5.5825 9 P 0 ;1
L 6.5325 5.6325 6.5325 5.6325 9 P 0 ;1
L 6.5325 5.6825 6.5325 5.6825 9 P 0 ;1
L 6.5325 5.7325 6.5325 5.7325 9 P 0 ;1
L 6.5325 5.7825 6.5325 5.7825 9 P 0 ;1
L 6.5325 5.8325 6.5325 5.8325 9 P 0 ;1
L 6.5325 5.8825 6.5325 5.8825 9 P 0 ;1
L 6.5825 0.5325 6.5825 0.5325 9 P 0 ;1
L 6.5825 0.5825 6.5825 0.5825 9 P 0 ;1
L 6.5825 0.6325 6.5825 0.6325 9 P 0 ;1
L 6.5825 0.6825 6.5825 0.6825 9 P 0 ;1
L 6.5825 0.7325 6.5825 0.7325 9 P 0 ;1
L 6.5825 0.7825 6.5825 0.7825 9 P 0 ;1
L 6.5825 0.8325 6.5825 0.8325 9 P 0 ;1
L 6.5825 0.8825 6.5825 0.8825 9 P 0 ;1
L 6.5825 0.9325 6.5825 0.9325 9 P 0 ;1
L 6.5825 0.9825 6.5825 0.9825 9 P 0 ;1
L 6.5825 1.0325 6.5825 1.0325 9 P 0 ;1
L 6.5825 1.0825 6.5825 1.0825 9 P 0 ;1
L 6.5825 1.1325 6.5825 1.1325 9 P 0 ;1
L 6.5825 1.1825 6.5825 1.1825 9 P 0 ;1
L 6.5825 1.2325 6.5825 1.2325 9 P 0 ;1
L 6.5825 1.2825 6.5825 1.2825 9 P 0 ;1
L 6.5825 1.3325 6.5825 1.3325 9 P 0 ;1
L 6.5825 1.3825 6.5825 1.3825 9 P 0 ;1
L 6.5825 1.4325 6.5825 1.4325 9 P 0 ;1
L 6.5825 1.4825 6.5825 1.4825 9 P 0 ;1
L 6.5825 1.5325 6.5825 1.5325 9 P 0 ;1
L 6.5825 1.5825 6.5825 1.5825 9 P 0 ;1
L 6.5825 1.6325 6.5825 1.6325 9 P 0 ;1
L 6.5825 1.6825 6.5825 1.6825 9 P 0 ;1
L 6.5825 1.7325 6.5825 1.7325 9 P 0 ;1
L 6.5825 1.7825 6.5825 1.7825 9 P 0 ;1
L 6.5825 1.8325 6.5825 1.8325 9 P 0 ;1
L 6.5825 1.8825 6.5825 1.8825 9 P 0 ;1
L 6.5825 1.9325 6.5825 1.9325 9 P 0 ;1
L 6.5825 1.9825 6.5825 1.9825 9 P 0 ;1
L 6.5825 2.0325 6.5825 2.0325 9 P 0 ;1
L 6.5825 2.0825 6.5825 2.0825 9 P 0 ;1
L 6.5825 2.1325 6.5825 2.1325 9 P 0 ;1
L 6.5825 2.1825 6.5825 2.1825 9 P 0 ;1
L 6.5825 2.2325 6.5825 2.2325 9 P 0 ;1
L 6.5825 2.2825 6.5825 2.2825 9 P 0 ;1
L 6.5825 2.3325 6.5825 2.3325 9 P 0 ;1
L 6.5825 2.3825 6.5825 2.3825 9 P 0 ;1
L 6.5825 2.4325 6.5825 2.4325 9 P 0 ;1
L 6.5825 2.4825 6.5825 2.4825 9 P 0 ;1
L 6.5825 2.5325 6.5825 2.5325 9 P 0 ;1
L 6.5825 2.5825 6.5825 2.5825 9 P 0 ;1
L 6.5825 2.6325 6.5825 2.6325 9 P 0 ;1
L 6.5825 2.6825 6.5825 2.6825 9 P 0 ;1
L 6.5825 2.7325 6.5825 2.7325 9 P 0 ;1
L 6.5825 2.7825 6.5825 2.7825 9 P 0 ;1
L 6.5825 2.8325 6.5825 2.8325 9 P 0 ;1
L 6.5825 2.8825 6.5825 2.8825 9 P 0 ;1
L 6.5825 2.9325 6.5825 2.9325 9 P 0 ;1
L 6.5825 2.9825 6.5825 2.9825 9 P 0 ;1
L 6.5825 3.0325 6.5825 3.0325 9 P 0 ;1
L 6.5825 3.0825 6.5825 3.0825 9 P 0 ;1
L 6.5825 3.1325 6.5825 3.1325 9 P 0 ;1
L 6.5825 3.1825 6.5825 3.1825 9 P 0 ;1
L 6.5825 3.2325 6.5825 3.2325 9 P 0 ;1
L 6.5825 3.2825 6.5825 3.2825 9 P 0 ;1
L 6.5825 3.3325 6.5825 3.3325 9 P 0 ;1
L 6.5825 3.3825 6.5825 3.3825 9 P 0 ;1
L 6.5825 3.4325 6.5825 3.4325 9 P 0 ;1
L 6.5825 3.4825 6.5825 3.4825 9 P 0 ;1
L 6.5825 3.5325 6.5825 3.5325 9 P 0 ;1
L 6.5825 3.5825 6.5825 3.5825 9 P 0 ;1
L 6.5825 3.6325 6.5825 3.6325 9 P 0 ;1
L 6.5825 3.6825 6.5825 3.6825 9 P 0 ;1
L 6.5825 3.7325 6.5825 3.7325 9 P 0 ;1
L 6.5825 3.7825 6.5825 3.7825 9 P 0 ;1
L 6.5825 3.8325 6.5825 3.8325 9 P 0 ;1
L 6.5825 3.8825 6.5825 3.8825 9 P 0 ;1
L 6.5825 3.9325 6.5825 3.9325 9 P 0 ;1
L 6.5825 3.9825 6.5825 3.9825 9 P 0 ;1
L 6.5825 4.0325 6.5825 4.0325 9 P 0 ;1
L 6.5825 4.0825 6.5825 4.0825 9 P 0 ;1
L 6.5825 4.1325 6.5825 4.1325 9 P 0 ;1
L 6.5825 4.1825 6.5825 4.1825 9 P 0 ;1
L 6.5825 4.2325 6.5825 4.2325 9 P 0 ;1
L 6.5825 4.2825 6.5825 4.2825 9 P 0 ;1
L 6.5825 4.3325 6.5825 4.3325 9 P 0 ;1
L 6.5825 4.3825 6.5825 4.3825 9 P 0 ;1
L 6.5825 4.4325 6.5825 4.4325 9 P 0 ;1
L 6.5825 4.4825 6.5825 4.4825 9 P 0 ;1
L 6.5825 4.5325 6.5825 4.5325 9 P 0 ;1
L 6.5825 5.1325 6.5825 5.1325 9 P 0 ;1
L 6.5825 5.1825 6.5825 5.1825 9 P 0 ;1
L 6.5825 5.2325 6.5825 5.2325 9 P 0 ;1
L 6.5825 5.2825 6.5825 5.2825 9 P 0 ;1
L 6.5825 5.3325 6.5825 5.3325 9 P 0 ;1
L 6.5825 5.3825 6.5825 5.3825 9 P 0 ;1
L 6.5825 5.4325 6.5825 5.4325 9 P 0 ;1
L 6.5825 5.4825 6.5825 5.4825 9 P 0 ;1
L 6.5825 5.5325 6.5825 5.5325 9 P 0 ;1
L 6.5825 5.5825 6.5825 5.5825 9 P 0 ;1
L 6.5825 5.6325 6.5825 5.6325 9 P 0 ;1
L 6.5825 5.6825 6.5825 5.6825 9 P 0 ;1
L 6.5825 5.7325 6.5825 5.7325 9 P 0 ;1
L 6.5825 5.7825 6.5825 5.7825 9 P 0 ;1
L 6.5825 5.8325 6.5825 5.8325 9 P 0 ;1
L 6.5825 5.8825 6.5825 5.8825 9 P 0 ;1
L 6.6325 0.5325 6.6325 0.5325 9 P 0 ;1
L 6.6325 0.5825 6.6325 0.5825 9 P 0 ;1
L 6.6325 0.6325 6.6325 0.6325 9 P 0 ;1
L 6.6325 0.6825 6.6325 0.6825 9 P 0 ;1
L 6.6325 0.7325 6.6325 0.7325 9 P 0 ;1
L 6.6325 0.7825 6.6325 0.7825 9 P 0 ;1
L 6.6325 0.8325 6.6325 0.8325 9 P 0 ;1
L 6.6325 0.8825 6.6325 0.8825 9 P 0 ;1
L 6.6325 0.9325 6.6325 0.9325 9 P 0 ;1
L 6.6325 0.9825 6.6325 0.9825 9 P 0 ;1
L 6.6325 1.0325 6.6325 1.0325 9 P 0 ;1
L 6.6325 1.0825 6.6325 1.0825 9 P 0 ;1
L 6.6325 1.1325 6.6325 1.1325 9 P 0 ;1
L 6.6325 1.1825 6.6325 1.1825 9 P 0 ;1
L 6.6325 1.2325 6.6325 1.2325 9 P 0 ;1
L 6.6325 1.2825 6.6325 1.2825 9 P 0 ;1
L 6.6325 1.3325 6.6325 1.3325 9 P 0 ;1
L 6.6325 1.3825 6.6325 1.3825 9 P 0 ;1
L 6.6325 1.4325 6.6325 1.4325 9 P 0 ;1
L 6.6325 1.4825 6.6325 1.4825 9 P 0 ;1
L 6.6325 1.5325 6.6325 1.5325 9 P 0 ;1
L 6.6325 1.5825 6.6325 1.5825 9 P 0 ;1
L 6.6325 1.6325 6.6325 1.6325 9 P 0 ;1
L 6.6325 1.6825 6.6325 1.6825 9 P 0 ;1
L 6.6325 1.7325 6.6325 1.7325 9 P 0 ;1
L 6.6325 1.7825 6.6325 1.7825 9 P 0 ;1
L 6.6325 1.8325 6.6325 1.8325 9 P 0 ;1
L 6.6325 1.8825 6.6325 1.8825 9 P 0 ;1
L 6.6325 1.9325 6.6325 1.9325 9 P 0 ;1
L 6.6325 1.9825 6.6325 1.9825 9 P 0 ;1
L 6.6325 2.0325 6.6325 2.0325 9 P 0 ;1
L 6.6325 2.0825 6.6325 2.0825 9 P 0 ;1
L 6.6325 2.1325 6.6325 2.1325 9 P 0 ;1
L 6.6325 2.1825 6.6325 2.1825 9 P 0 ;1
L 6.6325 2.2325 6.6325 2.2325 9 P 0 ;1
L 6.6325 2.2825 6.6325 2.2825 9 P 0 ;1
L 6.6325 2.3325 6.6325 2.3325 9 P 0 ;1
L 6.6325 2.3825 6.6325 2.3825 9 P 0 ;1
L 6.6325 2.4325 6.6325 2.4325 9 P 0 ;1
L 6.6325 2.4825 6.6325 2.4825 9 P 0 ;1
L 6.6325 2.5325 6.6325 2.5325 9 P 0 ;1
L 6.6325 2.5825 6.6325 2.5825 9 P 0 ;1
L 6.6325 2.6325 6.6325 2.6325 9 P 0 ;1
L 6.6325 2.6825 6.6325 2.6825 9 P 0 ;1
L 6.6325 2.7325 6.6325 2.7325 9 P 0 ;1
L 6.6325 2.7825 6.6325 2.7825 9 P 0 ;1
L 6.6325 2.8325 6.6325 2.8325 9 P 0 ;1
L 6.6325 2.8825 6.6325 2.8825 9 P 0 ;1
L 6.6325 2.9325 6.6325 2.9325 9 P 0 ;1
L 6.6325 2.9825 6.6325 2.9825 9 P 0 ;1
L 6.6325 3.0325 6.6325 3.0325 9 P 0 ;1
L 6.6325 3.0825 6.6325 3.0825 9 P 0 ;1
L 6.6325 3.1325 6.6325 3.1325 9 P 0 ;1
L 6.6325 3.1825 6.6325 3.1825 9 P 0 ;1
L 6.6325 3.2325 6.6325 3.2325 9 P 0 ;1
L 6.6325 3.2825 6.6325 3.2825 9 P 0 ;1
L 6.6325 3.3325 6.6325 3.3325 9 P 0 ;1
L 6.6325 3.3825 6.6325 3.3825 9 P 0 ;1
L 6.6325 3.4325 6.6325 3.4325 9 P 0 ;1
L 6.6325 3.4825 6.6325 3.4825 9 P 0 ;1
L 6.6325 3.5325 6.6325 3.5325 9 P 0 ;1
L 6.6325 3.5825 6.6325 3.5825 9 P 0 ;1
L 6.6325 3.6325 6.6325 3.6325 9 P 0 ;1
L 6.6325 3.6825 6.6325 3.6825 9 P 0 ;1
L 6.6325 3.7325 6.6325 3.7325 9 P 0 ;1
L 6.6325 3.7825 6.6325 3.7825 9 P 0 ;1
L 6.6325 3.8325 6.6325 3.8325 9 P 0 ;1
L 6.6325 3.8825 6.6325 3.8825 9 P 0 ;1
L 6.6325 3.9325 6.6325 3.9325 9 P 0 ;1
L 6.6325 3.9825 6.6325 3.9825 9 P 0 ;1
L 6.6325 4.0325 6.6325 4.0325 9 P 0 ;1
L 6.6325 4.0825 6.6325 4.0825 9 P 0 ;1
L 6.6325 4.1325 6.6325 4.1325 9 P 0 ;1
L 6.6325 4.1825 6.6325 4.1825 9 P 0 ;1
L 6.6325 4.2325 6.6325 4.2325 9 P 0 ;1
L 6.6325 4.2825 6.6325 4.2825 9 P 0 ;1
L 6.6325 4.3325 6.6325 4.3325 9 P 0 ;1
L 6.6325 4.3825 6.6325 4.3825 9 P 0 ;1
L 6.6325 4.4325 6.6325 4.4325 9 P 0 ;1
L 6.6325 4.4825 6.6325 4.4825 9 P 0 ;1
L 6.6325 4.5325 6.6325 4.5325 9 P 0 ;1
L 6.6325 5.1325 6.6325 5.1325 9 P 0 ;1
L 6.6325 5.1825 6.6325 5.1825 9 P 0 ;1
L 6.6325 5.2325 6.6325 5.2325 9 P 0 ;1
L 6.6325 5.2825 6.6325 5.2825 9 P 0 ;1
L 6.6325 5.3325 6.6325 5.3325 9 P 0 ;1
L 6.6325 5.3825 6.6325 5.3825 9 P 0 ;1
L 6.6325 5.4325 6.6325 5.4325 9 P 0 ;1
L 6.6325 5.4825 6.6325 5.4825 9 P 0 ;1
L 6.6325 5.5325 6.6325 5.5325 9 P 0 ;1
L 6.6325 5.5825 6.6325 5.5825 9 P 0 ;1
L 6.6325 5.6325 6.6325 5.6325 9 P 0 ;1
L 6.6325 5.6825 6.6325 5.6825 9 P 0 ;1
L 6.6325 5.7325 6.6325 5.7325 9 P 0 ;1
L 6.6325 5.7825 6.6325 5.7825 9 P 0 ;1
L 6.6325 5.8325 6.6325 5.8325 9 P 0 ;1
L 6.6325 5.8825 6.6325 5.8825 9 P 0 ;1
L 6.6825 0.4325 6.6825 0.4325 9 P 0 ;1
L 6.6825 0.4825 6.6825 0.4825 9 P 0 ;1
L 6.6825 0.5325 6.6825 0.5325 9 P 0 ;1
L 6.6825 0.5825 6.6825 0.5825 9 P 0 ;1
L 6.6825 0.6325 6.6825 0.6325 9 P 0 ;1
L 6.6825 0.6825 6.6825 0.6825 9 P 0 ;1
L 6.6825 0.7325 6.6825 0.7325 9 P 0 ;1
L 6.6825 0.7825 6.6825 0.7825 9 P 0 ;1
L 6.6825 0.8325 6.6825 0.8325 9 P 0 ;1
L 6.6825 0.8825 6.6825 0.8825 9 P 0 ;1
L 6.6825 0.9325 6.6825 0.9325 9 P 0 ;1
L 6.6825 0.9825 6.6825 0.9825 9 P 0 ;1
L 6.6825 1.0325 6.6825 1.0325 9 P 0 ;1
L 6.6825 1.0825 6.6825 1.0825 9 P 0 ;1
L 6.6825 1.1325 6.6825 1.1325 9 P 0 ;1
L 6.6825 1.1825 6.6825 1.1825 9 P 0 ;1
L 6.6825 1.2325 6.6825 1.2325 9 P 0 ;1
L 6.6825 1.2825 6.6825 1.2825 9 P 0 ;1
L 6.6825 1.3325 6.6825 1.3325 9 P 0 ;1
L 6.6825 1.3825 6.6825 1.3825 9 P 0 ;1
L 6.6825 1.4325 6.6825 1.4325 9 P 0 ;1
L 6.6825 1.4825 6.6825 1.4825 9 P 0 ;1
L 6.6825 1.5325 6.6825 1.5325 9 P 0 ;1
L 6.6825 1.5825 6.6825 1.5825 9 P 0 ;1
L 6.6825 1.6325 6.6825 1.6325 9 P 0 ;1
L 6.6825 1.6825 6.6825 1.6825 9 P 0 ;1
L 6.6825 1.7325 6.6825 1.7325 9 P 0 ;1
L 6.6825 1.7825 6.6825 1.7825 9 P 0 ;1
L 6.6825 1.8325 6.6825 1.8325 9 P 0 ;1
L 6.6825 1.8825 6.6825 1.8825 9 P 0 ;1
L 6.6825 1.9325 6.6825 1.9325 9 P 0 ;1
L 6.6825 1.9825 6.6825 1.9825 9 P 0 ;1
L 6.6825 2.0325 6.6825 2.0325 9 P 0 ;1
L 6.6825 2.0825 6.6825 2.0825 9 P 0 ;1
L 6.6825 2.1325 6.6825 2.1325 9 P 0 ;1
L 6.6825 2.1825 6.6825 2.1825 9 P 0 ;1
L 6.6825 2.2325 6.6825 2.2325 9 P 0 ;1
L 6.6825 2.2825 6.6825 2.2825 9 P 0 ;1
L 6.6825 2.3325 6.6825 2.3325 9 P 0 ;1
L 6.6825 2.3825 6.6825 2.3825 9 P 0 ;1
L 6.6825 2.4325 6.6825 2.4325 9 P 0 ;1
L 6.6825 2.4825 6.6825 2.4825 9 P 0 ;1
L 6.6825 2.5325 6.6825 2.5325 9 P 0 ;1
L 6.6825 2.5825 6.6825 2.5825 9 P 0 ;1
L 6.6825 2.6325 6.6825 2.6325 9 P 0 ;1
L 6.6825 2.6825 6.6825 2.6825 9 P 0 ;1
L 6.6825 2.7325 6.6825 2.7325 9 P 0 ;1
L 6.6825 2.7825 6.6825 2.7825 9 P 0 ;1
L 6.6825 2.8325 6.6825 2.8325 9 P 0 ;1
L 6.6825 2.8825 6.6825 2.8825 9 P 0 ;1
L 6.6825 2.9325 6.6825 2.9325 9 P 0 ;1
L 6.6825 2.9825 6.6825 2.9825 9 P 0 ;1
L 6.6825 3.0325 6.6825 3.0325 9 P 0 ;1
L 6.6825 3.0825 6.6825 3.0825 9 P 0 ;1
L 6.6825 3.1325 6.6825 3.1325 9 P 0 ;1
L 6.6825 3.1825 6.6825 3.1825 9 P 0 ;1
L 6.6825 3.2325 6.6825 3.2325 9 P 0 ;1
L 6.6825 3.2825 6.6825 3.2825 9 P 0 ;1
L 6.6825 3.3325 6.6825 3.3325 9 P 0 ;1
L 6.6825 3.3825 6.6825 3.3825 9 P 0 ;1
L 6.6825 3.4325 6.6825 3.4325 9 P 0 ;1
L 6.6825 3.4825 6.6825 3.4825 9 P 0 ;1
L 6.6825 3.5325 6.6825 3.5325 9 P 0 ;1
L 6.6825 3.5825 6.6825 3.5825 9 P 0 ;1
L 6.6825 3.6325 6.6825 3.6325 9 P 0 ;1
L 6.6825 3.6825 6.6825 3.6825 9 P 0 ;1
L 6.6825 3.7325 6.6825 3.7325 9 P 0 ;1
L 6.6825 3.7825 6.6825 3.7825 9 P 0 ;1
L 6.6825 3.8325 6.6825 3.8325 9 P 0 ;1
L 6.6825 3.8825 6.6825 3.8825 9 P 0 ;1
L 6.6825 3.9325 6.6825 3.9325 9 P 0 ;1
L 6.6825 3.9825 6.6825 3.9825 9 P 0 ;1
L 6.6825 4.0325 6.6825 4.0325 9 P 0 ;1
L 6.6825 4.0825 6.6825 4.0825 9 P 0 ;1
L 6.6825 4.1325 6.6825 4.1325 9 P 0 ;1
L 6.6825 4.1825 6.6825 4.1825 9 P 0 ;1
L 6.6825 4.2325 6.6825 4.2325 9 P 0 ;1
L 6.6825 4.2825 6.6825 4.2825 9 P 0 ;1
L 6.6825 4.3325 6.6825 4.3325 9 P 0 ;1
L 6.6825 4.3825 6.6825 4.3825 9 P 0 ;1
L 6.6825 4.4325 6.6825 4.4325 9 P 0 ;1
L 6.6825 4.4825 6.6825 4.4825 9 P 0 ;1
L 6.6825 5.1325 6.6825 5.1325 9 P 0 ;1
L 6.6825 5.1825 6.6825 5.1825 9 P 0 ;1
L 6.6825 5.2325 6.6825 5.2325 9 P 0 ;1
L 6.6825 5.2825 6.6825 5.2825 9 P 0 ;1
L 6.6825 5.3325 6.6825 5.3325 9 P 0 ;1
L 6.6825 5.3825 6.6825 5.3825 9 P 0 ;1
L 6.6825 5.4325 6.6825 5.4325 9 P 0 ;1
L 6.6825 5.4825 6.6825 5.4825 9 P 0 ;1
L 6.6825 5.5325 6.6825 5.5325 9 P 0 ;1
L 6.6825 5.5825 6.6825 5.5825 9 P 0 ;1
L 6.6825 5.6325 6.6825 5.6325 9 P 0 ;1
L 6.6825 5.6825 6.6825 5.6825 9 P 0 ;1
L 6.6825 5.7325 6.6825 5.7325 9 P 0 ;1
L 6.6825 5.7825 6.6825 5.7825 9 P 0 ;1
L 6.6825 5.8325 6.6825 5.8325 9 P 0 ;1
L 6.6825 5.8825 6.6825 5.8825 9 P 0 ;1
L 6.7325 0.1325 6.7325 0.1325 9 P 0 ;1
L 6.7325 0.1825 6.7325 0.1825 9 P 0 ;1
L 6.7325 0.2325 6.7325 0.2325 9 P 0 ;1
L 6.7325 0.2825 6.7325 0.2825 9 P 0 ;1
L 6.7325 0.3325 6.7325 0.3325 9 P 0 ;1
L 6.7325 0.3825 6.7325 0.3825 9 P 0 ;1
L 6.7325 0.4325 6.7325 0.4325 9 P 0 ;1
L 6.7325 0.4825 6.7325 0.4825 9 P 0 ;1
L 6.7325 0.5325 6.7325 0.5325 9 P 0 ;1
L 6.7325 0.5825 6.7325 0.5825 9 P 0 ;1
L 6.7325 0.6325 6.7325 0.6325 9 P 0 ;1
L 6.7325 0.6825 6.7325 0.6825 9 P 0 ;1
L 6.7325 0.7325 6.7325 0.7325 9 P 0 ;1
L 6.7325 0.7825 6.7325 0.7825 9 P 0 ;1
L 6.7325 0.8325 6.7325 0.8325 9 P 0 ;1
L 6.7325 0.8825 6.7325 0.8825 9 P 0 ;1
L 6.7325 0.9325 6.7325 0.9325 9 P 0 ;1
L 6.7325 0.9825 6.7325 0.9825 9 P 0 ;1
L 6.7325 1.0325 6.7325 1.0325 9 P 0 ;1
L 6.7325 1.0825 6.7325 1.0825 9 P 0 ;1
L 6.7325 1.1325 6.7325 1.1325 9 P 0 ;1
L 6.7325 1.1825 6.7325 1.1825 9 P 0 ;1
L 6.7325 1.2325 6.7325 1.2325 9 P 0 ;1
L 6.7325 1.2825 6.7325 1.2825 9 P 0 ;1
L 6.7325 1.3325 6.7325 1.3325 9 P 0 ;1
L 6.7325 1.3825 6.7325 1.3825 9 P 0 ;1
L 6.7325 1.4325 6.7325 1.4325 9 P 0 ;1
L 6.7325 1.4825 6.7325 1.4825 9 P 0 ;1
L 6.7325 1.5325 6.7325 1.5325 9 P 0 ;1
L 6.7325 1.5825 6.7325 1.5825 9 P 0 ;1
L 6.7325 1.6325 6.7325 1.6325 9 P 0 ;1
L 6.7325 1.6825 6.7325 1.6825 9 P 0 ;1
L 6.7325 1.7325 6.7325 1.7325 9 P 0 ;1
L 6.7325 1.7825 6.7325 1.7825 9 P 0 ;1
L 6.7325 1.8325 6.7325 1.8325 9 P 0 ;1
L 6.7325 1.8825 6.7325 1.8825 9 P 0 ;1
L 6.7325 1.9325 6.7325 1.9325 9 P 0 ;1
L 6.7325 1.9825 6.7325 1.9825 9 P 0 ;1
L 6.7325 2.0325 6.7325 2.0325 9 P 0 ;1
L 6.7325 2.0825 6.7325 2.0825 9 P 0 ;1
L 6.7325 2.1325 6.7325 2.1325 9 P 0 ;1
L 6.7325 2.1825 6.7325 2.1825 9 P 0 ;1
L 6.7325 2.2325 6.7325 2.2325 9 P 0 ;1
L 6.7325 2.2825 6.7325 2.2825 9 P 0 ;1
L 6.7325 2.3325 6.7325 2.3325 9 P 0 ;1
L 6.7325 2.3825 6.7325 2.3825 9 P 0 ;1
L 6.7325 2.4325 6.7325 2.4325 9 P 0 ;1
L 6.7325 2.4825 6.7325 2.4825 9 P 0 ;1
L 6.7325 2.5325 6.7325 2.5325 9 P 0 ;1
L 6.7325 2.5825 6.7325 2.5825 9 P 0 ;1
L 6.7325 2.6325 6.7325 2.6325 9 P 0 ;1
L 6.7325 2.6825 6.7325 2.6825 9 P 0 ;1
L 6.7325 2.7325 6.7325 2.7325 9 P 0 ;1
L 6.7325 2.7825 6.7325 2.7825 9 P 0 ;1
L 6.7325 2.8325 6.7325 2.8325 9 P 0 ;1
L 6.7325 2.8825 6.7325 2.8825 9 P 0 ;1
L 6.7325 2.9325 6.7325 2.9325 9 P 0 ;1
L 6.7325 2.9825 6.7325 2.9825 9 P 0 ;1
L 6.7325 3.0325 6.7325 3.0325 9 P 0 ;1
L 6.7325 3.0825 6.7325 3.0825 9 P 0 ;1
L 6.7325 3.1325 6.7325 3.1325 9 P 0 ;1
L 6.7325 3.1825 6.7325 3.1825 9 P 0 ;1
L 6.7325 3.2325 6.7325 3.2325 9 P 0 ;1
L 6.7325 3.2825 6.7325 3.2825 9 P 0 ;1
L 6.7325 3.3325 6.7325 3.3325 9 P 0 ;1
L 6.7325 3.3825 6.7325 3.3825 9 P 0 ;1
L 6.7325 3.4325 6.7325 3.4325 9 P 0 ;1
L 6.7325 3.4825 6.7325 3.4825 9 P 0 ;1
L 6.7325 3.5325 6.7325 3.5325 9 P 0 ;1
L 6.7325 3.5825 6.7325 3.5825 9 P 0 ;1
L 6.7325 3.6325 6.7325 3.6325 9 P 0 ;1
L 6.7325 3.6825 6.7325 3.6825 9 P 0 ;1
L 6.7325 3.7325 6.7325 3.7325 9 P 0 ;1
L 6.7325 3.7825 6.7325 3.7825 9 P 0 ;1
L 6.7325 3.8325 6.7325 3.8325 9 P 0 ;1
L 6.7325 3.8825 6.7325 3.8825 9 P 0 ;1
L 6.7325 3.9325 6.7325 3.9325 9 P 0 ;1
L 6.7325 3.9825 6.7325 3.9825 9 P 0 ;1
L 6.7325 4.0325 6.7325 4.0325 9 P 0 ;1
L 6.7325 4.0825 6.7325 4.0825 9 P 0 ;1
L 6.7325 4.1325 6.7325 4.1325 9 P 0 ;1
L 6.7325 4.1825 6.7325 4.1825 9 P 0 ;1
L 6.7325 4.2325 6.7325 4.2325 9 P 0 ;1
L 6.7325 4.2825 6.7325 4.2825 9 P 0 ;1
L 6.7325 4.3325 6.7325 4.3325 9 P 0 ;1
L 6.7325 4.3825 6.7325 4.3825 9 P 0 ;1
L 6.7325 4.4325 6.7325 4.4325 9 P 0 ;1
L 6.7325 4.4825 6.7325 4.4825 9 P 0 ;1
L 6.7325 5.0825 6.7325 5.0825 9 P 0 ;1
L 6.7325 5.1325 6.7325 5.1325 9 P 0 ;1
L 6.7325 5.1825 6.7325 5.1825 9 P 0 ;1
L 6.7325 5.2325 6.7325 5.2325 9 P 0 ;1
L 6.7325 5.2825 6.7325 5.2825 9 P 0 ;1
L 6.7325 5.3325 6.7325 5.3325 9 P 0 ;1
L 6.7325 5.3825 6.7325 5.3825 9 P 0 ;1
L 6.7325 5.4325 6.7325 5.4325 9 P 0 ;1
L 6.7325 5.4825 6.7325 5.4825 9 P 0 ;1
L 6.7325 5.5325 6.7325 5.5325 9 P 0 ;1
L 6.7325 5.5825 6.7325 5.5825 9 P 0 ;1
L 6.7325 5.6325 6.7325 5.6325 9 P 0 ;1
L 6.7325 5.6825 6.7325 5.6825 9 P 0 ;1
L 6.7325 5.7325 6.7325 5.7325 9 P 0 ;1
L 6.7325 5.7825 6.7325 5.7825 9 P 0 ;1
L 6.7325 5.8325 6.7325 5.8325 9 P 0 ;1
L 6.7325 5.8825 6.7325 5.8825 9 P 0 ;1
L 6.7825 0.1325 6.7825 0.1325 9 P 0 ;1
L 6.7825 0.1825 6.7825 0.1825 9 P 0 ;1
L 6.7825 0.2325 6.7825 0.2325 9 P 0 ;1
L 6.7825 0.2825 6.7825 0.2825 9 P 0 ;1
L 6.7825 0.3325 6.7825 0.3325 9 P 0 ;1
L 6.7825 0.3825 6.7825 0.3825 9 P 0 ;1
L 6.7825 0.4325 6.7825 0.4325 9 P 0 ;1
L 6.7825 0.4825 6.7825 0.4825 9 P 0 ;1
L 6.7825 0.5325 6.7825 0.5325 9 P 0 ;1
L 6.7825 0.5825 6.7825 0.5825 9 P 0 ;1
L 6.7825 0.6325 6.7825 0.6325 9 P 0 ;1
L 6.7825 0.6825 6.7825 0.6825 9 P 0 ;1
L 6.7825 0.7325 6.7825 0.7325 9 P 0 ;1
L 6.7825 0.7825 6.7825 0.7825 9 P 0 ;1
L 6.7825 0.8325 6.7825 0.8325 9 P 0 ;1
L 6.7825 0.8825 6.7825 0.8825 9 P 0 ;1
L 6.7825 0.9325 6.7825 0.9325 9 P 0 ;1
L 6.7825 0.9825 6.7825 0.9825 9 P 0 ;1
L 6.7825 1.0325 6.7825 1.0325 9 P 0 ;1
L 6.7825 1.0825 6.7825 1.0825 9 P 0 ;1
L 6.7825 1.1325 6.7825 1.1325 9 P 0 ;1
L 6.7825 1.1825 6.7825 1.1825 9 P 0 ;1
L 6.7825 1.2325 6.7825 1.2325 9 P 0 ;1
L 6.7825 1.2825 6.7825 1.2825 9 P 0 ;1
L 6.7825 1.3325 6.7825 1.3325 9 P 0 ;1
L 6.7825 1.3825 6.7825 1.3825 9 P 0 ;1
L 6.7825 1.4325 6.7825 1.4325 9 P 0 ;1
L 6.7825 1.6325 6.7825 1.6325 9 P 0 ;1
L 6.7825 1.6825 6.7825 1.6825 9 P 0 ;1
L 6.7825 1.7325 6.7825 1.7325 9 P 0 ;1
L 6.7825 1.7825 6.7825 1.7825 9 P 0 ;1
L 6.7825 1.8325 6.7825 1.8325 9 P 0 ;1
L 6.7825 1.8825 6.7825 1.8825 9 P 0 ;1
L 6.7825 1.9325 6.7825 1.9325 9 P 0 ;1
L 6.7825 1.9825 6.7825 1.9825 9 P 0 ;1
L 6.7825 2.0325 6.7825 2.0325 9 P 0 ;1
L 6.7825 2.0825 6.7825 2.0825 9 P 0 ;1
L 6.7825 2.1325 6.7825 2.1325 9 P 0 ;1
L 6.7825 2.1825 6.7825 2.1825 9 P 0 ;1
L 6.7825 2.2325 6.7825 2.2325 9 P 0 ;1
L 6.7825 2.2825 6.7825 2.2825 9 P 0 ;1
L 6.7825 2.3325 6.7825 2.3325 9 P 0 ;1
L 6.7825 2.3825 6.7825 2.3825 9 P 0 ;1
L 6.7825 2.4325 6.7825 2.4325 9 P 0 ;1
L 6.7825 2.4825 6.7825 2.4825 9 P 0 ;1
L 6.7825 2.5325 6.7825 2.5325 9 P 0 ;1
L 6.7825 2.5825 6.7825 2.5825 9 P 0 ;1
L 6.7825 2.6325 6.7825 2.6325 9 P 0 ;1
L 6.7825 2.6825 6.7825 2.6825 9 P 0 ;1
L 6.7825 2.7325 6.7825 2.7325 9 P 0 ;1
L 6.7825 2.7825 6.7825 2.7825 9 P 0 ;1
L 6.7825 2.8325 6.7825 2.8325 9 P 0 ;1
L 6.7825 2.8825 6.7825 2.8825 9 P 0 ;1
L 6.7825 2.9325 6.7825 2.9325 9 P 0 ;1
L 6.7825 2.9825 6.7825 2.9825 9 P 0 ;1
L 6.7825 3.0325 6.7825 3.0325 9 P 0 ;1
L 6.7825 3.0825 6.7825 3.0825 9 P 0 ;1
L 6.7825 3.1325 6.7825 3.1325 9 P 0 ;1
L 6.7825 3.1825 6.7825 3.1825 9 P 0 ;1
L 6.7825 3.2325 6.7825 3.2325 9 P 0 ;1
L 6.7825 3.2825 6.7825 3.2825 9 P 0 ;1
L 6.7825 3.3325 6.7825 3.3325 9 P 0 ;1
L 6.7825 3.3825 6.7825 3.3825 9 P 0 ;1
L 6.7825 3.4325 6.7825 3.4325 9 P 0 ;1
L 6.7825 3.4825 6.7825 3.4825 9 P 0 ;1
L 6.7825 3.5325 6.7825 3.5325 9 P 0 ;1
L 6.7825 3.5825 6.7825 3.5825 9 P 0 ;1
L 6.7825 3.6325 6.7825 3.6325 9 P 0 ;1
L 6.7825 3.6825 6.7825 3.6825 9 P 0 ;1
L 6.7825 3.7325 6.7825 3.7325 9 P 0 ;1
L 6.7825 3.7825 6.7825 3.7825 9 P 0 ;1
L 6.7825 3.8325 6.7825 3.8325 9 P 0 ;1
L 6.7825 3.8825 6.7825 3.8825 9 P 0 ;1
L 6.7825 3.9325 6.7825 3.9325 9 P 0 ;1
L 6.7825 3.9825 6.7825 3.9825 9 P 0 ;1
L 6.7825 4.0325 6.7825 4.0325 9 P 0 ;1
L 6.7825 4.0825 6.7825 4.0825 9 P 0 ;1
L 6.7825 4.1325 6.7825 4.1325 9 P 0 ;1
L 6.7825 4.2825 6.7825 4.2825 9 P 0 ;1
L 6.7825 4.3325 6.7825 4.3325 9 P 0 ;1
L 6.7825 4.3825 6.7825 4.3825 9 P 0 ;1
L 6.7825 4.4325 6.7825 4.4325 9 P 0 ;1
L 6.7825 4.4825 6.7825 4.4825 9 P 0 ;1
L 6.7825 5.0825 6.7825 5.0825 9 P 0 ;1
L 6.7825 5.1325 6.7825 5.1325 9 P 0 ;1
L 6.7825 5.1825 6.7825 5.1825 9 P 0 ;1
L 6.7825 5.2325 6.7825 5.2325 9 P 0 ;1
L 6.7825 5.2825 6.7825 5.2825 9 P 0 ;1
L 6.7825 5.3325 6.7825 5.3325 9 P 0 ;1
L 6.7825 5.3825 6.7825 5.3825 9 P 0 ;1
L 6.7825 5.4325 6.7825 5.4325 9 P 0 ;1
L 6.7825 5.4825 6.7825 5.4825 9 P 0 ;1
L 6.7825 5.5325 6.7825 5.5325 9 P 0 ;1
L 6.7825 5.5825 6.7825 5.5825 9 P 0 ;1
L 6.7825 5.6325 6.7825 5.6325 9 P 0 ;1
L 6.7825 5.6825 6.7825 5.6825 9 P 0 ;1
L 6.7825 5.7325 6.7825 5.7325 9 P 0 ;1
L 6.7825 5.7825 6.7825 5.7825 9 P 0 ;1
L 6.7825 5.8325 6.7825 5.8325 9 P 0 ;1
L 6.7825 5.8825 6.7825 5.8825 9 P 0 ;1
L 6.8325 0.1325 6.8325 0.1325 9 P 0 ;1
L 6.8325 0.1825 6.8325 0.1825 9 P 0 ;1
L 6.8325 0.2325 6.8325 0.2325 9 P 0 ;1
L 6.8325 0.2825 6.8325 0.2825 9 P 0 ;1
L 6.8325 0.3325 6.8325 0.3325 9 P 0 ;1
L 6.8325 0.3825 6.8325 0.3825 9 P 0 ;1
L 6.8325 0.4325 6.8325 0.4325 9 P 0 ;1
L 6.8325 0.4825 6.8325 0.4825 9 P 0 ;1
L 6.8325 0.5325 6.8325 0.5325 9 P 0 ;1
L 6.8325 0.5825 6.8325 0.5825 9 P 0 ;1
L 6.8325 0.6325 6.8325 0.6325 9 P 0 ;1
L 6.8325 0.6825 6.8325 0.6825 9 P 0 ;1
L 6.8325 0.7325 6.8325 0.7325 9 P 0 ;1
L 6.8325 0.7825 6.8325 0.7825 9 P 0 ;1
L 6.8325 0.8325 6.8325 0.8325 9 P 0 ;1
L 6.8325 0.8825 6.8325 0.8825 9 P 0 ;1
L 6.8325 0.9325 6.8325 0.9325 9 P 0 ;1
L 6.8325 0.9825 6.8325 0.9825 9 P 0 ;1
L 6.8325 1.0325 6.8325 1.0325 9 P 0 ;1
L 6.8325 1.0825 6.8325 1.0825 9 P 0 ;1
L 6.8325 1.1325 6.8325 1.1325 9 P 0 ;1
L 6.8325 1.1825 6.8325 1.1825 9 P 0 ;1
L 6.8325 1.2325 6.8325 1.2325 9 P 0 ;1
L 6.8325 1.2825 6.8325 1.2825 9 P 0 ;1
L 6.8325 1.3325 6.8325 1.3325 9 P 0 ;1
L 6.8325 1.7325 6.8325 1.7325 9 P 0 ;1
L 6.8325 1.7825 6.8325 1.7825 9 P 0 ;1
L 6.8325 1.8325 6.8325 1.8325 9 P 0 ;1
L 6.8325 1.8825 6.8325 1.8825 9 P 0 ;1
L 6.8325 1.9325 6.8325 1.9325 9 P 0 ;1
L 6.8325 1.9825 6.8325 1.9825 9 P 0 ;1
L 6.8325 2.0325 6.8325 2.0325 9 P 0 ;1
L 6.8325 2.0825 6.8325 2.0825 9 P 0 ;1
L 6.8325 2.1325 6.8325 2.1325 9 P 0 ;1
L 6.8325 2.1825 6.8325 2.1825 9 P 0 ;1
L 6.8325 2.2325 6.8325 2.2325 9 P 0 ;1
L 6.8325 2.2825 6.8325 2.2825 9 P 0 ;1
L 6.8325 2.3325 6.8325 2.3325 9 P 0 ;1
L 6.8325 2.3825 6.8325 2.3825 9 P 0 ;1
L 6.8325 2.4325 6.8325 2.4325 9 P 0 ;1
L 6.8325 2.4825 6.8325 2.4825 9 P 0 ;1
L 6.8325 2.5325 6.8325 2.5325 9 P 0 ;1
L 6.8325 2.5825 6.8325 2.5825 9 P 0 ;1
L 6.8325 2.6325 6.8325 2.6325 9 P 0 ;1
L 6.8325 2.6825 6.8325 2.6825 9 P 0 ;1
L 6.8325 2.7325 6.8325 2.7325 9 P 0 ;1
L 6.8325 2.7825 6.8325 2.7825 9 P 0 ;1
L 6.8325 2.8325 6.8325 2.8325 9 P 0 ;1
L 6.8325 2.8825 6.8325 2.8825 9 P 0 ;1
L 6.8325 2.9325 6.8325 2.9325 9 P 0 ;1
L 6.8325 2.9825 6.8325 2.9825 9 P 0 ;1
L 6.8325 3.0325 6.8325 3.0325 9 P 0 ;1
L 6.8325 3.0825 6.8325 3.0825 9 P 0 ;1
L 6.8325 3.1325 6.8325 3.1325 9 P 0 ;1
L 6.8325 3.1825 6.8325 3.1825 9 P 0 ;1
L 6.8325 3.2325 6.8325 3.2325 9 P 0 ;1
L 6.8325 3.2825 6.8325 3.2825 9 P 0 ;1
L 6.8325 3.3325 6.8325 3.3325 9 P 0 ;1
L 6.8325 3.3825 6.8325 3.3825 9 P 0 ;1
L 6.8325 3.4325 6.8325 3.4325 9 P 0 ;1
L 6.8325 3.4825 6.8325 3.4825 9 P 0 ;1
L 6.8325 3.5325 6.8325 3.5325 9 P 0 ;1
L 6.8325 3.5825 6.8325 3.5825 9 P 0 ;1
L 6.8325 3.6325 6.8325 3.6325 9 P 0 ;1
L 6.8325 3.6825 6.8325 3.6825 9 P 0 ;1
L 6.8325 3.7325 6.8325 3.7325 9 P 0 ;1
L 6.8325 3.7825 6.8325 3.7825 9 P 0 ;1
L 6.8325 3.8325 6.8325 3.8325 9 P 0 ;1
L 6.8325 3.8825 6.8325 3.8825 9 P 0 ;1
L 6.8325 3.9325 6.8325 3.9325 9 P 0 ;1
L 6.8325 3.9825 6.8325 3.9825 9 P 0 ;1
L 6.8325 4.0325 6.8325 4.0325 9 P 0 ;1
L 6.8325 4.3825 6.8325 4.3825 9 P 0 ;1
L 6.8325 4.4325 6.8325 4.4325 9 P 0 ;1
L 6.8325 4.4825 6.8325 4.4825 9 P 0 ;1
L 6.8325 5.0825 6.8325 5.0825 9 P 0 ;1
L 6.8325 5.1325 6.8325 5.1325 9 P 0 ;1
L 6.8325 5.1825 6.8325 5.1825 9 P 0 ;1
L 6.8325 5.2325 6.8325 5.2325 9 P 0 ;1
L 6.8325 5.2825 6.8325 5.2825 9 P 0 ;1
L 6.8325 5.3325 6.8325 5.3325 9 P 0 ;1
L 6.8325 5.3825 6.8325 5.3825 9 P 0 ;1
L 6.8325 5.4325 6.8325 5.4325 9 P 0 ;1
L 6.8325 5.4825 6.8325 5.4825 9 P 0 ;1
L 6.8325 5.5325 6.8325 5.5325 9 P 0 ;1
L 6.8325 5.5825 6.8325 5.5825 9 P 0 ;1
L 6.8325 5.6325 6.8325 5.6325 9 P 0 ;1
L 6.8325 5.6825 6.8325 5.6825 9 P 0 ;1
L 6.8325 5.7325 6.8325 5.7325 9 P 0 ;1
L 6.8325 5.7825 6.8325 5.7825 9 P 0 ;1
L 6.8325 5.8325 6.8325 5.8325 9 P 0 ;1
L 6.8325 5.8825 6.8325 5.8825 9 P 0 ;1
L 6.8825 0.1325 6.8825 0.1325 9 P 0 ;1
L 6.8825 0.1825 6.8825 0.1825 9 P 0 ;1
L 6.8825 0.2325 6.8825 0.2325 9 P 0 ;1
L 6.8825 0.2825 6.8825 0.2825 9 P 0 ;1
L 6.8825 0.3325 6.8825 0.3325 9 P 0 ;1
L 6.8825 0.3825 6.8825 0.3825 9 P 0 ;1
L 6.8825 0.4325 6.8825 0.4325 9 P 0 ;1
L 6.8825 0.4825 6.8825 0.4825 9 P 0 ;1
L 6.8825 0.5325 6.8825 0.5325 9 P 0 ;1
L 6.8825 0.5825 6.8825 0.5825 9 P 0 ;1
L 6.8825 0.6325 6.8825 0.6325 9 P 0 ;1
L 6.8825 0.6825 6.8825 0.6825 9 P 0 ;1
L 6.8825 0.7325 6.8825 0.7325 9 P 0 ;1
L 6.8825 0.7825 6.8825 0.7825 9 P 0 ;1
L 6.8825 0.8325 6.8825 0.8325 9 P 0 ;1
L 6.8825 0.8825 6.8825 0.8825 9 P 0 ;1
L 6.8825 0.9325 6.8825 0.9325 9 P 0 ;1
L 6.8825 0.9825 6.8825 0.9825 9 P 0 ;1
L 6.8825 1.0325 6.8825 1.0325 9 P 0 ;1
L 6.8825 1.0825 6.8825 1.0825 9 P 0 ;1
L 6.8825 1.1325 6.8825 1.1325 9 P 0 ;1
L 6.8825 1.1825 6.8825 1.1825 9 P 0 ;1
L 6.8825 1.2325 6.8825 1.2325 9 P 0 ;1
L 6.8825 1.2825 6.8825 1.2825 9 P 0 ;1
L 6.8825 1.3325 6.8825 1.3325 9 P 0 ;1
L 6.8825 1.7325 6.8825 1.7325 9 P 0 ;1
L 6.8825 1.7825 6.8825 1.7825 9 P 0 ;1
L 6.8825 1.8325 6.8825 1.8325 9 P 0 ;1
L 6.8825 1.8825 6.8825 1.8825 9 P 0 ;1
L 6.8825 1.9325 6.8825 1.9325 9 P 0 ;1
L 6.8825 1.9825 6.8825 1.9825 9 P 0 ;1
L 6.8825 2.0325 6.8825 2.0325 9 P 0 ;1
L 6.8825 2.0825 6.8825 2.0825 9 P 0 ;1
L 6.8825 2.1325 6.8825 2.1325 9 P 0 ;1
L 6.8825 2.1825 6.8825 2.1825 9 P 0 ;1
L 6.8825 2.2325 6.8825 2.2325 9 P 0 ;1
L 6.8825 2.2825 6.8825 2.2825 9 P 0 ;1
L 6.8825 2.3325 6.8825 2.3325 9 P 0 ;1
L 6.8825 2.3825 6.8825 2.3825 9 P 0 ;1
L 6.8825 2.4325 6.8825 2.4325 9 P 0 ;1
L 6.8825 2.4825 6.8825 2.4825 9 P 0 ;1
L 6.8825 2.5325 6.8825 2.5325 9 P 0 ;1
L 6.8825 2.5825 6.8825 2.5825 9 P 0 ;1
L 6.8825 2.6325 6.8825 2.6325 9 P 0 ;1
L 6.8825 2.6825 6.8825 2.6825 9 P 0 ;1
L 6.8825 2.7325 6.8825 2.7325 9 P 0 ;1
L 6.8825 2.7825 6.8825 2.7825 9 P 0 ;1
L 6.8825 2.8325 6.8825 2.8325 9 P 0 ;1
L 6.8825 2.8825 6.8825 2.8825 9 P 0 ;1
L 6.8825 2.9325 6.8825 2.9325 9 P 0 ;1
L 6.8825 2.9825 6.8825 2.9825 9 P 0 ;1
L 6.8825 3.0325 6.8825 3.0325 9 P 0 ;1
L 6.8825 3.0825 6.8825 3.0825 9 P 0 ;1
L 6.8825 3.1325 6.8825 3.1325 9 P 0 ;1
L 6.8825 3.1825 6.8825 3.1825 9 P 0 ;1
L 6.8825 3.2325 6.8825 3.2325 9 P 0 ;1
L 6.8825 3.2825 6.8825 3.2825 9 P 0 ;1
L 6.8825 3.3325 6.8825 3.3325 9 P 0 ;1
L 6.8825 3.3825 6.8825 3.3825 9 P 0 ;1
L 6.8825 3.4325 6.8825 3.4325 9 P 0 ;1
L 6.8825 3.4825 6.8825 3.4825 9 P 0 ;1
L 6.8825 3.5325 6.8825 3.5325 9 P 0 ;1
L 6.8825 3.5825 6.8825 3.5825 9 P 0 ;1
L 6.8825 3.6325 6.8825 3.6325 9 P 0 ;1
L 6.8825 3.6825 6.8825 3.6825 9 P 0 ;1
L 6.8825 3.7325 6.8825 3.7325 9 P 0 ;1
L 6.8825 3.7825 6.8825 3.7825 9 P 0 ;1
L 6.8825 3.8325 6.8825 3.8325 9 P 0 ;1
L 6.8825 3.8825 6.8825 3.8825 9 P 0 ;1
L 6.8825 3.9325 6.8825 3.9325 9 P 0 ;1
L 6.8825 3.9825 6.8825 3.9825 9 P 0 ;1
L 6.8825 4.0325 6.8825 4.0325 9 P 0 ;1
L 6.8825 4.3825 6.8825 4.3825 9 P 0 ;1
L 6.8825 4.4325 6.8825 4.4325 9 P 0 ;1
L 6.8825 4.4825 6.8825 4.4825 9 P 0 ;1
L 6.8825 4.6825 6.8825 4.6825 9 P 0 ;1
L 6.8825 5.0825 6.8825 5.0825 9 P 0 ;1
L 6.8825 5.1325 6.8825 5.1325 9 P 0 ;1
L 6.8825 5.1825 6.8825 5.1825 9 P 0 ;1
L 6.8825 5.2325 6.8825 5.2325 9 P 0 ;1
L 6.8825 5.2825 6.8825 5.2825 9 P 0 ;1
L 6.8825 5.3325 6.8825 5.3325 9 P 0 ;1
L 6.8825 5.3825 6.8825 5.3825 9 P 0 ;1
L 6.8825 5.4325 6.8825 5.4325 9 P 0 ;1
L 6.8825 5.4825 6.8825 5.4825 9 P 0 ;1
L 6.8825 5.5325 6.8825 5.5325 9 P 0 ;1
L 6.8825 5.5825 6.8825 5.5825 9 P 0 ;1
L 6.8825 5.6325 6.8825 5.6325 9 P 0 ;1
L 6.8825 5.6825 6.8825 5.6825 9 P 0 ;1
L 6.8825 5.7325 6.8825 5.7325 9 P 0 ;1
L 6.8825 5.7825 6.8825 5.7825 9 P 0 ;1
L 6.8825 5.8325 6.8825 5.8325 9 P 0 ;1
L 6.8825 5.8825 6.8825 5.8825 9 P 0 ;1
L 6.9325 0.1325 6.9325 0.1325 9 P 0 ;1
L 6.9325 0.1825 6.9325 0.1825 9 P 0 ;1
L 6.9325 0.2325 6.9325 0.2325 9 P 0 ;1
L 6.9325 0.2825 6.9325 0.2825 9 P 0 ;1
L 6.9325 0.3325 6.9325 0.3325 9 P 0 ;1
L 6.9325 0.3825 6.9325 0.3825 9 P 0 ;1
L 6.9325 0.4325 6.9325 0.4325 9 P 0 ;1
L 6.9325 0.4825 6.9325 0.4825 9 P 0 ;1
L 6.9325 0.5325 6.9325 0.5325 9 P 0 ;1
L 6.9325 0.5825 6.9325 0.5825 9 P 0 ;1
L 6.9325 0.6325 6.9325 0.6325 9 P 0 ;1
L 6.9325 0.6825 6.9325 0.6825 9 P 0 ;1
L 6.9325 0.7325 6.9325 0.7325 9 P 0 ;1
L 6.9325 0.7825 6.9325 0.7825 9 P 0 ;1
L 6.9325 0.8325 6.9325 0.8325 9 P 0 ;1
L 6.9325 0.8825 6.9325 0.8825 9 P 0 ;1
L 6.9325 0.9325 6.9325 0.9325 9 P 0 ;1
L 6.9325 0.9825 6.9325 0.9825 9 P 0 ;1
L 6.9325 1.0325 6.9325 1.0325 9 P 0 ;1
L 6.9325 1.0825 6.9325 1.0825 9 P 0 ;1
L 6.9325 1.1325 6.9325 1.1325 9 P 0 ;1
L 6.9325 1.1825 6.9325 1.1825 9 P 0 ;1
L 6.9325 1.2325 6.9325 1.2325 9 P 0 ;1
L 6.9325 1.2825 6.9325 1.2825 9 P 0 ;1
L 6.9325 1.7325 6.9325 1.7325 9 P 0 ;1
L 6.9325 1.7825 6.9325 1.7825 9 P 0 ;1
L 6.9325 1.8325 6.9325 1.8325 9 P 0 ;1
L 6.9325 1.8825 6.9325 1.8825 9 P 0 ;1
L 6.9325 1.9325 6.9325 1.9325 9 P 0 ;1
L 6.9325 1.9825 6.9325 1.9825 9 P 0 ;1
L 6.9325 2.0325 6.9325 2.0325 9 P 0 ;1
L 6.9325 2.0825 6.9325 2.0825 9 P 0 ;1
L 6.9325 2.1325 6.9325 2.1325 9 P 0 ;1
L 6.9325 2.1825 6.9325 2.1825 9 P 0 ;1
L 6.9325 2.2325 6.9325 2.2325 9 P 0 ;1
L 6.9325 2.2825 6.9325 2.2825 9 P 0 ;1
L 6.9325 2.3325 6.9325 2.3325 9 P 0 ;1
L 6.9325 2.3825 6.9325 2.3825 9 P 0 ;1
L 6.9325 2.4325 6.9325 2.4325 9 P 0 ;1
L 6.9325 2.7325 6.9325 2.7325 9 P 0 ;1
L 6.9325 2.7825 6.9325 2.7825 9 P 0 ;1
L 6.9325 2.8325 6.9325 2.8325 9 P 0 ;1
L 6.9325 2.8825 6.9325 2.8825 9 P 0 ;1
L 6.9325 2.9325 6.9325 2.9325 9 P 0 ;1
L 6.9325 2.9825 6.9325 2.9825 9 P 0 ;1
L 6.9325 3.0325 6.9325 3.0325 9 P 0 ;1
L 6.9325 3.0825 6.9325 3.0825 9 P 0 ;1
L 6.9325 3.1325 6.9325 3.1325 9 P 0 ;1
L 6.9325 3.1825 6.9325 3.1825 9 P 0 ;1
L 6.9325 3.2325 6.9325 3.2325 9 P 0 ;1
L 6.9325 3.2825 6.9325 3.2825 9 P 0 ;1
L 6.9325 3.3325 6.9325 3.3325 9 P 0 ;1
L 6.9325 3.3825 6.9325 3.3825 9 P 0 ;1
L 6.9325 3.4325 6.9325 3.4325 9 P 0 ;1
L 6.9325 3.4825 6.9325 3.4825 9 P 0 ;1
L 6.9325 3.5325 6.9325 3.5325 9 P 0 ;1
L 6.9325 3.5825 6.9325 3.5825 9 P 0 ;1
L 6.9325 3.6325 6.9325 3.6325 9 P 0 ;1
L 6.9325 3.6825 6.9325 3.6825 9 P 0 ;1
L 6.9325 3.7325 6.9325 3.7325 9 P 0 ;1
L 6.9325 3.7825 6.9325 3.7825 9 P 0 ;1
L 6.9325 3.8325 6.9325 3.8325 9 P 0 ;1
L 6.9325 3.8825 6.9325 3.8825 9 P 0 ;1
L 6.9325 3.9325 6.9325 3.9325 9 P 0 ;1
L 6.9325 3.9825 6.9325 3.9825 9 P 0 ;1
L 6.9325 4.4325 6.9325 4.4325 9 P 0 ;1
L 6.9325 4.4825 6.9325 4.4825 9 P 0 ;1
L 6.9325 5.0825 6.9325 5.0825 9 P 0 ;1
L 6.9325 5.1325 6.9325 5.1325 9 P 0 ;1
L 6.9325 5.1825 6.9325 5.1825 9 P 0 ;1
L 6.9325 5.2325 6.9325 5.2325 9 P 0 ;1
L 6.9325 5.2825 6.9325 5.2825 9 P 0 ;1
L 6.9325 5.3325 6.9325 5.3325 9 P 0 ;1
L 6.9325 5.3825 6.9325 5.3825 9 P 0 ;1
L 6.9325 5.4325 6.9325 5.4325 9 P 0 ;1
L 6.9325 5.4825 6.9325 5.4825 9 P 0 ;1
L 6.9325 5.5325 6.9325 5.5325 9 P 0 ;1
L 6.9325 5.5825 6.9325 5.5825 9 P 0 ;1
L 6.9325 5.6325 6.9325 5.6325 9 P 0 ;1
L 6.9325 5.6825 6.9325 5.6825 9 P 0 ;1
L 6.9325 5.7325 6.9325 5.7325 9 P 0 ;1
L 6.9325 5.7825 6.9325 5.7825 9 P 0 ;1
L 6.9325 5.8325 6.9325 5.8325 9 P 0 ;1
L 6.9325 5.8825 6.9325 5.8825 9 P 0 ;1
L 6.9825 0.1325 6.9825 0.1325 9 P 0 ;1
L 6.9825 0.3325 6.9825 0.3325 9 P 0 ;1
L 6.9825 0.3825 6.9825 0.3825 9 P 0 ;1
L 6.9825 0.4325 6.9825 0.4325 9 P 0 ;1
L 6.9825 0.4825 6.9825 0.4825 9 P 0 ;1
L 6.9825 0.5325 6.9825 0.5325 9 P 0 ;1
L 6.9825 0.5825 6.9825 0.5825 9 P 0 ;1
L 6.9825 0.6325 6.9825 0.6325 9 P 0 ;1
L 6.9825 0.6825 6.9825 0.6825 9 P 0 ;1
L 6.9825 0.7325 6.9825 0.7325 9 P 0 ;1
L 6.9825 0.7825 6.9825 0.7825 9 P 0 ;1
L 6.9825 0.8325 6.9825 0.8325 9 P 0 ;1
L 6.9825 0.8825 6.9825 0.8825 9 P 0 ;1
L 6.9825 0.9325 6.9825 0.9325 9 P 0 ;1
L 6.9825 0.9825 6.9825 0.9825 9 P 0 ;1
L 6.9825 1.0325 6.9825 1.0325 9 P 0 ;1
L 6.9825 1.0825 6.9825 1.0825 9 P 0 ;1
L 6.9825 1.1325 6.9825 1.1325 9 P 0 ;1
L 6.9825 1.1825 6.9825 1.1825 9 P 0 ;1
L 6.9825 1.2325 6.9825 1.2325 9 P 0 ;1
L 6.9825 1.2825 6.9825 1.2825 9 P 0 ;1
L 6.9825 1.7825 6.9825 1.7825 9 P 0 ;1
L 6.9825 1.8325 6.9825 1.8325 9 P 0 ;1
L 6.9825 1.8825 6.9825 1.8825 9 P 0 ;1
L 6.9825 1.9325 6.9825 1.9325 9 P 0 ;1
L 6.9825 1.9825 6.9825 1.9825 9 P 0 ;1
L 6.9825 2.0325 6.9825 2.0325 9 P 0 ;1
L 6.9825 2.0825 6.9825 2.0825 9 P 0 ;1
L 6.9825 2.1325 6.9825 2.1325 9 P 0 ;1
L 6.9825 2.1825 6.9825 2.1825 9 P 0 ;1
L 6.9825 2.2325 6.9825 2.2325 9 P 0 ;1
L 6.9825 2.2825 6.9825 2.2825 9 P 0 ;1
L 6.9825 2.3325 6.9825 2.3325 9 P 0 ;1
L 6.9825 2.3825 6.9825 2.3825 9 P 0 ;1
L 6.9825 2.4325 6.9825 2.4325 9 P 0 ;1
L 6.9825 2.7325 6.9825 2.7325 9 P 0 ;1
L 6.9825 2.7825 6.9825 2.7825 9 P 0 ;1
L 6.9825 2.8325 6.9825 2.8325 9 P 0 ;1
L 6.9825 2.8825 6.9825 2.8825 9 P 0 ;1
L 6.9825 2.9325 6.9825 2.9325 9 P 0 ;1
L 6.9825 2.9825 6.9825 2.9825 9 P 0 ;1
L 6.9825 3.0325 6.9825 3.0325 9 P 0 ;1
L 6.9825 3.0825 6.9825 3.0825 9 P 0 ;1
L 6.9825 3.1325 6.9825 3.1325 9 P 0 ;1
L 6.9825 3.1825 6.9825 3.1825 9 P 0 ;1
L 6.9825 3.2325 6.9825 3.2325 9 P 0 ;1
L 6.9825 3.2825 6.9825 3.2825 9 P 0 ;1
L 6.9825 3.3325 6.9825 3.3325 9 P 0 ;1
L 6.9825 3.3825 6.9825 3.3825 9 P 0 ;1
L 6.9825 3.4325 6.9825 3.4325 9 P 0 ;1
L 6.9825 3.4825 6.9825 3.4825 9 P 0 ;1
L 6.9825 3.5325 6.9825 3.5325 9 P 0 ;1
L 6.9825 3.5825 6.9825 3.5825 9 P 0 ;1
L 6.9825 3.6325 6.9825 3.6325 9 P 0 ;1
L 6.9825 3.6825 6.9825 3.6825 9 P 0 ;1
L 6.9825 3.7325 6.9825 3.7325 9 P 0 ;1
L 6.9825 3.7825 6.9825 3.7825 9 P 0 ;1
L 6.9825 3.8325 6.9825 3.8325 9 P 0 ;1
L 6.9825 3.8825 6.9825 3.8825 9 P 0 ;1
L 6.9825 3.9325 6.9825 3.9325 9 P 0 ;1
L 6.9825 3.9825 6.9825 3.9825 9 P 0 ;1
L 6.9825 4.4325 6.9825 4.4325 9 P 0 ;1
L 6.9825 4.4825 6.9825 4.4825 9 P 0 ;1
L 6.9825 4.5325 6.9825 4.5325 9 P 0 ;1
L 6.9825 4.5825 6.9825 4.5825 9 P 0 ;1
L 6.9825 4.6325 6.9825 4.6325 9 P 0 ;1
L 6.9825 4.9325 6.9825 4.9325 9 P 0 ;1
L 6.9825 4.9825 6.9825 4.9825 9 P 0 ;1
L 6.9825 5.0325 6.9825 5.0325 9 P 0 ;1
L 6.9825 5.0825 6.9825 5.0825 9 P 0 ;1
L 6.9825 5.1325 6.9825 5.1325 9 P 0 ;1
L 6.9825 5.1825 6.9825 5.1825 9 P 0 ;1
L 6.9825 5.2325 6.9825 5.2325 9 P 0 ;1
L 6.9825 5.2825 6.9825 5.2825 9 P 0 ;1
L 6.9825 5.3325 6.9825 5.3325 9 P 0 ;1
L 6.9825 5.3825 6.9825 5.3825 9 P 0 ;1
L 6.9825 5.4325 6.9825 5.4325 9 P 0 ;1
L 6.9825 5.4825 6.9825 5.4825 9 P 0 ;1
L 6.9825 5.5325 6.9825 5.5325 9 P 0 ;1
L 6.9825 5.5825 6.9825 5.5825 9 P 0 ;1
L 6.9825 5.6325 6.9825 5.6325 9 P 0 ;1
L 6.9825 5.6825 6.9825 5.6825 9 P 0 ;1
L 6.9825 5.8825 6.9825 5.8825 9 P 0 ;1
L 7.0325 0.4325 7.0325 0.4325 9 P 0 ;1
L 7.0325 0.4825 7.0325 0.4825 9 P 0 ;1
L 7.0325 0.5325 7.0325 0.5325 9 P 0 ;1
L 7.0325 0.5825 7.0325 0.5825 9 P 0 ;1
L 7.0325 0.6325 7.0325 0.6325 9 P 0 ;1
L 7.0325 0.6825 7.0325 0.6825 9 P 0 ;1
L 7.0325 0.7325 7.0325 0.7325 9 P 0 ;1
L 7.0325 0.7825 7.0325 0.7825 9 P 0 ;1
L 7.0325 0.8325 7.0325 0.8325 9 P 0 ;1
L 7.0325 0.8825 7.0325 0.8825 9 P 0 ;1
L 7.0325 0.9325 7.0325 0.9325 9 P 0 ;1
L 7.0325 0.9825 7.0325 0.9825 9 P 0 ;1
L 7.0325 1.0325 7.0325 1.0325 9 P 0 ;1
L 7.0325 1.0825 7.0325 1.0825 9 P 0 ;1
L 7.0325 1.1325 7.0325 1.1325 9 P 0 ;1
L 7.0325 1.1825 7.0325 1.1825 9 P 0 ;1
L 7.0325 1.2325 7.0325 1.2325 9 P 0 ;1
L 7.0325 1.2825 7.0325 1.2825 9 P 0 ;1
L 7.0325 1.3325 7.0325 1.3325 9 P 0 ;1
L 7.0325 1.7325 7.0325 1.7325 9 P 0 ;1
L 7.0325 1.7825 7.0325 1.7825 9 P 0 ;1
L 7.0325 1.8325 7.0325 1.8325 9 P 0 ;1
L 7.0325 1.8825 7.0325 1.8825 9 P 0 ;1
L 7.0325 1.9325 7.0325 1.9325 9 P 0 ;1
L 7.0325 1.9825 7.0325 1.9825 9 P 0 ;1
L 7.0325 2.0325 7.0325 2.0325 9 P 0 ;1
L 7.0325 2.0825 7.0325 2.0825 9 P 0 ;1
L 7.0325 2.1325 7.0325 2.1325 9 P 0 ;1
L 7.0325 2.1825 7.0325 2.1825 9 P 0 ;1
L 7.0325 2.2325 7.0325 2.2325 9 P 0 ;1
L 7.0325 2.2825 7.0325 2.2825 9 P 0 ;1
L 7.0325 2.3325 7.0325 2.3325 9 P 0 ;1
L 7.0325 2.3825 7.0325 2.3825 9 P 0 ;1
L 7.0325 2.4325 7.0325 2.4325 9 P 0 ;1
L 7.0325 2.7325 7.0325 2.7325 9 P 0 ;1
L 7.0325 2.7825 7.0325 2.7825 9 P 0 ;1
L 7.0325 2.8325 7.0325 2.8325 9 P 0 ;1
L 7.0325 2.8825 7.0325 2.8825 9 P 0 ;1
L 7.0325 2.9325 7.0325 2.9325 9 P 0 ;1
L 7.0325 2.9825 7.0325 2.9825 9 P 0 ;1
L 7.0325 3.0325 7.0325 3.0325 9 P 0 ;1
L 7.0325 3.0825 7.0325 3.0825 9 P 0 ;1
L 7.0325 3.1325 7.0325 3.1325 9 P 0 ;1
L 7.0325 3.1825 7.0325 3.1825 9 P 0 ;1
L 7.0325 3.2325 7.0325 3.2325 9 P 0 ;1
L 7.0325 3.2825 7.0325 3.2825 9 P 0 ;1
L 7.0325 3.3325 7.0325 3.3325 9 P 0 ;1
L 7.0325 3.3825 7.0325 3.3825 9 P 0 ;1
L 7.0325 3.4325 7.0325 3.4325 9 P 0 ;1
L 7.0325 3.4825 7.0325 3.4825 9 P 0 ;1
L 7.0325 3.5325 7.0325 3.5325 9 P 0 ;1
L 7.0325 3.5825 7.0325 3.5825 9 P 0 ;1
L 7.0325 3.6325 7.0325 3.6325 9 P 0 ;1
L 7.0325 3.6825 7.0325 3.6825 9 P 0 ;1
L 7.0325 3.7325 7.0325 3.7325 9 P 0 ;1
L 7.0325 3.7825 7.0325 3.7825 9 P 0 ;1
L 7.0325 3.8325 7.0325 3.8325 9 P 0 ;1
L 7.0325 3.8825 7.0325 3.8825 9 P 0 ;1
L 7.0325 3.9325 7.0325 3.9325 9 P 0 ;1
L 7.0325 3.9825 7.0325 3.9825 9 P 0 ;1
L 7.0325 4.3825 7.0325 4.3825 9 P 0 ;1
L 7.0325 4.4325 7.0325 4.4325 9 P 0 ;1
L 7.0325 4.4825 7.0325 4.4825 9 P 0 ;1
L 7.0325 4.5325 7.0325 4.5325 9 P 0 ;1
L 7.0325 4.5825 7.0325 4.5825 9 P 0 ;1
L 7.0325 4.6325 7.0325 4.6325 9 P 0 ;1
L 7.0325 4.6825 7.0325 4.6825 9 P 0 ;1
L 7.0325 4.7325 7.0325 4.7325 9 P 0 ;1
L 7.0325 4.7825 7.0325 4.7825 9 P 0 ;1
L 7.0325 4.8825 7.0325 4.8825 9 P 0 ;1
L 7.0325 4.9325 7.0325 4.9325 9 P 0 ;1
L 7.0325 4.9825 7.0325 4.9825 9 P 0 ;1
L 7.0325 5.0325 7.0325 5.0325 9 P 0 ;1
L 7.0325 5.0825 7.0325 5.0825 9 P 0 ;1
L 7.0325 5.1325 7.0325 5.1325 9 P 0 ;1
L 7.0325 5.1825 7.0325 5.1825 9 P 0 ;1
L 7.0325 5.2325 7.0325 5.2325 9 P 0 ;1
L 7.0325 5.2825 7.0325 5.2825 9 P 0 ;1
L 7.0325 5.3325 7.0325 5.3325 9 P 0 ;1
L 7.0325 5.3825 7.0325 5.3825 9 P 0 ;1
L 7.0325 5.4325 7.0325 5.4325 9 P 0 ;1
L 7.0325 5.4825 7.0325 5.4825 9 P 0 ;1
L 7.0325 5.5325 7.0325 5.5325 9 P 0 ;1
L 7.0325 5.5825 7.0325 5.5825 9 P 0 ;1
L 7.0825 0.4325 7.0825 0.4325 9 P 0 ;1
L 7.0825 0.4825 7.0825 0.4825 9 P 0 ;1
L 7.0825 0.5325 7.0825 0.5325 9 P 0 ;1
L 7.0825 0.5825 7.0825 0.5825 9 P 0 ;1
L 7.0825 0.6325 7.0825 0.6325 9 P 0 ;1
L 7.0825 0.6825 7.0825 0.6825 9 P 0 ;1
L 7.0825 0.7325 7.0825 0.7325 9 P 0 ;1
L 7.0825 0.7825 7.0825 0.7825 9 P 0 ;1
L 7.0825 0.8325 7.0825 0.8325 9 P 0 ;1
L 7.0825 0.8825 7.0825 0.8825 9 P 0 ;1
L 7.0825 0.9325 7.0825 0.9325 9 P 0 ;1
L 7.0825 0.9825 7.0825 0.9825 9 P 0 ;1
L 7.0825 1.0325 7.0825 1.0325 9 P 0 ;1
L 7.0825 1.0825 7.0825 1.0825 9 P 0 ;1
L 7.0825 1.1325 7.0825 1.1325 9 P 0 ;1
L 7.0825 1.1825 7.0825 1.1825 9 P 0 ;1
L 7.0825 1.2325 7.0825 1.2325 9 P 0 ;1
L 7.0825 1.2825 7.0825 1.2825 9 P 0 ;1
L 7.0825 1.3325 7.0825 1.3325 9 P 0 ;1
L 7.0825 1.7325 7.0825 1.7325 9 P 0 ;1
L 7.0825 1.7825 7.0825 1.7825 9 P 0 ;1
L 7.0825 1.8325 7.0825 1.8325 9 P 0 ;1
L 7.0825 1.8825 7.0825 1.8825 9 P 0 ;1
L 7.0825 1.9325 7.0825 1.9325 9 P 0 ;1
L 7.0825 1.9825 7.0825 1.9825 9 P 0 ;1
L 7.0825 2.0325 7.0825 2.0325 9 P 0 ;1
L 7.0825 2.0825 7.0825 2.0825 9 P 0 ;1
L 7.0825 2.1325 7.0825 2.1325 9 P 0 ;1
L 7.0825 2.1825 7.0825 2.1825 9 P 0 ;1
L 7.0825 2.2325 7.0825 2.2325 9 P 0 ;1
L 7.0825 2.2825 7.0825 2.2825 9 P 0 ;1
L 7.0825 2.3325 7.0825 2.3325 9 P 0 ;1
L 7.0825 2.3825 7.0825 2.3825 9 P 0 ;1
L 7.0825 2.4325 7.0825 2.4325 9 P 0 ;1
L 7.0825 2.7325 7.0825 2.7325 9 P 0 ;1
L 7.0825 2.7825 7.0825 2.7825 9 P 0 ;1
L 7.0825 2.8325 7.0825 2.8325 9 P 0 ;1
L 7.0825 2.8825 7.0825 2.8825 9 P 0 ;1
L 7.0825 2.9325 7.0825 2.9325 9 P 0 ;1
L 7.0825 2.9825 7.0825 2.9825 9 P 0 ;1
L 7.0825 3.0325 7.0825 3.0325 9 P 0 ;1
L 7.0825 3.0825 7.0825 3.0825 9 P 0 ;1
L 7.0825 3.1325 7.0825 3.1325 9 P 0 ;1
L 7.0825 3.1825 7.0825 3.1825 9 P 0 ;1
L 7.0825 3.2325 7.0825 3.2325 9 P 0 ;1
L 7.0825 3.2825 7.0825 3.2825 9 P 0 ;1
L 7.0825 3.3325 7.0825 3.3325 9 P 0 ;1
L 7.0825 3.3825 7.0825 3.3825 9 P 0 ;1
L 7.0825 3.4325 7.0825 3.4325 9 P 0 ;1
L 7.0825 3.4825 7.0825 3.4825 9 P 0 ;1
L 7.0825 3.5325 7.0825 3.5325 9 P 0 ;1
L 7.0825 3.5825 7.0825 3.5825 9 P 0 ;1
L 7.0825 3.6325 7.0825 3.6325 9 P 0 ;1
L 7.0825 3.6825 7.0825 3.6825 9 P 0 ;1
L 7.0825 3.7325 7.0825 3.7325 9 P 0 ;1
L 7.0825 3.7825 7.0825 3.7825 9 P 0 ;1
L 7.0825 3.8325 7.0825 3.8325 9 P 0 ;1
L 7.0825 3.8825 7.0825 3.8825 9 P 0 ;1
L 7.0825 3.9325 7.0825 3.9325 9 P 0 ;1
L 7.0825 3.9825 7.0825 3.9825 9 P 0 ;1
L 7.0825 4.0325 7.0825 4.0325 9 P 0 ;1
L 7.0825 4.3825 7.0825 4.3825 9 P 0 ;1
L 7.0825 4.4325 7.0825 4.4325 9 P 0 ;1
L 7.0825 4.4825 7.0825 4.4825 9 P 0 ;1
L 7.0825 4.5325 7.0825 4.5325 9 P 0 ;1
L 7.0825 4.5825 7.0825 4.5825 9 P 0 ;1
L 7.0825 4.6325 7.0825 4.6325 9 P 0 ;1
L 7.0825 4.6825 7.0825 4.6825 9 P 0 ;1
L 7.0825 4.7325 7.0825 4.7325 9 P 0 ;1
L 7.0825 4.7825 7.0825 4.7825 9 P 0 ;1
L 7.0825 4.8325 7.0825 4.8325 9 P 0 ;1
L 7.0825 4.8825 7.0825 4.8825 9 P 0 ;1
L 7.0825 4.9325 7.0825 4.9325 9 P 0 ;1
L 7.0825 4.9825 7.0825 4.9825 9 P 0 ;1
L 7.0825 5.0325 7.0825 5.0325 9 P 0 ;1
L 7.0825 5.0825 7.0825 5.0825 9 P 0 ;1
L 7.0825 5.1325 7.0825 5.1325 9 P 0 ;1
L 7.0825 5.1825 7.0825 5.1825 9 P 0 ;1
L 7.0825 5.2325 7.0825 5.2325 9 P 0 ;1
L 7.0825 5.2825 7.0825 5.2825 9 P 0 ;1
L 7.0825 5.3325 7.0825 5.3325 9 P 0 ;1
L 7.0825 5.3825 7.0825 5.3825 9 P 0 ;1
L 7.0825 5.4325 7.0825 5.4325 9 P 0 ;1
L 7.0825 5.4825 7.0825 5.4825 9 P 0 ;1
L 7.0825 5.5325 7.0825 5.5325 9 P 0 ;1
L 7.0825 5.5825 7.0825 5.5825 9 P 0 ;1
L 7.1325 0.4825 7.1325 0.4825 9 P 0 ;1
L 7.1325 0.5325 7.1325 0.5325 9 P 0 ;1
L 7.1325 0.5825 7.1325 0.5825 9 P 0 ;1
L 7.1325 0.6325 7.1325 0.6325 9 P 0 ;1
L 7.1325 0.6825 7.1325 0.6825 9 P 0 ;1
L 7.1325 0.7325 7.1325 0.7325 9 P 0 ;1
L 7.1325 0.7825 7.1325 0.7825 9 P 0 ;1
L 7.1325 0.8325 7.1325 0.8325 9 P 0 ;1
L 7.1325 0.8825 7.1325 0.8825 9 P 0 ;1
L 7.1325 0.9325 7.1325 0.9325 9 P 0 ;1
L 7.1325 0.9825 7.1325 0.9825 9 P 0 ;1
L 7.1325 1.0325 7.1325 1.0325 9 P 0 ;1
L 7.1325 1.0825 7.1325 1.0825 9 P 0 ;1
L 7.1325 1.1325 7.1325 1.1325 9 P 0 ;1
L 7.1325 1.1825 7.1325 1.1825 9 P 0 ;1
L 7.1325 1.2325 7.1325 1.2325 9 P 0 ;1
L 7.1325 1.2825 7.1325 1.2825 9 P 0 ;1
L 7.1325 1.3325 7.1325 1.3325 9 P 0 ;1
L 7.1325 1.3825 7.1325 1.3825 9 P 0 ;1
L 7.1325 1.6825 7.1325 1.6825 9 P 0 ;1
L 7.1325 1.7325 7.1325 1.7325 9 P 0 ;1
L 7.1325 1.7825 7.1325 1.7825 9 P 0 ;1
L 7.1325 1.8325 7.1325 1.8325 9 P 0 ;1
L 7.1325 1.8825 7.1325 1.8825 9 P 0 ;1
L 7.1325 1.9325 7.1325 1.9325 9 P 0 ;1
L 7.1325 1.9825 7.1325 1.9825 9 P 0 ;1
L 7.1325 2.0325 7.1325 2.0325 9 P 0 ;1
L 7.1325 2.0825 7.1325 2.0825 9 P 0 ;1
L 7.1325 2.1325 7.1325 2.1325 9 P 0 ;1
L 7.1325 2.1825 7.1325 2.1825 9 P 0 ;1
L 7.1325 2.2325 7.1325 2.2325 9 P 0 ;1
L 7.1325 2.2825 7.1325 2.2825 9 P 0 ;1
L 7.1325 2.3325 7.1325 2.3325 9 P 0 ;1
L 7.1325 2.3825 7.1325 2.3825 9 P 0 ;1
L 7.1325 2.4325 7.1325 2.4325 9 P 0 ;1
L 7.1325 2.7325 7.1325 2.7325 9 P 0 ;1
L 7.1325 2.7825 7.1325 2.7825 9 P 0 ;1
L 7.1325 2.8325 7.1325 2.8325 9 P 0 ;1
L 7.1325 2.8825 7.1325 2.8825 9 P 0 ;1
L 7.1325 2.9325 7.1325 2.9325 9 P 0 ;1
L 7.1325 2.9825 7.1325 2.9825 9 P 0 ;1
L 7.1325 3.0325 7.1325 3.0325 9 P 0 ;1
L 7.1325 3.0825 7.1325 3.0825 9 P 0 ;1
L 7.1325 3.1325 7.1325 3.1325 9 P 0 ;1
L 7.1325 3.1825 7.1325 3.1825 9 P 0 ;1
L 7.1325 3.2325 7.1325 3.2325 9 P 0 ;1
L 7.1325 3.2825 7.1325 3.2825 9 P 0 ;1
L 7.1325 3.3325 7.1325 3.3325 9 P 0 ;1
L 7.1325 3.3825 7.1325 3.3825 9 P 0 ;1
L 7.1325 3.4325 7.1325 3.4325 9 P 0 ;1
L 7.1325 3.4825 7.1325 3.4825 9 P 0 ;1
L 7.1325 3.5325 7.1325 3.5325 9 P 0 ;1
L 7.1325 3.5825 7.1325 3.5825 9 P 0 ;1
L 7.1325 3.6325 7.1325 3.6325 9 P 0 ;1
L 7.1325 3.6825 7.1325 3.6825 9 P 0 ;1
L 7.1325 3.7325 7.1325 3.7325 9 P 0 ;1
L 7.1325 3.7825 7.1325 3.7825 9 P 0 ;1
L 7.1325 3.8325 7.1325 3.8325 9 P 0 ;1
L 7.1325 3.8825 7.1325 3.8825 9 P 0 ;1
L 7.1325 3.9325 7.1325 3.9325 9 P 0 ;1
L 7.1325 3.9825 7.1325 3.9825 9 P 0 ;1
L 7.1325 4.0325 7.1325 4.0325 9 P 0 ;1
L 7.1325 4.0825 7.1325 4.0825 9 P 0 ;1
L 7.1325 4.3325 7.1325 4.3325 9 P 0 ;1
L 7.1325 4.3825 7.1325 4.3825 9 P 0 ;1
L 7.1325 4.4325 7.1325 4.4325 9 P 0 ;1
L 7.1325 4.4825 7.1325 4.4825 9 P 0 ;1
L 7.1325 4.5325 7.1325 4.5325 9 P 0 ;1
L 7.1325 4.5825 7.1325 4.5825 9 P 0 ;1
L 7.1325 4.6325 7.1325 4.6325 9 P 0 ;1
L 7.1325 4.6825 7.1325 4.6825 9 P 0 ;1
L 7.1325 4.7325 7.1325 4.7325 9 P 0 ;1
L 7.1325 4.7825 7.1325 4.7825 9 P 0 ;1
L 7.1325 4.8325 7.1325 4.8325 9 P 0 ;1
L 7.1325 4.8825 7.1325 4.8825 9 P 0 ;1
L 7.1325 5.2325 7.1325 5.2325 9 P 0 ;1
L 7.1325 5.2825 7.1325 5.2825 9 P 0 ;1
L 7.1325 5.3325 7.1325 5.3325 9 P 0 ;1
L 7.1325 5.3825 7.1325 5.3825 9 P 0 ;1
L 7.1325 5.4325 7.1325 5.4325 9 P 0 ;1
L 7.1325 5.4825 7.1325 5.4825 9 P 0 ;1
L 7.1325 5.5325 7.1325 5.5325 9 P 0 ;1
L 7.1825 0.4825 7.1825 0.4825 9 P 0 ;1
L 7.1825 0.5325 7.1825 0.5325 9 P 0 ;1
L 7.1825 0.5825 7.1825 0.5825 9 P 0 ;1
L 7.1825 0.6325 7.1825 0.6325 9 P 0 ;1
L 7.1825 0.6825 7.1825 0.6825 9 P 0 ;1
L 7.1825 0.7325 7.1825 0.7325 9 P 0 ;1
L 7.1825 0.7825 7.1825 0.7825 9 P 0 ;1
L 7.1825 0.8325 7.1825 0.8325 9 P 0 ;1
L 7.1825 0.8825 7.1825 0.8825 9 P 0 ;1
L 7.1825 0.9325 7.1825 0.9325 9 P 0 ;1
L 7.1825 0.9825 7.1825 0.9825 9 P 0 ;1
L 7.1825 1.0325 7.1825 1.0325 9 P 0 ;1
L 7.1825 1.0825 7.1825 1.0825 9 P 0 ;1
L 7.1825 1.1325 7.1825 1.1325 9 P 0 ;1
L 7.1825 1.1825 7.1825 1.1825 9 P 0 ;1
L 7.1825 1.2325 7.1825 1.2325 9 P 0 ;1
L 7.1825 1.2825 7.1825 1.2825 9 P 0 ;1
L 7.1825 1.3325 7.1825 1.3325 9 P 0 ;1
L 7.1825 1.3825 7.1825 1.3825 9 P 0 ;1
L 7.1825 1.4325 7.1825 1.4325 9 P 0 ;1
L 7.1825 1.4825 7.1825 1.4825 9 P 0 ;1
L 7.1825 1.5325 7.1825 1.5325 9 P 0 ;1
L 7.1825 1.5825 7.1825 1.5825 9 P 0 ;1
L 7.1825 1.6325 7.1825 1.6325 9 P 0 ;1
L 7.1825 1.6825 7.1825 1.6825 9 P 0 ;1
L 7.1825 1.7325 7.1825 1.7325 9 P 0 ;1
L 7.1825 1.7825 7.1825 1.7825 9 P 0 ;1
L 7.1825 1.8325 7.1825 1.8325 9 P 0 ;1
L 7.1825 1.8825 7.1825 1.8825 9 P 0 ;1
L 7.1825 1.9325 7.1825 1.9325 9 P 0 ;1
L 7.1825 1.9825 7.1825 1.9825 9 P 0 ;1
L 7.1825 2.0325 7.1825 2.0325 9 P 0 ;1
L 7.1825 2.0825 7.1825 2.0825 9 P 0 ;1
L 7.1825 2.1325 7.1825 2.1325 9 P 0 ;1
L 7.1825 2.1825 7.1825 2.1825 9 P 0 ;1
L 7.1825 2.2325 7.1825 2.2325 9 P 0 ;1
L 7.1825 2.2825 7.1825 2.2825 9 P 0 ;1
L 7.1825 2.3325 7.1825 2.3325 9 P 0 ;1
L 7.1825 2.3825 7.1825 2.3825 9 P 0 ;1
L 7.1825 2.4325 7.1825 2.4325 9 P 0 ;1
L 7.1825 2.7325 7.1825 2.7325 9 P 0 ;1
L 7.1825 2.7825 7.1825 2.7825 9 P 0 ;1
L 7.1825 2.8325 7.1825 2.8325 9 P 0 ;1
L 7.1825 2.8825 7.1825 2.8825 9 P 0 ;1
L 7.1825 2.9325 7.1825 2.9325 9 P 0 ;1
L 7.1825 2.9825 7.1825 2.9825 9 P 0 ;1
L 7.1825 3.0325 7.1825 3.0325 9 P 0 ;1
L 7.1825 3.0825 7.1825 3.0825 9 P 0 ;1
L 7.1825 3.1325 7.1825 3.1325 9 P 0 ;1
L 7.1825 3.1825 7.1825 3.1825 9 P 0 ;1
L 7.1825 3.2325 7.1825 3.2325 9 P 0 ;1
L 7.1825 3.2825 7.1825 3.2825 9 P 0 ;1
L 7.1825 3.3325 7.1825 3.3325 9 P 0 ;1
L 7.1825 3.3825 7.1825 3.3825 9 P 0 ;1
L 7.1825 3.4325 7.1825 3.4325 9 P 0 ;1
L 7.1825 3.4825 7.1825 3.4825 9 P 0 ;1
L 7.1825 3.5325 7.1825 3.5325 9 P 0 ;1
L 7.1825 3.5825 7.1825 3.5825 9 P 0 ;1
L 7.1825 3.6325 7.1825 3.6325 9 P 0 ;1
L 7.1825 3.6825 7.1825 3.6825 9 P 0 ;1
L 7.1825 3.7325 7.1825 3.7325 9 P 0 ;1
L 7.1825 3.7825 7.1825 3.7825 9 P 0 ;1
L 7.1825 3.8325 7.1825 3.8325 9 P 0 ;1
L 7.1825 3.8825 7.1825 3.8825 9 P 0 ;1
L 7.1825 3.9325 7.1825 3.9325 9 P 0 ;1
L 7.1825 3.9825 7.1825 3.9825 9 P 0 ;1
L 7.1825 4.0325 7.1825 4.0325 9 P 0 ;1
L 7.1825 4.0825 7.1825 4.0825 9 P 0 ;1
L 7.1825 4.1325 7.1825 4.1325 9 P 0 ;1
L 7.1825 4.1825 7.1825 4.1825 9 P 0 ;1
L 7.1825 4.2325 7.1825 4.2325 9 P 0 ;1
L 7.1825 4.2825 7.1825 4.2825 9 P 0 ;1
L 7.1825 4.3325 7.1825 4.3325 9 P 0 ;1
L 7.1825 4.3825 7.1825 4.3825 9 P 0 ;1
L 7.1825 4.4325 7.1825 4.4325 9 P 0 ;1
L 7.1825 4.4825 7.1825 4.4825 9 P 0 ;1
L 7.1825 4.5325 7.1825 4.5325 9 P 0 ;1
L 7.1825 4.7825 7.1825 4.7825 9 P 0 ;1
L 7.1825 4.8325 7.1825 4.8325 9 P 0 ;1
L 7.1825 5.2325 7.1825 5.2325 9 P 0 ;1
L 7.1825 5.2825 7.1825 5.2825 9 P 0 ;1
L 7.1825 5.3325 7.1825 5.3325 9 P 0 ;1
L 7.1825 5.3825 7.1825 5.3825 9 P 0 ;1
L 7.1825 5.4325 7.1825 5.4325 9 P 0 ;1
L 7.1825 5.4825 7.1825 5.4825 9 P 0 ;1
L 7.1825 5.5325 7.1825 5.5325 9 P 0 ;1
L 7.2325 0.4825 7.2325 0.4825 9 P 0 ;1
L 7.2325 0.5325 7.2325 0.5325 9 P 0 ;1
L 7.2325 0.5825 7.2325 0.5825 9 P 0 ;1
L 7.2325 0.6325 7.2325 0.6325 9 P 0 ;1
L 7.2325 0.6825 7.2325 0.6825 9 P 0 ;1
L 7.2325 0.7325 7.2325 0.7325 9 P 0 ;1
L 7.2325 0.7825 7.2325 0.7825 9 P 0 ;1
L 7.2325 0.8325 7.2325 0.8325 9 P 0 ;1
L 7.2325 0.8825 7.2325 0.8825 9 P 0 ;1
L 7.2325 0.9325 7.2325 0.9325 9 P 0 ;1
L 7.2325 0.9825 7.2325 0.9825 9 P 0 ;1
L 7.2325 1.0325 7.2325 1.0325 9 P 0 ;1
L 7.2325 1.0825 7.2325 1.0825 9 P 0 ;1
L 7.2325 1.1325 7.2325 1.1325 9 P 0 ;1
L 7.2325 1.1825 7.2325 1.1825 9 P 0 ;1
L 7.2325 1.2325 7.2325 1.2325 9 P 0 ;1
L 7.2325 1.2825 7.2325 1.2825 9 P 0 ;1
L 7.2325 1.3325 7.2325 1.3325 9 P 0 ;1
L 7.2325 1.3825 7.2325 1.3825 9 P 0 ;1
L 7.2325 1.4325 7.2325 1.4325 9 P 0 ;1
L 7.2325 1.4825 7.2325 1.4825 9 P 0 ;1
L 7.2325 1.5325 7.2325 1.5325 9 P 0 ;1
L 7.2325 1.5825 7.2325 1.5825 9 P 0 ;1
L 7.2325 1.6325 7.2325 1.6325 9 P 0 ;1
L 7.2325 1.6825 7.2325 1.6825 9 P 0 ;1
L 7.2325 1.7325 7.2325 1.7325 9 P 0 ;1
L 7.2325 1.7825 7.2325 1.7825 9 P 0 ;1
L 7.2325 1.8325 7.2325 1.8325 9 P 0 ;1
L 7.2325 1.8825 7.2325 1.8825 9 P 0 ;1
L 7.2325 1.9325 7.2325 1.9325 9 P 0 ;1
L 7.2325 1.9825 7.2325 1.9825 9 P 0 ;1
L 7.2325 2.0325 7.2325 2.0325 9 P 0 ;1
L 7.2325 2.0825 7.2325 2.0825 9 P 0 ;1
L 7.2325 2.1325 7.2325 2.1325 9 P 0 ;1
L 7.2325 2.1825 7.2325 2.1825 9 P 0 ;1
L 7.2325 2.2325 7.2325 2.2325 9 P 0 ;1
L 7.2325 2.2825 7.2325 2.2825 9 P 0 ;1
L 7.2325 2.3325 7.2325 2.3325 9 P 0 ;1
L 7.2325 2.3825 7.2325 2.3825 9 P 0 ;1
L 7.2325 2.4325 7.2325 2.4325 9 P 0 ;1
L 7.2325 2.4825 7.2325 2.4825 9 P 0 ;1
L 7.2325 2.5325 7.2325 2.5325 9 P 0 ;1
L 7.2325 2.6325 7.2325 2.6325 9 P 0 ;1
L 7.2325 2.6825 7.2325 2.6825 9 P 0 ;1
L 7.2325 2.7325 7.2325 2.7325 9 P 0 ;1
L 7.2325 2.7825 7.2325 2.7825 9 P 0 ;1
L 7.2325 2.8325 7.2325 2.8325 9 P 0 ;1
L 7.2325 2.8825 7.2325 2.8825 9 P 0 ;1
L 7.2325 2.9325 7.2325 2.9325 9 P 0 ;1
L 7.2325 2.9825 7.2325 2.9825 9 P 0 ;1
L 7.2325 3.0325 7.2325 3.0325 9 P 0 ;1
L 7.2325 3.0825 7.2325 3.0825 9 P 0 ;1
L 7.2325 3.1325 7.2325 3.1325 9 P 0 ;1
L 7.2325 3.1825 7.2325 3.1825 9 P 0 ;1
L 7.2325 3.2325 7.2325 3.2325 9 P 0 ;1
L 7.2325 3.2825 7.2325 3.2825 9 P 0 ;1
L 7.2325 3.3325 7.2325 3.3325 9 P 0 ;1
L 7.2325 3.3825 7.2325 3.3825 9 P 0 ;1
L 7.2325 3.4325 7.2325 3.4325 9 P 0 ;1
L 7.2325 3.4825 7.2325 3.4825 9 P 0 ;1
L 7.2325 3.5325 7.2325 3.5325 9 P 0 ;1
L 7.2325 3.5825 7.2325 3.5825 9 P 0 ;1
L 7.2325 3.6325 7.2325 3.6325 9 P 0 ;1
L 7.2325 3.6825 7.2325 3.6825 9 P 0 ;1
L 7.2325 3.7325 7.2325 3.7325 9 P 0 ;1
L 7.2325 3.7825 7.2325 3.7825 9 P 0 ;1
L 7.2325 3.8325 7.2325 3.8325 9 P 0 ;1
L 7.2325 3.8825 7.2325 3.8825 9 P 0 ;1
L 7.2325 3.9325 7.2325 3.9325 9 P 0 ;1
L 7.2325 3.9825 7.2325 3.9825 9 P 0 ;1
L 7.2325 4.0325 7.2325 4.0325 9 P 0 ;1
L 7.2325 4.0825 7.2325 4.0825 9 P 0 ;1
L 7.2325 4.1325 7.2325 4.1325 9 P 0 ;1
L 7.2325 4.1825 7.2325 4.1825 9 P 0 ;1
L 7.2325 4.2325 7.2325 4.2325 9 P 0 ;1
L 7.2325 4.2825 7.2325 4.2825 9 P 0 ;1
L 7.2325 4.3325 7.2325 4.3325 9 P 0 ;1
L 7.2325 4.3825 7.2325 4.3825 9 P 0 ;1
L 7.2325 4.4325 7.2325 4.4325 9 P 0 ;1
L 7.2325 4.4825 7.2325 4.4825 9 P 0 ;1
L 7.2325 4.7825 7.2325 4.7825 9 P 0 ;1
L 7.2325 4.8325 7.2325 4.8325 9 P 0 ;1
L 7.2325 4.8825 7.2325 4.8825 9 P 0 ;1
L 7.2325 5.2325 7.2325 5.2325 9 P 0 ;1
L 7.2325 5.2825 7.2325 5.2825 9 P 0 ;1
L 7.2325 5.3325 7.2325 5.3325 9 P 0 ;1
L 7.2325 5.3825 7.2325 5.3825 9 P 0 ;1
L 7.2325 5.4325 7.2325 5.4325 9 P 0 ;1
L 7.2325 5.4825 7.2325 5.4825 9 P 0 ;1
L 7.2325 5.5325 7.2325 5.5325 9 P 0 ;1
L 7.2325 5.5825 7.2325 5.5825 9 P 0 ;1
L 7.2825 0.4325 7.2825 0.4325 9 P 0 ;1
L 7.2825 0.4825 7.2825 0.4825 9 P 0 ;1
L 7.2825 0.5325 7.2825 0.5325 9 P 0 ;1
L 7.2825 0.5825 7.2825 0.5825 9 P 0 ;1
L 7.2825 0.6325 7.2825 0.6325 9 P 0 ;1
L 7.2825 0.6825 7.2825 0.6825 9 P 0 ;1
L 7.2825 0.7325 7.2825 0.7325 9 P 0 ;1
L 7.2825 0.7825 7.2825 0.7825 9 P 0 ;1
L 7.2825 0.8325 7.2825 0.8325 9 P 0 ;1
L 7.2825 0.8825 7.2825 0.8825 9 P 0 ;1
L 7.2825 0.9325 7.2825 0.9325 9 P 0 ;1
L 7.2825 0.9825 7.2825 0.9825 9 P 0 ;1
L 7.2825 1.0325 7.2825 1.0325 9 P 0 ;1
L 7.2825 1.0825 7.2825 1.0825 9 P 0 ;1
L 7.2825 1.1325 7.2825 1.1325 9 P 0 ;1
L 7.2825 1.1825 7.2825 1.1825 9 P 0 ;1
L 7.2825 1.2325 7.2825 1.2325 9 P 0 ;1
L 7.2825 1.2825 7.2825 1.2825 9 P 0 ;1
L 7.2825 1.3325 7.2825 1.3325 9 P 0 ;1
L 7.2825 1.3825 7.2825 1.3825 9 P 0 ;1
L 7.2825 1.4325 7.2825 1.4325 9 P 0 ;1
L 7.2825 1.4825 7.2825 1.4825 9 P 0 ;1
L 7.2825 1.5325 7.2825 1.5325 9 P 0 ;1
L 7.2825 1.5825 7.2825 1.5825 9 P 0 ;1
L 7.2825 1.6325 7.2825 1.6325 9 P 0 ;1
L 7.2825 1.6825 7.2825 1.6825 9 P 0 ;1
L 7.2825 1.7325 7.2825 1.7325 9 P 0 ;1
L 7.2825 1.7825 7.2825 1.7825 9 P 0 ;1
L 7.2825 1.8325 7.2825 1.8325 9 P 0 ;1
L 7.2825 1.8825 7.2825 1.8825 9 P 0 ;1
L 7.2825 1.9325 7.2825 1.9325 9 P 0 ;1
L 7.2825 1.9825 7.2825 1.9825 9 P 0 ;1
L 7.2825 2.0325 7.2825 2.0325 9 P 0 ;1
L 7.2825 2.0825 7.2825 2.0825 9 P 0 ;1
L 7.2825 2.1325 7.2825 2.1325 9 P 0 ;1
L 7.2825 2.1825 7.2825 2.1825 9 P 0 ;1
L 7.2825 2.2325 7.2825 2.2325 9 P 0 ;1
L 7.2825 2.2825 7.2825 2.2825 9 P 0 ;1
L 7.2825 2.3325 7.2825 2.3325 9 P 0 ;1
L 7.2825 2.3825 7.2825 2.3825 9 P 0 ;1
L 7.2825 2.4325 7.2825 2.4325 9 P 0 ;1
L 7.2825 2.4825 7.2825 2.4825 9 P 0 ;1
L 7.2825 2.5325 7.2825 2.5325 9 P 0 ;1
L 7.2825 2.5825 7.2825 2.5825 9 P 0 ;1
L 7.2825 2.6325 7.2825 2.6325 9 P 0 ;1
L 7.2825 2.6825 7.2825 2.6825 9 P 0 ;1
L 7.2825 2.7325 7.2825 2.7325 9 P 0 ;1
L 7.2825 2.7825 7.2825 2.7825 9 P 0 ;1
L 7.2825 2.8325 7.2825 2.8325 9 P 0 ;1
L 7.2825 2.8825 7.2825 2.8825 9 P 0 ;1
L 7.2825 2.9325 7.2825 2.9325 9 P 0 ;1
L 7.2825 2.9825 7.2825 2.9825 9 P 0 ;1
L 7.2825 3.0325 7.2825 3.0325 9 P 0 ;1
L 7.2825 3.0825 7.2825 3.0825 9 P 0 ;1
L 7.2825 3.1325 7.2825 3.1325 9 P 0 ;1
L 7.2825 3.1825 7.2825 3.1825 9 P 0 ;1
L 7.2825 3.2325 7.2825 3.2325 9 P 0 ;1
L 7.2825 3.2825 7.2825 3.2825 9 P 0 ;1
L 7.2825 3.3325 7.2825 3.3325 9 P 0 ;1
L 7.2825 3.3825 7.2825 3.3825 9 P 0 ;1
L 7.2825 3.4325 7.2825 3.4325 9 P 0 ;1
L 7.2825 3.4825 7.2825 3.4825 9 P 0 ;1
L 7.2825 3.5325 7.2825 3.5325 9 P 0 ;1
L 7.2825 3.5825 7.2825 3.5825 9 P 0 ;1
L 7.2825 3.6325 7.2825 3.6325 9 P 0 ;1
L 7.2825 3.6825 7.2825 3.6825 9 P 0 ;1
L 7.2825 3.7325 7.2825 3.7325 9 P 0 ;1
L 7.2825 3.7825 7.2825 3.7825 9 P 0 ;1
L 7.2825 3.8325 7.2825 3.8325 9 P 0 ;1
L 7.2825 3.8825 7.2825 3.8825 9 P 0 ;1
L 7.2825 3.9325 7.2825 3.9325 9 P 0 ;1
L 7.2825 3.9825 7.2825 3.9825 9 P 0 ;1
L 7.2825 4.0325 7.2825 4.0325 9 P 0 ;1
L 7.2825 4.0825 7.2825 4.0825 9 P 0 ;1
L 7.2825 4.1325 7.2825 4.1325 9 P 0 ;1
L 7.2825 4.1825 7.2825 4.1825 9 P 0 ;1
L 7.2825 4.2325 7.2825 4.2325 9 P 0 ;1
L 7.2825 4.2825 7.2825 4.2825 9 P 0 ;1
L 7.2825 4.3325 7.2825 4.3325 9 P 0 ;1
L 7.2825 4.3825 7.2825 4.3825 9 P 0 ;1
L 7.2825 4.4325 7.2825 4.4325 9 P 0 ;1
L 7.2825 4.4825 7.2825 4.4825 9 P 0 ;1
L 7.2825 4.7825 7.2825 4.7825 9 P 0 ;1
L 7.2825 4.9325 7.2825 4.9325 9 P 0 ;1
L 7.2825 5.2325 7.2825 5.2325 9 P 0 ;1
L 7.2825 5.2825 7.2825 5.2825 9 P 0 ;1
L 7.2825 5.3325 7.2825 5.3325 9 P 0 ;1
L 7.2825 5.3825 7.2825 5.3825 9 P 0 ;1
L 7.2825 5.4325 7.2825 5.4325 9 P 0 ;1
L 7.2825 5.4825 7.2825 5.4825 9 P 0 ;1
L 7.2825 5.5325 7.2825 5.5325 9 P 0 ;1
L 7.2825 5.5825 7.2825 5.5825 9 P 0 ;1
L 7.3325 0.4325 7.3325 0.4325 9 P 0 ;1
L 7.3325 0.4825 7.3325 0.4825 9 P 0 ;1
L 7.3325 0.5325 7.3325 0.5325 9 P 0 ;1
L 7.3325 0.5825 7.3325 0.5825 9 P 0 ;1
L 7.3325 0.6325 7.3325 0.6325 9 P 0 ;1
L 7.3325 0.6825 7.3325 0.6825 9 P 0 ;1
L 7.3325 0.7325 7.3325 0.7325 9 P 0 ;1
L 7.3325 0.7825 7.3325 0.7825 9 P 0 ;1
L 7.3325 0.8325 7.3325 0.8325 9 P 0 ;1
L 7.3325 0.8825 7.3325 0.8825 9 P 0 ;1
L 7.3325 0.9325 7.3325 0.9325 9 P 0 ;1
L 7.3325 0.9825 7.3325 0.9825 9 P 0 ;1
L 7.3325 1.0325 7.3325 1.0325 9 P 0 ;1
L 7.3325 1.0825 7.3325 1.0825 9 P 0 ;1
L 7.3325 1.1325 7.3325 1.1325 9 P 0 ;1
L 7.3325 1.1825 7.3325 1.1825 9 P 0 ;1
L 7.3325 1.2325 7.3325 1.2325 9 P 0 ;1
L 7.3325 1.2825 7.3325 1.2825 9 P 0 ;1
L 7.3325 1.3325 7.3325 1.3325 9 P 0 ;1
L 7.3325 1.3825 7.3325 1.3825 9 P 0 ;1
L 7.3325 1.4325 7.3325 1.4325 9 P 0 ;1
L 7.3325 1.4825 7.3325 1.4825 9 P 0 ;1
L 7.3325 1.5325 7.3325 1.5325 9 P 0 ;1
L 7.3325 1.5825 7.3325 1.5825 9 P 0 ;1
L 7.3325 1.6325 7.3325 1.6325 9 P 0 ;1
L 7.3325 1.6825 7.3325 1.6825 9 P 0 ;1
L 7.3325 1.7325 7.3325 1.7325 9 P 0 ;1
L 7.3325 1.7825 7.3325 1.7825 9 P 0 ;1
L 7.3325 1.8325 7.3325 1.8325 9 P 0 ;1
L 7.3325 1.8825 7.3325 1.8825 9 P 0 ;1
L 7.3325 1.9325 7.3325 1.9325 9 P 0 ;1
L 7.3325 1.9825 7.3325 1.9825 9 P 0 ;1
L 7.3325 2.0325 7.3325 2.0325 9 P 0 ;1
L 7.3325 2.0825 7.3325 2.0825 9 P 0 ;1
L 7.3325 2.1325 7.3325 2.1325 9 P 0 ;1
L 7.3325 2.1825 7.3325 2.1825 9 P 0 ;1
L 7.3325 2.2325 7.3325 2.2325 9 P 0 ;1
L 7.3325 2.2825 7.3325 2.2825 9 P 0 ;1
L 7.3325 2.3325 7.3325 2.3325 9 P 0 ;1
L 7.3325 2.3825 7.3325 2.3825 9 P 0 ;1
L 7.3325 2.4325 7.3325 2.4325 9 P 0 ;1
L 7.3325 2.4825 7.3325 2.4825 9 P 0 ;1
L 7.3325 2.5325 7.3325 2.5325 9 P 0 ;1
L 7.3325 2.5825 7.3325 2.5825 9 P 0 ;1
L 7.3325 2.6325 7.3325 2.6325 9 P 0 ;1
L 7.3325 2.6825 7.3325 2.6825 9 P 0 ;1
L 7.3325 2.7325 7.3325 2.7325 9 P 0 ;1
L 7.3325 2.7825 7.3325 2.7825 9 P 0 ;1
L 7.3325 2.8325 7.3325 2.8325 9 P 0 ;1
L 7.3325 2.8825 7.3325 2.8825 9 P 0 ;1
L 7.3325 2.9325 7.3325 2.9325 9 P 0 ;1
L 7.3325 2.9825 7.3325 2.9825 9 P 0 ;1
L 7.3325 3.0325 7.3325 3.0325 9 P 0 ;1
L 7.3325 3.0825 7.3325 3.0825 9 P 0 ;1
L 7.3325 3.1325 7.3325 3.1325 9 P 0 ;1
L 7.3325 3.1825 7.3325 3.1825 9 P 0 ;1
L 7.3325 3.2325 7.3325 3.2325 9 P 0 ;1
L 7.3325 3.2825 7.3325 3.2825 9 P 0 ;1
L 7.3325 3.3325 7.3325 3.3325 9 P 0 ;1
L 7.3325 3.3825 7.3325 3.3825 9 P 0 ;1
L 7.3325 3.4325 7.3325 3.4325 9 P 0 ;1
L 7.3325 3.4825 7.3325 3.4825 9 P 0 ;1
L 7.3325 3.5325 7.3325 3.5325 9 P 0 ;1
L 7.3325 3.5825 7.3325 3.5825 9 P 0 ;1
L 7.3325 3.6325 7.3325 3.6325 9 P 0 ;1
L 7.3325 3.6825 7.3325 3.6825 9 P 0 ;1
L 7.3325 3.7325 7.3325 3.7325 9 P 0 ;1
L 7.3325 3.7825 7.3325 3.7825 9 P 0 ;1
L 7.3325 3.8325 7.3325 3.8325 9 P 0 ;1
L 7.3325 3.8825 7.3325 3.8825 9 P 0 ;1
L 7.3325 3.9325 7.3325 3.9325 9 P 0 ;1
L 7.3325 3.9825 7.3325 3.9825 9 P 0 ;1
L 7.3325 4.0325 7.3325 4.0325 9 P 0 ;1
L 7.3325 4.0825 7.3325 4.0825 9 P 0 ;1
L 7.3325 4.1325 7.3325 4.1325 9 P 0 ;1
L 7.3325 4.1825 7.3325 4.1825 9 P 0 ;1
L 7.3325 4.2325 7.3325 4.2325 9 P 0 ;1
L 7.3325 4.2825 7.3325 4.2825 9 P 0 ;1
L 7.3325 4.3325 7.3325 4.3325 9 P 0 ;1
L 7.3325 4.3825 7.3325 4.3825 9 P 0 ;1
L 7.3325 4.4325 7.3325 4.4325 9 P 0 ;1
L 7.3325 4.4825 7.3325 4.4825 9 P 0 ;1
L 7.3325 4.5325 7.3325 4.5325 9 P 0 ;1
L 7.3325 5.2325 7.3325 5.2325 9 P 0 ;1
L 7.3325 5.2825 7.3325 5.2825 9 P 0 ;1
L 7.3325 5.3325 7.3325 5.3325 9 P 0 ;1
L 7.3325 5.3825 7.3325 5.3825 9 P 0 ;1
L 7.3325 5.4325 7.3325 5.4325 9 P 0 ;1
L 7.3325 5.4825 7.3325 5.4825 9 P 0 ;1
L 7.3325 5.5325 7.3325 5.5325 9 P 0 ;1
L 7.3325 5.5825 7.3325 5.5825 9 P 0 ;1
L 7.3825 0.1325 7.3825 0.1325 9 P 0 ;1
L 7.3825 0.3325 7.3825 0.3325 9 P 0 ;1
L 7.3825 0.3825 7.3825 0.3825 9 P 0 ;1
L 7.3825 0.4325 7.3825 0.4325 9 P 0 ;1
L 7.3825 0.4825 7.3825 0.4825 9 P 0 ;1
L 7.3825 0.5325 7.3825 0.5325 9 P 0 ;1
L 7.3825 0.5825 7.3825 0.5825 9 P 0 ;1
L 7.3825 0.6325 7.3825 0.6325 9 P 0 ;1
L 7.3825 0.6825 7.3825 0.6825 9 P 0 ;1
L 7.3825 0.7325 7.3825 0.7325 9 P 0 ;1
L 7.3825 0.7825 7.3825 0.7825 9 P 0 ;1
L 7.3825 0.8325 7.3825 0.8325 9 P 0 ;1
L 7.3825 0.8825 7.3825 0.8825 9 P 0 ;1
L 7.3825 0.9325 7.3825 0.9325 9 P 0 ;1
L 7.3825 0.9825 7.3825 0.9825 9 P 0 ;1
L 7.3825 1.0325 7.3825 1.0325 9 P 0 ;1
L 7.3825 1.0825 7.3825 1.0825 9 P 0 ;1
L 7.3825 1.1325 7.3825 1.1325 9 P 0 ;1
L 7.3825 1.1825 7.3825 1.1825 9 P 0 ;1
L 7.3825 1.2325 7.3825 1.2325 9 P 0 ;1
L 7.3825 1.2825 7.3825 1.2825 9 P 0 ;1
L 7.3825 1.3325 7.3825 1.3325 9 P 0 ;1
L 7.3825 1.3825 7.3825 1.3825 9 P 0 ;1
L 7.3825 1.4325 7.3825 1.4325 9 P 0 ;1
L 7.3825 1.4825 7.3825 1.4825 9 P 0 ;1
L 7.3825 1.5325 7.3825 1.5325 9 P 0 ;1
L 7.3825 1.5825 7.3825 1.5825 9 P 0 ;1
L 7.3825 1.6325 7.3825 1.6325 9 P 0 ;1
L 7.3825 1.7825 7.3825 1.7825 9 P 0 ;1
L 7.3825 1.8325 7.3825 1.8325 9 P 0 ;1
L 7.3825 1.8825 7.3825 1.8825 9 P 0 ;1
L 7.3825 1.9325 7.3825 1.9325 9 P 0 ;1
L 7.3825 1.9825 7.3825 1.9825 9 P 0 ;1
L 7.3825 2.0325 7.3825 2.0325 9 P 0 ;1
L 7.3825 2.0825 7.3825 2.0825 9 P 0 ;1
L 7.3825 2.1325 7.3825 2.1325 9 P 0 ;1
L 7.3825 2.1825 7.3825 2.1825 9 P 0 ;1
L 7.3825 2.2325 7.3825 2.2325 9 P 0 ;1
L 7.3825 2.2825 7.3825 2.2825 9 P 0 ;1
L 7.3825 2.3325 7.3825 2.3325 9 P 0 ;1
L 7.3825 2.3825 7.3825 2.3825 9 P 0 ;1
L 7.3825 2.4325 7.3825 2.4325 9 P 0 ;1
L 7.3825 2.4825 7.3825 2.4825 9 P 0 ;1
L 7.3825 2.5325 7.3825 2.5325 9 P 0 ;1
L 7.3825 2.5825 7.3825 2.5825 9 P 0 ;1
L 7.3825 2.6325 7.3825 2.6325 9 P 0 ;1
L 7.3825 2.6825 7.3825 2.6825 9 P 0 ;1
L 7.3825 2.7325 7.3825 2.7325 9 P 0 ;1
L 7.3825 2.7825 7.3825 2.7825 9 P 0 ;1
L 7.3825 2.8325 7.3825 2.8325 9 P 0 ;1
L 7.3825 2.8825 7.3825 2.8825 9 P 0 ;1
L 7.3825 2.9325 7.3825 2.9325 9 P 0 ;1
L 7.3825 2.9825 7.3825 2.9825 9 P 0 ;1
L 7.3825 3.0325 7.3825 3.0325 9 P 0 ;1
L 7.3825 3.0825 7.3825 3.0825 9 P 0 ;1
L 7.3825 3.1325 7.3825 3.1325 9 P 0 ;1
L 7.3825 3.1825 7.3825 3.1825 9 P 0 ;1
L 7.3825 3.2325 7.3825 3.2325 9 P 0 ;1
L 7.3825 3.2825 7.3825 3.2825 9 P 0 ;1
L 7.3825 3.3325 7.3825 3.3325 9 P 0 ;1
L 7.3825 3.5325 7.3825 3.5325 9 P 0 ;1
L 7.3825 3.5825 7.3825 3.5825 9 P 0 ;1
L 7.3825 3.6325 7.3825 3.6325 9 P 0 ;1
L 7.3825 3.6825 7.3825 3.6825 9 P 0 ;1
L 7.3825 3.7325 7.3825 3.7325 9 P 0 ;1
L 7.3825 3.7825 7.3825 3.7825 9 P 0 ;1
L 7.3825 3.8325 7.3825 3.8325 9 P 0 ;1
L 7.3825 3.8825 7.3825 3.8825 9 P 0 ;1
L 7.3825 3.9325 7.3825 3.9325 9 P 0 ;1
L 7.3825 3.9825 7.3825 3.9825 9 P 0 ;1
L 7.3825 4.0325 7.3825 4.0325 9 P 0 ;1
L 7.3825 4.0825 7.3825 4.0825 9 P 0 ;1
L 7.3825 4.1325 7.3825 4.1325 9 P 0 ;1
L 7.3825 4.1825 7.3825 4.1825 9 P 0 ;1
L 7.3825 4.2325 7.3825 4.2325 9 P 0 ;1
L 7.3825 4.2825 7.3825 4.2825 9 P 0 ;1
L 7.3825 4.3325 7.3825 4.3325 9 P 0 ;1
L 7.3825 4.3825 7.3825 4.3825 9 P 0 ;1
L 7.3825 4.4325 7.3825 4.4325 9 P 0 ;1
L 7.3825 4.4825 7.3825 4.4825 9 P 0 ;1
L 7.3825 4.5325 7.3825 4.5325 9 P 0 ;1
L 7.3825 4.5825 7.3825 4.5825 9 P 0 ;1
L 7.3825 4.7825 7.3825 4.7825 9 P 0 ;1
L 7.3825 4.9325 7.3825 4.9325 9 P 0 ;1
L 7.3825 4.9825 7.3825 4.9825 9 P 0 ;1
L 7.3825 5.0325 7.3825 5.0325 9 P 0 ;1
L 7.3825 5.0825 7.3825 5.0825 9 P 0 ;1
L 7.3825 5.2325 7.3825 5.2325 9 P 0 ;1
L 7.3825 5.2825 7.3825 5.2825 9 P 0 ;1
L 7.3825 5.3325 7.3825 5.3325 9 P 0 ;1
L 7.3825 5.3825 7.3825 5.3825 9 P 0 ;1
L 7.3825 5.4325 7.3825 5.4325 9 P 0 ;1
L 7.3825 5.4825 7.3825 5.4825 9 P 0 ;1
L 7.3825 5.5325 7.3825 5.5325 9 P 0 ;1
L 7.3825 5.5825 7.3825 5.5825 9 P 0 ;1
L 7.3825 5.6325 7.3825 5.6325 9 P 0 ;1
L 7.3825 5.6825 7.3825 5.6825 9 P 0 ;1
L 7.3825 5.7325 7.3825 5.7325 9 P 0 ;1
L 7.3825 5.8825 7.3825 5.8825 9 P 0 ;1
L 7.4325 0.1325 7.4325 0.1325 9 P 0 ;1
L 7.4325 0.1825 7.4325 0.1825 9 P 0 ;1
L 7.4325 0.2325 7.4325 0.2325 9 P 0 ;1
L 7.4325 0.2825 7.4325 0.2825 9 P 0 ;1
L 7.4325 0.3325 7.4325 0.3325 9 P 0 ;1
L 7.4325 0.3825 7.4325 0.3825 9 P 0 ;1
L 7.4325 0.4325 7.4325 0.4325 9 P 0 ;1
L 7.4325 0.4825 7.4325 0.4825 9 P 0 ;1
L 7.4325 0.5325 7.4325 0.5325 9 P 0 ;1
L 7.4325 0.5825 7.4325 0.5825 9 P 0 ;1
L 7.4325 0.6325 7.4325 0.6325 9 P 0 ;1
L 7.4325 0.6825 7.4325 0.6825 9 P 0 ;1
L 7.4325 0.7325 7.4325 0.7325 9 P 0 ;1
L 7.4325 0.7825 7.4325 0.7825 9 P 0 ;1
L 7.4325 0.8325 7.4325 0.8325 9 P 0 ;1
L 7.4325 0.8825 7.4325 0.8825 9 P 0 ;1
L 7.4325 0.9325 7.4325 0.9325 9 P 0 ;1
L 7.4325 0.9825 7.4325 0.9825 9 P 0 ;1
L 7.4325 1.0325 7.4325 1.0325 9 P 0 ;1
L 7.4325 1.0825 7.4325 1.0825 9 P 0 ;1
L 7.4325 1.1325 7.4325 1.1325 9 P 0 ;1
L 7.4325 1.1825 7.4325 1.1825 9 P 0 ;1
L 7.4325 1.2325 7.4325 1.2325 9 P 0 ;1
L 7.4325 1.2825 7.4325 1.2825 9 P 0 ;1
L 7.4325 1.3325 7.4325 1.3325 9 P 0 ;1
L 7.4325 1.3825 7.4325 1.3825 9 P 0 ;1
L 7.4325 1.4325 7.4325 1.4325 9 P 0 ;1
L 7.4325 1.4825 7.4325 1.4825 9 P 0 ;1
L 7.4325 1.5325 7.4325 1.5325 9 P 0 ;1
L 7.4325 1.5825 7.4325 1.5825 9 P 0 ;1
L 7.4325 1.7825 7.4325 1.7825 9 P 0 ;1
L 7.4325 1.8325 7.4325 1.8325 9 P 0 ;1
L 7.4325 1.8825 7.4325 1.8825 9 P 0 ;1
L 7.4325 1.9325 7.4325 1.9325 9 P 0 ;1
L 7.4325 1.9825 7.4325 1.9825 9 P 0 ;1
L 7.4325 2.0325 7.4325 2.0325 9 P 0 ;1
L 7.4325 2.0825 7.4325 2.0825 9 P 0 ;1
L 7.4325 2.1325 7.4325 2.1325 9 P 0 ;1
L 7.4325 2.1825 7.4325 2.1825 9 P 0 ;1
L 7.4325 2.2325 7.4325 2.2325 9 P 0 ;1
L 7.4325 2.2825 7.4325 2.2825 9 P 0 ;1
L 7.4325 2.3325 7.4325 2.3325 9 P 0 ;1
L 7.4325 2.3825 7.4325 2.3825 9 P 0 ;1
L 7.4325 2.4325 7.4325 2.4325 9 P 0 ;1
L 7.4325 2.4825 7.4325 2.4825 9 P 0 ;1
L 7.4325 2.5325 7.4325 2.5325 9 P 0 ;1
L 7.4325 2.5825 7.4325 2.5825 9 P 0 ;1
L 7.4325 2.6325 7.4325 2.6325 9 P 0 ;1
L 7.4325 2.6825 7.4325 2.6825 9 P 0 ;1
L 7.4325 2.7325 7.4325 2.7325 9 P 0 ;1
L 7.4325 2.7825 7.4325 2.7825 9 P 0 ;1
L 7.4325 2.8325 7.4325 2.8325 9 P 0 ;1
L 7.4325 2.8825 7.4325 2.8825 9 P 0 ;1
L 7.4325 2.9325 7.4325 2.9325 9 P 0 ;1
L 7.4325 2.9825 7.4325 2.9825 9 P 0 ;1
L 7.4325 3.0325 7.4325 3.0325 9 P 0 ;1
L 7.4325 3.0825 7.4325 3.0825 9 P 0 ;1
L 7.4325 3.1325 7.4325 3.1325 9 P 0 ;1
L 7.4325 3.1825 7.4325 3.1825 9 P 0 ;1
L 7.4325 3.2325 7.4325 3.2325 9 P 0 ;1
L 7.4325 3.2825 7.4325 3.2825 9 P 0 ;1
L 7.4325 3.3325 7.4325 3.3325 9 P 0 ;1
L 7.4325 3.5325 7.4325 3.5325 9 P 0 ;1
L 7.4325 3.5825 7.4325 3.5825 9 P 0 ;1
L 7.4325 3.6325 7.4325 3.6325 9 P 0 ;1
L 7.4325 3.6825 7.4325 3.6825 9 P 0 ;1
L 7.4325 3.7325 7.4325 3.7325 9 P 0 ;1
L 7.4325 3.7825 7.4325 3.7825 9 P 0 ;1
L 7.4325 3.8325 7.4325 3.8325 9 P 0 ;1
L 7.4325 3.8825 7.4325 3.8825 9 P 0 ;1
L 7.4325 3.9325 7.4325 3.9325 9 P 0 ;1
L 7.4325 3.9825 7.4325 3.9825 9 P 0 ;1
L 7.4325 4.0325 7.4325 4.0325 9 P 0 ;1
L 7.4325 4.0825 7.4325 4.0825 9 P 0 ;1
L 7.4325 4.1325 7.4325 4.1325 9 P 0 ;1
L 7.4325 4.1825 7.4325 4.1825 9 P 0 ;1
L 7.4325 4.2325 7.4325 4.2325 9 P 0 ;1
L 7.4325 4.2825 7.4325 4.2825 9 P 0 ;1
L 7.4325 4.3325 7.4325 4.3325 9 P 0 ;1
L 7.4325 4.3825 7.4325 4.3825 9 P 0 ;1
L 7.4325 4.4325 7.4325 4.4325 9 P 0 ;1
L 7.4325 4.4825 7.4325 4.4825 9 P 0 ;1
L 7.4325 4.5325 7.4325 4.5325 9 P 0 ;1
L 7.4325 4.5825 7.4325 4.5825 9 P 0 ;1
L 7.4325 4.6325 7.4325 4.6325 9 P 0 ;1
L 7.4325 4.6825 7.4325 4.6825 9 P 0 ;1
L 7.4325 4.7325 7.4325 4.7325 9 P 0 ;1
L 7.4325 4.8325 7.4325 4.8325 9 P 0 ;1
L 7.4325 4.8825 7.4325 4.8825 9 P 0 ;1
L 7.4325 4.9325 7.4325 4.9325 9 P 0 ;1
L 7.4325 4.9825 7.4325 4.9825 9 P 0 ;1
L 7.4325 5.0325 7.4325 5.0325 9 P 0 ;1
L 7.4325 5.2825 7.4325 5.2825 9 P 0 ;1
L 7.4325 5.3325 7.4325 5.3325 9 P 0 ;1
L 7.4325 5.3825 7.4325 5.3825 9 P 0 ;1
L 7.4325 5.4325 7.4325 5.4325 9 P 0 ;1
L 7.4325 5.4825 7.4325 5.4825 9 P 0 ;1
L 7.4325 5.5325 7.4325 5.5325 9 P 0 ;1
L 7.4325 5.5825 7.4325 5.5825 9 P 0 ;1
L 7.4325 5.6325 7.4325 5.6325 9 P 0 ;1
L 7.4325 5.6825 7.4325 5.6825 9 P 0 ;1
L 7.4325 5.7325 7.4325 5.7325 9 P 0 ;1
L 7.4325 5.7825 7.4325 5.7825 9 P 0 ;1
L 7.4325 5.8325 7.4325 5.8325 9 P 0 ;1
L 7.4325 5.8825 7.4325 5.8825 9 P 0 ;1
L 7.4825 0.1325 7.4825 0.1325 9 P 0 ;1
L 7.4825 0.1825 7.4825 0.1825 9 P 0 ;1
L 7.4825 0.2325 7.4825 0.2325 9 P 0 ;1
L 7.4825 0.2825 7.4825 0.2825 9 P 0 ;1
L 7.4825 0.3325 7.4825 0.3325 9 P 0 ;1
L 7.4825 0.3825 7.4825 0.3825 9 P 0 ;1
L 7.4825 0.4325 7.4825 0.4325 9 P 0 ;1
L 7.4825 0.4825 7.4825 0.4825 9 P 0 ;1
L 7.4825 0.5325 7.4825 0.5325 9 P 0 ;1
L 7.4825 0.5825 7.4825 0.5825 9 P 0 ;1
L 7.4825 0.6325 7.4825 0.6325 9 P 0 ;1
L 7.4825 0.6825 7.4825 0.6825 9 P 0 ;1
L 7.4825 0.7325 7.4825 0.7325 9 P 0 ;1
L 7.4825 0.7825 7.4825 0.7825 9 P 0 ;1
L 7.4825 0.8325 7.4825 0.8325 9 P 0 ;1
L 7.4825 0.8825 7.4825 0.8825 9 P 0 ;1
L 7.4825 0.9325 7.4825 0.9325 9 P 0 ;1
L 7.4825 0.9825 7.4825 0.9825 9 P 0 ;1
L 7.4825 1.0325 7.4825 1.0325 9 P 0 ;1
L 7.4825 1.0825 7.4825 1.0825 9 P 0 ;1
L 7.4825 1.1325 7.4825 1.1325 9 P 0 ;1
L 7.4825 1.1825 7.4825 1.1825 9 P 0 ;1
L 7.4825 1.2325 7.4825 1.2325 9 P 0 ;1
L 7.4825 1.2825 7.4825 1.2825 9 P 0 ;1
L 7.4825 1.3325 7.4825 1.3325 9 P 0 ;1
L 7.4825 1.3825 7.4825 1.3825 9 P 0 ;1
L 7.4825 1.4325 7.4825 1.4325 9 P 0 ;1
L 7.4825 1.4825 7.4825 1.4825 9 P 0 ;1
L 7.4825 1.5325 7.4825 1.5325 9 P 0 ;1
L 7.4825 1.5825 7.4825 1.5825 9 P 0 ;1
L 7.4825 1.6325 7.4825 1.6325 9 P 0 ;1
L 7.4825 1.7825 7.4825 1.7825 9 P 0 ;1
L 7.4825 1.8325 7.4825 1.8325 9 P 0 ;1
L 7.4825 1.8825 7.4825 1.8825 9 P 0 ;1
L 7.4825 1.9325 7.4825 1.9325 9 P 0 ;1
L 7.4825 1.9825 7.4825 1.9825 9 P 0 ;1
L 7.4825 2.0325 7.4825 2.0325 9 P 0 ;1
L 7.4825 2.0825 7.4825 2.0825 9 P 0 ;1
L 7.4825 2.1325 7.4825 2.1325 9 P 0 ;1
L 7.4825 2.1825 7.4825 2.1825 9 P 0 ;1
L 7.4825 2.2325 7.4825 2.2325 9 P 0 ;1
L 7.4825 2.2825 7.4825 2.2825 9 P 0 ;1
L 7.4825 2.3325 7.4825 2.3325 9 P 0 ;1
L 7.4825 2.3825 7.4825 2.3825 9 P 0 ;1
L 7.4825 2.4325 7.4825 2.4325 9 P 0 ;1
L 7.4825 2.4825 7.4825 2.4825 9 P 0 ;1
L 7.4825 2.5325 7.4825 2.5325 9 P 0 ;1
L 7.4825 2.5825 7.4825 2.5825 9 P 0 ;1
L 7.4825 2.6325 7.4825 2.6325 9 P 0 ;1
L 7.4825 2.6825 7.4825 2.6825 9 P 0 ;1
L 7.4825 2.7325 7.4825 2.7325 9 P 0 ;1
L 7.4825 2.7825 7.4825 2.7825 9 P 0 ;1
L 7.4825 2.8325 7.4825 2.8325 9 P 0 ;1
L 7.4825 2.8825 7.4825 2.8825 9 P 0 ;1
L 7.4825 2.9325 7.4825 2.9325 9 P 0 ;1
L 7.4825 2.9825 7.4825 2.9825 9 P 0 ;1
L 7.4825 3.0325 7.4825 3.0325 9 P 0 ;1
L 7.4825 3.0825 7.4825 3.0825 9 P 0 ;1
L 7.4825 3.1325 7.4825 3.1325 9 P 0 ;1
L 7.4825 3.1825 7.4825 3.1825 9 P 0 ;1
L 7.4825 3.2325 7.4825 3.2325 9 P 0 ;1
L 7.4825 3.2825 7.4825 3.2825 9 P 0 ;1
L 7.4825 3.3325 7.4825 3.3325 9 P 0 ;1
L 7.4825 3.5325 7.4825 3.5325 9 P 0 ;1
L 7.4825 3.5825 7.4825 3.5825 9 P 0 ;1
L 7.4825 3.6325 7.4825 3.6325 9 P 0 ;1
L 7.4825 3.6825 7.4825 3.6825 9 P 0 ;1
L 7.4825 3.7325 7.4825 3.7325 9 P 0 ;1
L 7.4825 3.7825 7.4825 3.7825 9 P 0 ;1
L 7.4825 3.8325 7.4825 3.8325 9 P 0 ;1
L 7.4825 3.8825 7.4825 3.8825 9 P 0 ;1
L 7.4825 3.9325 7.4825 3.9325 9 P 0 ;1
L 7.4825 3.9825 7.4825 3.9825 9 P 0 ;1
L 7.4825 4.0325 7.4825 4.0325 9 P 0 ;1
L 7.4825 4.0825 7.4825 4.0825 9 P 0 ;1
L 7.4825 4.1325 7.4825 4.1325 9 P 0 ;1
L 7.4825 4.1825 7.4825 4.1825 9 P 0 ;1
L 7.4825 4.2325 7.4825 4.2325 9 P 0 ;1
L 7.4825 4.2825 7.4825 4.2825 9 P 0 ;1
L 7.4825 4.3325 7.4825 4.3325 9 P 0 ;1
L 7.4825 4.3825 7.4825 4.3825 9 P 0 ;1
L 7.4825 4.4325 7.4825 4.4325 9 P 0 ;1
L 7.4825 4.4825 7.4825 4.4825 9 P 0 ;1
L 7.4825 4.5325 7.4825 4.5325 9 P 0 ;1
L 7.4825 4.5825 7.4825 4.5825 9 P 0 ;1
L 7.4825 4.6325 7.4825 4.6325 9 P 0 ;1
L 7.4825 4.6825 7.4825 4.6825 9 P 0 ;1
L 7.4825 5.2325 7.4825 5.2325 9 P 0 ;1
L 7.4825 5.2825 7.4825 5.2825 9 P 0 ;1
L 7.4825 5.3325 7.4825 5.3325 9 P 0 ;1
L 7.4825 5.3825 7.4825 5.3825 9 P 0 ;1
L 7.4825 5.4325 7.4825 5.4325 9 P 0 ;1
L 7.4825 5.4825 7.4825 5.4825 9 P 0 ;1
L 7.4825 5.5325 7.4825 5.5325 9 P 0 ;1
L 7.4825 5.5825 7.4825 5.5825 9 P 0 ;1
L 7.4825 5.6325 7.4825 5.6325 9 P 0 ;1
L 7.4825 5.6825 7.4825 5.6825 9 P 0 ;1
L 7.4825 5.7325 7.4825 5.7325 9 P 0 ;1
L 7.4825 5.7825 7.4825 5.7825 9 P 0 ;1
L 7.4825 5.8325 7.4825 5.8325 9 P 0 ;1
L 7.4825 5.8825 7.4825 5.8825 9 P 0 ;1
L 7.5325 0.1325 7.5325 0.1325 9 P 0 ;1
L 7.5325 0.1825 7.5325 0.1825 9 P 0 ;1
L 7.5325 0.2325 7.5325 0.2325 9 P 0 ;1
L 7.5325 0.2825 7.5325 0.2825 9 P 0 ;1
L 7.5325 0.3325 7.5325 0.3325 9 P 0 ;1
L 7.5325 0.3825 7.5325 0.3825 9 P 0 ;1
L 7.5325 0.4325 7.5325 0.4325 9 P 0 ;1
L 7.5325 0.4825 7.5325 0.4825 9 P 0 ;1
L 7.5325 0.5325 7.5325 0.5325 9 P 0 ;1
L 7.5325 0.5825 7.5325 0.5825 9 P 0 ;1
L 7.5325 0.6325 7.5325 0.6325 9 P 0 ;1
L 7.5325 0.6825 7.5325 0.6825 9 P 0 ;1
L 7.5325 0.7325 7.5325 0.7325 9 P 0 ;1
L 7.5325 0.7825 7.5325 0.7825 9 P 0 ;1
L 7.5325 0.8325 7.5325 0.8325 9 P 0 ;1
L 7.5325 0.8825 7.5325 0.8825 9 P 0 ;1
L 7.5325 0.9325 7.5325 0.9325 9 P 0 ;1
L 7.5325 0.9825 7.5325 0.9825 9 P 0 ;1
L 7.5325 1.0325 7.5325 1.0325 9 P 0 ;1
L 7.5325 1.0825 7.5325 1.0825 9 P 0 ;1
L 7.5325 1.1325 7.5325 1.1325 9 P 0 ;1
L 7.5325 1.1825 7.5325 1.1825 9 P 0 ;1
L 7.5325 1.2325 7.5325 1.2325 9 P 0 ;1
L 7.5325 1.2825 7.5325 1.2825 9 P 0 ;1
L 7.5325 1.3325 7.5325 1.3325 9 P 0 ;1
L 7.5325 1.3825 7.5325 1.3825 9 P 0 ;1
L 7.5325 1.4325 7.5325 1.4325 9 P 0 ;1
L 7.5325 1.4825 7.5325 1.4825 9 P 0 ;1
L 7.5325 1.5325 7.5325 1.5325 9 P 0 ;1
L 7.5325 1.5825 7.5325 1.5825 9 P 0 ;1
L 7.5325 1.6325 7.5325 1.6325 9 P 0 ;1
L 7.5325 1.6825 7.5325 1.6825 9 P 0 ;1
L 7.5325 1.7325 7.5325 1.7325 9 P 0 ;1
L 7.5325 1.7825 7.5325 1.7825 9 P 0 ;1
L 7.5325 1.8325 7.5325 1.8325 9 P 0 ;1
L 7.5325 1.8825 7.5325 1.8825 9 P 0 ;1
L 7.5325 1.9325 7.5325 1.9325 9 P 0 ;1
L 7.5325 1.9825 7.5325 1.9825 9 P 0 ;1
L 7.5325 2.0325 7.5325 2.0325 9 P 0 ;1
L 7.5325 2.0825 7.5325 2.0825 9 P 0 ;1
L 7.5325 2.1325 7.5325 2.1325 9 P 0 ;1
L 7.5325 2.1825 7.5325 2.1825 9 P 0 ;1
L 7.5325 2.2325 7.5325 2.2325 9 P 0 ;1
L 7.5325 2.2825 7.5325 2.2825 9 P 0 ;1
L 7.5325 2.3325 7.5325 2.3325 9 P 0 ;1
L 7.5325 2.3825 7.5325 2.3825 9 P 0 ;1
L 7.5325 2.4325 7.5325 2.4325 9 P 0 ;1
L 7.5325 2.4825 7.5325 2.4825 9 P 0 ;1
L 7.5325 2.5325 7.5325 2.5325 9 P 0 ;1
L 7.5325 2.5825 7.5325 2.5825 9 P 0 ;1
L 7.5325 2.6325 7.5325 2.6325 9 P 0 ;1
L 7.5325 2.6825 7.5325 2.6825 9 P 0 ;1
L 7.5325 2.7325 7.5325 2.7325 9 P 0 ;1
L 7.5325 2.7825 7.5325 2.7825 9 P 0 ;1
L 7.5325 2.8325 7.5325 2.8325 9 P 0 ;1
L 7.5325 2.8825 7.5325 2.8825 9 P 0 ;1
L 7.5325 2.9325 7.5325 2.9325 9 P 0 ;1
L 7.5325 2.9825 7.5325 2.9825 9 P 0 ;1
L 7.5325 3.0325 7.5325 3.0325 9 P 0 ;1
L 7.5325 3.0825 7.5325 3.0825 9 P 0 ;1
L 7.5325 3.1325 7.5325 3.1325 9 P 0 ;1
L 7.5325 3.1825 7.5325 3.1825 9 P 0 ;1
L 7.5325 3.2325 7.5325 3.2325 9 P 0 ;1
L 7.5325 3.2825 7.5325 3.2825 9 P 0 ;1
L 7.5325 3.3325 7.5325 3.3325 9 P 0 ;1
L 7.5325 3.3825 7.5325 3.3825 9 P 0 ;1
L 7.5325 3.4325 7.5325 3.4325 9 P 0 ;1
L 7.5325 3.4825 7.5325 3.4825 9 P 0 ;1
L 7.5325 3.5325 7.5325 3.5325 9 P 0 ;1
L 7.5325 3.5825 7.5325 3.5825 9 P 0 ;1
L 7.5325 3.6325 7.5325 3.6325 9 P 0 ;1
L 7.5325 3.6825 7.5325 3.6825 9 P 0 ;1
L 7.5325 3.7325 7.5325 3.7325 9 P 0 ;1
L 7.5325 3.7825 7.5325 3.7825 9 P 0 ;1
L 7.5325 3.8325 7.5325 3.8325 9 P 0 ;1
L 7.5325 3.8825 7.5325 3.8825 9 P 0 ;1
L 7.5325 3.9325 7.5325 3.9325 9 P 0 ;1
L 7.5325 3.9825 7.5325 3.9825 9 P 0 ;1
L 7.5325 4.0325 7.5325 4.0325 9 P 0 ;1
L 7.5325 4.0825 7.5325 4.0825 9 P 0 ;1
L 7.5325 4.1325 7.5325 4.1325 9 P 0 ;1
L 7.5325 4.1825 7.5325 4.1825 9 P 0 ;1
L 7.5325 4.2325 7.5325 4.2325 9 P 0 ;1
L 7.5325 4.2825 7.5325 4.2825 9 P 0 ;1
L 7.5325 4.3325 7.5325 4.3325 9 P 0 ;1
L 7.5325 4.3825 7.5325 4.3825 9 P 0 ;1
L 7.5325 4.4325 7.5325 4.4325 9 P 0 ;1
L 7.5325 4.4825 7.5325 4.4825 9 P 0 ;1
L 7.5325 4.5325 7.5325 4.5325 9 P 0 ;1
L 7.5325 4.5825 7.5325 4.5825 9 P 0 ;1
L 7.5325 5.2325 7.5325 5.2325 9 P 0 ;1
L 7.5325 5.2825 7.5325 5.2825 9 P 0 ;1
L 7.5325 5.3325 7.5325 5.3325 9 P 0 ;1
L 7.5325 5.3825 7.5325 5.3825 9 P 0 ;1
L 7.5325 5.4325 7.5325 5.4325 9 P 0 ;1
L 7.5325 5.4825 7.5325 5.4825 9 P 0 ;1
L 7.5325 5.5325 7.5325 5.5325 9 P 0 ;1
L 7.5325 5.5825 7.5325 5.5825 9 P 0 ;1
L 7.5325 5.6325 7.5325 5.6325 9 P 0 ;1
L 7.5325 5.6825 7.5325 5.6825 9 P 0 ;1
L 7.5325 5.7325 7.5325 5.7325 9 P 0 ;1
L 7.5325 5.7825 7.5325 5.7825 9 P 0 ;1
L 7.5325 5.8325 7.5325 5.8325 9 P 0 ;1
L 7.5325 5.8825 7.5325 5.8825 9 P 0 ;1
L 7.5825 0.1325 7.5825 0.1325 9 P 0 ;1
L 7.5825 0.1825 7.5825 0.1825 9 P 0 ;1
L 7.5825 0.2325 7.5825 0.2325 9 P 0 ;1
L 7.5825 0.2825 7.5825 0.2825 9 P 0 ;1
L 7.5825 0.3325 7.5825 0.3325 9 P 0 ;1
L 7.5825 0.3825 7.5825 0.3825 9 P 0 ;1
L 7.5825 0.4325 7.5825 0.4325 9 P 0 ;1
L 7.5825 0.4825 7.5825 0.4825 9 P 0 ;1
L 7.5825 0.5325 7.5825 0.5325 9 P 0 ;1
L 7.5825 0.5825 7.5825 0.5825 9 P 0 ;1
L 7.5825 0.6325 7.5825 0.6325 9 P 0 ;1
L 7.5825 0.6825 7.5825 0.6825 9 P 0 ;1
L 7.5825 0.7325 7.5825 0.7325 9 P 0 ;1
L 7.5825 0.7825 7.5825 0.7825 9 P 0 ;1
L 7.5825 0.8325 7.5825 0.8325 9 P 0 ;1
L 7.5825 0.8825 7.5825 0.8825 9 P 0 ;1
L 7.5825 0.9325 7.5825 0.9325 9 P 0 ;1
L 7.5825 0.9825 7.5825 0.9825 9 P 0 ;1
L 7.5825 1.0325 7.5825 1.0325 9 P 0 ;1
L 7.5825 1.0825 7.5825 1.0825 9 P 0 ;1
L 7.5825 1.1325 7.5825 1.1325 9 P 0 ;1
L 7.5825 1.1825 7.5825 1.1825 9 P 0 ;1
L 7.5825 1.2325 7.5825 1.2325 9 P 0 ;1
L 7.5825 1.2825 7.5825 1.2825 9 P 0 ;1
L 7.5825 1.3325 7.5825 1.3325 9 P 0 ;1
L 7.5825 1.3825 7.5825 1.3825 9 P 0 ;1
L 7.5825 1.4325 7.5825 1.4325 9 P 0 ;1
L 7.5825 1.4825 7.5825 1.4825 9 P 0 ;1
L 7.5825 1.5325 7.5825 1.5325 9 P 0 ;1
L 7.5825 1.5825 7.5825 1.5825 9 P 0 ;1
L 7.5825 1.6325 7.5825 1.6325 9 P 0 ;1
L 7.5825 1.6825 7.5825 1.6825 9 P 0 ;1
L 7.5825 1.7325 7.5825 1.7325 9 P 0 ;1
L 7.5825 1.7825 7.5825 1.7825 9 P 0 ;1
L 7.5825 1.8325 7.5825 1.8325 9 P 0 ;1
L 7.5825 1.8825 7.5825 1.8825 9 P 0 ;1
L 7.5825 1.9325 7.5825 1.9325 9 P 0 ;1
L 7.5825 1.9825 7.5825 1.9825 9 P 0 ;1
L 7.5825 2.0325 7.5825 2.0325 9 P 0 ;1
L 7.5825 2.0825 7.5825 2.0825 9 P 0 ;1
L 7.5825 2.1325 7.5825 2.1325 9 P 0 ;1
L 7.5825 2.1825 7.5825 2.1825 9 P 0 ;1
L 7.5825 2.2325 7.5825 2.2325 9 P 0 ;1
L 7.5825 2.2825 7.5825 2.2825 9 P 0 ;1
L 7.5825 2.3325 7.5825 2.3325 9 P 0 ;1
L 7.5825 2.3825 7.5825 2.3825 9 P 0 ;1
L 7.5825 2.4325 7.5825 2.4325 9 P 0 ;1
L 7.5825 2.4825 7.5825 2.4825 9 P 0 ;1
L 7.5825 2.5325 7.5825 2.5325 9 P 0 ;1
L 7.5825 2.5825 7.5825 2.5825 9 P 0 ;1
L 7.5825 2.6325 7.5825 2.6325 9 P 0 ;1
L 7.5825 2.6825 7.5825 2.6825 9 P 0 ;1
L 7.5825 2.7325 7.5825 2.7325 9 P 0 ;1
L 7.5825 2.7825 7.5825 2.7825 9 P 0 ;1
L 7.5825 2.8325 7.5825 2.8325 9 P 0 ;1
L 7.5825 2.8825 7.5825 2.8825 9 P 0 ;1
L 7.5825 2.9325 7.5825 2.9325 9 P 0 ;1
L 7.5825 2.9825 7.5825 2.9825 9 P 0 ;1
L 7.5825 3.0325 7.5825 3.0325 9 P 0 ;1
L 7.5825 3.0825 7.5825 3.0825 9 P 0 ;1
L 7.5825 3.1325 7.5825 3.1325 9 P 0 ;1
L 7.5825 3.1825 7.5825 3.1825 9 P 0 ;1
L 7.5825 3.2325 7.5825 3.2325 9 P 0 ;1
L 7.5825 3.2825 7.5825 3.2825 9 P 0 ;1
L 7.5825 3.3325 7.5825 3.3325 9 P 0 ;1
L 7.5825 3.3825 7.5825 3.3825 9 P 0 ;1
L 7.5825 3.4325 7.5825 3.4325 9 P 0 ;1
L 7.5825 3.4825 7.5825 3.4825 9 P 0 ;1
L 7.5825 3.5325 7.5825 3.5325 9 P 0 ;1
L 7.5825 3.5825 7.5825 3.5825 9 P 0 ;1
L 7.5825 3.6325 7.5825 3.6325 9 P 0 ;1
L 7.5825 3.6825 7.5825 3.6825 9 P 0 ;1
L 7.5825 3.7325 7.5825 3.7325 9 P 0 ;1
L 7.5825 3.7825 7.5825 3.7825 9 P 0 ;1
L 7.5825 3.8325 7.5825 3.8325 9 P 0 ;1
L 7.5825 3.8825 7.5825 3.8825 9 P 0 ;1
L 7.5825 3.9325 7.5825 3.9325 9 P 0 ;1
L 7.5825 3.9825 7.5825 3.9825 9 P 0 ;1
L 7.5825 4.0325 7.5825 4.0325 9 P 0 ;1
L 7.5825 4.0825 7.5825 4.0825 9 P 0 ;1
L 7.5825 4.1325 7.5825 4.1325 9 P 0 ;1
L 7.5825 4.1825 7.5825 4.1825 9 P 0 ;1
L 7.5825 4.2325 7.5825 4.2325 9 P 0 ;1
L 7.5825 4.2825 7.5825 4.2825 9 P 0 ;1
L 7.5825 4.3325 7.5825 4.3325 9 P 0 ;1
L 7.5825 4.3825 7.5825 4.3825 9 P 0 ;1
L 7.5825 4.4325 7.5825 4.4325 9 P 0 ;1
L 7.5825 4.4825 7.5825 4.4825 9 P 0 ;1
L 7.5825 4.5325 7.5825 4.5325 9 P 0 ;1
L 7.5825 4.5825 7.5825 4.5825 9 P 0 ;1
L 7.5825 5.2825 7.5825 5.2825 9 P 0 ;1
L 7.5825 5.3325 7.5825 5.3325 9 P 0 ;1
L 7.5825 5.3825 7.5825 5.3825 9 P 0 ;1
L 7.5825 5.4325 7.5825 5.4325 9 P 0 ;1
L 7.5825 5.4825 7.5825 5.4825 9 P 0 ;1
L 7.5825 5.5325 7.5825 5.5325 9 P 0 ;1
L 7.5825 5.5825 7.5825 5.5825 9 P 0 ;1
L 7.5825 5.6325 7.5825 5.6325 9 P 0 ;1
L 7.5825 5.6825 7.5825 5.6825 9 P 0 ;1
L 7.5825 5.7325 7.5825 5.7325 9 P 0 ;1
L 7.5825 5.7825 7.5825 5.7825 9 P 0 ;1
L 7.5825 5.8325 7.5825 5.8325 9 P 0 ;1
L 7.5825 5.8825 7.5825 5.8825 9 P 0 ;1
L 7.6325 0.1325 7.6325 0.1325 9 P 0 ;1
L 7.6325 0.1825 7.6325 0.1825 9 P 0 ;1
L 7.6325 0.2325 7.6325 0.2325 9 P 0 ;1
L 7.6325 0.2825 7.6325 0.2825 9 P 0 ;1
L 7.6325 0.3325 7.6325 0.3325 9 P 0 ;1
L 7.6325 0.3825 7.6325 0.3825 9 P 0 ;1
L 7.6325 0.4325 7.6325 0.4325 9 P 0 ;1
L 7.6325 0.4825 7.6325 0.4825 9 P 0 ;1
L 7.6325 0.5325 7.6325 0.5325 9 P 0 ;1
L 7.6325 0.5825 7.6325 0.5825 9 P 0 ;1
L 7.6325 0.6325 7.6325 0.6325 9 P 0 ;1
L 7.6325 0.6825 7.6325 0.6825 9 P 0 ;1
L 7.6325 0.7325 7.6325 0.7325 9 P 0 ;1
L 7.6325 0.7825 7.6325 0.7825 9 P 0 ;1
L 7.6325 0.8325 7.6325 0.8325 9 P 0 ;1
L 7.6325 0.8825 7.6325 0.8825 9 P 0 ;1
L 7.6325 0.9325 7.6325 0.9325 9 P 0 ;1
L 7.6325 0.9825 7.6325 0.9825 9 P 0 ;1
L 7.6325 1.0325 7.6325 1.0325 9 P 0 ;1
L 7.6325 1.0825 7.6325 1.0825 9 P 0 ;1
L 7.6325 1.1325 7.6325 1.1325 9 P 0 ;1
L 7.6325 1.1825 7.6325 1.1825 9 P 0 ;1
L 7.6325 1.2325 7.6325 1.2325 9 P 0 ;1
L 7.6325 1.2825 7.6325 1.2825 9 P 0 ;1
L 7.6325 1.3325 7.6325 1.3325 9 P 0 ;1
L 7.6325 1.3825 7.6325 1.3825 9 P 0 ;1
L 7.6325 1.4325 7.6325 1.4325 9 P 0 ;1
L 7.6325 1.4825 7.6325 1.4825 9 P 0 ;1
L 7.6325 1.5325 7.6325 1.5325 9 P 0 ;1
L 7.6325 1.5825 7.6325 1.5825 9 P 0 ;1
L 7.6325 1.6325 7.6325 1.6325 9 P 0 ;1
L 7.6325 1.6825 7.6325 1.6825 9 P 0 ;1
L 7.6325 1.7325 7.6325 1.7325 9 P 0 ;1
L 7.6325 1.7825 7.6325 1.7825 9 P 0 ;1
L 7.6325 1.8325 7.6325 1.8325 9 P 0 ;1
L 7.6325 1.8825 7.6325 1.8825 9 P 0 ;1
L 7.6325 1.9325 7.6325 1.9325 9 P 0 ;1
L 7.6325 1.9825 7.6325 1.9825 9 P 0 ;1
L 7.6325 2.0325 7.6325 2.0325 9 P 0 ;1
L 7.6325 2.0825 7.6325 2.0825 9 P 0 ;1
L 7.6325 2.1325 7.6325 2.1325 9 P 0 ;1
L 7.6325 2.1825 7.6325 2.1825 9 P 0 ;1
L 7.6325 2.2325 7.6325 2.2325 9 P 0 ;1
L 7.6325 2.2825 7.6325 2.2825 9 P 0 ;1
L 7.6325 2.3325 7.6325 2.3325 9 P 0 ;1
L 7.6325 2.3825 7.6325 2.3825 9 P 0 ;1
L 7.6325 2.4325 7.6325 2.4325 9 P 0 ;1
L 7.6325 2.4825 7.6325 2.4825 9 P 0 ;1
L 7.6325 2.5325 7.6325 2.5325 9 P 0 ;1
L 7.6325 2.5825 7.6325 2.5825 9 P 0 ;1
L 7.6325 2.6325 7.6325 2.6325 9 P 0 ;1
L 7.6325 2.6825 7.6325 2.6825 9 P 0 ;1
L 7.6325 2.7325 7.6325 2.7325 9 P 0 ;1
L 7.6325 2.7825 7.6325 2.7825 9 P 0 ;1
L 7.6325 2.8325 7.6325 2.8325 9 P 0 ;1
L 7.6325 2.8825 7.6325 2.8825 9 P 0 ;1
L 7.6325 2.9325 7.6325 2.9325 9 P 0 ;1
L 7.6325 2.9825 7.6325 2.9825 9 P 0 ;1
L 7.6325 3.0325 7.6325 3.0325 9 P 0 ;1
L 7.6325 3.0825 7.6325 3.0825 9 P 0 ;1
L 7.6325 3.1325 7.6325 3.1325 9 P 0 ;1
L 7.6325 3.1825 7.6325 3.1825 9 P 0 ;1
L 7.6325 3.2325 7.6325 3.2325 9 P 0 ;1
L 7.6325 3.2825 7.6325 3.2825 9 P 0 ;1
L 7.6325 3.3325 7.6325 3.3325 9 P 0 ;1
L 7.6325 3.3825 7.6325 3.3825 9 P 0 ;1
L 7.6325 3.4325 7.6325 3.4325 9 P 0 ;1
L 7.6325 3.4825 7.6325 3.4825 9 P 0 ;1
L 7.6325 3.5325 7.6325 3.5325 9 P 0 ;1
L 7.6325 3.5825 7.6325 3.5825 9 P 0 ;1
L 7.6325 3.6325 7.6325 3.6325 9 P 0 ;1
L 7.6325 3.6825 7.6325 3.6825 9 P 0 ;1
L 7.6325 3.7325 7.6325 3.7325 9 P 0 ;1
L 7.6325 3.7825 7.6325 3.7825 9 P 0 ;1
L 7.6325 3.8325 7.6325 3.8325 9 P 0 ;1
L 7.6325 3.8825 7.6325 3.8825 9 P 0 ;1
L 7.6325 3.9325 7.6325 3.9325 9 P 0 ;1
L 7.6325 3.9825 7.6325 3.9825 9 P 0 ;1
L 7.6325 4.0325 7.6325 4.0325 9 P 0 ;1
L 7.6325 4.0825 7.6325 4.0825 9 P 0 ;1
L 7.6325 4.1325 7.6325 4.1325 9 P 0 ;1
L 7.6325 4.1825 7.6325 4.1825 9 P 0 ;1
L 7.6325 4.2325 7.6325 4.2325 9 P 0 ;1
L 7.6325 4.2825 7.6325 4.2825 9 P 0 ;1
L 7.6325 4.3325 7.6325 4.3325 9 P 0 ;1
L 7.6325 4.3825 7.6325 4.3825 9 P 0 ;1
L 7.6325 4.4325 7.6325 4.4325 9 P 0 ;1
L 7.6325 4.4825 7.6325 4.4825 9 P 0 ;1
L 7.6325 4.5325 7.6325 4.5325 9 P 0 ;1
L 7.6325 4.5825 7.6325 4.5825 9 P 0 ;1
L 7.6325 5.2825 7.6325 5.2825 9 P 0 ;1
L 7.6325 5.3325 7.6325 5.3325 9 P 0 ;1
L 7.6325 5.3825 7.6325 5.3825 9 P 0 ;1
L 7.6325 5.4325 7.6325 5.4325 9 P 0 ;1
L 7.6325 5.4825 7.6325 5.4825 9 P 0 ;1
L 7.6325 5.5325 7.6325 5.5325 9 P 0 ;1
L 7.6325 5.5825 7.6325 5.5825 9 P 0 ;1
L 7.6325 5.6325 7.6325 5.6325 9 P 0 ;1
L 7.6325 5.6825 7.6325 5.6825 9 P 0 ;1
L 7.6325 5.7325 7.6325 5.7325 9 P 0 ;1
L 7.6325 5.7825 7.6325 5.7825 9 P 0 ;1
L 7.6325 5.8325 7.6325 5.8325 9 P 0 ;1
L 7.6325 5.8825 7.6325 5.8825 9 P 0 ;1
L 7.6825 0.1325 7.6825 0.1325 9 P 0 ;1
L 7.6825 0.1825 7.6825 0.1825 9 P 0 ;1
L 7.6825 0.2325 7.6825 0.2325 9 P 0 ;1
L 7.6825 0.2825 7.6825 0.2825 9 P 0 ;1
L 7.6825 0.3325 7.6825 0.3325 9 P 0 ;1
L 7.6825 0.3825 7.6825 0.3825 9 P 0 ;1
L 7.6825 0.4325 7.6825 0.4325 9 P 0 ;1
L 7.6825 0.4825 7.6825 0.4825 9 P 0 ;1
L 7.6825 0.5325 7.6825 0.5325 9 P 0 ;1
L 7.6825 0.5825 7.6825 0.5825 9 P 0 ;1
L 7.6825 0.6325 7.6825 0.6325 9 P 0 ;1
L 7.6825 0.6825 7.6825 0.6825 9 P 0 ;1
L 7.6825 0.7325 7.6825 0.7325 9 P 0 ;1
L 7.6825 0.7825 7.6825 0.7825 9 P 0 ;1
L 7.6825 0.8325 7.6825 0.8325 9 P 0 ;1
L 7.6825 0.8825 7.6825 0.8825 9 P 0 ;1
L 7.6825 0.9325 7.6825 0.9325 9 P 0 ;1
L 7.6825 0.9825 7.6825 0.9825 9 P 0 ;1
L 7.6825 1.0325 7.6825 1.0325 9 P 0 ;1
L 7.6825 1.0825 7.6825 1.0825 9 P 0 ;1
L 7.6825 1.1325 7.6825 1.1325 9 P 0 ;1
L 7.6825 1.1825 7.6825 1.1825 9 P 0 ;1
L 7.6825 1.2325 7.6825 1.2325 9 P 0 ;1
L 7.6825 1.2825 7.6825 1.2825 9 P 0 ;1
L 7.6825 1.3325 7.6825 1.3325 9 P 0 ;1
L 7.6825 1.3825 7.6825 1.3825 9 P 0 ;1
L 7.6825 1.4325 7.6825 1.4325 9 P 0 ;1
L 7.6825 1.4825 7.6825 1.4825 9 P 0 ;1
L 7.6825 1.5325 7.6825 1.5325 9 P 0 ;1
L 7.6825 1.5825 7.6825 1.5825 9 P 0 ;1
L 7.6825 1.6325 7.6825 1.6325 9 P 0 ;1
L 7.6825 1.6825 7.6825 1.6825 9 P 0 ;1
L 7.6825 1.7325 7.6825 1.7325 9 P 0 ;1
L 7.6825 1.7825 7.6825 1.7825 9 P 0 ;1
L 7.6825 1.8325 7.6825 1.8325 9 P 0 ;1
L 7.6825 1.8825 7.6825 1.8825 9 P 0 ;1
L 7.6825 1.9325 7.6825 1.9325 9 P 0 ;1
L 7.6825 1.9825 7.6825 1.9825 9 P 0 ;1
L 7.6825 2.0325 7.6825 2.0325 9 P 0 ;1
L 7.6825 2.0825 7.6825 2.0825 9 P 0 ;1
L 7.6825 2.1325 7.6825 2.1325 9 P 0 ;1
L 7.6825 2.1825 7.6825 2.1825 9 P 0 ;1
L 7.6825 2.2325 7.6825 2.2325 9 P 0 ;1
L 7.6825 2.2825 7.6825 2.2825 9 P 0 ;1
L 7.6825 2.3325 7.6825 2.3325 9 P 0 ;1
L 7.6825 2.3825 7.6825 2.3825 9 P 0 ;1
L 7.6825 2.4325 7.6825 2.4325 9 P 0 ;1
L 7.6825 2.4825 7.6825 2.4825 9 P 0 ;1
L 7.6825 2.5325 7.6825 2.5325 9 P 0 ;1
L 7.6825 2.5825 7.6825 2.5825 9 P 0 ;1
L 7.6825 2.6325 7.6825 2.6325 9 P 0 ;1
L 7.6825 2.6825 7.6825 2.6825 9 P 0 ;1
L 7.6825 2.7325 7.6825 2.7325 9 P 0 ;1
L 7.6825 2.7825 7.6825 2.7825 9 P 0 ;1
L 7.6825 2.8325 7.6825 2.8325 9 P 0 ;1
L 7.6825 2.8825 7.6825 2.8825 9 P 0 ;1
L 7.6825 2.9325 7.6825 2.9325 9 P 0 ;1
L 7.6825 2.9825 7.6825 2.9825 9 P 0 ;1
L 7.6825 3.0325 7.6825 3.0325 9 P 0 ;1
L 7.6825 3.0825 7.6825 3.0825 9 P 0 ;1
L 7.6825 3.1325 7.6825 3.1325 9 P 0 ;1
L 7.6825 3.1825 7.6825 3.1825 9 P 0 ;1
L 7.6825 3.2325 7.6825 3.2325 9 P 0 ;1
L 7.6825 3.2825 7.6825 3.2825 9 P 0 ;1
L 7.6825 3.3325 7.6825 3.3325 9 P 0 ;1
L 7.6825 3.3825 7.6825 3.3825 9 P 0 ;1
L 7.6825 3.4325 7.6825 3.4325 9 P 0 ;1
L 7.6825 3.4825 7.6825 3.4825 9 P 0 ;1
L 7.6825 3.5325 7.6825 3.5325 9 P 0 ;1
L 7.6825 3.5825 7.6825 3.5825 9 P 0 ;1
L 7.6825 3.6325 7.6825 3.6325 9 P 0 ;1
L 7.6825 3.6825 7.6825 3.6825 9 P 0 ;1
L 7.6825 3.7325 7.6825 3.7325 9 P 0 ;1
L 7.6825 3.7825 7.6825 3.7825 9 P 0 ;1
L 7.6825 3.8325 7.6825 3.8325 9 P 0 ;1
L 7.6825 3.8825 7.6825 3.8825 9 P 0 ;1
L 7.6825 3.9325 7.6825 3.9325 9 P 0 ;1
L 7.6825 3.9825 7.6825 3.9825 9 P 0 ;1
L 7.6825 4.0325 7.6825 4.0325 9 P 0 ;1
L 7.6825 4.0825 7.6825 4.0825 9 P 0 ;1
L 7.6825 4.1325 7.6825 4.1325 9 P 0 ;1
L 7.6825 4.1825 7.6825 4.1825 9 P 0 ;1
L 7.6825 4.2325 7.6825 4.2325 9 P 0 ;1
L 7.6825 4.2825 7.6825 4.2825 9 P 0 ;1
L 7.6825 4.3325 7.6825 4.3325 9 P 0 ;1
L 7.6825 4.3825 7.6825 4.3825 9 P 0 ;1
L 7.6825 4.4325 7.6825 4.4325 9 P 0 ;1
L 7.6825 4.4825 7.6825 4.4825 9 P 0 ;1
L 7.6825 4.5325 7.6825 4.5325 9 P 0 ;1
L 7.6825 4.5825 7.6825 4.5825 9 P 0 ;1
L 7.6825 5.2325 7.6825 5.2325 9 P 0 ;1
L 7.6825 5.2825 7.6825 5.2825 9 P 0 ;1
L 7.6825 5.3325 7.6825 5.3325 9 P 0 ;1
L 7.6825 5.3825 7.6825 5.3825 9 P 0 ;1
L 7.6825 5.4325 7.6825 5.4325 9 P 0 ;1
L 7.6825 5.4825 7.6825 5.4825 9 P 0 ;1
L 7.6825 5.5325 7.6825 5.5325 9 P 0 ;1
L 7.6825 5.5825 7.6825 5.5825 9 P 0 ;1
L 7.6825 5.6325 7.6825 5.6325 9 P 0 ;1
L 7.6825 5.6825 7.6825 5.6825 9 P 0 ;1
L 7.6825 5.7325 7.6825 5.7325 9 P 0 ;1
L 7.6825 5.7825 7.6825 5.7825 9 P 0 ;1
L 7.6825 5.8325 7.6825 5.8325 9 P 0 ;1
L 7.6825 5.8825 7.6825 5.8825 9 P 0 ;1
L 7.7325 0.1325 7.7325 0.1325 9 P 0 ;1
L 7.7325 0.1825 7.7325 0.1825 9 P 0 ;1
L 7.7325 0.2325 7.7325 0.2325 9 P 0 ;1
L 7.7325 0.2825 7.7325 0.2825 9 P 0 ;1
L 7.7325 0.3325 7.7325 0.3325 9 P 0 ;1
L 7.7325 0.3825 7.7325 0.3825 9 P 0 ;1
L 7.7325 0.4325 7.7325 0.4325 9 P 0 ;1
L 7.7325 0.4825 7.7325 0.4825 9 P 0 ;1
L 7.7325 0.5325 7.7325 0.5325 9 P 0 ;1
L 7.7325 0.5825 7.7325 0.5825 9 P 0 ;1
L 7.7325 0.6325 7.7325 0.6325 9 P 0 ;1
L 7.7325 0.6825 7.7325 0.6825 9 P 0 ;1
L 7.7325 0.7325 7.7325 0.7325 9 P 0 ;1
L 7.7325 0.7825 7.7325 0.7825 9 P 0 ;1
L 7.7325 0.8325 7.7325 0.8325 9 P 0 ;1
L 7.7325 0.8825 7.7325 0.8825 9 P 0 ;1
L 7.7325 0.9325 7.7325 0.9325 9 P 0 ;1
L 7.7325 0.9825 7.7325 0.9825 9 P 0 ;1
L 7.7325 1.0325 7.7325 1.0325 9 P 0 ;1
L 7.7325 1.0825 7.7325 1.0825 9 P 0 ;1
L 7.7325 1.1325 7.7325 1.1325 9 P 0 ;1
L 7.7325 1.1825 7.7325 1.1825 9 P 0 ;1
L 7.7325 1.2325 7.7325 1.2325 9 P 0 ;1
L 7.7325 1.2825 7.7325 1.2825 9 P 0 ;1
L 7.7325 1.3325 7.7325 1.3325 9 P 0 ;1
L 7.7325 1.3825 7.7325 1.3825 9 P 0 ;1
L 7.7325 1.4325 7.7325 1.4325 9 P 0 ;1
L 7.7325 1.4825 7.7325 1.4825 9 P 0 ;1
L 7.7325 1.5325 7.7325 1.5325 9 P 0 ;1
L 7.7325 1.5825 7.7325 1.5825 9 P 0 ;1
L 7.7325 1.6325 7.7325 1.6325 9 P 0 ;1
L 7.7325 1.6825 7.7325 1.6825 9 P 0 ;1
L 7.7325 1.7325 7.7325 1.7325 9 P 0 ;1
L 7.7325 1.7825 7.7325 1.7825 9 P 0 ;1
L 7.7325 1.8325 7.7325 1.8325 9 P 0 ;1
L 7.7325 1.8825 7.7325 1.8825 9 P 0 ;1
L 7.7325 1.9325 7.7325 1.9325 9 P 0 ;1
L 7.7325 1.9825 7.7325 1.9825 9 P 0 ;1
L 7.7325 2.0325 7.7325 2.0325 9 P 0 ;1
L 7.7325 2.0825 7.7325 2.0825 9 P 0 ;1
L 7.7325 2.1325 7.7325 2.1325 9 P 0 ;1
L 7.7325 2.1825 7.7325 2.1825 9 P 0 ;1
L 7.7325 2.2325 7.7325 2.2325 9 P 0 ;1
L 7.7325 2.2825 7.7325 2.2825 9 P 0 ;1
L 7.7325 2.3325 7.7325 2.3325 9 P 0 ;1
L 7.7325 2.3825 7.7325 2.3825 9 P 0 ;1
L 7.7325 2.5825 7.7325 2.5825 9 P 0 ;1
L 7.7325 2.6325 7.7325 2.6325 9 P 0 ;1
L 7.7325 2.6825 7.7325 2.6825 9 P 0 ;1
L 7.7325 2.7325 7.7325 2.7325 9 P 0 ;1
L 7.7325 2.7825 7.7325 2.7825 9 P 0 ;1
L 7.7325 2.8325 7.7325 2.8325 9 P 0 ;1
L 7.7325 2.8825 7.7325 2.8825 9 P 0 ;1
L 7.7325 2.9325 7.7325 2.9325 9 P 0 ;1
L 7.7325 2.9825 7.7325 2.9825 9 P 0 ;1
L 7.7325 3.0325 7.7325 3.0325 9 P 0 ;1
L 7.7325 3.0825 7.7325 3.0825 9 P 0 ;1
L 7.7325 3.1325 7.7325 3.1325 9 P 0 ;1
L 7.7325 3.1825 7.7325 3.1825 9 P 0 ;1
L 7.7325 3.2325 7.7325 3.2325 9 P 0 ;1
L 7.7325 3.2825 7.7325 3.2825 9 P 0 ;1
L 7.7325 3.3325 7.7325 3.3325 9 P 0 ;1
L 7.7325 3.3825 7.7325 3.3825 9 P 0 ;1
L 7.7325 3.4325 7.7325 3.4325 9 P 0 ;1
L 7.7325 3.4825 7.7325 3.4825 9 P 0 ;1
L 7.7325 3.5325 7.7325 3.5325 9 P 0 ;1
L 7.7325 3.5825 7.7325 3.5825 9 P 0 ;1
L 7.7325 3.6325 7.7325 3.6325 9 P 0 ;1
L 7.7325 3.6825 7.7325 3.6825 9 P 0 ;1
L 7.7325 3.7325 7.7325 3.7325 9 P 0 ;1
L 7.7325 3.7825 7.7325 3.7825 9 P 0 ;1
L 7.7325 3.8325 7.7325 3.8325 9 P 0 ;1
L 7.7325 3.8825 7.7325 3.8825 9 P 0 ;1
L 7.7325 3.9325 7.7325 3.9325 9 P 0 ;1
L 7.7325 3.9825 7.7325 3.9825 9 P 0 ;1
L 7.7325 4.0325 7.7325 4.0325 9 P 0 ;1
L 7.7325 4.0825 7.7325 4.0825 9 P 0 ;1
L 7.7325 4.1325 7.7325 4.1325 9 P 0 ;1
L 7.7325 4.1825 7.7325 4.1825 9 P 0 ;1
L 7.7325 4.2325 7.7325 4.2325 9 P 0 ;1
L 7.7325 4.2825 7.7325 4.2825 9 P 0 ;1
L 7.7325 4.3325 7.7325 4.3325 9 P 0 ;1
L 7.7325 4.3825 7.7325 4.3825 9 P 0 ;1
L 7.7325 4.5325 7.7325 4.5325 9 P 0 ;1
L 7.7325 4.5825 7.7325 4.5825 9 P 0 ;1
L 7.7325 4.6325 7.7325 4.6325 9 P 0 ;1
L 7.7325 5.1825 7.7325 5.1825 9 P 0 ;1
L 7.7325 5.2325 7.7325 5.2325 9 P 0 ;1
L 7.7325 5.2825 7.7325 5.2825 9 P 0 ;1
L 7.7325 5.3325 7.7325 5.3325 9 P 0 ;1
L 7.7325 5.3825 7.7325 5.3825 9 P 0 ;1
L 7.7325 5.4325 7.7325 5.4325 9 P 0 ;1
L 7.7325 5.4825 7.7325 5.4825 9 P 0 ;1
L 7.7325 5.5325 7.7325 5.5325 9 P 0 ;1
L 7.7325 5.5825 7.7325 5.5825 9 P 0 ;1
L 7.7325 5.6325 7.7325 5.6325 9 P 0 ;1
L 7.7325 5.6825 7.7325 5.6825 9 P 0 ;1
L 7.7325 5.7325 7.7325 5.7325 9 P 0 ;1
L 7.7325 5.7825 7.7325 5.7825 9 P 0 ;1
L 7.7325 5.8325 7.7325 5.8325 9 P 0 ;1
L 7.7325 5.8825 7.7325 5.8825 9 P 0 ;1
L 7.7825 0.1325 7.7825 0.1325 9 P 0 ;1
L 7.7825 0.1825 7.7825 0.1825 9 P 0 ;1
L 7.7825 0.2325 7.7825 0.2325 9 P 0 ;1
L 7.7825 0.2825 7.7825 0.2825 9 P 0 ;1
L 7.7825 0.3325 7.7825 0.3325 9 P 0 ;1
L 7.7825 0.3825 7.7825 0.3825 9 P 0 ;1
L 7.7825 0.4325 7.7825 0.4325 9 P 0 ;1
L 7.7825 0.4825 7.7825 0.4825 9 P 0 ;1
L 7.7825 0.5325 7.7825 0.5325 9 P 0 ;1
L 7.7825 0.5825 7.7825 0.5825 9 P 0 ;1
L 7.7825 0.6325 7.7825 0.6325 9 P 0 ;1
L 7.7825 0.6825 7.7825 0.6825 9 P 0 ;1
L 7.7825 0.7325 7.7825 0.7325 9 P 0 ;1
L 7.7825 0.7825 7.7825 0.7825 9 P 0 ;1
L 7.7825 0.8325 7.7825 0.8325 9 P 0 ;1
L 7.7825 0.8825 7.7825 0.8825 9 P 0 ;1
L 7.7825 0.9325 7.7825 0.9325 9 P 0 ;1
L 7.7825 0.9825 7.7825 0.9825 9 P 0 ;1
L 7.7825 1.0325 7.7825 1.0325 9 P 0 ;1
L 7.7825 1.0825 7.7825 1.0825 9 P 0 ;1
L 7.7825 1.1325 7.7825 1.1325 9 P 0 ;1
L 7.7825 1.1825 7.7825 1.1825 9 P 0 ;1
L 7.7825 1.2325 7.7825 1.2325 9 P 0 ;1
L 7.7825 1.2825 7.7825 1.2825 9 P 0 ;1
L 7.7825 1.3325 7.7825 1.3325 9 P 0 ;1
L 7.7825 1.3825 7.7825 1.3825 9 P 0 ;1
L 7.7825 1.4325 7.7825 1.4325 9 P 0 ;1
L 7.7825 1.4825 7.7825 1.4825 9 P 0 ;1
L 7.7825 1.5325 7.7825 1.5325 9 P 0 ;1
L 7.7825 1.5825 7.7825 1.5825 9 P 0 ;1
L 7.7825 1.6325 7.7825 1.6325 9 P 0 ;1
L 7.7825 1.6825 7.7825 1.6825 9 P 0 ;1
L 7.7825 1.7325 7.7825 1.7325 9 P 0 ;1
L 7.7825 1.7825 7.7825 1.7825 9 P 0 ;1
L 7.7825 1.8325 7.7825 1.8325 9 P 0 ;1
L 7.7825 1.8825 7.7825 1.8825 9 P 0 ;1
L 7.7825 1.9325 7.7825 1.9325 9 P 0 ;1
L 7.7825 1.9825 7.7825 1.9825 9 P 0 ;1
L 7.7825 2.0325 7.7825 2.0325 9 P 0 ;1
L 7.7825 2.0825 7.7825 2.0825 9 P 0 ;1
L 7.7825 2.1325 7.7825 2.1325 9 P 0 ;1
L 7.7825 2.1825 7.7825 2.1825 9 P 0 ;1
L 7.7825 2.2325 7.7825 2.2325 9 P 0 ;1
L 7.7825 2.2825 7.7825 2.2825 9 P 0 ;1
L 7.7825 2.3325 7.7825 2.3325 9 P 0 ;1
L 7.7825 2.3825 7.7825 2.3825 9 P 0 ;1
L 7.7825 2.5825 7.7825 2.5825 9 P 0 ;1
L 7.7825 2.6325 7.7825 2.6325 9 P 0 ;1
L 7.7825 2.6825 7.7825 2.6825 9 P 0 ;1
L 7.7825 2.7325 7.7825 2.7325 9 P 0 ;1
L 7.7825 2.7825 7.7825 2.7825 9 P 0 ;1
L 7.7825 2.8325 7.7825 2.8325 9 P 0 ;1
L 7.7825 2.8825 7.7825 2.8825 9 P 0 ;1
L 7.7825 2.9325 7.7825 2.9325 9 P 0 ;1
L 7.7825 2.9825 7.7825 2.9825 9 P 0 ;1
L 7.7825 3.0325 7.7825 3.0325 9 P 0 ;1
L 7.7825 3.0825 7.7825 3.0825 9 P 0 ;1
L 7.7825 3.1325 7.7825 3.1325 9 P 0 ;1
L 7.7825 3.1825 7.7825 3.1825 9 P 0 ;1
L 7.7825 3.2325 7.7825 3.2325 9 P 0 ;1
L 7.7825 3.2825 7.7825 3.2825 9 P 0 ;1
L 7.7825 3.3325 7.7825 3.3325 9 P 0 ;1
L 7.7825 3.3825 7.7825 3.3825 9 P 0 ;1
L 7.7825 3.4325 7.7825 3.4325 9 P 0 ;1
L 7.7825 3.4825 7.7825 3.4825 9 P 0 ;1
L 7.7825 3.5325 7.7825 3.5325 9 P 0 ;1
L 7.7825 3.5825 7.7825 3.5825 9 P 0 ;1
L 7.7825 3.6325 7.7825 3.6325 9 P 0 ;1
L 7.7825 3.6825 7.7825 3.6825 9 P 0 ;1
L 7.7825 3.7325 7.7825 3.7325 9 P 0 ;1
L 7.7825 3.7825 7.7825 3.7825 9 P 0 ;1
L 7.7825 3.8325 7.7825 3.8325 9 P 0 ;1
L 7.7825 3.8825 7.7825 3.8825 9 P 0 ;1
L 7.7825 3.9325 7.7825 3.9325 9 P 0 ;1
L 7.7825 3.9825 7.7825 3.9825 9 P 0 ;1
L 7.7825 4.0325 7.7825 4.0325 9 P 0 ;1
L 7.7825 4.0825 7.7825 4.0825 9 P 0 ;1
L 7.7825 4.1325 7.7825 4.1325 9 P 0 ;1
L 7.7825 4.1825 7.7825 4.1825 9 P 0 ;1
L 7.7825 4.2325 7.7825 4.2325 9 P 0 ;1
L 7.7825 4.2825 7.7825 4.2825 9 P 0 ;1
L 7.7825 4.3325 7.7825 4.3325 9 P 0 ;1
L 7.7825 4.5325 7.7825 4.5325 9 P 0 ;1
L 7.7825 4.5825 7.7825 4.5825 9 P 0 ;1
L 7.7825 5.1825 7.7825 5.1825 9 P 0 ;1
L 7.7825 5.2325 7.7825 5.2325 9 P 0 ;1
L 7.7825 5.2825 7.7825 5.2825 9 P 0 ;1
L 7.7825 5.3325 7.7825 5.3325 9 P 0 ;1
L 7.7825 5.3825 7.7825 5.3825 9 P 0 ;1
L 7.7825 5.4325 7.7825 5.4325 9 P 0 ;1
L 7.7825 5.4825 7.7825 5.4825 9 P 0 ;1
L 7.7825 5.5325 7.7825 5.5325 9 P 0 ;1
L 7.7825 5.5825 7.7825 5.5825 9 P 0 ;1
L 7.7825 5.6325 7.7825 5.6325 9 P 0 ;1
L 7.7825 5.6825 7.7825 5.6825 9 P 0 ;1
L 7.7825 5.7325 7.7825 5.7325 9 P 0 ;1
L 7.7825 5.7825 7.7825 5.7825 9 P 0 ;1
L 7.7825 5.8325 7.7825 5.8325 9 P 0 ;1
L 7.7825 5.8825 7.7825 5.8825 9 P 0 ;1
L 7.8325 0.1325 7.8325 0.1325 9 P 0 ;1
L 7.8325 0.1825 7.8325 0.1825 9 P 0 ;1
L 7.8325 0.2325 7.8325 0.2325 9 P 0 ;1
L 7.8325 0.2825 7.8325 0.2825 9 P 0 ;1
L 7.8325 0.3325 7.8325 0.3325 9 P 0 ;1
L 7.8325 0.3825 7.8325 0.3825 9 P 0 ;1
L 7.8325 0.4325 7.8325 0.4325 9 P 0 ;1
L 7.8325 0.4825 7.8325 0.4825 9 P 0 ;1
L 7.8325 0.5325 7.8325 0.5325 9 P 0 ;1
L 7.8325 0.5825 7.8325 0.5825 9 P 0 ;1
L 7.8325 0.6325 7.8325 0.6325 9 P 0 ;1
L 7.8325 0.6825 7.8325 0.6825 9 P 0 ;1
L 7.8325 0.7325 7.8325 0.7325 9 P 0 ;1
L 7.8325 0.7825 7.8325 0.7825 9 P 0 ;1
L 7.8325 0.8325 7.8325 0.8325 9 P 0 ;1
L 7.8325 0.8825 7.8325 0.8825 9 P 0 ;1
L 7.8325 0.9325 7.8325 0.9325 9 P 0 ;1
L 7.8325 0.9825 7.8325 0.9825 9 P 0 ;1
L 7.8325 1.0325 7.8325 1.0325 9 P 0 ;1
L 7.8325 1.0825 7.8325 1.0825 9 P 0 ;1
L 7.8325 1.1325 7.8325 1.1325 9 P 0 ;1
L 7.8325 1.1825 7.8325 1.1825 9 P 0 ;1
L 7.8325 1.2325 7.8325 1.2325 9 P 0 ;1
L 7.8325 1.2825 7.8325 1.2825 9 P 0 ;1
L 7.8325 1.3325 7.8325 1.3325 9 P 0 ;1
L 7.8325 1.3825 7.8325 1.3825 9 P 0 ;1
L 7.8325 1.4325 7.8325 1.4325 9 P 0 ;1
L 7.8325 1.4825 7.8325 1.4825 9 P 0 ;1
L 7.8325 1.5325 7.8325 1.5325 9 P 0 ;1
L 7.8325 1.5825 7.8325 1.5825 9 P 0 ;1
L 7.8325 1.6325 7.8325 1.6325 9 P 0 ;1
L 7.8325 1.6825 7.8325 1.6825 9 P 0 ;1
L 7.8325 1.7325 7.8325 1.7325 9 P 0 ;1
L 7.8325 1.7825 7.8325 1.7825 9 P 0 ;1
L 7.8325 1.8325 7.8325 1.8325 9 P 0 ;1
L 7.8325 1.8825 7.8325 1.8825 9 P 0 ;1
L 7.8325 1.9325 7.8325 1.9325 9 P 0 ;1
L 7.8325 1.9825 7.8325 1.9825 9 P 0 ;1
L 7.8325 2.0325 7.8325 2.0325 9 P 0 ;1
L 7.8325 2.0825 7.8325 2.0825 9 P 0 ;1
L 7.8325 2.1325 7.8325 2.1325 9 P 0 ;1
L 7.8325 2.1825 7.8325 2.1825 9 P 0 ;1
L 7.8325 2.2325 7.8325 2.2325 9 P 0 ;1
L 7.8325 2.2825 7.8325 2.2825 9 P 0 ;1
L 7.8325 2.3325 7.8325 2.3325 9 P 0 ;1
L 7.8325 2.3825 7.8325 2.3825 9 P 0 ;1
L 7.8325 2.5825 7.8325 2.5825 9 P 0 ;1
L 7.8325 2.6325 7.8325 2.6325 9 P 0 ;1
L 7.8325 2.6825 7.8325 2.6825 9 P 0 ;1
L 7.8325 2.7325 7.8325 2.7325 9 P 0 ;1
L 7.8325 2.7825 7.8325 2.7825 9 P 0 ;1
L 7.8325 2.8325 7.8325 2.8325 9 P 0 ;1
L 7.8325 2.8825 7.8325 2.8825 9 P 0 ;1
L 7.8325 2.9325 7.8325 2.9325 9 P 0 ;1
L 7.8325 2.9825 7.8325 2.9825 9 P 0 ;1
L 7.8325 3.0325 7.8325 3.0325 9 P 0 ;1
L 7.8325 3.0825 7.8325 3.0825 9 P 0 ;1
L 7.8325 3.1325 7.8325 3.1325 9 P 0 ;1
L 7.8325 3.1825 7.8325 3.1825 9 P 0 ;1
L 7.8325 3.2325 7.8325 3.2325 9 P 0 ;1
L 7.8325 3.2825 7.8325 3.2825 9 P 0 ;1
L 7.8325 3.3325 7.8325 3.3325 9 P 0 ;1
L 7.8325 3.3825 7.8325 3.3825 9 P 0 ;1
L 7.8325 3.4325 7.8325 3.4325 9 P 0 ;1
L 7.8325 3.4825 7.8325 3.4825 9 P 0 ;1
L 7.8325 3.5325 7.8325 3.5325 9 P 0 ;1
L 7.8325 3.5825 7.8325 3.5825 9 P 0 ;1
L 7.8325 3.6325 7.8325 3.6325 9 P 0 ;1
L 7.8325 3.6825 7.8325 3.6825 9 P 0 ;1
L 7.8325 3.7325 7.8325 3.7325 9 P 0 ;1
L 7.8325 3.7825 7.8325 3.7825 9 P 0 ;1
L 7.8325 3.8325 7.8325 3.8325 9 P 0 ;1
L 7.8325 3.8825 7.8325 3.8825 9 P 0 ;1
L 7.8325 3.9325 7.8325 3.9325 9 P 0 ;1
L 7.8325 3.9825 7.8325 3.9825 9 P 0 ;1
L 7.8325 4.0325 7.8325 4.0325 9 P 0 ;1
L 7.8325 4.0825 7.8325 4.0825 9 P 0 ;1
L 7.8325 4.1325 7.8325 4.1325 9 P 0 ;1
L 7.8325 4.1825 7.8325 4.1825 9 P 0 ;1
L 7.8325 4.2325 7.8325 4.2325 9 P 0 ;1
L 7.8325 4.2825 7.8325 4.2825 9 P 0 ;1
L 7.8325 4.3325 7.8325 4.3325 9 P 0 ;1
L 7.8325 4.5325 7.8325 4.5325 9 P 0 ;1
L 7.8325 5.2825 7.8325 5.2825 9 P 0 ;1
L 7.8325 5.3325 7.8325 5.3325 9 P 0 ;1
L 7.8325 5.3825 7.8325 5.3825 9 P 0 ;1
L 7.8325 5.4325 7.8325 5.4325 9 P 0 ;1
L 7.8325 5.4825 7.8325 5.4825 9 P 0 ;1
L 7.8325 5.5325 7.8325 5.5325 9 P 0 ;1
L 7.8325 5.5825 7.8325 5.5825 9 P 0 ;1
L 7.8325 5.6325 7.8325 5.6325 9 P 0 ;1
L 7.8325 5.6825 7.8325 5.6825 9 P 0 ;1
L 7.8325 5.7325 7.8325 5.7325 9 P 0 ;1
L 7.8325 5.7825 7.8325 5.7825 9 P 0 ;1
L 7.8325 5.8325 7.8325 5.8325 9 P 0 ;1
L 7.8325 5.8825 7.8325 5.8825 9 P 0 ;1
L 7.8825 0.1325 7.8825 0.1325 9 P 0 ;1
L 7.8825 0.1825 7.8825 0.1825 9 P 0 ;1
L 7.8825 0.2325 7.8825 0.2325 9 P 0 ;1
L 7.8825 0.2825 7.8825 0.2825 9 P 0 ;1
L 7.8825 0.3325 7.8825 0.3325 9 P 0 ;1
L 7.8825 0.3825 7.8825 0.3825 9 P 0 ;1
L 7.8825 0.4325 7.8825 0.4325 9 P 0 ;1
L 7.8825 0.4825 7.8825 0.4825 9 P 0 ;1
L 7.8825 0.5325 7.8825 0.5325 9 P 0 ;1
L 7.8825 0.5825 7.8825 0.5825 9 P 0 ;1
L 7.8825 0.6325 7.8825 0.6325 9 P 0 ;1
L 7.8825 0.6825 7.8825 0.6825 9 P 0 ;1
L 7.8825 0.7325 7.8825 0.7325 9 P 0 ;1
L 7.8825 0.7825 7.8825 0.7825 9 P 0 ;1
L 7.8825 0.8325 7.8825 0.8325 9 P 0 ;1
L 7.8825 0.8825 7.8825 0.8825 9 P 0 ;1
L 7.8825 0.9325 7.8825 0.9325 9 P 0 ;1
L 7.8825 0.9825 7.8825 0.9825 9 P 0 ;1
L 7.8825 1.0325 7.8825 1.0325 9 P 0 ;1
L 7.8825 1.0825 7.8825 1.0825 9 P 0 ;1
L 7.8825 1.1325 7.8825 1.1325 9 P 0 ;1
L 7.8825 1.1825 7.8825 1.1825 9 P 0 ;1
L 7.8825 1.2325 7.8825 1.2325 9 P 0 ;1
L 7.8825 1.2825 7.8825 1.2825 9 P 0 ;1
L 7.8825 1.3325 7.8825 1.3325 9 P 0 ;1
L 7.8825 1.3825 7.8825 1.3825 9 P 0 ;1
L 7.8825 1.4325 7.8825 1.4325 9 P 0 ;1
L 7.8825 1.4825 7.8825 1.4825 9 P 0 ;1
L 7.8825 1.5325 7.8825 1.5325 9 P 0 ;1
L 7.8825 1.5825 7.8825 1.5825 9 P 0 ;1
L 7.8825 1.6325 7.8825 1.6325 9 P 0 ;1
L 7.8825 1.6825 7.8825 1.6825 9 P 0 ;1
L 7.8825 1.7325 7.8825 1.7325 9 P 0 ;1
L 7.8825 1.7825 7.8825 1.7825 9 P 0 ;1
L 7.8825 1.8325 7.8825 1.8325 9 P 0 ;1
L 7.8825 1.8825 7.8825 1.8825 9 P 0 ;1
L 7.8825 1.9325 7.8825 1.9325 9 P 0 ;1
L 7.8825 1.9825 7.8825 1.9825 9 P 0 ;1
L 7.8825 2.0325 7.8825 2.0325 9 P 0 ;1
L 7.8825 2.0825 7.8825 2.0825 9 P 0 ;1
L 7.8825 2.1325 7.8825 2.1325 9 P 0 ;1
L 7.8825 2.1825 7.8825 2.1825 9 P 0 ;1
L 7.8825 2.2325 7.8825 2.2325 9 P 0 ;1
L 7.8825 2.2825 7.8825 2.2825 9 P 0 ;1
L 7.8825 2.3325 7.8825 2.3325 9 P 0 ;1
L 7.8825 2.3825 7.8825 2.3825 9 P 0 ;1
L 7.8825 2.4325 7.8825 2.4325 9 P 0 ;1
L 7.8825 2.4825 7.8825 2.4825 9 P 0 ;1
L 7.8825 2.5325 7.8825 2.5325 9 P 0 ;1
L 7.8825 2.5825 7.8825 2.5825 9 P 0 ;1
L 7.8825 2.6325 7.8825 2.6325 9 P 0 ;1
L 7.8825 2.6825 7.8825 2.6825 9 P 0 ;1
L 7.8825 2.7325 7.8825 2.7325 9 P 0 ;1
L 7.8825 2.7825 7.8825 2.7825 9 P 0 ;1
L 7.8825 2.8325 7.8825 2.8325 9 P 0 ;1
L 7.8825 2.8825 7.8825 2.8825 9 P 0 ;1
L 7.8825 2.9325 7.8825 2.9325 9 P 0 ;1
L 7.8825 2.9825 7.8825 2.9825 9 P 0 ;1
L 7.8825 3.0325 7.8825 3.0325 9 P 0 ;1
L 7.8825 3.0825 7.8825 3.0825 9 P 0 ;1
L 7.8825 3.1325 7.8825 3.1325 9 P 0 ;1
L 7.8825 3.1825 7.8825 3.1825 9 P 0 ;1
L 7.8825 3.2325 7.8825 3.2325 9 P 0 ;1
L 7.8825 3.2825 7.8825 3.2825 9 P 0 ;1
L 7.8825 3.3325 7.8825 3.3325 9 P 0 ;1
L 7.8825 3.3825 7.8825 3.3825 9 P 0 ;1
L 7.8825 3.4325 7.8825 3.4325 9 P 0 ;1
L 7.8825 3.4825 7.8825 3.4825 9 P 0 ;1
L 7.8825 3.5325 7.8825 3.5325 9 P 0 ;1
L 7.8825 3.5825 7.8825 3.5825 9 P 0 ;1
L 7.8825 3.6325 7.8825 3.6325 9 P 0 ;1
L 7.8825 3.6825 7.8825 3.6825 9 P 0 ;1
L 7.8825 3.7325 7.8825 3.7325 9 P 0 ;1
L 7.8825 3.7825 7.8825 3.7825 9 P 0 ;1
L 7.8825 3.8325 7.8825 3.8325 9 P 0 ;1
L 7.8825 3.8825 7.8825 3.8825 9 P 0 ;1
L 7.8825 3.9325 7.8825 3.9325 9 P 0 ;1
L 7.8825 3.9825 7.8825 3.9825 9 P 0 ;1
L 7.8825 4.0325 7.8825 4.0325 9 P 0 ;1
L 7.8825 4.0825 7.8825 4.0825 9 P 0 ;1
L 7.8825 4.1325 7.8825 4.1325 9 P 0 ;1
L 7.8825 4.1825 7.8825 4.1825 9 P 0 ;1
L 7.8825 4.2325 7.8825 4.2325 9 P 0 ;1
L 7.8825 4.2825 7.8825 4.2825 9 P 0 ;1
L 7.8825 4.3325 7.8825 4.3325 9 P 0 ;1
L 7.8825 4.3825 7.8825 4.3825 9 P 0 ;1
L 7.8825 4.5325 7.8825 4.5325 9 P 0 ;1
L 7.8825 5.2825 7.8825 5.2825 9 P 0 ;1
L 7.8825 5.4825 7.8825 5.4825 9 P 0 ;1
L 7.8825 5.5325 7.8825 5.5325 9 P 0 ;1
L 7.8825 5.5825 7.8825 5.5825 9 P 0 ;1
L 7.8825 5.6325 7.8825 5.6325 9 P 0 ;1
L 7.8825 5.6825 7.8825 5.6825 9 P 0 ;1
L 7.8825 5.7325 7.8825 5.7325 9 P 0 ;1
L 7.8825 5.7825 7.8825 5.7825 9 P 0 ;1
L 7.8825 5.8325 7.8825 5.8325 9 P 0 ;1
L 7.8825 5.8825 7.8825 5.8825 9 P 0 ;1
L 7.9325 0.1325 7.9325 0.1325 9 P 0 ;1
L 7.9325 0.1825 7.9325 0.1825 9 P 0 ;1
L 7.9325 0.2325 7.9325 0.2325 9 P 0 ;1
L 7.9325 0.2825 7.9325 0.2825 9 P 0 ;1
L 7.9325 0.3325 7.9325 0.3325 9 P 0 ;1
L 7.9325 0.3825 7.9325 0.3825 9 P 0 ;1
L 7.9325 0.4325 7.9325 0.4325 9 P 0 ;1
L 7.9325 0.4825 7.9325 0.4825 9 P 0 ;1
L 7.9325 0.5325 7.9325 0.5325 9 P 0 ;1
L 7.9325 0.5825 7.9325 0.5825 9 P 0 ;1
L 7.9325 0.6325 7.9325 0.6325 9 P 0 ;1
L 7.9325 0.6825 7.9325 0.6825 9 P 0 ;1
L 7.9325 0.7325 7.9325 0.7325 9 P 0 ;1
L 7.9325 0.7825 7.9325 0.7825 9 P 0 ;1
L 7.9325 0.8325 7.9325 0.8325 9 P 0 ;1
L 7.9325 0.8825 7.9325 0.8825 9 P 0 ;1
L 7.9325 0.9325 7.9325 0.9325 9 P 0 ;1
L 7.9325 0.9825 7.9325 0.9825 9 P 0 ;1
L 7.9325 1.0325 7.9325 1.0325 9 P 0 ;1
L 7.9325 1.0825 7.9325 1.0825 9 P 0 ;1
L 7.9325 1.1325 7.9325 1.1325 9 P 0 ;1
L 7.9325 1.1825 7.9325 1.1825 9 P 0 ;1
L 7.9325 1.2325 7.9325 1.2325 9 P 0 ;1
L 7.9325 1.2825 7.9325 1.2825 9 P 0 ;1
L 7.9325 1.3325 7.9325 1.3325 9 P 0 ;1
L 7.9325 1.3825 7.9325 1.3825 9 P 0 ;1
L 7.9325 1.4325 7.9325 1.4325 9 P 0 ;1
L 7.9325 1.4825 7.9325 1.4825 9 P 0 ;1
L 7.9325 1.5325 7.9325 1.5325 9 P 0 ;1
L 7.9325 1.5825 7.9325 1.5825 9 P 0 ;1
L 7.9325 1.6325 7.9325 1.6325 9 P 0 ;1
L 7.9325 1.6825 7.9325 1.6825 9 P 0 ;1
L 7.9325 1.7325 7.9325 1.7325 9 P 0 ;1
L 7.9325 1.7825 7.9325 1.7825 9 P 0 ;1
L 7.9325 1.8325 7.9325 1.8325 9 P 0 ;1
L 7.9325 1.8825 7.9325 1.8825 9 P 0 ;1
L 7.9325 1.9325 7.9325 1.9325 9 P 0 ;1
L 7.9325 1.9825 7.9325 1.9825 9 P 0 ;1
L 7.9325 2.0325 7.9325 2.0325 9 P 0 ;1
L 7.9325 2.0825 7.9325 2.0825 9 P 0 ;1
L 7.9325 2.1325 7.9325 2.1325 9 P 0 ;1
L 7.9325 2.1825 7.9325 2.1825 9 P 0 ;1
L 7.9325 2.2325 7.9325 2.2325 9 P 0 ;1
L 7.9325 2.2825 7.9325 2.2825 9 P 0 ;1
L 7.9325 2.3325 7.9325 2.3325 9 P 0 ;1
L 7.9325 2.3825 7.9325 2.3825 9 P 0 ;1
L 7.9325 2.4325 7.9325 2.4325 9 P 0 ;1
L 7.9325 2.4825 7.9325 2.4825 9 P 0 ;1
L 7.9325 2.5325 7.9325 2.5325 9 P 0 ;1
L 7.9325 2.5825 7.9325 2.5825 9 P 0 ;1
L 7.9325 2.6325 7.9325 2.6325 9 P 0 ;1
L 7.9325 2.9325 7.9325 2.9325 9 P 0 ;1
L 7.9325 2.9825 7.9325 2.9825 9 P 0 ;1
L 7.9325 3.0325 7.9325 3.0325 9 P 0 ;1
L 7.9325 3.0825 7.9325 3.0825 9 P 0 ;1
L 7.9325 3.1325 7.9325 3.1325 9 P 0 ;1
L 7.9325 3.1825 7.9325 3.1825 9 P 0 ;1
L 7.9325 3.2325 7.9325 3.2325 9 P 0 ;1
L 7.9325 3.2825 7.9325 3.2825 9 P 0 ;1
L 7.9325 3.3325 7.9325 3.3325 9 P 0 ;1
L 7.9325 3.6325 7.9325 3.6325 9 P 0 ;1
L 7.9325 3.6825 7.9325 3.6825 9 P 0 ;1
L 7.9325 3.7325 7.9325 3.7325 9 P 0 ;1
L 7.9325 3.7825 7.9325 3.7825 9 P 0 ;1
L 7.9325 3.8325 7.9325 3.8325 9 P 0 ;1
L 7.9325 3.8825 7.9325 3.8825 9 P 0 ;1
L 7.9325 3.9325 7.9325 3.9325 9 P 0 ;1
L 7.9325 3.9825 7.9325 3.9825 9 P 0 ;1
L 7.9325 4.0325 7.9325 4.0325 9 P 0 ;1
L 7.9325 4.0825 7.9325 4.0825 9 P 0 ;1
L 7.9325 4.1325 7.9325 4.1325 9 P 0 ;1
L 7.9325 4.1825 7.9325 4.1825 9 P 0 ;1
L 7.9325 4.2325 7.9325 4.2325 9 P 0 ;1
L 7.9325 4.2825 7.9325 4.2825 9 P 0 ;1
L 7.9325 4.3325 7.9325 4.3325 9 P 0 ;1
L 7.9325 4.3825 7.9325 4.3825 9 P 0 ;1
L 7.9325 4.4325 7.9325 4.4325 9 P 0 ;1
L 7.9325 4.4825 7.9325 4.4825 9 P 0 ;1
L 7.9325 4.5325 7.9325 4.5325 9 P 0 ;1
L 7.9325 4.7325 7.9325 4.7325 9 P 0 ;1
L 7.9325 5.4825 7.9325 5.4825 9 P 0 ;1
L 7.9325 5.5325 7.9325 5.5325 9 P 0 ;1
L 7.9325 5.5825 7.9325 5.5825 9 P 0 ;1
L 7.9325 5.6325 7.9325 5.6325 9 P 0 ;1
L 7.9325 5.6825 7.9325 5.6825 9 P 0 ;1
L 7.9325 5.7325 7.9325 5.7325 9 P 0 ;1
L 7.9325 5.7825 7.9325 5.7825 9 P 0 ;1
L 7.9325 5.8325 7.9325 5.8325 9 P 0 ;1
L 7.9325 5.8825 7.9325 5.8825 9 P 0 ;1
L 7.9825 0.1325 7.9825 0.1325 9 P 0 ;1
L 7.9825 0.1825 7.9825 0.1825 9 P 0 ;1
L 7.9825 0.2325 7.9825 0.2325 9 P 0 ;1
L 7.9825 0.2825 7.9825 0.2825 9 P 0 ;1
L 7.9825 0.3325 7.9825 0.3325 9 P 0 ;1
L 7.9825 0.3825 7.9825 0.3825 9 P 0 ;1
L 7.9825 0.4325 7.9825 0.4325 9 P 0 ;1
L 7.9825 0.4825 7.9825 0.4825 9 P 0 ;1
L 7.9825 0.5325 7.9825 0.5325 9 P 0 ;1
L 7.9825 0.5825 7.9825 0.5825 9 P 0 ;1
L 7.9825 0.6325 7.9825 0.6325 9 P 0 ;1
L 7.9825 0.6825 7.9825 0.6825 9 P 0 ;1
L 7.9825 0.7325 7.9825 0.7325 9 P 0 ;1
L 7.9825 0.7825 7.9825 0.7825 9 P 0 ;1
L 7.9825 0.8325 7.9825 0.8325 9 P 0 ;1
L 7.9825 0.8825 7.9825 0.8825 9 P 0 ;1
L 7.9825 0.9325 7.9825 0.9325 9 P 0 ;1
L 7.9825 0.9825 7.9825 0.9825 9 P 0 ;1
L 7.9825 1.0325 7.9825 1.0325 9 P 0 ;1
L 7.9825 1.0825 7.9825 1.0825 9 P 0 ;1
L 7.9825 1.1325 7.9825 1.1325 9 P 0 ;1
L 7.9825 1.1825 7.9825 1.1825 9 P 0 ;1
L 7.9825 1.2325 7.9825 1.2325 9 P 0 ;1
L 7.9825 1.2825 7.9825 1.2825 9 P 0 ;1
L 7.9825 1.3325 7.9825 1.3325 9 P 0 ;1
L 7.9825 1.3825 7.9825 1.3825 9 P 0 ;1
L 7.9825 1.4325 7.9825 1.4325 9 P 0 ;1
L 7.9825 1.4825 7.9825 1.4825 9 P 0 ;1
L 7.9825 1.5325 7.9825 1.5325 9 P 0 ;1
L 7.9825 1.5825 7.9825 1.5825 9 P 0 ;1
L 7.9825 1.6325 7.9825 1.6325 9 P 0 ;1
L 7.9825 1.6825 7.9825 1.6825 9 P 0 ;1
L 7.9825 1.7325 7.9825 1.7325 9 P 0 ;1
L 7.9825 1.7825 7.9825 1.7825 9 P 0 ;1
L 7.9825 3.9325 7.9825 3.9325 9 P 0 ;1
L 7.9825 3.9825 7.9825 3.9825 9 P 0 ;1
L 7.9825 4.0325 7.9825 4.0325 9 P 0 ;1
L 7.9825 4.0825 7.9825 4.0825 9 P 0 ;1
L 7.9825 4.1325 7.9825 4.1325 9 P 0 ;1
L 7.9825 4.1825 7.9825 4.1825 9 P 0 ;1
L 7.9825 4.2325 7.9825 4.2325 9 P 0 ;1
L 7.9825 4.2825 7.9825 4.2825 9 P 0 ;1
L 7.9825 4.3325 7.9825 4.3325 9 P 0 ;1
L 7.9825 4.3825 7.9825 4.3825 9 P 0 ;1
L 7.9825 4.4325 7.9825 4.4325 9 P 0 ;1
L 7.9825 4.4825 7.9825 4.4825 9 P 0 ;1
L 7.9825 4.5325 7.9825 4.5325 9 P 0 ;1
L 7.9825 4.7325 7.9825 4.7325 9 P 0 ;1
L 7.9825 5.1825 7.9825 5.1825 9 P 0 ;1
L 7.9825 5.4825 7.9825 5.4825 9 P 0 ;1
L 7.9825 5.5325 7.9825 5.5325 9 P 0 ;1
L 7.9825 5.5825 7.9825 5.5825 9 P 0 ;1
L 7.9825 5.6325 7.9825 5.6325 9 P 0 ;1
L 7.9825 5.6825 7.9825 5.6825 9 P 0 ;1
L 7.9825 5.7325 7.9825 5.7325 9 P 0 ;1
L 7.9825 5.7825 7.9825 5.7825 9 P 0 ;1
L 7.9825 5.8325 7.9825 5.8325 9 P 0 ;1
L 7.9825 5.8825 7.9825 5.8825 9 P 0 ;1
L 8.0325 0.1325 8.0325 0.1325 9 P 0 ;1
L 8.0325 0.1825 8.0325 0.1825 9 P 0 ;1
L 8.0325 0.2325 8.0325 0.2325 9 P 0 ;1
L 8.0325 0.2825 8.0325 0.2825 9 P 0 ;1
L 8.0325 0.3325 8.0325 0.3325 9 P 0 ;1
L 8.0325 0.3825 8.0325 0.3825 9 P 0 ;1
L 8.0325 0.4325 8.0325 0.4325 9 P 0 ;1
L 8.0325 0.4825 8.0325 0.4825 9 P 0 ;1
L 8.0325 0.5325 8.0325 0.5325 9 P 0 ;1
L 8.0325 0.5825 8.0325 0.5825 9 P 0 ;1
L 8.0325 0.6325 8.0325 0.6325 9 P 0 ;1
L 8.0325 0.6825 8.0325 0.6825 9 P 0 ;1
L 8.0325 0.7325 8.0325 0.7325 9 P 0 ;1
L 8.0325 0.7825 8.0325 0.7825 9 P 0 ;1
L 8.0325 0.8325 8.0325 0.8325 9 P 0 ;1
L 8.0325 0.8825 8.0325 0.8825 9 P 0 ;1
L 8.0325 0.9325 8.0325 0.9325 9 P 0 ;1
L 8.0325 0.9825 8.0325 0.9825 9 P 0 ;1
L 8.0325 1.0325 8.0325 1.0325 9 P 0 ;1
L 8.0325 1.0825 8.0325 1.0825 9 P 0 ;1
L 8.0325 1.1325 8.0325 1.1325 9 P 0 ;1
L 8.0325 1.1825 8.0325 1.1825 9 P 0 ;1
L 8.0325 1.2325 8.0325 1.2325 9 P 0 ;1
L 8.0325 1.2825 8.0325 1.2825 9 P 0 ;1
L 8.0325 1.3325 8.0325 1.3325 9 P 0 ;1
L 8.0325 1.3825 8.0325 1.3825 9 P 0 ;1
L 8.0325 1.4325 8.0325 1.4325 9 P 0 ;1
L 8.0325 1.4825 8.0325 1.4825 9 P 0 ;1
L 8.0325 1.5325 8.0325 1.5325 9 P 0 ;1
L 8.0325 1.5825 8.0325 1.5825 9 P 0 ;1
L 8.0325 1.6325 8.0325 1.6325 9 P 0 ;1
L 8.0325 1.6825 8.0325 1.6825 9 P 0 ;1
L 8.0325 1.7325 8.0325 1.7325 9 P 0 ;1
L 8.0325 1.7825 8.0325 1.7825 9 P 0 ;1
L 8.0325 3.9825 8.0325 3.9825 9 P 0 ;1
L 8.0325 4.0325 8.0325 4.0325 9 P 0 ;1
L 8.0325 4.0825 8.0325 4.0825 9 P 0 ;1
L 8.0325 4.1325 8.0325 4.1325 9 P 0 ;1
L 8.0325 4.1825 8.0325 4.1825 9 P 0 ;1
L 8.0325 4.2325 8.0325 4.2325 9 P 0 ;1
L 8.0325 4.2825 8.0325 4.2825 9 P 0 ;1
L 8.0325 4.3325 8.0325 4.3325 9 P 0 ;1
L 8.0325 4.3825 8.0325 4.3825 9 P 0 ;1
L 8.0325 4.4325 8.0325 4.4325 9 P 0 ;1
L 8.0325 4.4825 8.0325 4.4825 9 P 0 ;1
L 8.0325 4.5325 8.0325 4.5325 9 P 0 ;1
L 8.0325 5.3825 8.0325 5.3825 9 P 0 ;1
L 8.0325 5.4325 8.0325 5.4325 9 P 0 ;1
L 8.0325 5.4825 8.0325 5.4825 9 P 0 ;1
L 8.0325 5.5325 8.0325 5.5325 9 P 0 ;1
L 8.0325 5.5825 8.0325 5.5825 9 P 0 ;1
L 8.0325 5.6325 8.0325 5.6325 9 P 0 ;1
L 8.0325 5.6825 8.0325 5.6825 9 P 0 ;1
L 8.0325 5.7325 8.0325 5.7325 9 P 0 ;1
L 8.0325 5.7825 8.0325 5.7825 9 P 0 ;1
L 8.0325 5.8325 8.0325 5.8325 9 P 0 ;1
L 8.0325 5.8825 8.0325 5.8825 9 P 0 ;1
L 8.0825 0.1325 8.0825 0.1325 9 P 0 ;1
L 8.0825 0.1825 8.0825 0.1825 9 P 0 ;1
L 8.0825 0.2325 8.0825 0.2325 9 P 0 ;1
L 8.0825 0.2825 8.0825 0.2825 9 P 0 ;1
L 8.0825 0.3325 8.0825 0.3325 9 P 0 ;1
L 8.0825 0.3825 8.0825 0.3825 9 P 0 ;1
L 8.0825 0.4325 8.0825 0.4325 9 P 0 ;1
L 8.0825 0.4825 8.0825 0.4825 9 P 0 ;1
L 8.0825 0.5325 8.0825 0.5325 9 P 0 ;1
L 8.0825 0.5825 8.0825 0.5825 9 P 0 ;1
L 8.0825 0.6325 8.0825 0.6325 9 P 0 ;1
L 8.0825 0.6825 8.0825 0.6825 9 P 0 ;1
L 8.0825 0.7325 8.0825 0.7325 9 P 0 ;1
L 8.0825 0.7825 8.0825 0.7825 9 P 0 ;1
L 8.0825 0.8325 8.0825 0.8325 9 P 0 ;1
L 8.0825 0.8825 8.0825 0.8825 9 P 0 ;1
L 8.0825 0.9325 8.0825 0.9325 9 P 0 ;1
L 8.0825 0.9825 8.0825 0.9825 9 P 0 ;1
L 8.0825 1.0325 8.0825 1.0325 9 P 0 ;1
L 8.0825 1.0825 8.0825 1.0825 9 P 0 ;1
L 8.0825 1.1325 8.0825 1.1325 9 P 0 ;1
L 8.0825 1.1825 8.0825 1.1825 9 P 0 ;1
L 8.0825 1.2325 8.0825 1.2325 9 P 0 ;1
L 8.0825 1.2825 8.0825 1.2825 9 P 0 ;1
L 8.0825 1.3325 8.0825 1.3325 9 P 0 ;1
L 8.0825 1.3825 8.0825 1.3825 9 P 0 ;1
L 8.0825 1.6325 8.0825 1.6325 9 P 0 ;1
L 8.0825 1.6825 8.0825 1.6825 9 P 0 ;1
L 8.0825 1.7325 8.0825 1.7325 9 P 0 ;1
L 8.0825 1.7825 8.0825 1.7825 9 P 0 ;1
L 8.0825 3.9825 8.0825 3.9825 9 P 0 ;1
L 8.0825 4.0325 8.0825 4.0325 9 P 0 ;1
L 8.0825 4.0825 8.0825 4.0825 9 P 0 ;1
L 8.0825 4.3825 8.0825 4.3825 9 P 0 ;1
L 8.0825 4.4325 8.0825 4.4325 9 P 0 ;1
L 8.0825 4.4825 8.0825 4.4825 9 P 0 ;1
L 8.0825 4.5325 8.0825 4.5325 9 P 0 ;1
L 8.0825 5.4325 8.0825 5.4325 9 P 0 ;1
L 8.0825 5.4825 8.0825 5.4825 9 P 0 ;1
L 8.0825 5.5325 8.0825 5.5325 9 P 0 ;1
L 8.0825 5.5825 8.0825 5.5825 9 P 0 ;1
L 8.0825 5.6325 8.0825 5.6325 9 P 0 ;1
L 8.0825 5.6825 8.0825 5.6825 9 P 0 ;1
L 8.0825 5.7325 8.0825 5.7325 9 P 0 ;1
L 8.0825 5.7825 8.0825 5.7825 9 P 0 ;1
L 8.0825 5.8325 8.0825 5.8325 9 P 0 ;1
L 8.0825 5.8825 8.0825 5.8825 9 P 0 ;1
L 8.1325 0.1325 8.1325 0.1325 9 P 0 ;1
L 8.1325 0.1825 8.1325 0.1825 9 P 0 ;1
L 8.1325 0.2325 8.1325 0.2325 9 P 0 ;1
L 8.1325 0.2825 8.1325 0.2825 9 P 0 ;1
L 8.1325 0.3325 8.1325 0.3325 9 P 0 ;1
L 8.1325 0.3825 8.1325 0.3825 9 P 0 ;1
L 8.1325 0.4325 8.1325 0.4325 9 P 0 ;1
L 8.1325 0.4825 8.1325 0.4825 9 P 0 ;1
L 8.1325 0.5325 8.1325 0.5325 9 P 0 ;1
L 8.1325 0.5825 8.1325 0.5825 9 P 0 ;1
L 8.1325 0.6325 8.1325 0.6325 9 P 0 ;1
L 8.1325 0.6825 8.1325 0.6825 9 P 0 ;1
L 8.1325 0.7325 8.1325 0.7325 9 P 0 ;1
L 8.1325 0.7825 8.1325 0.7825 9 P 0 ;1
L 8.1325 0.8325 8.1325 0.8325 9 P 0 ;1
L 8.1325 0.8825 8.1325 0.8825 9 P 0 ;1
L 8.1325 0.9325 8.1325 0.9325 9 P 0 ;1
L 8.1325 0.9825 8.1325 0.9825 9 P 0 ;1
L 8.1325 1.0325 8.1325 1.0325 9 P 0 ;1
L 8.1325 1.0825 8.1325 1.0825 9 P 0 ;1
L 8.1325 1.1325 8.1325 1.1325 9 P 0 ;1
L 8.1325 1.1825 8.1325 1.1825 9 P 0 ;1
L 8.1325 1.2325 8.1325 1.2325 9 P 0 ;1
L 8.1325 1.2825 8.1325 1.2825 9 P 0 ;1
L 8.1325 1.3325 8.1325 1.3325 9 P 0 ;1
L 8.1325 1.6825 8.1325 1.6825 9 P 0 ;1
L 8.1325 1.7325 8.1325 1.7325 9 P 0 ;1
L 8.1325 1.7825 8.1325 1.7825 9 P 0 ;1
L 8.1325 3.9825 8.1325 3.9825 9 P 0 ;1
L 8.1325 4.0325 8.1325 4.0325 9 P 0 ;1
L 8.1325 4.4325 8.1325 4.4325 9 P 0 ;1
L 8.1325 4.4825 8.1325 4.4825 9 P 0 ;1
L 8.1325 4.5325 8.1325 4.5325 9 P 0 ;1
L 8.1325 5.4825 8.1325 5.4825 9 P 0 ;1
L 8.1325 5.5325 8.1325 5.5325 9 P 0 ;1
L 8.1325 5.5825 8.1325 5.5825 9 P 0 ;1
L 8.1325 5.6325 8.1325 5.6325 9 P 0 ;1
L 8.1325 5.6825 8.1325 5.6825 9 P 0 ;1
L 8.1325 5.7325 8.1325 5.7325 9 P 0 ;1
L 8.1325 5.7825 8.1325 5.7825 9 P 0 ;1
L 8.1325 5.8325 8.1325 5.8325 9 P 0 ;1
L 8.1325 5.8825 8.1325 5.8825 9 P 0 ;1
L 8.1825 0.1325 8.1825 0.1325 9 P 0 ;1
L 8.1825 0.1825 8.1825 0.1825 9 P 0 ;1
L 8.1825 0.2325 8.1825 0.2325 9 P 0 ;1
L 8.1825 0.2825 8.1825 0.2825 9 P 0 ;1
L 8.1825 0.3325 8.1825 0.3325 9 P 0 ;1
L 8.1825 0.3825 8.1825 0.3825 9 P 0 ;1
L 8.1825 0.4325 8.1825 0.4325 9 P 0 ;1
L 8.1825 0.4825 8.1825 0.4825 9 P 0 ;1
L 8.1825 0.5325 8.1825 0.5325 9 P 0 ;1
L 8.1825 0.5825 8.1825 0.5825 9 P 0 ;1
L 8.1825 0.6325 8.1825 0.6325 9 P 0 ;1
L 8.1825 0.6825 8.1825 0.6825 9 P 0 ;1
L 8.1825 0.7325 8.1825 0.7325 9 P 0 ;1
L 8.1825 0.7825 8.1825 0.7825 9 P 0 ;1
L 8.1825 0.8325 8.1825 0.8325 9 P 0 ;1
L 8.1825 0.8825 8.1825 0.8825 9 P 0 ;1
L 8.1825 0.9325 8.1825 0.9325 9 P 0 ;1
L 8.1825 0.9825 8.1825 0.9825 9 P 0 ;1
L 8.1825 1.0325 8.1825 1.0325 9 P 0 ;1
L 8.1825 1.0825 8.1825 1.0825 9 P 0 ;1
L 8.1825 1.1325 8.1825 1.1325 9 P 0 ;1
L 8.1825 1.1825 8.1825 1.1825 9 P 0 ;1
L 8.1825 1.2325 8.1825 1.2325 9 P 0 ;1
L 8.1825 1.2825 8.1825 1.2825 9 P 0 ;1
L 8.1825 1.3325 8.1825 1.3325 9 P 0 ;1
L 8.1825 1.6825 8.1825 1.6825 9 P 0 ;1
L 8.1825 1.7325 8.1825 1.7325 9 P 0 ;1
L 8.1825 1.7825 8.1825 1.7825 9 P 0 ;1
L 8.1825 3.9825 8.1825 3.9825 9 P 0 ;1
L 8.1825 4.0325 8.1825 4.0325 9 P 0 ;1
L 8.1825 4.4325 8.1825 4.4325 9 P 0 ;1
L 8.1825 4.4825 8.1825 4.4825 9 P 0 ;1
L 8.1825 4.5325 8.1825 4.5325 9 P 0 ;1
L 8.1825 5.2325 8.1825 5.2325 9 P 0 ;1
L 8.1825 5.2825 8.1825 5.2825 9 P 0 ;1
L 8.1825 5.4825 8.1825 5.4825 9 P 0 ;1
L 8.1825 5.5325 8.1825 5.5325 9 P 0 ;1
L 8.1825 5.5825 8.1825 5.5825 9 P 0 ;1
L 8.1825 5.6325 8.1825 5.6325 9 P 0 ;1
L 8.1825 5.6825 8.1825 5.6825 9 P 0 ;1
L 8.1825 5.7325 8.1825 5.7325 9 P 0 ;1
L 8.1825 5.7825 8.1825 5.7825 9 P 0 ;1
L 8.1825 5.8325 8.1825 5.8325 9 P 0 ;1
L 8.1825 5.8825 8.1825 5.8825 9 P 0 ;1
L 8.2325 0.1325 8.2325 0.1325 9 P 0 ;1
L 8.2325 0.1825 8.2325 0.1825 9 P 0 ;1
L 8.2325 0.2325 8.2325 0.2325 9 P 0 ;1
L 8.2325 0.2825 8.2325 0.2825 9 P 0 ;1
L 8.2325 0.3325 8.2325 0.3325 9 P 0 ;1
L 8.2325 0.3825 8.2325 0.3825 9 P 0 ;1
L 8.2325 0.4325 8.2325 0.4325 9 P 0 ;1
L 8.2325 0.4825 8.2325 0.4825 9 P 0 ;1
L 8.2325 0.5325 8.2325 0.5325 9 P 0 ;1
L 8.2325 0.5825 8.2325 0.5825 9 P 0 ;1
L 8.2325 0.6325 8.2325 0.6325 9 P 0 ;1
L 8.2325 0.6825 8.2325 0.6825 9 P 0 ;1
L 8.2325 0.7325 8.2325 0.7325 9 P 0 ;1
L 8.2325 0.7825 8.2325 0.7825 9 P 0 ;1
L 8.2325 0.8325 8.2325 0.8325 9 P 0 ;1
L 8.2325 0.8825 8.2325 0.8825 9 P 0 ;1
L 8.2325 0.9325 8.2325 0.9325 9 P 0 ;1
L 8.2325 0.9825 8.2325 0.9825 9 P 0 ;1
L 8.2325 1.0325 8.2325 1.0325 9 P 0 ;1
L 8.2325 1.0825 8.2325 1.0825 9 P 0 ;1
L 8.2325 1.1325 8.2325 1.1325 9 P 0 ;1
L 8.2325 1.1825 8.2325 1.1825 9 P 0 ;1
L 8.2325 1.2325 8.2325 1.2325 9 P 0 ;1
L 8.2325 1.2825 8.2325 1.2825 9 P 0 ;1
L 8.2325 1.7325 8.2325 1.7325 9 P 0 ;1
L 8.2325 1.7825 8.2325 1.7825 9 P 0 ;1
L 8.2325 3.9825 8.2325 3.9825 9 P 0 ;1
L 8.2325 4.4325 8.2325 4.4325 9 P 0 ;1
L 8.2325 4.4825 8.2325 4.4825 9 P 0 ;1
L 8.2325 4.5325 8.2325 4.5325 9 P 0 ;1
L 8.2325 5.1825 8.2325 5.1825 9 P 0 ;1
L 8.2325 5.2325 8.2325 5.2325 9 P 0 ;1
L 8.2325 5.2825 8.2325 5.2825 9 P 0 ;1
L 8.2325 5.3325 8.2325 5.3325 9 P 0 ;1
L 8.2325 5.3825 8.2325 5.3825 9 P 0 ;1
L 8.2325 5.4325 8.2325 5.4325 9 P 0 ;1
L 8.2325 5.4825 8.2325 5.4825 9 P 0 ;1
L 8.2325 5.5325 8.2325 5.5325 9 P 0 ;1
L 8.2325 5.5825 8.2325 5.5825 9 P 0 ;1
L 8.2325 5.6325 8.2325 5.6325 9 P 0 ;1
L 8.2325 5.6825 8.2325 5.6825 9 P 0 ;1
L 8.2325 5.7325 8.2325 5.7325 9 P 0 ;1
L 8.2325 5.7825 8.2325 5.7825 9 P 0 ;1
L 8.2325 5.8325 8.2325 5.8325 9 P 0 ;1
L 8.2325 5.8825 8.2325 5.8825 9 P 0 ;1
L 8.2825 0.1325 8.2825 0.1325 9 P 0 ;1
L 8.2825 0.1825 8.2825 0.1825 9 P 0 ;1
L 8.2825 0.2325 8.2825 0.2325 9 P 0 ;1
L 8.2825 0.2825 8.2825 0.2825 9 P 0 ;1
L 8.2825 0.3325 8.2825 0.3325 9 P 0 ;1
L 8.2825 0.3825 8.2825 0.3825 9 P 0 ;1
L 8.2825 0.4325 8.2825 0.4325 9 P 0 ;1
L 8.2825 0.4825 8.2825 0.4825 9 P 0 ;1
L 8.2825 0.5325 8.2825 0.5325 9 P 0 ;1
L 8.2825 0.5825 8.2825 0.5825 9 P 0 ;1
L 8.2825 0.6325 8.2825 0.6325 9 P 0 ;1
L 8.2825 0.6825 8.2825 0.6825 9 P 0 ;1
L 8.2825 0.7325 8.2825 0.7325 9 P 0 ;1
L 8.2825 0.7825 8.2825 0.7825 9 P 0 ;1
L 8.2825 0.8325 8.2825 0.8325 9 P 0 ;1
L 8.2825 0.8825 8.2825 0.8825 9 P 0 ;1
L 8.2825 0.9325 8.2825 0.9325 9 P 0 ;1
L 8.2825 0.9825 8.2825 0.9825 9 P 0 ;1
L 8.2825 1.0325 8.2825 1.0325 9 P 0 ;1
L 8.2825 1.0825 8.2825 1.0825 9 P 0 ;1
L 8.2825 1.1325 8.2825 1.1325 9 P 0 ;1
L 8.2825 1.1825 8.2825 1.1825 9 P 0 ;1
L 8.2825 1.2325 8.2825 1.2325 9 P 0 ;1
L 8.2825 1.2825 8.2825 1.2825 9 P 0 ;1
L 8.2825 1.7325 8.2825 1.7325 9 P 0 ;1
L 8.2825 1.7825 8.2825 1.7825 9 P 0 ;1
L 8.2825 3.9825 8.2825 3.9825 9 P 0 ;1
L 8.2825 4.4325 8.2825 4.4325 9 P 0 ;1
L 8.2825 4.4825 8.2825 4.4825 9 P 0 ;1
L 8.2825 4.5325 8.2825 4.5325 9 P 0 ;1
L 8.2825 5.2325 8.2825 5.2325 9 P 0 ;1
L 8.2825 5.2825 8.2825 5.2825 9 P 0 ;1
L 8.2825 5.3325 8.2825 5.3325 9 P 0 ;1
L 8.2825 5.3825 8.2825 5.3825 9 P 0 ;1
L 8.2825 5.4325 8.2825 5.4325 9 P 0 ;1
L 8.2825 5.4825 8.2825 5.4825 9 P 0 ;1
L 8.2825 5.5325 8.2825 5.5325 9 P 0 ;1
L 8.2825 5.5825 8.2825 5.5825 9 P 0 ;1
L 8.2825 5.6325 8.2825 5.6325 9 P 0 ;1
L 8.2825 5.6825 8.2825 5.6825 9 P 0 ;1
L 8.2825 5.7325 8.2825 5.7325 9 P 0 ;1
L 8.2825 5.7825 8.2825 5.7825 9 P 0 ;1
L 8.2825 5.8325 8.2825 5.8325 9 P 0 ;1
L 8.2825 5.8825 8.2825 5.8825 9 P 0 ;1
L 8.3325 0.1325 8.3325 0.1325 9 P 0 ;1
L 8.3325 0.1825 8.3325 0.1825 9 P 0 ;1
L 8.3325 0.2325 8.3325 0.2325 9 P 0 ;1
L 8.3325 0.2825 8.3325 0.2825 9 P 0 ;1
L 8.3325 0.3325 8.3325 0.3325 9 P 0 ;1
L 8.3325 0.3825 8.3325 0.3825 9 P 0 ;1
L 8.3325 0.4325 8.3325 0.4325 9 P 0 ;1
L 8.3325 0.4825 8.3325 0.4825 9 P 0 ;1
L 8.3325 0.5325 8.3325 0.5325 9 P 0 ;1
L 8.3325 0.5825 8.3325 0.5825 9 P 0 ;1
L 8.3325 0.6325 8.3325 0.6325 9 P 0 ;1
L 8.3325 0.6825 8.3325 0.6825 9 P 0 ;1
L 8.3325 0.7325 8.3325 0.7325 9 P 0 ;1
L 8.3325 0.7825 8.3325 0.7825 9 P 0 ;1
L 8.3325 0.8325 8.3325 0.8325 9 P 0 ;1
L 8.3325 0.8825 8.3325 0.8825 9 P 0 ;1
L 8.3325 0.9325 8.3325 0.9325 9 P 0 ;1
L 8.3325 0.9825 8.3325 0.9825 9 P 0 ;1
L 8.3325 1.0325 8.3325 1.0325 9 P 0 ;1
L 8.3325 1.0825 8.3325 1.0825 9 P 0 ;1
L 8.3325 1.1325 8.3325 1.1325 9 P 0 ;1
L 8.3325 1.1825 8.3325 1.1825 9 P 0 ;1
L 8.3325 1.2325 8.3325 1.2325 9 P 0 ;1
L 8.3325 1.2825 8.3325 1.2825 9 P 0 ;1
L 8.3325 1.3325 8.3325 1.3325 9 P 0 ;1
L 8.3325 1.6825 8.3325 1.6825 9 P 0 ;1
L 8.3325 1.7325 8.3325 1.7325 9 P 0 ;1
L 8.3325 1.7825 8.3325 1.7825 9 P 0 ;1
L 8.3325 3.9825 8.3325 3.9825 9 P 0 ;1
L 8.3325 4.0325 8.3325 4.0325 9 P 0 ;1
L 8.3325 4.4325 8.3325 4.4325 9 P 0 ;1
L 8.3325 4.4825 8.3325 4.4825 9 P 0 ;1
L 8.3325 4.5325 8.3325 4.5325 9 P 0 ;1
L 8.3325 5.2325 8.3325 5.2325 9 P 0 ;1
L 8.3325 5.2825 8.3325 5.2825 9 P 0 ;1
L 8.3325 5.3325 8.3325 5.3325 9 P 0 ;1
L 8.3325 5.3825 8.3325 5.3825 9 P 0 ;1
L 8.3325 5.4325 8.3325 5.4325 9 P 0 ;1
L 8.3325 5.4825 8.3325 5.4825 9 P 0 ;1
L 8.3325 5.5325 8.3325 5.5325 9 P 0 ;1
L 8.3325 5.5825 8.3325 5.5825 9 P 0 ;1
L 8.3325 5.6325 8.3325 5.6325 9 P 0 ;1
L 8.3325 5.6825 8.3325 5.6825 9 P 0 ;1
L 8.3325 5.7325 8.3325 5.7325 9 P 0 ;1
L 8.3325 5.7825 8.3325 5.7825 9 P 0 ;1
L 8.3325 5.8325 8.3325 5.8325 9 P 0 ;1
L 8.3325 5.8825 8.3325 5.8825 9 P 0 ;1
L 8.3825 0.1325 8.3825 0.1325 9 P 0 ;1
L 8.3825 0.1825 8.3825 0.1825 9 P 0 ;1
L 8.3825 0.2325 8.3825 0.2325 9 P 0 ;1
L 8.3825 0.2825 8.3825 0.2825 9 P 0 ;1
L 8.3825 0.3325 8.3825 0.3325 9 P 0 ;1
L 8.3825 0.3825 8.3825 0.3825 9 P 0 ;1
L 8.3825 0.4325 8.3825 0.4325 9 P 0 ;1
L 8.3825 0.4825 8.3825 0.4825 9 P 0 ;1
L 8.3825 0.5325 8.3825 0.5325 9 P 0 ;1
L 8.3825 0.5825 8.3825 0.5825 9 P 0 ;1
L 8.3825 0.6325 8.3825 0.6325 9 P 0 ;1
L 8.3825 0.6825 8.3825 0.6825 9 P 0 ;1
L 8.3825 0.7325 8.3825 0.7325 9 P 0 ;1
L 8.3825 0.7825 8.3825 0.7825 9 P 0 ;1
L 8.3825 0.8325 8.3825 0.8325 9 P 0 ;1
L 8.3825 0.8825 8.3825 0.8825 9 P 0 ;1
L 8.3825 0.9325 8.3825 0.9325 9 P 0 ;1
L 8.3825 0.9825 8.3825 0.9825 9 P 0 ;1
L 8.3825 1.0325 8.3825 1.0325 9 P 0 ;1
L 8.3825 1.0825 8.3825 1.0825 9 P 0 ;1
L 8.3825 1.1325 8.3825 1.1325 9 P 0 ;1
L 8.3825 1.1825 8.3825 1.1825 9 P 0 ;1
L 8.3825 1.2325 8.3825 1.2325 9 P 0 ;1
L 8.3825 1.2825 8.3825 1.2825 9 P 0 ;1
L 8.3825 1.3325 8.3825 1.3325 9 P 0 ;1
L 8.3825 1.6825 8.3825 1.6825 9 P 0 ;1
L 8.3825 1.7325 8.3825 1.7325 9 P 0 ;1
L 8.3825 1.7825 8.3825 1.7825 9 P 0 ;1
L 8.3825 3.9825 8.3825 3.9825 9 P 0 ;1
L 8.3825 4.0325 8.3825 4.0325 9 P 0 ;1
L 8.3825 4.4325 8.3825 4.4325 9 P 0 ;1
L 8.3825 4.4825 8.3825 4.4825 9 P 0 ;1
L 8.3825 4.5325 8.3825 4.5325 9 P 0 ;1
L 8.3825 4.5825 8.3825 4.5825 9 P 0 ;1
L 8.3825 5.2325 8.3825 5.2325 9 P 0 ;1
L 8.3825 5.2825 8.3825 5.2825 9 P 0 ;1
L 8.3825 5.3325 8.3825 5.3325 9 P 0 ;1
L 8.3825 5.3825 8.3825 5.3825 9 P 0 ;1
L 8.3825 5.4325 8.3825 5.4325 9 P 0 ;1
L 8.3825 5.4825 8.3825 5.4825 9 P 0 ;1
L 8.3825 5.5325 8.3825 5.5325 9 P 0 ;1
L 8.3825 5.5825 8.3825 5.5825 9 P 0 ;1
L 8.3825 5.6325 8.3825 5.6325 9 P 0 ;1
L 8.3825 5.6825 8.3825 5.6825 9 P 0 ;1
L 8.3825 5.7325 8.3825 5.7325 9 P 0 ;1
L 8.3825 5.7825 8.3825 5.7825 9 P 0 ;1
L 8.3825 5.8325 8.3825 5.8325 9 P 0 ;1
L 8.3825 5.8825 8.3825 5.8825 9 P 0 ;1
L 8.4325 0.1325 8.4325 0.1325 9 P 0 ;1
L 8.4325 0.1825 8.4325 0.1825 9 P 0 ;1
L 8.4325 0.2325 8.4325 0.2325 9 P 0 ;1
L 8.4325 0.2825 8.4325 0.2825 9 P 0 ;1
L 8.4325 0.3325 8.4325 0.3325 9 P 0 ;1
L 8.4325 0.3825 8.4325 0.3825 9 P 0 ;1
L 8.4325 0.4325 8.4325 0.4325 9 P 0 ;1
L 8.4325 0.4825 8.4325 0.4825 9 P 0 ;1
L 8.4325 0.5325 8.4325 0.5325 9 P 0 ;1
L 8.4325 0.5825 8.4325 0.5825 9 P 0 ;1
L 8.4325 0.6325 8.4325 0.6325 9 P 0 ;1
L 8.4325 0.6825 8.4325 0.6825 9 P 0 ;1
L 8.4325 0.7325 8.4325 0.7325 9 P 0 ;1
L 8.4325 0.7825 8.4325 0.7825 9 P 0 ;1
L 8.4325 0.8325 8.4325 0.8325 9 P 0 ;1
L 8.4325 0.8825 8.4325 0.8825 9 P 0 ;1
L 8.4325 0.9325 8.4325 0.9325 9 P 0 ;1
L 8.4325 0.9825 8.4325 0.9825 9 P 0 ;1
L 8.4325 1.0325 8.4325 1.0325 9 P 0 ;1
L 8.4325 1.0825 8.4325 1.0825 9 P 0 ;1
L 8.4325 1.1325 8.4325 1.1325 9 P 0 ;1
L 8.4325 1.1825 8.4325 1.1825 9 P 0 ;1
L 8.4325 1.2325 8.4325 1.2325 9 P 0 ;1
L 8.4325 1.2825 8.4325 1.2825 9 P 0 ;1
L 8.4325 1.3325 8.4325 1.3325 9 P 0 ;1
L 8.4325 1.3825 8.4325 1.3825 9 P 0 ;1
L 8.4325 1.4325 8.4325 1.4325 9 P 0 ;1
L 8.4325 1.5825 8.4325 1.5825 9 P 0 ;1
L 8.4325 1.6325 8.4325 1.6325 9 P 0 ;1
L 8.4325 1.6825 8.4325 1.6825 9 P 0 ;1
L 8.4325 1.7325 8.4325 1.7325 9 P 0 ;1
L 8.4325 1.7825 8.4325 1.7825 9 P 0 ;1
L 8.4325 3.9825 8.4325 3.9825 9 P 0 ;1
L 8.4325 4.0325 8.4325 4.0325 9 P 0 ;1
L 8.4325 4.0825 8.4325 4.0825 9 P 0 ;1
L 8.4325 4.1325 8.4325 4.1325 9 P 0 ;1
L 8.4325 4.3325 8.4325 4.3325 9 P 0 ;1
L 8.4325 4.3825 8.4325 4.3825 9 P 0 ;1
L 8.4325 4.4325 8.4325 4.4325 9 P 0 ;1
L 8.4325 4.4825 8.4325 4.4825 9 P 0 ;1
L 8.4325 4.5325 8.4325 4.5325 9 P 0 ;1
L 8.4325 4.5825 8.4325 4.5825 9 P 0 ;1
L 8.4325 5.2325 8.4325 5.2325 9 P 0 ;1
L 8.4325 5.2825 8.4325 5.2825 9 P 0 ;1
L 8.4325 5.3325 8.4325 5.3325 9 P 0 ;1
L 8.4325 5.3825 8.4325 5.3825 9 P 0 ;1
L 8.4325 5.4325 8.4325 5.4325 9 P 0 ;1
L 8.4325 5.4825 8.4325 5.4825 9 P 0 ;1
L 8.4325 5.5325 8.4325 5.5325 9 P 0 ;1
L 8.4325 5.5825 8.4325 5.5825 9 P 0 ;1
L 8.4325 5.6325 8.4325 5.6325 9 P 0 ;1
L 8.4325 5.6825 8.4325 5.6825 9 P 0 ;1
L 8.4325 5.7325 8.4325 5.7325 9 P 0 ;1
L 8.4325 5.7825 8.4325 5.7825 9 P 0 ;1
L 8.4325 5.8325 8.4325 5.8325 9 P 0 ;1
L 8.4325 5.8825 8.4325 5.8825 9 P 0 ;1
L 8.4825 0.1325 8.4825 0.1325 9 P 0 ;1
L 8.4825 0.1825 8.4825 0.1825 9 P 0 ;1
L 8.4825 0.2325 8.4825 0.2325 9 P 0 ;1
L 8.4825 0.2825 8.4825 0.2825 9 P 0 ;1
L 8.4825 0.3325 8.4825 0.3325 9 P 0 ;1
L 8.4825 0.3825 8.4825 0.3825 9 P 0 ;1
L 8.4825 0.4325 8.4825 0.4325 9 P 0 ;1
L 8.4825 0.4825 8.4825 0.4825 9 P 0 ;1
L 8.4825 0.5325 8.4825 0.5325 9 P 0 ;1
L 8.4825 0.5825 8.4825 0.5825 9 P 0 ;1
L 8.4825 0.6325 8.4825 0.6325 9 P 0 ;1
L 8.4825 0.6825 8.4825 0.6825 9 P 0 ;1
L 8.4825 0.7325 8.4825 0.7325 9 P 0 ;1
L 8.4825 0.7825 8.4825 0.7825 9 P 0 ;1
L 8.4825 0.8325 8.4825 0.8325 9 P 0 ;1
L 8.4825 0.8825 8.4825 0.8825 9 P 0 ;1
L 8.4825 0.9325 8.4825 0.9325 9 P 0 ;1
L 8.4825 0.9825 8.4825 0.9825 9 P 0 ;1
L 8.4825 1.0325 8.4825 1.0325 9 P 0 ;1
L 8.4825 1.0825 8.4825 1.0825 9 P 0 ;1
L 8.4825 1.1325 8.4825 1.1325 9 P 0 ;1
L 8.4825 1.1825 8.4825 1.1825 9 P 0 ;1
L 8.4825 1.2325 8.4825 1.2325 9 P 0 ;1
L 8.4825 1.2825 8.4825 1.2825 9 P 0 ;1
L 8.4825 1.3325 8.4825 1.3325 9 P 0 ;1
L 8.4825 1.3825 8.4825 1.3825 9 P 0 ;1
L 8.4825 1.4325 8.4825 1.4325 9 P 0 ;1
L 8.4825 1.4825 8.4825 1.4825 9 P 0 ;1
L 8.4825 1.5325 8.4825 1.5325 9 P 0 ;1
L 8.4825 1.5825 8.4825 1.5825 9 P 0 ;1
L 8.4825 1.6325 8.4825 1.6325 9 P 0 ;1
L 8.4825 1.6825 8.4825 1.6825 9 P 0 ;1
L 8.4825 1.7325 8.4825 1.7325 9 P 0 ;1
L 8.4825 1.7825 8.4825 1.7825 9 P 0 ;1
L 8.4825 3.9825 8.4825 3.9825 9 P 0 ;1
L 8.4825 4.0325 8.4825 4.0325 9 P 0 ;1
L 8.4825 4.0825 8.4825 4.0825 9 P 0 ;1
L 8.4825 4.1325 8.4825 4.1325 9 P 0 ;1
L 8.4825 4.1825 8.4825 4.1825 9 P 0 ;1
L 8.4825 4.2325 8.4825 4.2325 9 P 0 ;1
L 8.4825 4.2825 8.4825 4.2825 9 P 0 ;1
L 8.4825 4.3325 8.4825 4.3325 9 P 0 ;1
L 8.4825 4.3825 8.4825 4.3825 9 P 0 ;1
L 8.4825 4.4325 8.4825 4.4325 9 P 0 ;1
L 8.4825 4.4825 8.4825 4.4825 9 P 0 ;1
L 8.4825 4.5325 8.4825 4.5325 9 P 0 ;1
L 8.4825 4.5825 8.4825 4.5825 9 P 0 ;1
L 8.4825 4.6325 8.4825 4.6325 9 P 0 ;1
L 8.4825 5.2325 8.4825 5.2325 9 P 0 ;1
L 8.4825 5.2825 8.4825 5.2825 9 P 0 ;1
L 8.4825 5.3325 8.4825 5.3325 9 P 0 ;1
L 8.4825 5.3825 8.4825 5.3825 9 P 0 ;1
L 8.4825 5.4325 8.4825 5.4325 9 P 0 ;1
L 8.4825 5.4825 8.4825 5.4825 9 P 0 ;1
L 8.4825 5.5325 8.4825 5.5325 9 P 0 ;1
L 8.4825 5.5825 8.4825 5.5825 9 P 0 ;1
L 8.4825 5.6325 8.4825 5.6325 9 P 0 ;1
L 8.4825 5.6825 8.4825 5.6825 9 P 0 ;1
L 8.4825 5.7325 8.4825 5.7325 9 P 0 ;1
L 8.4825 5.7825 8.4825 5.7825 9 P 0 ;1
L 8.4825 5.8325 8.4825 5.8325 9 P 0 ;1
L 8.4825 5.8825 8.4825 5.8825 9 P 0 ;1
L 8.5325 0.1325 8.5325 0.1325 9 P 0 ;1
L 8.5325 0.1825 8.5325 0.1825 9 P 0 ;1
L 8.5325 0.2325 8.5325 0.2325 9 P 0 ;1
L 8.5325 0.2825 8.5325 0.2825 9 P 0 ;1
L 8.5325 0.3325 8.5325 0.3325 9 P 0 ;1
L 8.5325 0.3825 8.5325 0.3825 9 P 0 ;1
L 8.5325 0.4325 8.5325 0.4325 9 P 0 ;1
L 8.5325 0.4825 8.5325 0.4825 9 P 0 ;1
L 8.5325 0.5325 8.5325 0.5325 9 P 0 ;1
L 8.5325 0.5825 8.5325 0.5825 9 P 0 ;1
L 8.5325 0.6325 8.5325 0.6325 9 P 0 ;1
L 8.5325 0.6825 8.5325 0.6825 9 P 0 ;1
L 8.5325 0.7325 8.5325 0.7325 9 P 0 ;1
L 8.5325 0.7825 8.5325 0.7825 9 P 0 ;1
L 8.5325 0.8325 8.5325 0.8325 9 P 0 ;1
L 8.5325 0.8825 8.5325 0.8825 9 P 0 ;1
L 8.5325 0.9325 8.5325 0.9325 9 P 0 ;1
L 8.5325 0.9825 8.5325 0.9825 9 P 0 ;1
L 8.5325 1.0325 8.5325 1.0325 9 P 0 ;1
L 8.5325 1.0825 8.5325 1.0825 9 P 0 ;1
L 8.5325 1.1325 8.5325 1.1325 9 P 0 ;1
L 8.5325 1.1825 8.5325 1.1825 9 P 0 ;1
L 8.5325 1.2325 8.5325 1.2325 9 P 0 ;1
L 8.5325 1.2825 8.5325 1.2825 9 P 0 ;1
L 8.5325 1.3325 8.5325 1.3325 9 P 0 ;1
L 8.5325 1.3825 8.5325 1.3825 9 P 0 ;1
L 8.5325 1.4325 8.5325 1.4325 9 P 0 ;1
L 8.5325 1.4825 8.5325 1.4825 9 P 0 ;1
L 8.5325 1.5325 8.5325 1.5325 9 P 0 ;1
L 8.5325 1.5825 8.5325 1.5825 9 P 0 ;1
L 8.5325 1.6325 8.5325 1.6325 9 P 0 ;1
L 8.5325 1.6825 8.5325 1.6825 9 P 0 ;1
L 8.5325 1.7325 8.5325 1.7325 9 P 0 ;1
L 8.5325 1.7825 8.5325 1.7825 9 P 0 ;1
L 8.5325 3.9825 8.5325 3.9825 9 P 0 ;1
L 8.5325 4.0325 8.5325 4.0325 9 P 0 ;1
L 8.5325 4.0825 8.5325 4.0825 9 P 0 ;1
L 8.5325 4.1325 8.5325 4.1325 9 P 0 ;1
L 8.5325 4.1825 8.5325 4.1825 9 P 0 ;1
L 8.5325 4.2325 8.5325 4.2325 9 P 0 ;1
L 8.5325 4.2825 8.5325 4.2825 9 P 0 ;1
L 8.5325 4.3325 8.5325 4.3325 9 P 0 ;1
L 8.5325 4.3825 8.5325 4.3825 9 P 0 ;1
L 8.5325 4.4325 8.5325 4.4325 9 P 0 ;1
L 8.5325 4.4825 8.5325 4.4825 9 P 0 ;1
L 8.5325 4.5325 8.5325 4.5325 9 P 0 ;1
L 8.5325 4.5825 8.5325 4.5825 9 P 0 ;1
L 8.5325 4.6325 8.5325 4.6325 9 P 0 ;1
L 8.5325 4.6825 8.5325 4.6825 9 P 0 ;1
L 8.5325 4.8825 8.5325 4.8825 9 P 0 ;1
L 8.5325 4.9325 8.5325 4.9325 9 P 0 ;1
L 8.5325 4.9825 8.5325 4.9825 9 P 0 ;1
L 8.5325 5.0325 8.5325 5.0325 9 P 0 ;1
L 8.5325 5.0825 8.5325 5.0825 9 P 0 ;1
L 8.5325 5.1325 8.5325 5.1325 9 P 0 ;1
L 8.5325 5.1825 8.5325 5.1825 9 P 0 ;1
L 8.5325 5.2325 8.5325 5.2325 9 P 0 ;1
L 8.5325 5.2825 8.5325 5.2825 9 P 0 ;1
L 8.5325 5.3325 8.5325 5.3325 9 P 0 ;1
L 8.5325 5.3825 8.5325 5.3825 9 P 0 ;1
L 8.5325 5.4325 8.5325 5.4325 9 P 0 ;1
L 8.5325 5.4825 8.5325 5.4825 9 P 0 ;1
L 8.5325 5.5325 8.5325 5.5325 9 P 0 ;1
L 8.5325 5.5825 8.5325 5.5825 9 P 0 ;1
L 8.5325 5.6325 8.5325 5.6325 9 P 0 ;1
L 8.5325 5.6825 8.5325 5.6825 9 P 0 ;1
L 8.5325 5.7325 8.5325 5.7325 9 P 0 ;1
L 8.5325 5.7825 8.5325 5.7825 9 P 0 ;1
L 8.5325 5.8325 8.5325 5.8325 9 P 0 ;1
L 8.5325 5.8825 8.5325 5.8825 9 P 0 ;1
L 8.5825 0.1325 8.5825 0.1325 9 P 0 ;1
L 8.5825 0.1825 8.5825 0.1825 9 P 0 ;1
L 8.5825 0.2325 8.5825 0.2325 9 P 0 ;1
L 8.5825 0.2825 8.5825 0.2825 9 P 0 ;1
L 8.5825 0.3325 8.5825 0.3325 9 P 0 ;1
L 8.5825 0.3825 8.5825 0.3825 9 P 0 ;1
L 8.5825 0.4325 8.5825 0.4325 9 P 0 ;1
L 8.5825 0.4825 8.5825 0.4825 9 P 0 ;1
L 8.5825 0.5325 8.5825 0.5325 9 P 0 ;1
L 8.5825 0.5825 8.5825 0.5825 9 P 0 ;1
L 8.5825 0.6325 8.5825 0.6325 9 P 0 ;1
L 8.5825 0.6825 8.5825 0.6825 9 P 0 ;1
L 8.5825 0.7325 8.5825 0.7325 9 P 0 ;1
L 8.5825 0.7825 8.5825 0.7825 9 P 0 ;1
L 8.5825 0.8325 8.5825 0.8325 9 P 0 ;1
L 8.5825 0.8825 8.5825 0.8825 9 P 0 ;1
L 8.5825 0.9325 8.5825 0.9325 9 P 0 ;1
L 8.5825 0.9825 8.5825 0.9825 9 P 0 ;1
L 8.5825 1.0325 8.5825 1.0325 9 P 0 ;1
L 8.5825 1.0825 8.5825 1.0825 9 P 0 ;1
L 8.5825 1.1325 8.5825 1.1325 9 P 0 ;1
L 8.5825 1.1825 8.5825 1.1825 9 P 0 ;1
L 8.5825 1.2325 8.5825 1.2325 9 P 0 ;1
L 8.5825 1.2825 8.5825 1.2825 9 P 0 ;1
L 8.5825 1.3325 8.5825 1.3325 9 P 0 ;1
L 8.5825 1.3825 8.5825 1.3825 9 P 0 ;1
L 8.5825 1.4325 8.5825 1.4325 9 P 0 ;1
L 8.5825 1.4825 8.5825 1.4825 9 P 0 ;1
L 8.5825 1.5325 8.5825 1.5325 9 P 0 ;1
L 8.5825 1.5825 8.5825 1.5825 9 P 0 ;1
L 8.5825 1.6325 8.5825 1.6325 9 P 0 ;1
L 8.5825 1.6825 8.5825 1.6825 9 P 0 ;1
L 8.5825 1.7325 8.5825 1.7325 9 P 0 ;1
L 8.5825 1.7825 8.5825 1.7825 9 P 0 ;1
L 8.5825 1.8325 8.5825 1.8325 9 P 0 ;1
L 8.5825 1.8825 8.5825 1.8825 9 P 0 ;1
L 8.5825 1.9325 8.5825 1.9325 9 P 0 ;1
L 8.5825 1.9825 8.5825 1.9825 9 P 0 ;1
L 8.5825 2.0325 8.5825 2.0325 9 P 0 ;1
L 8.5825 2.0825 8.5825 2.0825 9 P 0 ;1
L 8.5825 2.1325 8.5825 2.1325 9 P 0 ;1
L 8.5825 2.1825 8.5825 2.1825 9 P 0 ;1
L 8.5825 2.2325 8.5825 2.2325 9 P 0 ;1
L 8.5825 2.2825 8.5825 2.2825 9 P 0 ;1
L 8.5825 2.3325 8.5825 2.3325 9 P 0 ;1
L 8.5825 2.3825 8.5825 2.3825 9 P 0 ;1
L 8.5825 2.4325 8.5825 2.4325 9 P 0 ;1
L 8.5825 2.4825 8.5825 2.4825 9 P 0 ;1
L 8.5825 2.5325 8.5825 2.5325 9 P 0 ;1
L 8.5825 2.5825 8.5825 2.5825 9 P 0 ;1
L 8.5825 2.6325 8.5825 2.6325 9 P 0 ;1
L 8.5825 2.6825 8.5825 2.6825 9 P 0 ;1
L 8.5825 2.7325 8.5825 2.7325 9 P 0 ;1
L 8.5825 2.7825 8.5825 2.7825 9 P 0 ;1
L 8.5825 2.8325 8.5825 2.8325 9 P 0 ;1
L 8.5825 2.8825 8.5825 2.8825 9 P 0 ;1
L 8.5825 2.9325 8.5825 2.9325 9 P 0 ;1
L 8.5825 2.9825 8.5825 2.9825 9 P 0 ;1
L 8.5825 3.0325 8.5825 3.0325 9 P 0 ;1
L 8.5825 3.0825 8.5825 3.0825 9 P 0 ;1
L 8.5825 3.1325 8.5825 3.1325 9 P 0 ;1
L 8.5825 3.1825 8.5825 3.1825 9 P 0 ;1
L 8.5825 3.2325 8.5825 3.2325 9 P 0 ;1
L 8.5825 3.2825 8.5825 3.2825 9 P 0 ;1
L 8.5825 3.3325 8.5825 3.3325 9 P 0 ;1
L 8.5825 3.3825 8.5825 3.3825 9 P 0 ;1
L 8.5825 3.4325 8.5825 3.4325 9 P 0 ;1
L 8.5825 3.4825 8.5825 3.4825 9 P 0 ;1
L 8.5825 3.5325 8.5825 3.5325 9 P 0 ;1
L 8.5825 3.5825 8.5825 3.5825 9 P 0 ;1
L 8.5825 3.6325 8.5825 3.6325 9 P 0 ;1
L 8.5825 3.6825 8.5825 3.6825 9 P 0 ;1
L 8.5825 3.7325 8.5825 3.7325 9 P 0 ;1
L 8.5825 3.7825 8.5825 3.7825 9 P 0 ;1
L 8.5825 3.8325 8.5825 3.8325 9 P 0 ;1
L 8.5825 3.8825 8.5825 3.8825 9 P 0 ;1
L 8.5825 3.9325 8.5825 3.9325 9 P 0 ;1
L 8.5825 3.9825 8.5825 3.9825 9 P 0 ;1
L 8.5825 4.0325 8.5825 4.0325 9 P 0 ;1
L 8.5825 4.0825 8.5825 4.0825 9 P 0 ;1
L 8.5825 4.1325 8.5825 4.1325 9 P 0 ;1
L 8.5825 4.1825 8.5825 4.1825 9 P 0 ;1
L 8.5825 4.2325 8.5825 4.2325 9 P 0 ;1
L 8.5825 4.2825 8.5825 4.2825 9 P 0 ;1
L 8.5825 4.3325 8.5825 4.3325 9 P 0 ;1
L 8.5825 4.3825 8.5825 4.3825 9 P 0 ;1
L 8.5825 4.4325 8.5825 4.4325 9 P 0 ;1
L 8.5825 4.4825 8.5825 4.4825 9 P 0 ;1
L 8.5825 4.5325 8.5825 4.5325 9 P 0 ;1
L 8.5825 4.5825 8.5825 4.5825 9 P 0 ;1
L 8.5825 4.6325 8.5825 4.6325 9 P 0 ;1
L 8.5825 4.6825 8.5825 4.6825 9 P 0 ;1
L 8.5825 4.7325 8.5825 4.7325 9 P 0 ;1
L 8.5825 4.7825 8.5825 4.7825 9 P 0 ;1
L 8.5825 4.8325 8.5825 4.8325 9 P 0 ;1
L 8.5825 4.8825 8.5825 4.8825 9 P 0 ;1
L 8.5825 4.9325 8.5825 4.9325 9 P 0 ;1
L 8.5825 4.9825 8.5825 4.9825 9 P 0 ;1
L 8.5825 5.0325 8.5825 5.0325 9 P 0 ;1
L 8.5825 5.0825 8.5825 5.0825 9 P 0 ;1
L 8.5825 5.1325 8.5825 5.1325 9 P 0 ;1
L 8.5825 5.1825 8.5825 5.1825 9 P 0 ;1
L 8.5825 5.2325 8.5825 5.2325 9 P 0 ;1
L 8.5825 5.2825 8.5825 5.2825 9 P 0 ;1
L 8.5825 5.3325 8.5825 5.3325 9 P 0 ;1
L 8.5825 5.3825 8.5825 5.3825 9 P 0 ;1
L 8.5825 5.4325 8.5825 5.4325 9 P 0 ;1
L 8.5825 5.4825 8.5825 5.4825 9 P 0 ;1
L 8.5825 5.5325 8.5825 5.5325 9 P 0 ;1
L 8.5825 5.5825 8.5825 5.5825 9 P 0 ;1
L 8.5825 5.6325 8.5825 5.6325 9 P 0 ;1
L 8.5825 5.6825 8.5825 5.6825 9 P 0 ;1
L 8.5825 5.7325 8.5825 5.7325 9 P 0 ;1
L 8.5825 5.7825 8.5825 5.7825 9 P 0 ;1
L 8.5825 5.8325 8.5825 5.8325 9 P 0 ;1
L 8.5825 5.8825 8.5825 5.8825 9 P 0 ;1
L 8.6325 0.1325 8.6325 0.1325 9 P 0 ;1
L 8.6325 0.1825 8.6325 0.1825 9 P 0 ;1
L 8.6325 0.2325 8.6325 0.2325 9 P 0 ;1
L 8.6325 0.2825 8.6325 0.2825 9 P 0 ;1
L 8.6325 0.3325 8.6325 0.3325 9 P 0 ;1
L 8.6325 0.3825 8.6325 0.3825 9 P 0 ;1
L 8.6325 0.4325 8.6325 0.4325 9 P 0 ;1
L 8.6325 0.4825 8.6325 0.4825 9 P 0 ;1
L 8.6325 0.5325 8.6325 0.5325 9 P 0 ;1
L 8.6325 0.5825 8.6325 0.5825 9 P 0 ;1
L 8.6325 0.6325 8.6325 0.6325 9 P 0 ;1
L 8.6325 0.6825 8.6325 0.6825 9 P 0 ;1
L 8.6325 0.7325 8.6325 0.7325 9 P 0 ;1
L 8.6325 0.7825 8.6325 0.7825 9 P 0 ;1
L 8.6325 0.8325 8.6325 0.8325 9 P 0 ;1
L 8.6325 0.8825 8.6325 0.8825 9 P 0 ;1
L 8.6325 0.9325 8.6325 0.9325 9 P 0 ;1
L 8.6325 0.9825 8.6325 0.9825 9 P 0 ;1
L 8.6325 1.0325 8.6325 1.0325 9 P 0 ;1
L 8.6325 1.0825 8.6325 1.0825 9 P 0 ;1
L 8.6325 1.1325 8.6325 1.1325 9 P 0 ;1
L 8.6325 1.1825 8.6325 1.1825 9 P 0 ;1
L 8.6325 1.2325 8.6325 1.2325 9 P 0 ;1
L 8.6325 1.2825 8.6325 1.2825 9 P 0 ;1
L 8.6325 1.3325 8.6325 1.3325 9 P 0 ;1
L 8.6325 1.3825 8.6325 1.3825 9 P 0 ;1
L 8.6325 1.4325 8.6325 1.4325 9 P 0 ;1
L 8.6325 1.4825 8.6325 1.4825 9 P 0 ;1
L 8.6325 1.5325 8.6325 1.5325 9 P 0 ;1
L 8.6325 1.5825 8.6325 1.5825 9 P 0 ;1
L 8.6325 1.6325 8.6325 1.6325 9 P 0 ;1
L 8.6325 1.6825 8.6325 1.6825 9 P 0 ;1
L 8.6325 1.7325 8.6325 1.7325 9 P 0 ;1
L 8.6325 1.7825 8.6325 1.7825 9 P 0 ;1
L 8.6325 1.8325 8.6325 1.8325 9 P 0 ;1
L 8.6325 1.8825 8.6325 1.8825 9 P 0 ;1
L 8.6325 1.9325 8.6325 1.9325 9 P 0 ;1
L 8.6325 1.9825 8.6325 1.9825 9 P 0 ;1
L 8.6325 2.0325 8.6325 2.0325 9 P 0 ;1
L 8.6325 2.0825 8.6325 2.0825 9 P 0 ;1
L 8.6325 2.1325 8.6325 2.1325 9 P 0 ;1
L 8.6325 2.1825 8.6325 2.1825 9 P 0 ;1
L 8.6325 2.2325 8.6325 2.2325 9 P 0 ;1
L 8.6325 2.2825 8.6325 2.2825 9 P 0 ;1
L 8.6325 2.3325 8.6325 2.3325 9 P 0 ;1
L 8.6325 2.3825 8.6325 2.3825 9 P 0 ;1
L 8.6325 2.4325 8.6325 2.4325 9 P 0 ;1
L 8.6325 2.4825 8.6325 2.4825 9 P 0 ;1
L 8.6325 2.5325 8.6325 2.5325 9 P 0 ;1
L 8.6325 2.5825 8.6325 2.5825 9 P 0 ;1
L 8.6325 2.6325 8.6325 2.6325 9 P 0 ;1
L 8.6325 2.6825 8.6325 2.6825 9 P 0 ;1
L 8.6325 2.7325 8.6325 2.7325 9 P 0 ;1
L 8.6325 2.7825 8.6325 2.7825 9 P 0 ;1
L 8.6325 2.8325 8.6325 2.8325 9 P 0 ;1
L 8.6325 2.8825 8.6325 2.8825 9 P 0 ;1
L 8.6325 2.9325 8.6325 2.9325 9 P 0 ;1
L 8.6325 2.9825 8.6325 2.9825 9 P 0 ;1
L 8.6325 3.0325 8.6325 3.0325 9 P 0 ;1
L 8.6325 3.0825 8.6325 3.0825 9 P 0 ;1
L 8.6325 3.1325 8.6325 3.1325 9 P 0 ;1
L 8.6325 3.1825 8.6325 3.1825 9 P 0 ;1
L 8.6325 3.2325 8.6325 3.2325 9 P 0 ;1
L 8.6325 3.2825 8.6325 3.2825 9 P 0 ;1
L 8.6325 3.3325 8.6325 3.3325 9 P 0 ;1
L 8.6325 3.3825 8.6325 3.3825 9 P 0 ;1
L 8.6325 3.4325 8.6325 3.4325 9 P 0 ;1
L 8.6325 3.4825 8.6325 3.4825 9 P 0 ;1
L 8.6325 3.5325 8.6325 3.5325 9 P 0 ;1
L 8.6325 3.5825 8.6325 3.5825 9 P 0 ;1
L 8.6325 3.6325 8.6325 3.6325 9 P 0 ;1
L 8.6325 3.6825 8.6325 3.6825 9 P 0 ;1
L 8.6325 3.7325 8.6325 3.7325 9 P 0 ;1
L 8.6325 3.7825 8.6325 3.7825 9 P 0 ;1
L 8.6325 3.8325 8.6325 3.8325 9 P 0 ;1
L 8.6325 3.8825 8.6325 3.8825 9 P 0 ;1
L 8.6325 3.9325 8.6325 3.9325 9 P 0 ;1
L 8.6325 3.9825 8.6325 3.9825 9 P 0 ;1
L 8.6325 4.0325 8.6325 4.0325 9 P 0 ;1
L 8.6325 4.0825 8.6325 4.0825 9 P 0 ;1
L 8.6325 4.1325 8.6325 4.1325 9 P 0 ;1
L 8.6325 4.1825 8.6325 4.1825 9 P 0 ;1
L 8.6325 4.2325 8.6325 4.2325 9 P 0 ;1
L 8.6325 4.2825 8.6325 4.2825 9 P 0 ;1
L 8.6325 4.3325 8.6325 4.3325 9 P 0 ;1
L 8.6325 4.3825 8.6325 4.3825 9 P 0 ;1
L 8.6325 4.4325 8.6325 4.4325 9 P 0 ;1
L 8.6325 4.4825 8.6325 4.4825 9 P 0 ;1
L 8.6325 4.5325 8.6325 4.5325 9 P 0 ;1
L 8.6325 4.5825 8.6325 4.5825 9 P 0 ;1
L 8.6325 4.6325 8.6325 4.6325 9 P 0 ;1
L 8.6325 4.6825 8.6325 4.6825 9 P 0 ;1
L 8.6325 4.9825 8.6325 4.9825 9 P 0 ;1
L 8.6325 5.1325 8.6325 5.1325 9 P 0 ;1
L 8.6325 5.1825 8.6325 5.1825 9 P 0 ;1
L 8.6325 5.2325 8.6325 5.2325 9 P 0 ;1
L 8.6325 5.2825 8.6325 5.2825 9 P 0 ;1
L 8.6325 5.3325 8.6325 5.3325 9 P 0 ;1
L 8.6325 5.3825 8.6325 5.3825 9 P 0 ;1
L 8.6325 5.4325 8.6325 5.4325 9 P 0 ;1
L 8.6325 5.4825 8.6325 5.4825 9 P 0 ;1
L 8.6325 5.5325 8.6325 5.5325 9 P 0 ;1
L 8.6325 5.5825 8.6325 5.5825 9 P 0 ;1
L 8.6325 5.6325 8.6325 5.6325 9 P 0 ;1
L 8.6325 5.6825 8.6325 5.6825 9 P 0 ;1
L 8.6325 5.7325 8.6325 5.7325 9 P 0 ;1
L 8.6325 5.7825 8.6325 5.7825 9 P 0 ;1
L 8.6325 5.8325 8.6325 5.8325 9 P 0 ;1
L 8.6325 5.8825 8.6325 5.8825 9 P 0 ;1
L 8.6825 0.1325 8.6825 0.1325 9 P 0 ;1
L 8.6825 0.1825 8.6825 0.1825 9 P 0 ;1
L 8.6825 0.2325 8.6825 0.2325 9 P 0 ;1
L 8.6825 0.2825 8.6825 0.2825 9 P 0 ;1
L 8.6825 0.3325 8.6825 0.3325 9 P 0 ;1
L 8.6825 0.3825 8.6825 0.3825 9 P 0 ;1
L 8.6825 0.4325 8.6825 0.4325 9 P 0 ;1
L 8.6825 0.4825 8.6825 0.4825 9 P 0 ;1
L 8.6825 0.5325 8.6825 0.5325 9 P 0 ;1
L 8.6825 0.5825 8.6825 0.5825 9 P 0 ;1
L 8.6825 0.6325 8.6825 0.6325 9 P 0 ;1
L 8.6825 0.6825 8.6825 0.6825 9 P 0 ;1
L 8.6825 0.7325 8.6825 0.7325 9 P 0 ;1
L 8.6825 0.7825 8.6825 0.7825 9 P 0 ;1
L 8.6825 0.8325 8.6825 0.8325 9 P 0 ;1
L 8.6825 0.8825 8.6825 0.8825 9 P 0 ;1
L 8.6825 0.9325 8.6825 0.9325 9 P 0 ;1
L 8.6825 0.9825 8.6825 0.9825 9 P 0 ;1
L 8.6825 1.0325 8.6825 1.0325 9 P 0 ;1
L 8.6825 1.0825 8.6825 1.0825 9 P 0 ;1
L 8.6825 1.1325 8.6825 1.1325 9 P 0 ;1
L 8.6825 1.1825 8.6825 1.1825 9 P 0 ;1
L 8.6825 1.2325 8.6825 1.2325 9 P 0 ;1
L 8.6825 1.2825 8.6825 1.2825 9 P 0 ;1
L 8.6825 1.3325 8.6825 1.3325 9 P 0 ;1
L 8.6825 1.3825 8.6825 1.3825 9 P 0 ;1
L 8.6825 1.4325 8.6825 1.4325 9 P 0 ;1
L 8.6825 1.4825 8.6825 1.4825 9 P 0 ;1
L 8.6825 1.5325 8.6825 1.5325 9 P 0 ;1
L 8.6825 1.5825 8.6825 1.5825 9 P 0 ;1
L 8.6825 1.6325 8.6825 1.6325 9 P 0 ;1
L 8.6825 1.6825 8.6825 1.6825 9 P 0 ;1
L 8.6825 1.7325 8.6825 1.7325 9 P 0 ;1
L 8.6825 1.7825 8.6825 1.7825 9 P 0 ;1
L 8.6825 1.8325 8.6825 1.8325 9 P 0 ;1
L 8.6825 1.8825 8.6825 1.8825 9 P 0 ;1
L 8.6825 1.9325 8.6825 1.9325 9 P 0 ;1
L 8.6825 1.9825 8.6825 1.9825 9 P 0 ;1
L 8.6825 2.0325 8.6825 2.0325 9 P 0 ;1
L 8.6825 2.0825 8.6825 2.0825 9 P 0 ;1
L 8.6825 2.1325 8.6825 2.1325 9 P 0 ;1
L 8.6825 2.1825 8.6825 2.1825 9 P 0 ;1
L 8.6825 2.2325 8.6825 2.2325 9 P 0 ;1
L 8.6825 2.2825 8.6825 2.2825 9 P 0 ;1
L 8.6825 2.3325 8.6825 2.3325 9 P 0 ;1
L 8.6825 2.3825 8.6825 2.3825 9 P 0 ;1
L 8.6825 2.4325 8.6825 2.4325 9 P 0 ;1
L 8.6825 2.4825 8.6825 2.4825 9 P 0 ;1
L 8.6825 2.5325 8.6825 2.5325 9 P 0 ;1
L 8.6825 2.5825 8.6825 2.5825 9 P 0 ;1
L 8.6825 2.6325 8.6825 2.6325 9 P 0 ;1
L 8.6825 2.6825 8.6825 2.6825 9 P 0 ;1
L 8.6825 2.7325 8.6825 2.7325 9 P 0 ;1
L 8.6825 2.7825 8.6825 2.7825 9 P 0 ;1
L 8.6825 2.8325 8.6825 2.8325 9 P 0 ;1
L 8.6825 2.8825 8.6825 2.8825 9 P 0 ;1
L 8.6825 2.9325 8.6825 2.9325 9 P 0 ;1
L 8.6825 2.9825 8.6825 2.9825 9 P 0 ;1
L 8.6825 3.0325 8.6825 3.0325 9 P 0 ;1
L 8.6825 3.0825 8.6825 3.0825 9 P 0 ;1
L 8.6825 3.1325 8.6825 3.1325 9 P 0 ;1
L 8.6825 3.1825 8.6825 3.1825 9 P 0 ;1
L 8.6825 3.2325 8.6825 3.2325 9 P 0 ;1
L 8.6825 3.2825 8.6825 3.2825 9 P 0 ;1
L 8.6825 3.3325 8.6825 3.3325 9 P 0 ;1
L 8.6825 3.3825 8.6825 3.3825 9 P 0 ;1
L 8.6825 3.4325 8.6825 3.4325 9 P 0 ;1
L 8.6825 3.4825 8.6825 3.4825 9 P 0 ;1
L 8.6825 3.5325 8.6825 3.5325 9 P 0 ;1
L 8.6825 3.5825 8.6825 3.5825 9 P 0 ;1
L 8.6825 3.6325 8.6825 3.6325 9 P 0 ;1
L 8.6825 3.6825 8.6825 3.6825 9 P 0 ;1
L 8.6825 3.7325 8.6825 3.7325 9 P 0 ;1
L 8.6825 3.7825 8.6825 3.7825 9 P 0 ;1
L 8.6825 3.8325 8.6825 3.8325 9 P 0 ;1
L 8.6825 3.8825 8.6825 3.8825 9 P 0 ;1
L 8.6825 3.9325 8.6825 3.9325 9 P 0 ;1
L 8.6825 3.9825 8.6825 3.9825 9 P 0 ;1
L 8.6825 4.0325 8.6825 4.0325 9 P 0 ;1
L 8.6825 4.0825 8.6825 4.0825 9 P 0 ;1
L 8.6825 4.1325 8.6825 4.1325 9 P 0 ;1
L 8.6825 4.1825 8.6825 4.1825 9 P 0 ;1
L 8.6825 4.2325 8.6825 4.2325 9 P 0 ;1
L 8.6825 4.2825 8.6825 4.2825 9 P 0 ;1
L 8.6825 4.3325 8.6825 4.3325 9 P 0 ;1
L 8.6825 4.3825 8.6825 4.3825 9 P 0 ;1
L 8.6825 4.4325 8.6825 4.4325 9 P 0 ;1
L 8.6825 4.4825 8.6825 4.4825 9 P 0 ;1
L 8.6825 4.5325 8.6825 4.5325 9 P 0 ;1
L 8.6825 4.5825 8.6825 4.5825 9 P 0 ;1
L 8.6825 5.2825 8.6825 5.2825 9 P 0 ;1
L 8.6825 5.3325 8.6825 5.3325 9 P 0 ;1
L 8.6825 5.3825 8.6825 5.3825 9 P 0 ;1
L 8.6825 5.4325 8.6825 5.4325 9 P 0 ;1
L 8.6825 5.4825 8.6825 5.4825 9 P 0 ;1
L 8.6825 5.5325 8.6825 5.5325 9 P 0 ;1
L 8.6825 5.5825 8.6825 5.5825 9 P 0 ;1
L 8.6825 5.6325 8.6825 5.6325 9 P 0 ;1
L 8.6825 5.6825 8.6825 5.6825 9 P 0 ;1
L 8.6825 5.7325 8.6825 5.7325 9 P 0 ;1
L 8.6825 5.7825 8.6825 5.7825 9 P 0 ;1
L 8.6825 5.8325 8.6825 5.8325 9 P 0 ;1
L 8.6825 5.8825 8.6825 5.8825 9 P 0 ;1
L 8.7325 0.1325 8.7325 0.1325 9 P 0 ;1
L 8.7325 0.1825 8.7325 0.1825 9 P 0 ;1
L 8.7325 0.2325 8.7325 0.2325 9 P 0 ;1
L 8.7325 0.2825 8.7325 0.2825 9 P 0 ;1
L 8.7325 0.3325 8.7325 0.3325 9 P 0 ;1
L 8.7325 0.3825 8.7325 0.3825 9 P 0 ;1
L 8.7325 0.4325 8.7325 0.4325 9 P 0 ;1
L 8.7325 0.4825 8.7325 0.4825 9 P 0 ;1
L 8.7325 0.5325 8.7325 0.5325 9 P 0 ;1
L 8.7325 0.5825 8.7325 0.5825 9 P 0 ;1
L 8.7325 0.6325 8.7325 0.6325 9 P 0 ;1
L 8.7325 0.6825 8.7325 0.6825 9 P 0 ;1
L 8.7325 0.7325 8.7325 0.7325 9 P 0 ;1
L 8.7325 0.7825 8.7325 0.7825 9 P 0 ;1
L 8.7325 0.8325 8.7325 0.8325 9 P 0 ;1
L 8.7325 0.8825 8.7325 0.8825 9 P 0 ;1
L 8.7325 0.9325 8.7325 0.9325 9 P 0 ;1
L 8.7325 0.9825 8.7325 0.9825 9 P 0 ;1
L 8.7325 1.0325 8.7325 1.0325 9 P 0 ;1
L 8.7325 1.0825 8.7325 1.0825 9 P 0 ;1
L 8.7325 1.1325 8.7325 1.1325 9 P 0 ;1
L 8.7325 1.1825 8.7325 1.1825 9 P 0 ;1
L 8.7325 1.2325 8.7325 1.2325 9 P 0 ;1
L 8.7325 1.2825 8.7325 1.2825 9 P 0 ;1
L 8.7325 1.3325 8.7325 1.3325 9 P 0 ;1
L 8.7325 1.3825 8.7325 1.3825 9 P 0 ;1
L 8.7325 1.4325 8.7325 1.4325 9 P 0 ;1
L 8.7325 1.4825 8.7325 1.4825 9 P 0 ;1
L 8.7325 1.5325 8.7325 1.5325 9 P 0 ;1
L 8.7325 1.5825 8.7325 1.5825 9 P 0 ;1
L 8.7325 1.6325 8.7325 1.6325 9 P 0 ;1
L 8.7325 1.6825 8.7325 1.6825 9 P 0 ;1
L 8.7325 1.7325 8.7325 1.7325 9 P 0 ;1
L 8.7325 1.7825 8.7325 1.7825 9 P 0 ;1
L 8.7325 1.8325 8.7325 1.8325 9 P 0 ;1
L 8.7325 1.8825 8.7325 1.8825 9 P 0 ;1
L 8.7325 1.9325 8.7325 1.9325 9 P 0 ;1
L 8.7325 1.9825 8.7325 1.9825 9 P 0 ;1
L 8.7325 2.0325 8.7325 2.0325 9 P 0 ;1
L 8.7325 2.0825 8.7325 2.0825 9 P 0 ;1
L 8.7325 2.1325 8.7325 2.1325 9 P 0 ;1
L 8.7325 2.1825 8.7325 2.1825 9 P 0 ;1
L 8.7325 2.2325 8.7325 2.2325 9 P 0 ;1
L 8.7325 2.2825 8.7325 2.2825 9 P 0 ;1
L 8.7325 2.3325 8.7325 2.3325 9 P 0 ;1
L 8.7325 2.3825 8.7325 2.3825 9 P 0 ;1
L 8.7325 2.4325 8.7325 2.4325 9 P 0 ;1
L 8.7325 2.4825 8.7325 2.4825 9 P 0 ;1
L 8.7325 2.5325 8.7325 2.5325 9 P 0 ;1
L 8.7325 2.5825 8.7325 2.5825 9 P 0 ;1
L 8.7325 2.6325 8.7325 2.6325 9 P 0 ;1
L 8.7325 2.6825 8.7325 2.6825 9 P 0 ;1
L 8.7325 2.7325 8.7325 2.7325 9 P 0 ;1
L 8.7325 2.7825 8.7325 2.7825 9 P 0 ;1
L 8.7325 2.8325 8.7325 2.8325 9 P 0 ;1
L 8.7325 2.8825 8.7325 2.8825 9 P 0 ;1
L 8.7325 2.9325 8.7325 2.9325 9 P 0 ;1
L 8.7325 2.9825 8.7325 2.9825 9 P 0 ;1
L 8.7325 3.0325 8.7325 3.0325 9 P 0 ;1
L 8.7325 3.0825 8.7325 3.0825 9 P 0 ;1
L 8.7325 3.1325 8.7325 3.1325 9 P 0 ;1
L 8.7325 3.1825 8.7325 3.1825 9 P 0 ;1
L 8.7325 3.2325 8.7325 3.2325 9 P 0 ;1
L 8.7325 3.2825 8.7325 3.2825 9 P 0 ;1
L 8.7325 3.3325 8.7325 3.3325 9 P 0 ;1
L 8.7325 3.3825 8.7325 3.3825 9 P 0 ;1
L 8.7325 3.4325 8.7325 3.4325 9 P 0 ;1
L 8.7325 3.4825 8.7325 3.4825 9 P 0 ;1
L 8.7325 3.5325 8.7325 3.5325 9 P 0 ;1
L 8.7325 3.5825 8.7325 3.5825 9 P 0 ;1
L 8.7325 3.6325 8.7325 3.6325 9 P 0 ;1
L 8.7325 3.6825 8.7325 3.6825 9 P 0 ;1
L 8.7325 3.7325 8.7325 3.7325 9 P 0 ;1
L 8.7325 3.7825 8.7325 3.7825 9 P 0 ;1
L 8.7325 3.8325 8.7325 3.8325 9 P 0 ;1
L 8.7325 3.8825 8.7325 3.8825 9 P 0 ;1
L 8.7325 3.9325 8.7325 3.9325 9 P 0 ;1
L 8.7325 3.9825 8.7325 3.9825 9 P 0 ;1
L 8.7325 4.0325 8.7325 4.0325 9 P 0 ;1
L 8.7325 4.0825 8.7325 4.0825 9 P 0 ;1
L 8.7325 4.1325 8.7325 4.1325 9 P 0 ;1
L 8.7325 4.1825 8.7325 4.1825 9 P 0 ;1
L 8.7325 4.2325 8.7325 4.2325 9 P 0 ;1
L 8.7325 4.2825 8.7325 4.2825 9 P 0 ;1
L 8.7325 4.3325 8.7325 4.3325 9 P 0 ;1
L 8.7325 4.3825 8.7325 4.3825 9 P 0 ;1
L 8.7325 4.4325 8.7325 4.4325 9 P 0 ;1
L 8.7325 4.4825 8.7325 4.4825 9 P 0 ;1
L 8.7325 4.5325 8.7325 4.5325 9 P 0 ;1
L 8.7325 4.5825 8.7325 4.5825 9 P 0 ;1
L 8.7325 5.2825 8.7325 5.2825 9 P 0 ;1
L 8.7325 5.3325 8.7325 5.3325 9 P 0 ;1
L 8.7325 5.3825 8.7325 5.3825 9 P 0 ;1
L 8.7325 5.4325 8.7325 5.4325 9 P 0 ;1
L 8.7325 5.4825 8.7325 5.4825 9 P 0 ;1
L 8.7325 5.5325 8.7325 5.5325 9 P 0 ;1
L 8.7325 5.5825 8.7325 5.5825 9 P 0 ;1
L 8.7325 5.6325 8.7325 5.6325 9 P 0 ;1
L 8.7325 5.6825 8.7325 5.6825 9 P 0 ;1
L 8.7325 5.7325 8.7325 5.7325 9 P 0 ;1
L 8.7325 5.7825 8.7325 5.7825 9 P 0 ;1
L 8.7325 5.8325 8.7325 5.8325 9 P 0 ;1
L 8.7325 5.8825 8.7325 5.8825 9 P 0 ;1
L 8.7825 0.1325 8.7825 0.1325 9 P 0 ;1
L 8.7825 0.1825 8.7825 0.1825 9 P 0 ;1
L 8.7825 0.2325 8.7825 0.2325 9 P 0 ;1
L 8.7825 0.2825 8.7825 0.2825 9 P 0 ;1
L 8.7825 0.3325 8.7825 0.3325 9 P 0 ;1
L 8.7825 0.3825 8.7825 0.3825 9 P 0 ;1
L 8.7825 0.4325 8.7825 0.4325 9 P 0 ;1
L 8.7825 0.4825 8.7825 0.4825 9 P 0 ;1
L 8.7825 0.5325 8.7825 0.5325 9 P 0 ;1
L 8.7825 0.5825 8.7825 0.5825 9 P 0 ;1
L 8.7825 0.6325 8.7825 0.6325 9 P 0 ;1
L 8.7825 0.6825 8.7825 0.6825 9 P 0 ;1
L 8.7825 0.7325 8.7825 0.7325 9 P 0 ;1
L 8.7825 0.7825 8.7825 0.7825 9 P 0 ;1
L 8.7825 0.8325 8.7825 0.8325 9 P 0 ;1
L 8.7825 0.8825 8.7825 0.8825 9 P 0 ;1
L 8.7825 0.9325 8.7825 0.9325 9 P 0 ;1
L 8.7825 0.9825 8.7825 0.9825 9 P 0 ;1
L 8.7825 1.0325 8.7825 1.0325 9 P 0 ;1
L 8.7825 1.0825 8.7825 1.0825 9 P 0 ;1
L 8.7825 1.1325 8.7825 1.1325 9 P 0 ;1
L 8.7825 1.1825 8.7825 1.1825 9 P 0 ;1
L 8.7825 1.2325 8.7825 1.2325 9 P 0 ;1
L 8.7825 1.2825 8.7825 1.2825 9 P 0 ;1
L 8.7825 1.3325 8.7825 1.3325 9 P 0 ;1
L 8.7825 1.3825 8.7825 1.3825 9 P 0 ;1
L 8.7825 1.4325 8.7825 1.4325 9 P 0 ;1
L 8.7825 1.4825 8.7825 1.4825 9 P 0 ;1
L 8.7825 1.5325 8.7825 1.5325 9 P 0 ;1
L 8.7825 1.5825 8.7825 1.5825 9 P 0 ;1
L 8.7825 1.6325 8.7825 1.6325 9 P 0 ;1
L 8.7825 1.6825 8.7825 1.6825 9 P 0 ;1
L 8.7825 1.7325 8.7825 1.7325 9 P 0 ;1
L 8.7825 1.7825 8.7825 1.7825 9 P 0 ;1
L 8.7825 1.8325 8.7825 1.8325 9 P 0 ;1
L 8.7825 1.8825 8.7825 1.8825 9 P 0 ;1
L 8.7825 1.9325 8.7825 1.9325 9 P 0 ;1
L 8.7825 1.9825 8.7825 1.9825 9 P 0 ;1
L 8.7825 2.0325 8.7825 2.0325 9 P 0 ;1
L 8.7825 2.0825 8.7825 2.0825 9 P 0 ;1
L 8.7825 2.1325 8.7825 2.1325 9 P 0 ;1
L 8.7825 2.1825 8.7825 2.1825 9 P 0 ;1
L 8.7825 2.2325 8.7825 2.2325 9 P 0 ;1
L 8.7825 2.2825 8.7825 2.2825 9 P 0 ;1
L 8.7825 2.3325 8.7825 2.3325 9 P 0 ;1
L 8.7825 2.3825 8.7825 2.3825 9 P 0 ;1
L 8.7825 2.4325 8.7825 2.4325 9 P 0 ;1
L 8.7825 2.4825 8.7825 2.4825 9 P 0 ;1
L 8.7825 2.5325 8.7825 2.5325 9 P 0 ;1
L 8.7825 2.5825 8.7825 2.5825 9 P 0 ;1
L 8.7825 2.6325 8.7825 2.6325 9 P 0 ;1
L 8.7825 2.6825 8.7825 2.6825 9 P 0 ;1
L 8.7825 2.7325 8.7825 2.7325 9 P 0 ;1
L 8.7825 2.7825 8.7825 2.7825 9 P 0 ;1
L 8.7825 2.8325 8.7825 2.8325 9 P 0 ;1
L 8.7825 2.8825 8.7825 2.8825 9 P 0 ;1
L 8.7825 2.9325 8.7825 2.9325 9 P 0 ;1
L 8.7825 2.9825 8.7825 2.9825 9 P 0 ;1
L 8.7825 3.0325 8.7825 3.0325 9 P 0 ;1
L 8.7825 3.0825 8.7825 3.0825 9 P 0 ;1
L 8.7825 3.1325 8.7825 3.1325 9 P 0 ;1
L 8.7825 3.1825 8.7825 3.1825 9 P 0 ;1
L 8.7825 3.2325 8.7825 3.2325 9 P 0 ;1
L 8.7825 3.2825 8.7825 3.2825 9 P 0 ;1
L 8.7825 3.3325 8.7825 3.3325 9 P 0 ;1
L 8.7825 3.3825 8.7825 3.3825 9 P 0 ;1
L 8.7825 3.4325 8.7825 3.4325 9 P 0 ;1
L 8.7825 3.4825 8.7825 3.4825 9 P 0 ;1
L 8.7825 3.5325 8.7825 3.5325 9 P 0 ;1
L 8.7825 3.5825 8.7825 3.5825 9 P 0 ;1
L 8.7825 3.6325 8.7825 3.6325 9 P 0 ;1
L 8.7825 3.6825 8.7825 3.6825 9 P 0 ;1
L 8.7825 3.7325 8.7825 3.7325 9 P 0 ;1
L 8.7825 3.7825 8.7825 3.7825 9 P 0 ;1
L 8.7825 3.8325 8.7825 3.8325 9 P 0 ;1
L 8.7825 3.8825 8.7825 3.8825 9 P 0 ;1
L 8.7825 3.9325 8.7825 3.9325 9 P 0 ;1
L 8.7825 3.9825 8.7825 3.9825 9 P 0 ;1
L 8.7825 4.0325 8.7825 4.0325 9 P 0 ;1
L 8.7825 4.0825 8.7825 4.0825 9 P 0 ;1
L 8.7825 4.1325 8.7825 4.1325 9 P 0 ;1
L 8.7825 4.1825 8.7825 4.1825 9 P 0 ;1
L 8.7825 4.2325 8.7825 4.2325 9 P 0 ;1
L 8.7825 4.2825 8.7825 4.2825 9 P 0 ;1
L 8.7825 4.3325 8.7825 4.3325 9 P 0 ;1
L 8.7825 4.3825 8.7825 4.3825 9 P 0 ;1
L 8.7825 4.4325 8.7825 4.4325 9 P 0 ;1
L 8.7825 4.4825 8.7825 4.4825 9 P 0 ;1
L 8.7825 4.5325 8.7825 4.5325 9 P 0 ;1
L 8.7825 4.5825 8.7825 4.5825 9 P 0 ;1
L 8.7825 5.2825 8.7825 5.2825 9 P 0 ;1
L 8.7825 5.3325 8.7825 5.3325 9 P 0 ;1
L 8.7825 5.3825 8.7825 5.3825 9 P 0 ;1
L 8.7825 5.4325 8.7825 5.4325 9 P 0 ;1
L 8.7825 5.4825 8.7825 5.4825 9 P 0 ;1
L 8.7825 5.5325 8.7825 5.5325 9 P 0 ;1
L 8.7825 5.5825 8.7825 5.5825 9 P 0 ;1
L 8.7825 5.6325 8.7825 5.6325 9 P 0 ;1
L 8.7825 5.6825 8.7825 5.6825 9 P 0 ;1
L 8.7825 5.7325 8.7825 5.7325 9 P 0 ;1
L 8.7825 5.7825 8.7825 5.7825 9 P 0 ;1
L 8.7825 5.8325 8.7825 5.8325 9 P 0 ;1
L 8.7825 5.8825 8.7825 5.8825 9 P 0 ;1
L 8.8325 0.1325 8.8325 0.1325 9 P 0 ;1
L 8.8325 0.1825 8.8325 0.1825 9 P 0 ;1
L 8.8325 0.2325 8.8325 0.2325 9 P 0 ;1
L 8.8325 0.2825 8.8325 0.2825 9 P 0 ;1
L 8.8325 0.3325 8.8325 0.3325 9 P 0 ;1
L 8.8325 0.3825 8.8325 0.3825 9 P 0 ;1
L 8.8325 0.4325 8.8325 0.4325 9 P 0 ;1
L 8.8325 0.4825 8.8325 0.4825 9 P 0 ;1
L 8.8325 0.5325 8.8325 0.5325 9 P 0 ;1
L 8.8325 0.5825 8.8325 0.5825 9 P 0 ;1
L 8.8325 0.6325 8.8325 0.6325 9 P 0 ;1
L 8.8325 0.6825 8.8325 0.6825 9 P 0 ;1
L 8.8325 0.7325 8.8325 0.7325 9 P 0 ;1
L 8.8325 0.7825 8.8325 0.7825 9 P 0 ;1
L 8.8325 0.8325 8.8325 0.8325 9 P 0 ;1
L 8.8325 0.8825 8.8325 0.8825 9 P 0 ;1
L 8.8325 0.9325 8.8325 0.9325 9 P 0 ;1
L 8.8325 0.9825 8.8325 0.9825 9 P 0 ;1
L 8.8325 1.0325 8.8325 1.0325 9 P 0 ;1
L 8.8325 1.0825 8.8325 1.0825 9 P 0 ;1
L 8.8325 1.1325 8.8325 1.1325 9 P 0 ;1
L 8.8325 1.1825 8.8325 1.1825 9 P 0 ;1
L 8.8325 1.2325 8.8325 1.2325 9 P 0 ;1
L 8.8325 1.2825 8.8325 1.2825 9 P 0 ;1
L 8.8325 1.3325 8.8325 1.3325 9 P 0 ;1
L 8.8325 1.3825 8.8325 1.3825 9 P 0 ;1
L 8.8325 1.4325 8.8325 1.4325 9 P 0 ;1
L 8.8325 1.4825 8.8325 1.4825 9 P 0 ;1
L 8.8325 1.5325 8.8325 1.5325 9 P 0 ;1
L 8.8325 1.5825 8.8325 1.5825 9 P 0 ;1
L 8.8325 1.6325 8.8325 1.6325 9 P 0 ;1
L 8.8325 1.6825 8.8325 1.6825 9 P 0 ;1
L 8.8325 1.7325 8.8325 1.7325 9 P 0 ;1
L 8.8325 1.7825 8.8325 1.7825 9 P 0 ;1
L 8.8325 1.8325 8.8325 1.8325 9 P 0 ;1
L 8.8325 1.8825 8.8325 1.8825 9 P 0 ;1
L 8.8325 1.9325 8.8325 1.9325 9 P 0 ;1
L 8.8325 1.9825 8.8325 1.9825 9 P 0 ;1
L 8.8325 2.0325 8.8325 2.0325 9 P 0 ;1
L 8.8325 2.0825 8.8325 2.0825 9 P 0 ;1
L 8.8325 2.1325 8.8325 2.1325 9 P 0 ;1
L 8.8325 2.1825 8.8325 2.1825 9 P 0 ;1
L 8.8325 2.2325 8.8325 2.2325 9 P 0 ;1
L 8.8325 2.2825 8.8325 2.2825 9 P 0 ;1
L 8.8325 2.3325 8.8325 2.3325 9 P 0 ;1
L 8.8325 2.3825 8.8325 2.3825 9 P 0 ;1
L 8.8325 2.4325 8.8325 2.4325 9 P 0 ;1
L 8.8325 2.4825 8.8325 2.4825 9 P 0 ;1
L 8.8325 2.5325 8.8325 2.5325 9 P 0 ;1
L 8.8325 2.5825 8.8325 2.5825 9 P 0 ;1
L 8.8325 2.6325 8.8325 2.6325 9 P 0 ;1
L 8.8325 2.6825 8.8325 2.6825 9 P 0 ;1
L 8.8325 2.7325 8.8325 2.7325 9 P 0 ;1
L 8.8325 2.7825 8.8325 2.7825 9 P 0 ;1
L 8.8325 2.8325 8.8325 2.8325 9 P 0 ;1
L 8.8325 2.8825 8.8325 2.8825 9 P 0 ;1
L 8.8325 2.9325 8.8325 2.9325 9 P 0 ;1
L 8.8325 2.9825 8.8325 2.9825 9 P 0 ;1
L 8.8325 3.0325 8.8325 3.0325 9 P 0 ;1
L 8.8325 3.0825 8.8325 3.0825 9 P 0 ;1
L 8.8325 3.1325 8.8325 3.1325 9 P 0 ;1
L 8.8325 3.1825 8.8325 3.1825 9 P 0 ;1
L 8.8325 3.2325 8.8325 3.2325 9 P 0 ;1
L 8.8325 3.2825 8.8325 3.2825 9 P 0 ;1
L 8.8325 3.3325 8.8325 3.3325 9 P 0 ;1
L 8.8325 3.3825 8.8325 3.3825 9 P 0 ;1
L 8.8325 3.4325 8.8325 3.4325 9 P 0 ;1
L 8.8325 3.4825 8.8325 3.4825 9 P 0 ;1
L 8.8325 3.5325 8.8325 3.5325 9 P 0 ;1
L 8.8325 3.5825 8.8325 3.5825 9 P 0 ;1
L 8.8325 3.6325 8.8325 3.6325 9 P 0 ;1
L 8.8325 3.6825 8.8325 3.6825 9 P 0 ;1
L 8.8325 3.7325 8.8325 3.7325 9 P 0 ;1
L 8.8325 3.7825 8.8325 3.7825 9 P 0 ;1
L 8.8325 3.8325 8.8325 3.8325 9 P 0 ;1
L 8.8325 3.8825 8.8325 3.8825 9 P 0 ;1
L 8.8325 3.9325 8.8325 3.9325 9 P 0 ;1
L 8.8325 3.9825 8.8325 3.9825 9 P 0 ;1
L 8.8325 4.0325 8.8325 4.0325 9 P 0 ;1
L 8.8325 4.0825 8.8325 4.0825 9 P 0 ;1
L 8.8325 4.1325 8.8325 4.1325 9 P 0 ;1
L 8.8325 4.1825 8.8325 4.1825 9 P 0 ;1
L 8.8325 4.2325 8.8325 4.2325 9 P 0 ;1
L 8.8325 4.2825 8.8325 4.2825 9 P 0 ;1
L 8.8325 4.3325 8.8325 4.3325 9 P 0 ;1
L 8.8325 4.3825 8.8325 4.3825 9 P 0 ;1
L 8.8325 4.4325 8.8325 4.4325 9 P 0 ;1
L 8.8325 4.4825 8.8325 4.4825 9 P 0 ;1
L 8.8325 4.5325 8.8325 4.5325 9 P 0 ;1
L 8.8325 4.5825 8.8325 4.5825 9 P 0 ;1
L 8.8325 5.2825 8.8325 5.2825 9 P 0 ;1
L 8.8325 5.3325 8.8325 5.3325 9 P 0 ;1
L 8.8325 5.3825 8.8325 5.3825 9 P 0 ;1
L 8.8325 5.4325 8.8325 5.4325 9 P 0 ;1
L 8.8325 5.4825 8.8325 5.4825 9 P 0 ;1
L 8.8325 5.5325 8.8325 5.5325 9 P 0 ;1
L 8.8325 5.5825 8.8325 5.5825 9 P 0 ;1
L 8.8325 5.6325 8.8325 5.6325 9 P 0 ;1
L 8.8325 5.6825 8.8325 5.6825 9 P 0 ;1
L 8.8325 5.7325 8.8325 5.7325 9 P 0 ;1
L 8.8325 5.7825 8.8325 5.7825 9 P 0 ;1
L 8.8325 5.8325 8.8325 5.8325 9 P 0 ;1
L 8.8325 5.8825 8.8325 5.8825 9 P 0 ;1
L 8.8825 0.1325 8.8825 0.1325 9 P 0 ;1
L 8.8825 0.1825 8.8825 0.1825 9 P 0 ;1
L 8.8825 0.2325 8.8825 0.2325 9 P 0 ;1
L 8.8825 0.2825 8.8825 0.2825 9 P 0 ;1
L 8.8825 0.3325 8.8825 0.3325 9 P 0 ;1
L 8.8825 0.3825 8.8825 0.3825 9 P 0 ;1
L 8.8825 0.4325 8.8825 0.4325 9 P 0 ;1
L 8.8825 0.4825 8.8825 0.4825 9 P 0 ;1
L 8.8825 0.5325 8.8825 0.5325 9 P 0 ;1
L 8.8825 0.5825 8.8825 0.5825 9 P 0 ;1
L 8.8825 0.6325 8.8825 0.6325 9 P 0 ;1
L 8.8825 0.6825 8.8825 0.6825 9 P 0 ;1
L 8.8825 0.7325 8.8825 0.7325 9 P 0 ;1
L 8.8825 0.7825 8.8825 0.7825 9 P 0 ;1
L 8.8825 0.8325 8.8825 0.8325 9 P 0 ;1
L 8.8825 0.8825 8.8825 0.8825 9 P 0 ;1
L 8.8825 0.9325 8.8825 0.9325 9 P 0 ;1
L 8.8825 0.9825 8.8825 0.9825 9 P 0 ;1
L 8.8825 1.0325 8.8825 1.0325 9 P 0 ;1
L 8.8825 1.0825 8.8825 1.0825 9 P 0 ;1
L 8.8825 1.1325 8.8825 1.1325 9 P 0 ;1
L 8.8825 1.1825 8.8825 1.1825 9 P 0 ;1
L 8.8825 1.2325 8.8825 1.2325 9 P 0 ;1
L 8.8825 1.2825 8.8825 1.2825 9 P 0 ;1
L 8.8825 1.3325 8.8825 1.3325 9 P 0 ;1
L 8.8825 1.3825 8.8825 1.3825 9 P 0 ;1
L 8.8825 1.4325 8.8825 1.4325 9 P 0 ;1
L 8.8825 1.4825 8.8825 1.4825 9 P 0 ;1
L 8.8825 1.5325 8.8825 1.5325 9 P 0 ;1
L 8.8825 1.5825 8.8825 1.5825 9 P 0 ;1
L 8.8825 1.6325 8.8825 1.6325 9 P 0 ;1
L 8.8825 1.6825 8.8825 1.6825 9 P 0 ;1
L 8.8825 1.7325 8.8825 1.7325 9 P 0 ;1
L 8.8825 1.7825 8.8825 1.7825 9 P 0 ;1
L 8.8825 1.8325 8.8825 1.8325 9 P 0 ;1
L 8.8825 1.8825 8.8825 1.8825 9 P 0 ;1
L 8.8825 1.9325 8.8825 1.9325 9 P 0 ;1
L 8.8825 1.9825 8.8825 1.9825 9 P 0 ;1
L 8.8825 2.0325 8.8825 2.0325 9 P 0 ;1
L 8.8825 2.0825 8.8825 2.0825 9 P 0 ;1
L 8.8825 2.1325 8.8825 2.1325 9 P 0 ;1
L 8.8825 2.1825 8.8825 2.1825 9 P 0 ;1
L 8.8825 2.2325 8.8825 2.2325 9 P 0 ;1
L 8.8825 2.2825 8.8825 2.2825 9 P 0 ;1
L 8.8825 2.3325 8.8825 2.3325 9 P 0 ;1
L 8.8825 2.3825 8.8825 2.3825 9 P 0 ;1
L 8.8825 2.4325 8.8825 2.4325 9 P 0 ;1
L 8.8825 2.4825 8.8825 2.4825 9 P 0 ;1
L 8.8825 2.5325 8.8825 2.5325 9 P 0 ;1
L 8.8825 2.5825 8.8825 2.5825 9 P 0 ;1
L 8.8825 2.6325 8.8825 2.6325 9 P 0 ;1
L 8.8825 2.6825 8.8825 2.6825 9 P 0 ;1
L 8.8825 2.7325 8.8825 2.7325 9 P 0 ;1
L 8.8825 2.7825 8.8825 2.7825 9 P 0 ;1
L 8.8825 2.8325 8.8825 2.8325 9 P 0 ;1
L 8.8825 2.9825 8.8825 2.9825 9 P 0 ;1
L 8.8825 3.0325 8.8825 3.0325 9 P 0 ;1
L 8.8825 3.0825 8.8825 3.0825 9 P 0 ;1
L 8.8825 3.1325 8.8825 3.1325 9 P 0 ;1
L 8.8825 3.1825 8.8825 3.1825 9 P 0 ;1
L 8.8825 3.2325 8.8825 3.2325 9 P 0 ;1
L 8.8825 3.2825 8.8825 3.2825 9 P 0 ;1
L 8.8825 3.3325 8.8825 3.3325 9 P 0 ;1
L 8.8825 3.3825 8.8825 3.3825 9 P 0 ;1
L 8.8825 3.4325 8.8825 3.4325 9 P 0 ;1
L 8.8825 3.4825 8.8825 3.4825 9 P 0 ;1
L 8.8825 3.5325 8.8825 3.5325 9 P 0 ;1
L 8.8825 3.5825 8.8825 3.5825 9 P 0 ;1
L 8.8825 3.6325 8.8825 3.6325 9 P 0 ;1
L 8.8825 3.6825 8.8825 3.6825 9 P 0 ;1
L 8.8825 3.7325 8.8825 3.7325 9 P 0 ;1
L 8.8825 3.7825 8.8825 3.7825 9 P 0 ;1
L 8.8825 3.8325 8.8825 3.8325 9 P 0 ;1
L 8.8825 3.8825 8.8825 3.8825 9 P 0 ;1
L 8.8825 3.9325 8.8825 3.9325 9 P 0 ;1
L 8.8825 3.9825 8.8825 3.9825 9 P 0 ;1
L 8.8825 4.0325 8.8825 4.0325 9 P 0 ;1
L 8.8825 4.0825 8.8825 4.0825 9 P 0 ;1
L 8.8825 4.1325 8.8825 4.1325 9 P 0 ;1
L 8.8825 4.1825 8.8825 4.1825 9 P 0 ;1
L 8.8825 4.2325 8.8825 4.2325 9 P 0 ;1
L 8.8825 4.2825 8.8825 4.2825 9 P 0 ;1
L 8.8825 4.3325 8.8825 4.3325 9 P 0 ;1
L 8.8825 4.3825 8.8825 4.3825 9 P 0 ;1
L 8.8825 4.4325 8.8825 4.4325 9 P 0 ;1
L 8.8825 4.4825 8.8825 4.4825 9 P 0 ;1
L 8.8825 4.5325 8.8825 4.5325 9 P 0 ;1
L 8.8825 4.5825 8.8825 4.5825 9 P 0 ;1
L 8.8825 5.3325 8.8825 5.3325 9 P 0 ;1
L 8.8825 5.3825 8.8825 5.3825 9 P 0 ;1
L 8.8825 5.4325 8.8825 5.4325 9 P 0 ;1
L 8.8825 5.4825 8.8825 5.4825 9 P 0 ;1
L 8.8825 5.5325 8.8825 5.5325 9 P 0 ;1
L 8.8825 5.5825 8.8825 5.5825 9 P 0 ;1
L 8.8825 5.6325 8.8825 5.6325 9 P 0 ;1
L 8.8825 5.6825 8.8825 5.6825 9 P 0 ;1
L 8.8825 5.7325 8.8825 5.7325 9 P 0 ;1
L 8.8825 5.7825 8.8825 5.7825 9 P 0 ;1
L 8.8825 5.8325 8.8825 5.8325 9 P 0 ;1
L 8.8825 5.8825 8.8825 5.8825 9 P 0 ;1
L 8.9325 0.1325 8.9325 0.1325 9 P 0 ;1
L 8.9325 0.1825 8.9325 0.1825 9 P 0 ;1
L 8.9325 0.2325 8.9325 0.2325 9 P 0 ;1
L 8.9325 0.2825 8.9325 0.2825 9 P 0 ;1
L 8.9325 0.3325 8.9325 0.3325 9 P 0 ;1
L 8.9325 0.3825 8.9325 0.3825 9 P 0 ;1
L 8.9325 0.4325 8.9325 0.4325 9 P 0 ;1
L 8.9325 0.4825 8.9325 0.4825 9 P 0 ;1
L 8.9325 0.5325 8.9325 0.5325 9 P 0 ;1
L 8.9325 0.5825 8.9325 0.5825 9 P 0 ;1
L 8.9325 0.6325 8.9325 0.6325 9 P 0 ;1
L 8.9325 0.6825 8.9325 0.6825 9 P 0 ;1
L 8.9325 0.7325 8.9325 0.7325 9 P 0 ;1
L 8.9325 0.7825 8.9325 0.7825 9 P 0 ;1
L 8.9325 0.8325 8.9325 0.8325 9 P 0 ;1
L 8.9325 0.8825 8.9325 0.8825 9 P 0 ;1
L 8.9325 0.9325 8.9325 0.9325 9 P 0 ;1
L 8.9325 0.9825 8.9325 0.9825 9 P 0 ;1
L 8.9325 1.0325 8.9325 1.0325 9 P 0 ;1
L 8.9325 1.0825 8.9325 1.0825 9 P 0 ;1
L 8.9325 1.1325 8.9325 1.1325 9 P 0 ;1
L 8.9325 1.1825 8.9325 1.1825 9 P 0 ;1
L 8.9325 1.2325 8.9325 1.2325 9 P 0 ;1
L 8.9325 1.2825 8.9325 1.2825 9 P 0 ;1
L 8.9325 1.3325 8.9325 1.3325 9 P 0 ;1
L 8.9325 1.3825 8.9325 1.3825 9 P 0 ;1
L 8.9325 1.4325 8.9325 1.4325 9 P 0 ;1
L 8.9325 1.4825 8.9325 1.4825 9 P 0 ;1
L 8.9325 1.5325 8.9325 1.5325 9 P 0 ;1
L 8.9325 1.5825 8.9325 1.5825 9 P 0 ;1
L 8.9325 1.6325 8.9325 1.6325 9 P 0 ;1
L 8.9325 1.6825 8.9325 1.6825 9 P 0 ;1
L 8.9325 1.7325 8.9325 1.7325 9 P 0 ;1
L 8.9325 1.7825 8.9325 1.7825 9 P 0 ;1
L 8.9325 1.8325 8.9325 1.8325 9 P 0 ;1
L 8.9325 1.8825 8.9325 1.8825 9 P 0 ;1
L 8.9325 1.9325 8.9325 1.9325 9 P 0 ;1
L 8.9325 1.9825 8.9325 1.9825 9 P 0 ;1
L 8.9325 2.0325 8.9325 2.0325 9 P 0 ;1
L 8.9325 2.0825 8.9325 2.0825 9 P 0 ;1
L 8.9325 2.1325 8.9325 2.1325 9 P 0 ;1
L 8.9325 2.1825 8.9325 2.1825 9 P 0 ;1
L 8.9325 2.2325 8.9325 2.2325 9 P 0 ;1
L 8.9325 2.2825 8.9325 2.2825 9 P 0 ;1
L 8.9325 2.3325 8.9325 2.3325 9 P 0 ;1
L 8.9325 2.3825 8.9325 2.3825 9 P 0 ;1
L 8.9325 2.4325 8.9325 2.4325 9 P 0 ;1
L 8.9325 2.4825 8.9325 2.4825 9 P 0 ;1
L 8.9325 2.5325 8.9325 2.5325 9 P 0 ;1
L 8.9325 2.5825 8.9325 2.5825 9 P 0 ;1
L 8.9325 2.6325 8.9325 2.6325 9 P 0 ;1
L 8.9325 2.6825 8.9325 2.6825 9 P 0 ;1
L 8.9325 3.0325 8.9325 3.0325 9 P 0 ;1
L 8.9325 3.0825 8.9325 3.0825 9 P 0 ;1
L 8.9325 3.1325 8.9325 3.1325 9 P 0 ;1
L 8.9325 3.1825 8.9325 3.1825 9 P 0 ;1
L 8.9325 3.2325 8.9325 3.2325 9 P 0 ;1
L 8.9325 3.2825 8.9325 3.2825 9 P 0 ;1
L 8.9325 3.3325 8.9325 3.3325 9 P 0 ;1
L 8.9325 3.3825 8.9325 3.3825 9 P 0 ;1
L 8.9325 3.4325 8.9325 3.4325 9 P 0 ;1
L 8.9325 3.4825 8.9325 3.4825 9 P 0 ;1
L 8.9325 3.5325 8.9325 3.5325 9 P 0 ;1
L 8.9325 3.5825 8.9325 3.5825 9 P 0 ;1
L 8.9325 3.6325 8.9325 3.6325 9 P 0 ;1
L 8.9325 3.6825 8.9325 3.6825 9 P 0 ;1
L 8.9325 3.7325 8.9325 3.7325 9 P 0 ;1
L 8.9325 3.7825 8.9325 3.7825 9 P 0 ;1
L 8.9325 3.8325 8.9325 3.8325 9 P 0 ;1
L 8.9325 3.8825 8.9325 3.8825 9 P 0 ;1
L 8.9325 3.9325 8.9325 3.9325 9 P 0 ;1
L 8.9325 3.9825 8.9325 3.9825 9 P 0 ;1
L 8.9325 4.0325 8.9325 4.0325 9 P 0 ;1
L 8.9325 4.0825 8.9325 4.0825 9 P 0 ;1
L 8.9325 4.1325 8.9325 4.1325 9 P 0 ;1
L 8.9325 4.1825 8.9325 4.1825 9 P 0 ;1
L 8.9325 4.2325 8.9325 4.2325 9 P 0 ;1
L 8.9325 4.2825 8.9325 4.2825 9 P 0 ;1
L 8.9325 4.3325 8.9325 4.3325 9 P 0 ;1
L 8.9325 4.3825 8.9325 4.3825 9 P 0 ;1
L 8.9325 4.4325 8.9325 4.4325 9 P 0 ;1
L 8.9325 4.4825 8.9325 4.4825 9 P 0 ;1
L 8.9325 4.5325 8.9325 4.5325 9 P 0 ;1
L 8.9325 4.5825 8.9325 4.5825 9 P 0 ;1
L 8.9325 5.3325 8.9325 5.3325 9 P 0 ;1
L 8.9325 5.3825 8.9325 5.3825 9 P 0 ;1
L 8.9325 5.4325 8.9325 5.4325 9 P 0 ;1
L 8.9325 5.4825 8.9325 5.4825 9 P 0 ;1
L 8.9325 5.5325 8.9325 5.5325 9 P 0 ;1
L 8.9325 5.5825 8.9325 5.5825 9 P 0 ;1
L 8.9325 5.6325 8.9325 5.6325 9 P 0 ;1
L 8.9325 5.6825 8.9325 5.6825 9 P 0 ;1
L 8.9325 5.7325 8.9325 5.7325 9 P 0 ;1
L 8.9325 5.7825 8.9325 5.7825 9 P 0 ;1
L 8.9325 5.8325 8.9325 5.8325 9 P 0 ;1
L 8.9325 5.8825 8.9325 5.8825 9 P 0 ;1
L 8.9825 0.1325 8.9825 0.1325 9 P 0 ;1
L 8.9825 0.1825 8.9825 0.1825 9 P 0 ;1
L 8.9825 0.2325 8.9825 0.2325 9 P 0 ;1
L 8.9825 0.2825 8.9825 0.2825 9 P 0 ;1
L 8.9825 0.3325 8.9825 0.3325 9 P 0 ;1
L 8.9825 0.3825 8.9825 0.3825 9 P 0 ;1
L 8.9825 0.4325 8.9825 0.4325 9 P 0 ;1
L 8.9825 0.4825 8.9825 0.4825 9 P 0 ;1
L 8.9825 0.5325 8.9825 0.5325 9 P 0 ;1
L 8.9825 0.5825 8.9825 0.5825 9 P 0 ;1
L 8.9825 0.6325 8.9825 0.6325 9 P 0 ;1
L 8.9825 0.6825 8.9825 0.6825 9 P 0 ;1
L 8.9825 0.7325 8.9825 0.7325 9 P 0 ;1
L 8.9825 0.7825 8.9825 0.7825 9 P 0 ;1
L 8.9825 0.8325 8.9825 0.8325 9 P 0 ;1
L 8.9825 0.8825 8.9825 0.8825 9 P 0 ;1
L 8.9825 0.9325 8.9825 0.9325 9 P 0 ;1
L 8.9825 0.9825 8.9825 0.9825 9 P 0 ;1
L 8.9825 1.0325 8.9825 1.0325 9 P 0 ;1
L 8.9825 1.0825 8.9825 1.0825 9 P 0 ;1
L 8.9825 1.1325 8.9825 1.1325 9 P 0 ;1
L 8.9825 1.1825 8.9825 1.1825 9 P 0 ;1
L 8.9825 1.2325 8.9825 1.2325 9 P 0 ;1
L 8.9825 1.2825 8.9825 1.2825 9 P 0 ;1
L 8.9825 1.3325 8.9825 1.3325 9 P 0 ;1
L 8.9825 1.3825 8.9825 1.3825 9 P 0 ;1
L 8.9825 1.4325 8.9825 1.4325 9 P 0 ;1
L 8.9825 1.4825 8.9825 1.4825 9 P 0 ;1
L 8.9825 1.5325 8.9825 1.5325 9 P 0 ;1
L 8.9825 1.5825 8.9825 1.5825 9 P 0 ;1
L 8.9825 1.6325 8.9825 1.6325 9 P 0 ;1
L 8.9825 1.6825 8.9825 1.6825 9 P 0 ;1
L 8.9825 1.7325 8.9825 1.7325 9 P 0 ;1
L 8.9825 1.7825 8.9825 1.7825 9 P 0 ;1
L 8.9825 1.8325 8.9825 1.8325 9 P 0 ;1
L 8.9825 1.8825 8.9825 1.8825 9 P 0 ;1
L 8.9825 1.9325 8.9825 1.9325 9 P 0 ;1
L 8.9825 1.9825 8.9825 1.9825 9 P 0 ;1
L 8.9825 2.0325 8.9825 2.0325 9 P 0 ;1
L 8.9825 2.0825 8.9825 2.0825 9 P 0 ;1
L 8.9825 2.1325 8.9825 2.1325 9 P 0 ;1
L 8.9825 2.1825 8.9825 2.1825 9 P 0 ;1
L 8.9825 2.2325 8.9825 2.2325 9 P 0 ;1
L 8.9825 2.2825 8.9825 2.2825 9 P 0 ;1
L 8.9825 2.3325 8.9825 2.3325 9 P 0 ;1
L 8.9825 2.3825 8.9825 2.3825 9 P 0 ;1
L 8.9825 2.4325 8.9825 2.4325 9 P 0 ;1
L 8.9825 2.4825 8.9825 2.4825 9 P 0 ;1
L 8.9825 2.5325 8.9825 2.5325 9 P 0 ;1
L 8.9825 2.5825 8.9825 2.5825 9 P 0 ;1
L 8.9825 2.6325 8.9825 2.6325 9 P 0 ;1
L 8.9825 2.6825 8.9825 2.6825 9 P 0 ;1
L 8.9825 3.0325 8.9825 3.0325 9 P 0 ;1
L 8.9825 3.0825 8.9825 3.0825 9 P 0 ;1
L 8.9825 3.1325 8.9825 3.1325 9 P 0 ;1
L 8.9825 3.1825 8.9825 3.1825 9 P 0 ;1
L 8.9825 3.2325 8.9825 3.2325 9 P 0 ;1
L 8.9825 3.2825 8.9825 3.2825 9 P 0 ;1
L 8.9825 3.3325 8.9825 3.3325 9 P 0 ;1
L 8.9825 3.3825 8.9825 3.3825 9 P 0 ;1
L 8.9825 3.4325 8.9825 3.4325 9 P 0 ;1
L 8.9825 3.4825 8.9825 3.4825 9 P 0 ;1
L 8.9825 3.5325 8.9825 3.5325 9 P 0 ;1
L 8.9825 3.5825 8.9825 3.5825 9 P 0 ;1
L 8.9825 3.6325 8.9825 3.6325 9 P 0 ;1
L 8.9825 3.6825 8.9825 3.6825 9 P 0 ;1
L 8.9825 3.7325 8.9825 3.7325 9 P 0 ;1
L 8.9825 3.7825 8.9825 3.7825 9 P 0 ;1
L 8.9825 3.8325 8.9825 3.8325 9 P 0 ;1
L 8.9825 3.8825 8.9825 3.8825 9 P 0 ;1
L 8.9825 3.9325 8.9825 3.9325 9 P 0 ;1
L 8.9825 3.9825 8.9825 3.9825 9 P 0 ;1
L 8.9825 4.0325 8.9825 4.0325 9 P 0 ;1
L 8.9825 4.0825 8.9825 4.0825 9 P 0 ;1
L 8.9825 4.1325 8.9825 4.1325 9 P 0 ;1
L 8.9825 4.1825 8.9825 4.1825 9 P 0 ;1
L 8.9825 4.2325 8.9825 4.2325 9 P 0 ;1
L 8.9825 4.2825 8.9825 4.2825 9 P 0 ;1
L 8.9825 4.3325 8.9825 4.3325 9 P 0 ;1
L 8.9825 4.3825 8.9825 4.3825 9 P 0 ;1
L 8.9825 4.4325 8.9825 4.4325 9 P 0 ;1
L 8.9825 4.4825 8.9825 4.4825 9 P 0 ;1
L 8.9825 4.5325 8.9825 4.5325 9 P 0 ;1
L 8.9825 4.5825 8.9825 4.5825 9 P 0 ;1
L 8.9825 5.2825 8.9825 5.2825 9 P 0 ;1
L 8.9825 5.3325 8.9825 5.3325 9 P 0 ;1
L 8.9825 5.3825 8.9825 5.3825 9 P 0 ;1
L 8.9825 5.4325 8.9825 5.4325 9 P 0 ;1
L 8.9825 5.4825 8.9825 5.4825 9 P 0 ;1
L 8.9825 5.5325 8.9825 5.5325 9 P 0 ;1
L 8.9825 5.5825 8.9825 5.5825 9 P 0 ;1
L 8.9825 5.6325 8.9825 5.6325 9 P 0 ;1
L 8.9825 5.6825 8.9825 5.6825 9 P 0 ;1
L 8.9825 5.7325 8.9825 5.7325 9 P 0 ;1
L 8.9825 5.7825 8.9825 5.7825 9 P 0 ;1
L 8.9825 5.8325 8.9825 5.8325 9 P 0 ;1
L 8.9825 5.8825 8.9825 5.8825 9 P 0 ;1
L 9.0325 0.1325 9.0325 0.1325 9 P 0 ;1
L 9.0325 0.1825 9.0325 0.1825 9 P 0 ;1
L 9.0325 0.2325 9.0325 0.2325 9 P 0 ;1
L 9.0325 0.2825 9.0325 0.2825 9 P 0 ;1
L 9.0325 0.3325 9.0325 0.3325 9 P 0 ;1
L 9.0325 0.3825 9.0325 0.3825 9 P 0 ;1
L 9.0325 0.4325 9.0325 0.4325 9 P 0 ;1
L 9.0325 0.4825 9.0325 0.4825 9 P 0 ;1
L 9.0325 0.5325 9.0325 0.5325 9 P 0 ;1
L 9.0325 0.5825 9.0325 0.5825 9 P 0 ;1
L 9.0325 0.6325 9.0325 0.6325 9 P 0 ;1
L 9.0325 0.6825 9.0325 0.6825 9 P 0 ;1
L 9.0325 0.7325 9.0325 0.7325 9 P 0 ;1
L 9.0325 0.7825 9.0325 0.7825 9 P 0 ;1
L 9.0325 0.8325 9.0325 0.8325 9 P 0 ;1
L 9.0325 0.8825 9.0325 0.8825 9 P 0 ;1
L 9.0325 0.9325 9.0325 0.9325 9 P 0 ;1
L 9.0325 0.9825 9.0325 0.9825 9 P 0 ;1
L 9.0325 1.0325 9.0325 1.0325 9 P 0 ;1
L 9.0325 1.0825 9.0325 1.0825 9 P 0 ;1
L 9.0325 1.1325 9.0325 1.1325 9 P 0 ;1
L 9.0325 1.1825 9.0325 1.1825 9 P 0 ;1
L 9.0325 1.2325 9.0325 1.2325 9 P 0 ;1
L 9.0325 1.2825 9.0325 1.2825 9 P 0 ;1
L 9.0325 1.3325 9.0325 1.3325 9 P 0 ;1
L 9.0325 1.3825 9.0325 1.3825 9 P 0 ;1
L 9.0325 1.4325 9.0325 1.4325 9 P 0 ;1
L 9.0325 1.4825 9.0325 1.4825 9 P 0 ;1
L 9.0325 1.5325 9.0325 1.5325 9 P 0 ;1
L 9.0325 1.5825 9.0325 1.5825 9 P 0 ;1
L 9.0325 1.6325 9.0325 1.6325 9 P 0 ;1
L 9.0325 1.6825 9.0325 1.6825 9 P 0 ;1
L 9.0325 1.7325 9.0325 1.7325 9 P 0 ;1
L 9.0325 1.7825 9.0325 1.7825 9 P 0 ;1
L 9.0325 1.8325 9.0325 1.8325 9 P 0 ;1
L 9.0325 1.8825 9.0325 1.8825 9 P 0 ;1
L 9.0325 1.9325 9.0325 1.9325 9 P 0 ;1
L 9.0325 1.9825 9.0325 1.9825 9 P 0 ;1
L 9.0325 2.0325 9.0325 2.0325 9 P 0 ;1
L 9.0325 2.0825 9.0325 2.0825 9 P 0 ;1
L 9.0325 2.1325 9.0325 2.1325 9 P 0 ;1
L 9.0325 2.1825 9.0325 2.1825 9 P 0 ;1
L 9.0325 2.2325 9.0325 2.2325 9 P 0 ;1
L 9.0325 2.2825 9.0325 2.2825 9 P 0 ;1
L 9.0325 2.3325 9.0325 2.3325 9 P 0 ;1
L 9.0325 2.3825 9.0325 2.3825 9 P 0 ;1
L 9.0325 2.4325 9.0325 2.4325 9 P 0 ;1
L 9.0325 2.4825 9.0325 2.4825 9 P 0 ;1
L 9.0325 2.5325 9.0325 2.5325 9 P 0 ;1
L 9.0325 2.5825 9.0325 2.5825 9 P 0 ;1
L 9.0325 2.6325 9.0325 2.6325 9 P 0 ;1
L 9.0325 2.6825 9.0325 2.6825 9 P 0 ;1
L 9.0325 2.9825 9.0325 2.9825 9 P 0 ;1
L 9.0325 3.0325 9.0325 3.0325 9 P 0 ;1
L 9.0325 3.0825 9.0325 3.0825 9 P 0 ;1
L 9.0325 3.1325 9.0325 3.1325 9 P 0 ;1
L 9.0325 3.1825 9.0325 3.1825 9 P 0 ;1
L 9.0325 3.2325 9.0325 3.2325 9 P 0 ;1
L 9.0325 3.2825 9.0325 3.2825 9 P 0 ;1
L 9.0325 3.3325 9.0325 3.3325 9 P 0 ;1
L 9.0325 3.3825 9.0325 3.3825 9 P 0 ;1
L 9.0325 3.4325 9.0325 3.4325 9 P 0 ;1
L 9.0325 3.4825 9.0325 3.4825 9 P 0 ;1
L 9.0325 3.5325 9.0325 3.5325 9 P 0 ;1
L 9.0325 3.5825 9.0325 3.5825 9 P 0 ;1
L 9.0325 3.6325 9.0325 3.6325 9 P 0 ;1
L 9.0325 3.6825 9.0325 3.6825 9 P 0 ;1
L 9.0325 3.7325 9.0325 3.7325 9 P 0 ;1
L 9.0325 3.7825 9.0325 3.7825 9 P 0 ;1
L 9.0325 3.8325 9.0325 3.8325 9 P 0 ;1
L 9.0325 3.8825 9.0325 3.8825 9 P 0 ;1
L 9.0325 3.9325 9.0325 3.9325 9 P 0 ;1
L 9.0325 3.9825 9.0325 3.9825 9 P 0 ;1
L 9.0325 4.0325 9.0325 4.0325 9 P 0 ;1
L 9.0325 4.0825 9.0325 4.0825 9 P 0 ;1
L 9.0325 4.1325 9.0325 4.1325 9 P 0 ;1
L 9.0325 4.1825 9.0325 4.1825 9 P 0 ;1
L 9.0325 4.2325 9.0325 4.2325 9 P 0 ;1
L 9.0325 4.2825 9.0325 4.2825 9 P 0 ;1
L 9.0325 4.3325 9.0325 4.3325 9 P 0 ;1
L 9.0325 4.5325 9.0325 4.5325 9 P 0 ;1
L 9.0325 4.5825 9.0325 4.5825 9 P 0 ;1
L 9.0325 5.4325 9.0325 5.4325 9 P 0 ;1
L 9.0325 5.4825 9.0325 5.4825 9 P 0 ;1
L 9.0325 5.5325 9.0325 5.5325 9 P 0 ;1
L 9.0325 5.5825 9.0325 5.5825 9 P 0 ;1
L 9.0325 5.6325 9.0325 5.6325 9 P 0 ;1
L 9.0325 5.6825 9.0325 5.6825 9 P 0 ;1
L 9.0325 5.7325 9.0325 5.7325 9 P 0 ;1
L 9.0325 5.7825 9.0325 5.7825 9 P 0 ;1
L 9.0325 5.8325 9.0325 5.8325 9 P 0 ;1
L 9.0325 5.8825 9.0325 5.8825 9 P 0 ;1
L 9.0825 0.1325 9.0825 0.1325 9 P 0 ;1
L 9.0825 0.1825 9.0825 0.1825 9 P 0 ;1
L 9.0825 0.2325 9.0825 0.2325 9 P 0 ;1
L 9.0825 0.2825 9.0825 0.2825 9 P 0 ;1
L 9.0825 0.3325 9.0825 0.3325 9 P 0 ;1
L 9.0825 0.3825 9.0825 0.3825 9 P 0 ;1
L 9.0825 0.4325 9.0825 0.4325 9 P 0 ;1
L 9.0825 0.4825 9.0825 0.4825 9 P 0 ;1
L 9.0825 0.5325 9.0825 0.5325 9 P 0 ;1
L 9.0825 0.5825 9.0825 0.5825 9 P 0 ;1
L 9.0825 0.6325 9.0825 0.6325 9 P 0 ;1
L 9.0825 0.6825 9.0825 0.6825 9 P 0 ;1
L 9.0825 0.7325 9.0825 0.7325 9 P 0 ;1
L 9.0825 0.7825 9.0825 0.7825 9 P 0 ;1
L 9.0825 0.8325 9.0825 0.8325 9 P 0 ;1
L 9.0825 0.8825 9.0825 0.8825 9 P 0 ;1
L 9.0825 0.9325 9.0825 0.9325 9 P 0 ;1
L 9.0825 0.9825 9.0825 0.9825 9 P 0 ;1
L 9.0825 1.0325 9.0825 1.0325 9 P 0 ;1
L 9.0825 1.0825 9.0825 1.0825 9 P 0 ;1
L 9.0825 1.1325 9.0825 1.1325 9 P 0 ;1
L 9.0825 1.1825 9.0825 1.1825 9 P 0 ;1
L 9.0825 1.2325 9.0825 1.2325 9 P 0 ;1
L 9.0825 1.2825 9.0825 1.2825 9 P 0 ;1
L 9.0825 1.3325 9.0825 1.3325 9 P 0 ;1
L 9.0825 1.3825 9.0825 1.3825 9 P 0 ;1
L 9.0825 1.4325 9.0825 1.4325 9 P 0 ;1
L 9.0825 1.4825 9.0825 1.4825 9 P 0 ;1
L 9.0825 1.5325 9.0825 1.5325 9 P 0 ;1
L 9.0825 1.5825 9.0825 1.5825 9 P 0 ;1
L 9.0825 1.6325 9.0825 1.6325 9 P 0 ;1
L 9.0825 1.6825 9.0825 1.6825 9 P 0 ;1
L 9.0825 1.7325 9.0825 1.7325 9 P 0 ;1
L 9.0825 1.7825 9.0825 1.7825 9 P 0 ;1
L 9.0825 1.8325 9.0825 1.8325 9 P 0 ;1
L 9.0825 1.8825 9.0825 1.8825 9 P 0 ;1
L 9.0825 1.9325 9.0825 1.9325 9 P 0 ;1
L 9.0825 1.9825 9.0825 1.9825 9 P 0 ;1
L 9.0825 2.0325 9.0825 2.0325 9 P 0 ;1
L 9.0825 2.0825 9.0825 2.0825 9 P 0 ;1
L 9.0825 2.1325 9.0825 2.1325 9 P 0 ;1
L 9.0825 2.1825 9.0825 2.1825 9 P 0 ;1
L 9.0825 2.2325 9.0825 2.2325 9 P 0 ;1
L 9.0825 2.2825 9.0825 2.2825 9 P 0 ;1
L 9.0825 2.3325 9.0825 2.3325 9 P 0 ;1
L 9.0825 2.3825 9.0825 2.3825 9 P 0 ;1
L 9.0825 2.4325 9.0825 2.4325 9 P 0 ;1
L 9.0825 2.4825 9.0825 2.4825 9 P 0 ;1
L 9.0825 2.5325 9.0825 2.5325 9 P 0 ;1
L 9.0825 2.5825 9.0825 2.5825 9 P 0 ;1
L 9.0825 2.6325 9.0825 2.6325 9 P 0 ;1
L 9.0825 2.6825 9.0825 2.6825 9 P 0 ;1
L 9.0825 2.7325 9.0825 2.7325 9 P 0 ;1
L 9.0825 2.7825 9.0825 2.7825 9 P 0 ;1
L 9.0825 2.8325 9.0825 2.8325 9 P 0 ;1
L 9.0825 2.8825 9.0825 2.8825 9 P 0 ;1
L 9.0825 2.9325 9.0825 2.9325 9 P 0 ;1
L 9.0825 2.9825 9.0825 2.9825 9 P 0 ;1
L 9.0825 3.0325 9.0825 3.0325 9 P 0 ;1
L 9.0825 3.0825 9.0825 3.0825 9 P 0 ;1
L 9.0825 3.1325 9.0825 3.1325 9 P 0 ;1
L 9.0825 3.1825 9.0825 3.1825 9 P 0 ;1
L 9.0825 3.2325 9.0825 3.2325 9 P 0 ;1
L 9.0825 3.2825 9.0825 3.2825 9 P 0 ;1
L 9.0825 3.3325 9.0825 3.3325 9 P 0 ;1
L 9.0825 3.3825 9.0825 3.3825 9 P 0 ;1
L 9.0825 3.4325 9.0825 3.4325 9 P 0 ;1
L 9.0825 3.4825 9.0825 3.4825 9 P 0 ;1
L 9.0825 3.5325 9.0825 3.5325 9 P 0 ;1
L 9.0825 3.5825 9.0825 3.5825 9 P 0 ;1
L 9.0825 3.6325 9.0825 3.6325 9 P 0 ;1
L 9.0825 3.6825 9.0825 3.6825 9 P 0 ;1
L 9.0825 3.7325 9.0825 3.7325 9 P 0 ;1
L 9.0825 3.7825 9.0825 3.7825 9 P 0 ;1
L 9.0825 3.8325 9.0825 3.8325 9 P 0 ;1
L 9.0825 3.8825 9.0825 3.8825 9 P 0 ;1
L 9.0825 3.9325 9.0825 3.9325 9 P 0 ;1
L 9.0825 3.9825 9.0825 3.9825 9 P 0 ;1
L 9.0825 4.0325 9.0825 4.0325 9 P 0 ;1
L 9.0825 4.0825 9.0825 4.0825 9 P 0 ;1
L 9.0825 4.1325 9.0825 4.1325 9 P 0 ;1
L 9.0825 4.1825 9.0825 4.1825 9 P 0 ;1
L 9.0825 4.2325 9.0825 4.2325 9 P 0 ;1
L 9.0825 4.2825 9.0825 4.2825 9 P 0 ;1
L 9.0825 4.3325 9.0825 4.3325 9 P 0 ;1
L 9.0825 4.5825 9.0825 4.5825 9 P 0 ;1
L 9.0825 5.4325 9.0825 5.4325 9 P 0 ;1
L 9.0825 5.4825 9.0825 5.4825 9 P 0 ;1
L 9.0825 5.5325 9.0825 5.5325 9 P 0 ;1
L 9.0825 5.5825 9.0825 5.5825 9 P 0 ;1
L 9.0825 5.6325 9.0825 5.6325 9 P 0 ;1
L 9.0825 5.6825 9.0825 5.6825 9 P 0 ;1
L 9.0825 5.7325 9.0825 5.7325 9 P 0 ;1
L 9.0825 5.7825 9.0825 5.7825 9 P 0 ;1
L 9.0825 5.8325 9.0825 5.8325 9 P 0 ;1
L 9.0825 5.8825 9.0825 5.8825 9 P 0 ;1
L 9.1325 0.1325 9.1325 0.1325 9 P 0 ;1
L 9.1325 0.1825 9.1325 0.1825 9 P 0 ;1
L 9.1325 0.2325 9.1325 0.2325 9 P 0 ;1
L 9.1325 0.2825 9.1325 0.2825 9 P 0 ;1
L 9.1325 0.3325 9.1325 0.3325 9 P 0 ;1
L 9.1325 0.3825 9.1325 0.3825 9 P 0 ;1
L 9.1325 0.4325 9.1325 0.4325 9 P 0 ;1
L 9.1325 0.4825 9.1325 0.4825 9 P 0 ;1
L 9.1325 0.5325 9.1325 0.5325 9 P 0 ;1
L 9.1325 0.5825 9.1325 0.5825 9 P 0 ;1
L 9.1325 0.6325 9.1325 0.6325 9 P 0 ;1
L 9.1325 0.6825 9.1325 0.6825 9 P 0 ;1
L 9.1325 0.7325 9.1325 0.7325 9 P 0 ;1
L 9.1325 0.7825 9.1325 0.7825 9 P 0 ;1
L 9.1325 0.8325 9.1325 0.8325 9 P 0 ;1
L 9.1325 0.8825 9.1325 0.8825 9 P 0 ;1
L 9.1325 0.9325 9.1325 0.9325 9 P 0 ;1
L 9.1325 0.9825 9.1325 0.9825 9 P 0 ;1
L 9.1325 1.0325 9.1325 1.0325 9 P 0 ;1
L 9.1325 1.0825 9.1325 1.0825 9 P 0 ;1
L 9.1325 1.1325 9.1325 1.1325 9 P 0 ;1
L 9.1325 1.1825 9.1325 1.1825 9 P 0 ;1
L 9.1325 1.2325 9.1325 1.2325 9 P 0 ;1
L 9.1325 1.2825 9.1325 1.2825 9 P 0 ;1
L 9.1325 1.3325 9.1325 1.3325 9 P 0 ;1
L 9.1325 1.3825 9.1325 1.3825 9 P 0 ;1
L 9.1325 1.4325 9.1325 1.4325 9 P 0 ;1
L 9.1325 1.4825 9.1325 1.4825 9 P 0 ;1
L 9.1325 1.5325 9.1325 1.5325 9 P 0 ;1
L 9.1325 1.5825 9.1325 1.5825 9 P 0 ;1
L 9.1325 1.6325 9.1325 1.6325 9 P 0 ;1
L 9.1325 1.6825 9.1325 1.6825 9 P 0 ;1
L 9.1325 1.7325 9.1325 1.7325 9 P 0 ;1
L 9.1325 1.7825 9.1325 1.7825 9 P 0 ;1
L 9.1325 1.8325 9.1325 1.8325 9 P 0 ;1
L 9.1325 1.8825 9.1325 1.8825 9 P 0 ;1
L 9.1325 1.9325 9.1325 1.9325 9 P 0 ;1
L 9.1325 1.9825 9.1325 1.9825 9 P 0 ;1
L 9.1325 2.0325 9.1325 2.0325 9 P 0 ;1
L 9.1325 2.0825 9.1325 2.0825 9 P 0 ;1
L 9.1325 2.1325 9.1325 2.1325 9 P 0 ;1
L 9.1325 2.1825 9.1325 2.1825 9 P 0 ;1
L 9.1325 2.2325 9.1325 2.2325 9 P 0 ;1
L 9.1325 2.2825 9.1325 2.2825 9 P 0 ;1
L 9.1325 2.3325 9.1325 2.3325 9 P 0 ;1
L 9.1325 2.3825 9.1325 2.3825 9 P 0 ;1
L 9.1325 2.4325 9.1325 2.4325 9 P 0 ;1
L 9.1325 2.4825 9.1325 2.4825 9 P 0 ;1
L 9.1325 2.5325 9.1325 2.5325 9 P 0 ;1
L 9.1325 2.5825 9.1325 2.5825 9 P 0 ;1
L 9.1325 2.6325 9.1325 2.6325 9 P 0 ;1
L 9.1325 2.6825 9.1325 2.6825 9 P 0 ;1
L 9.1325 2.7325 9.1325 2.7325 9 P 0 ;1
L 9.1325 2.7825 9.1325 2.7825 9 P 0 ;1
L 9.1325 2.8325 9.1325 2.8325 9 P 0 ;1
L 9.1325 2.8825 9.1325 2.8825 9 P 0 ;1
L 9.1325 2.9325 9.1325 2.9325 9 P 0 ;1
L 9.1325 2.9825 9.1325 2.9825 9 P 0 ;1
L 9.1325 3.0325 9.1325 3.0325 9 P 0 ;1
L 9.1325 3.0825 9.1325 3.0825 9 P 0 ;1
L 9.1325 3.1325 9.1325 3.1325 9 P 0 ;1
L 9.1325 3.1825 9.1325 3.1825 9 P 0 ;1
L 9.1325 3.2325 9.1325 3.2325 9 P 0 ;1
L 9.1325 3.2825 9.1325 3.2825 9 P 0 ;1
L 9.1325 3.3325 9.1325 3.3325 9 P 0 ;1
L 9.1325 3.3825 9.1325 3.3825 9 P 0 ;1
L 9.1325 3.4325 9.1325 3.4325 9 P 0 ;1
L 9.1325 3.4825 9.1325 3.4825 9 P 0 ;1
L 9.1325 3.5325 9.1325 3.5325 9 P 0 ;1
L 9.1325 3.5825 9.1325 3.5825 9 P 0 ;1
L 9.1325 3.6325 9.1325 3.6325 9 P 0 ;1
L 9.1325 3.6825 9.1325 3.6825 9 P 0 ;1
L 9.1325 3.7325 9.1325 3.7325 9 P 0 ;1
L 9.1325 3.7825 9.1325 3.7825 9 P 0 ;1
L 9.1325 3.8325 9.1325 3.8325 9 P 0 ;1
L 9.1325 3.8825 9.1325 3.8825 9 P 0 ;1
L 9.1325 3.9325 9.1325 3.9325 9 P 0 ;1
L 9.1325 3.9825 9.1325 3.9825 9 P 0 ;1
L 9.1325 4.0325 9.1325 4.0325 9 P 0 ;1
L 9.1325 4.0825 9.1325 4.0825 9 P 0 ;1
L 9.1325 4.1325 9.1325 4.1325 9 P 0 ;1
L 9.1325 4.1825 9.1325 4.1825 9 P 0 ;1
L 9.1325 4.2325 9.1325 4.2325 9 P 0 ;1
L 9.1325 4.2825 9.1325 4.2825 9 P 0 ;1
L 9.1325 4.3325 9.1325 4.3325 9 P 0 ;1
L 9.1325 4.5825 9.1325 4.5825 9 P 0 ;1
L 9.1325 5.4325 9.1325 5.4325 9 P 0 ;1
L 9.1325 5.4825 9.1325 5.4825 9 P 0 ;1
L 9.1325 5.5325 9.1325 5.5325 9 P 0 ;1
L 9.1325 5.5825 9.1325 5.5825 9 P 0 ;1
L 9.1325 5.6325 9.1325 5.6325 9 P 0 ;1
L 9.1325 5.6825 9.1325 5.6825 9 P 0 ;1
L 9.1325 5.7325 9.1325 5.7325 9 P 0 ;1
L 9.1325 5.7825 9.1325 5.7825 9 P 0 ;1
L 9.1325 5.8325 9.1325 5.8325 9 P 0 ;1
L 9.1325 5.8825 9.1325 5.8825 9 P 0 ;1
L 9.1825 0.1325 9.1825 0.1325 9 P 0 ;1
L 9.1825 0.1825 9.1825 0.1825 9 P 0 ;1
L 9.1825 0.2325 9.1825 0.2325 9 P 0 ;1
L 9.1825 0.2825 9.1825 0.2825 9 P 0 ;1
L 9.1825 0.3325 9.1825 0.3325 9 P 0 ;1
L 9.1825 0.3825 9.1825 0.3825 9 P 0 ;1
L 9.1825 0.4325 9.1825 0.4325 9 P 0 ;1
L 9.1825 0.4825 9.1825 0.4825 9 P 0 ;1
L 9.1825 0.5325 9.1825 0.5325 9 P 0 ;1
L 9.1825 0.5825 9.1825 0.5825 9 P 0 ;1
L 9.1825 0.6325 9.1825 0.6325 9 P 0 ;1
L 9.1825 0.6825 9.1825 0.6825 9 P 0 ;1
L 9.1825 0.7325 9.1825 0.7325 9 P 0 ;1
L 9.1825 0.7825 9.1825 0.7825 9 P 0 ;1
L 9.1825 0.8325 9.1825 0.8325 9 P 0 ;1
L 9.1825 0.8825 9.1825 0.8825 9 P 0 ;1
L 9.1825 0.9325 9.1825 0.9325 9 P 0 ;1
L 9.1825 0.9825 9.1825 0.9825 9 P 0 ;1
L 9.1825 1.0325 9.1825 1.0325 9 P 0 ;1
L 9.1825 1.0825 9.1825 1.0825 9 P 0 ;1
L 9.1825 1.1325 9.1825 1.1325 9 P 0 ;1
L 9.1825 1.1825 9.1825 1.1825 9 P 0 ;1
L 9.1825 1.2325 9.1825 1.2325 9 P 0 ;1
L 9.1825 1.2825 9.1825 1.2825 9 P 0 ;1
L 9.1825 1.3325 9.1825 1.3325 9 P 0 ;1
L 9.1825 1.3825 9.1825 1.3825 9 P 0 ;1
L 9.1825 1.4325 9.1825 1.4325 9 P 0 ;1
L 9.1825 1.4825 9.1825 1.4825 9 P 0 ;1
L 9.1825 1.5325 9.1825 1.5325 9 P 0 ;1
L 9.1825 1.5825 9.1825 1.5825 9 P 0 ;1
L 9.1825 1.6325 9.1825 1.6325 9 P 0 ;1
L 9.1825 1.6825 9.1825 1.6825 9 P 0 ;1
L 9.1825 1.7325 9.1825 1.7325 9 P 0 ;1
L 9.1825 1.7825 9.1825 1.7825 9 P 0 ;1
L 9.1825 1.8325 9.1825 1.8325 9 P 0 ;1
L 9.1825 1.8825 9.1825 1.8825 9 P 0 ;1
L 9.1825 1.9325 9.1825 1.9325 9 P 0 ;1
L 9.1825 1.9825 9.1825 1.9825 9 P 0 ;1
L 9.1825 2.0325 9.1825 2.0325 9 P 0 ;1
L 9.1825 2.0825 9.1825 2.0825 9 P 0 ;1
L 9.1825 2.1325 9.1825 2.1325 9 P 0 ;1
L 9.1825 2.1825 9.1825 2.1825 9 P 0 ;1
L 9.1825 2.2325 9.1825 2.2325 9 P 0 ;1
L 9.1825 2.2825 9.1825 2.2825 9 P 0 ;1
L 9.1825 2.3325 9.1825 2.3325 9 P 0 ;1
L 9.1825 2.3825 9.1825 2.3825 9 P 0 ;1
L 9.1825 2.4325 9.1825 2.4325 9 P 0 ;1
L 9.1825 2.4825 9.1825 2.4825 9 P 0 ;1
L 9.1825 2.5325 9.1825 2.5325 9 P 0 ;1
L 9.1825 2.5825 9.1825 2.5825 9 P 0 ;1
L 9.1825 2.6325 9.1825 2.6325 9 P 0 ;1
L 9.1825 2.6825 9.1825 2.6825 9 P 0 ;1
L 9.1825 2.7325 9.1825 2.7325 9 P 0 ;1
L 9.1825 2.7825 9.1825 2.7825 9 P 0 ;1
L 9.1825 2.8325 9.1825 2.8325 9 P 0 ;1
L 9.1825 2.8825 9.1825 2.8825 9 P 0 ;1
L 9.1825 2.9325 9.1825 2.9325 9 P 0 ;1
L 9.1825 2.9825 9.1825 2.9825 9 P 0 ;1
L 9.1825 3.0325 9.1825 3.0325 9 P 0 ;1
L 9.1825 3.0825 9.1825 3.0825 9 P 0 ;1
L 9.1825 3.1325 9.1825 3.1325 9 P 0 ;1
L 9.1825 3.1825 9.1825 3.1825 9 P 0 ;1
L 9.1825 3.2325 9.1825 3.2325 9 P 0 ;1
L 9.1825 3.2825 9.1825 3.2825 9 P 0 ;1
L 9.1825 3.3325 9.1825 3.3325 9 P 0 ;1
L 9.1825 3.3825 9.1825 3.3825 9 P 0 ;1
L 9.1825 3.4325 9.1825 3.4325 9 P 0 ;1
L 9.1825 3.4825 9.1825 3.4825 9 P 0 ;1
L 9.1825 3.5325 9.1825 3.5325 9 P 0 ;1
L 9.1825 3.5825 9.1825 3.5825 9 P 0 ;1
L 9.1825 3.6325 9.1825 3.6325 9 P 0 ;1
L 9.1825 3.6825 9.1825 3.6825 9 P 0 ;1
L 9.1825 3.7325 9.1825 3.7325 9 P 0 ;1
L 9.1825 3.7825 9.1825 3.7825 9 P 0 ;1
L 9.1825 3.8325 9.1825 3.8325 9 P 0 ;1
L 9.1825 3.8825 9.1825 3.8825 9 P 0 ;1
L 9.1825 3.9325 9.1825 3.9325 9 P 0 ;1
L 9.1825 3.9825 9.1825 3.9825 9 P 0 ;1
L 9.1825 4.0325 9.1825 4.0325 9 P 0 ;1
L 9.1825 4.0825 9.1825 4.0825 9 P 0 ;1
L 9.1825 4.1325 9.1825 4.1325 9 P 0 ;1
L 9.1825 4.1825 9.1825 4.1825 9 P 0 ;1
L 9.1825 4.2325 9.1825 4.2325 9 P 0 ;1
L 9.1825 4.2825 9.1825 4.2825 9 P 0 ;1
L 9.1825 4.3325 9.1825 4.3325 9 P 0 ;1
L 9.1825 4.3825 9.1825 4.3825 9 P 0 ;1
L 9.1825 4.4325 9.1825 4.4325 9 P 0 ;1
L 9.1825 4.5325 9.1825 4.5325 9 P 0 ;1
L 9.1825 4.5825 9.1825 4.5825 9 P 0 ;1
L 9.1825 5.3825 9.1825 5.3825 9 P 0 ;1
L 9.1825 5.4325 9.1825 5.4325 9 P 0 ;1
L 9.1825 5.4825 9.1825 5.4825 9 P 0 ;1
L 9.1825 5.5325 9.1825 5.5325 9 P 0 ;1
L 9.1825 5.5825 9.1825 5.5825 9 P 0 ;1
L 9.1825 5.6325 9.1825 5.6325 9 P 0 ;1
L 9.1825 5.6825 9.1825 5.6825 9 P 0 ;1
L 9.1825 5.7325 9.1825 5.7325 9 P 0 ;1
L 9.1825 5.7825 9.1825 5.7825 9 P 0 ;1
L 9.1825 5.8325 9.1825 5.8325 9 P 0 ;1
L 9.1825 5.8825 9.1825 5.8825 9 P 0 ;1
L 9.2325 0.1325 9.2325 0.1325 9 P 0 ;1
L 9.2325 0.1825 9.2325 0.1825 9 P 0 ;1
L 9.2325 0.2325 9.2325 0.2325 9 P 0 ;1
L 9.2325 0.2825 9.2325 0.2825 9 P 0 ;1
L 9.2325 0.3325 9.2325 0.3325 9 P 0 ;1
L 9.2325 0.3825 9.2325 0.3825 9 P 0 ;1
L 9.2325 0.4325 9.2325 0.4325 9 P 0 ;1
L 9.2325 0.4825 9.2325 0.4825 9 P 0 ;1
L 9.2325 0.5325 9.2325 0.5325 9 P 0 ;1
L 9.2325 0.5825 9.2325 0.5825 9 P 0 ;1
L 9.2325 0.6325 9.2325 0.6325 9 P 0 ;1
L 9.2325 0.6825 9.2325 0.6825 9 P 0 ;1
L 9.2325 0.7325 9.2325 0.7325 9 P 0 ;1
L 9.2325 0.7825 9.2325 0.7825 9 P 0 ;1
L 9.2325 0.8325 9.2325 0.8325 9 P 0 ;1
L 9.2325 0.8825 9.2325 0.8825 9 P 0 ;1
L 9.2325 0.9325 9.2325 0.9325 9 P 0 ;1
L 9.2325 0.9825 9.2325 0.9825 9 P 0 ;1
L 9.2325 1.0325 9.2325 1.0325 9 P 0 ;1
L 9.2325 1.0825 9.2325 1.0825 9 P 0 ;1
L 9.2325 1.1325 9.2325 1.1325 9 P 0 ;1
L 9.2325 1.1825 9.2325 1.1825 9 P 0 ;1
L 9.2325 1.2325 9.2325 1.2325 9 P 0 ;1
L 9.2325 1.2825 9.2325 1.2825 9 P 0 ;1
L 9.2325 1.3325 9.2325 1.3325 9 P 0 ;1
L 9.2325 1.3825 9.2325 1.3825 9 P 0 ;1
L 9.2325 1.4325 9.2325 1.4325 9 P 0 ;1
L 9.2325 1.4825 9.2325 1.4825 9 P 0 ;1
L 9.2325 1.5325 9.2325 1.5325 9 P 0 ;1
L 9.2325 1.5825 9.2325 1.5825 9 P 0 ;1
L 9.2325 1.6325 9.2325 1.6325 9 P 0 ;1
L 9.2325 1.6825 9.2325 1.6825 9 P 0 ;1
L 9.2325 1.7325 9.2325 1.7325 9 P 0 ;1
L 9.2325 1.7825 9.2325 1.7825 9 P 0 ;1
L 9.2325 1.8325 9.2325 1.8325 9 P 0 ;1
L 9.2325 1.8825 9.2325 1.8825 9 P 0 ;1
L 9.2325 1.9325 9.2325 1.9325 9 P 0 ;1
L 9.2325 1.9825 9.2325 1.9825 9 P 0 ;1
L 9.2325 2.0325 9.2325 2.0325 9 P 0 ;1
L 9.2325 2.0825 9.2325 2.0825 9 P 0 ;1
L 9.2325 2.1325 9.2325 2.1325 9 P 0 ;1
L 9.2325 2.1825 9.2325 2.1825 9 P 0 ;1
L 9.2325 2.2325 9.2325 2.2325 9 P 0 ;1
L 9.2325 2.2825 9.2325 2.2825 9 P 0 ;1
L 9.2325 2.3325 9.2325 2.3325 9 P 0 ;1
L 9.2325 2.3825 9.2325 2.3825 9 P 0 ;1
L 9.2325 2.4325 9.2325 2.4325 9 P 0 ;1
L 9.2325 2.4825 9.2325 2.4825 9 P 0 ;1
L 9.2325 2.5325 9.2325 2.5325 9 P 0 ;1
L 9.2325 2.5825 9.2325 2.5825 9 P 0 ;1
L 9.2325 2.6325 9.2325 2.6325 9 P 0 ;1
L 9.2325 2.6825 9.2325 2.6825 9 P 0 ;1
L 9.2325 2.7325 9.2325 2.7325 9 P 0 ;1
L 9.2325 2.7825 9.2325 2.7825 9 P 0 ;1
L 9.2325 2.8325 9.2325 2.8325 9 P 0 ;1
L 9.2325 2.8825 9.2325 2.8825 9 P 0 ;1
L 9.2325 2.9325 9.2325 2.9325 9 P 0 ;1
L 9.2325 2.9825 9.2325 2.9825 9 P 0 ;1
L 9.2325 3.0325 9.2325 3.0325 9 P 0 ;1
L 9.2325 3.0825 9.2325 3.0825 9 P 0 ;1
L 9.2325 3.1325 9.2325 3.1325 9 P 0 ;1
L 9.2325 3.1825 9.2325 3.1825 9 P 0 ;1
L 9.2325 3.2325 9.2325 3.2325 9 P 0 ;1
L 9.2325 3.2825 9.2325 3.2825 9 P 0 ;1
L 9.2325 3.3325 9.2325 3.3325 9 P 0 ;1
L 9.2325 3.3825 9.2325 3.3825 9 P 0 ;1
L 9.2325 3.4325 9.2325 3.4325 9 P 0 ;1
L 9.2325 3.4825 9.2325 3.4825 9 P 0 ;1
L 9.2325 3.5325 9.2325 3.5325 9 P 0 ;1
L 9.2325 3.5825 9.2325 3.5825 9 P 0 ;1
L 9.2325 3.6325 9.2325 3.6325 9 P 0 ;1
L 9.2325 3.6825 9.2325 3.6825 9 P 0 ;1
L 9.2325 3.7325 9.2325 3.7325 9 P 0 ;1
L 9.2325 3.7825 9.2325 3.7825 9 P 0 ;1
L 9.2325 3.8325 9.2325 3.8325 9 P 0 ;1
L 9.2325 3.8825 9.2325 3.8825 9 P 0 ;1
L 9.2325 3.9325 9.2325 3.9325 9 P 0 ;1
L 9.2325 3.9825 9.2325 3.9825 9 P 0 ;1
L 9.2325 4.0325 9.2325 4.0325 9 P 0 ;1
L 9.2325 4.0825 9.2325 4.0825 9 P 0 ;1
L 9.2325 4.1325 9.2325 4.1325 9 P 0 ;1
L 9.2325 4.1825 9.2325 4.1825 9 P 0 ;1
L 9.2325 4.2325 9.2325 4.2325 9 P 0 ;1
L 9.2325 4.2825 9.2325 4.2825 9 P 0 ;1
L 9.2325 4.3325 9.2325 4.3325 9 P 0 ;1
L 9.2325 4.3825 9.2325 4.3825 9 P 0 ;1
L 9.2325 4.4325 9.2325 4.4325 9 P 0 ;1
L 9.2325 4.4825 9.2325 4.4825 9 P 0 ;1
L 9.2325 4.5325 9.2325 4.5325 9 P 0 ;1
L 9.2325 5.4325 9.2325 5.4325 9 P 0 ;1
L 9.2325 5.4825 9.2325 5.4825 9 P 0 ;1
L 9.2325 5.5325 9.2325 5.5325 9 P 0 ;1
L 9.2325 5.5825 9.2325 5.5825 9 P 0 ;1
L 9.2325 5.6325 9.2325 5.6325 9 P 0 ;1
L 9.2325 5.6825 9.2325 5.6825 9 P 0 ;1
L 9.2325 5.7325 9.2325 5.7325 9 P 0 ;1
L 9.2325 5.7825 9.2325 5.7825 9 P 0 ;1
L 9.2325 5.8325 9.2325 5.8325 9 P 0 ;1
L 9.2325 5.8825 9.2325 5.8825 9 P 0 ;1
L 9.2825 0.1325 9.2825 0.1325 9 P 0 ;1
L 9.2825 0.1825 9.2825 0.1825 9 P 0 ;1
L 9.2825 0.2325 9.2825 0.2325 9 P 0 ;1
L 9.2825 0.2825 9.2825 0.2825 9 P 0 ;1
L 9.2825 0.3325 9.2825 0.3325 9 P 0 ;1
L 9.2825 0.3825 9.2825 0.3825 9 P 0 ;1
L 9.2825 0.4325 9.2825 0.4325 9 P 0 ;1
L 9.2825 0.5325 9.2825 0.5325 9 P 0 ;1
L 9.2825 0.5825 9.2825 0.5825 9 P 0 ;1
L 9.2825 0.6325 9.2825 0.6325 9 P 0 ;1
L 9.2825 0.6825 9.2825 0.6825 9 P 0 ;1
L 9.2825 0.7325 9.2825 0.7325 9 P 0 ;1
L 9.2825 0.7825 9.2825 0.7825 9 P 0 ;1
L 9.2825 0.8325 9.2825 0.8325 9 P 0 ;1
L 9.2825 0.8825 9.2825 0.8825 9 P 0 ;1
L 9.2825 0.9325 9.2825 0.9325 9 P 0 ;1
L 9.2825 0.9825 9.2825 0.9825 9 P 0 ;1
L 9.2825 1.0325 9.2825 1.0325 9 P 0 ;1
L 9.2825 1.0825 9.2825 1.0825 9 P 0 ;1
L 9.2825 1.1325 9.2825 1.1325 9 P 0 ;1
L 9.2825 1.1825 9.2825 1.1825 9 P 0 ;1
L 9.2825 1.2325 9.2825 1.2325 9 P 0 ;1
L 9.2825 1.2825 9.2825 1.2825 9 P 0 ;1
L 9.2825 1.3325 9.2825 1.3325 9 P 0 ;1
L 9.2825 1.3825 9.2825 1.3825 9 P 0 ;1
L 9.2825 1.4325 9.2825 1.4325 9 P 0 ;1
L 9.2825 1.4825 9.2825 1.4825 9 P 0 ;1
L 9.2825 1.5325 9.2825 1.5325 9 P 0 ;1
L 9.2825 1.5825 9.2825 1.5825 9 P 0 ;1
L 9.2825 1.6325 9.2825 1.6325 9 P 0 ;1
L 9.2825 1.6825 9.2825 1.6825 9 P 0 ;1
L 9.2825 1.7325 9.2825 1.7325 9 P 0 ;1
L 9.2825 1.7825 9.2825 1.7825 9 P 0 ;1
L 9.2825 1.8325 9.2825 1.8325 9 P 0 ;1
L 9.2825 1.8825 9.2825 1.8825 9 P 0 ;1
L 9.2825 1.9325 9.2825 1.9325 9 P 0 ;1
L 9.2825 1.9825 9.2825 1.9825 9 P 0 ;1
L 9.2825 2.0325 9.2825 2.0325 9 P 0 ;1
L 9.2825 2.0825 9.2825 2.0825 9 P 0 ;1
L 9.2825 2.1325 9.2825 2.1325 9 P 0 ;1
L 9.2825 2.1825 9.2825 2.1825 9 P 0 ;1
L 9.2825 2.2325 9.2825 2.2325 9 P 0 ;1
L 9.2825 2.2825 9.2825 2.2825 9 P 0 ;1
L 9.2825 2.3325 9.2825 2.3325 9 P 0 ;1
L 9.2825 2.3825 9.2825 2.3825 9 P 0 ;1
L 9.2825 2.4325 9.2825 2.4325 9 P 0 ;1
L 9.2825 2.4825 9.2825 2.4825 9 P 0 ;1
L 9.2825 2.5325 9.2825 2.5325 9 P 0 ;1
L 9.2825 2.5825 9.2825 2.5825 9 P 0 ;1
L 9.2825 2.6325 9.2825 2.6325 9 P 0 ;1
L 9.2825 2.6825 9.2825 2.6825 9 P 0 ;1
L 9.2825 2.7325 9.2825 2.7325 9 P 0 ;1
L 9.2825 2.7825 9.2825 2.7825 9 P 0 ;1
L 9.2825 2.8325 9.2825 2.8325 9 P 0 ;1
L 9.2825 2.8825 9.2825 2.8825 9 P 0 ;1
L 9.2825 2.9325 9.2825 2.9325 9 P 0 ;1
L 9.2825 2.9825 9.2825 2.9825 9 P 0 ;1
L 9.2825 3.0325 9.2825 3.0325 9 P 0 ;1
L 9.2825 3.0825 9.2825 3.0825 9 P 0 ;1
L 9.2825 3.1325 9.2825 3.1325 9 P 0 ;1
L 9.2825 3.1825 9.2825 3.1825 9 P 0 ;1
L 9.2825 3.2325 9.2825 3.2325 9 P 0 ;1
L 9.2825 3.2825 9.2825 3.2825 9 P 0 ;1
L 9.2825 3.3325 9.2825 3.3325 9 P 0 ;1
L 9.2825 3.3825 9.2825 3.3825 9 P 0 ;1
L 9.2825 3.4325 9.2825 3.4325 9 P 0 ;1
L 9.2825 3.4825 9.2825 3.4825 9 P 0 ;1
L 9.2825 3.5325 9.2825 3.5325 9 P 0 ;1
L 9.2825 3.5825 9.2825 3.5825 9 P 0 ;1
L 9.2825 3.6325 9.2825 3.6325 9 P 0 ;1
L 9.2825 3.6825 9.2825 3.6825 9 P 0 ;1
L 9.2825 3.7325 9.2825 3.7325 9 P 0 ;1
L 9.2825 3.7825 9.2825 3.7825 9 P 0 ;1
L 9.2825 3.8325 9.2825 3.8325 9 P 0 ;1
L 9.2825 3.8825 9.2825 3.8825 9 P 0 ;1
L 9.2825 3.9325 9.2825 3.9325 9 P 0 ;1
L 9.2825 3.9825 9.2825 3.9825 9 P 0 ;1
L 9.2825 4.0325 9.2825 4.0325 9 P 0 ;1
L 9.2825 4.0825 9.2825 4.0825 9 P 0 ;1
L 9.2825 4.1325 9.2825 4.1325 9 P 0 ;1
L 9.2825 4.1825 9.2825 4.1825 9 P 0 ;1
L 9.2825 4.2325 9.2825 4.2325 9 P 0 ;1
L 9.2825 4.2825 9.2825 4.2825 9 P 0 ;1
L 9.2825 4.3325 9.2825 4.3325 9 P 0 ;1
L 9.2825 4.3825 9.2825 4.3825 9 P 0 ;1
L 9.2825 4.4325 9.2825 4.4325 9 P 0 ;1
L 9.2825 4.4825 9.2825 4.4825 9 P 0 ;1
L 9.2825 4.5325 9.2825 4.5325 9 P 0 ;1
L 9.2825 5.4325 9.2825 5.4325 9 P 0 ;1
L 9.2825 5.4825 9.2825 5.4825 9 P 0 ;1
L 9.2825 5.5325 9.2825 5.5325 9 P 0 ;1
L 9.2825 5.5825 9.2825 5.5825 9 P 0 ;1
L 9.2825 5.6325 9.2825 5.6325 9 P 0 ;1
L 9.2825 5.6825 9.2825 5.6825 9 P 0 ;1
L 9.2825 5.7325 9.2825 5.7325 9 P 0 ;1
L 9.2825 5.7825 9.2825 5.7825 9 P 0 ;1
L 9.2825 5.8325 9.2825 5.8325 9 P 0 ;1
L 9.2825 5.8825 9.2825 5.8825 9 P 0 ;1
L 9.3325 0.1325 9.3325 0.1325 9 P 0 ;1
L 9.3325 0.1825 9.3325 0.1825 9 P 0 ;1
L 9.3325 0.2325 9.3325 0.2325 9 P 0 ;1
L 9.3325 0.3325 9.3325 0.3325 9 P 0 ;1
L 9.3325 0.3825 9.3325 0.3825 9 P 0 ;1
L 9.3325 0.5825 9.3325 0.5825 9 P 0 ;1
L 9.3325 0.6325 9.3325 0.6325 9 P 0 ;1
L 9.3325 0.6825 9.3325 0.6825 9 P 0 ;1
L 9.3325 0.7325 9.3325 0.7325 9 P 0 ;1
L 9.3325 0.7825 9.3325 0.7825 9 P 0 ;1
L 9.3325 0.8325 9.3325 0.8325 9 P 0 ;1
L 9.3325 0.8825 9.3325 0.8825 9 P 0 ;1
L 9.3325 0.9325 9.3325 0.9325 9 P 0 ;1
L 9.3325 0.9825 9.3325 0.9825 9 P 0 ;1
L 9.3325 1.0325 9.3325 1.0325 9 P 0 ;1
L 9.3325 1.0825 9.3325 1.0825 9 P 0 ;1
L 9.3325 1.1325 9.3325 1.1325 9 P 0 ;1
L 9.3325 1.1825 9.3325 1.1825 9 P 0 ;1
L 9.3325 1.2325 9.3325 1.2325 9 P 0 ;1
L 9.3325 1.2825 9.3325 1.2825 9 P 0 ;1
L 9.3325 1.3325 9.3325 1.3325 9 P 0 ;1
L 9.3325 1.3825 9.3325 1.3825 9 P 0 ;1
L 9.3325 1.4325 9.3325 1.4325 9 P 0 ;1
L 9.3325 1.4825 9.3325 1.4825 9 P 0 ;1
L 9.3325 1.5325 9.3325 1.5325 9 P 0 ;1
L 9.3325 1.5825 9.3325 1.5825 9 P 0 ;1
L 9.3325 1.6325 9.3325 1.6325 9 P 0 ;1
L 9.3325 1.6825 9.3325 1.6825 9 P 0 ;1
L 9.3325 1.7325 9.3325 1.7325 9 P 0 ;1
L 9.3325 1.7825 9.3325 1.7825 9 P 0 ;1
L 9.3325 1.8325 9.3325 1.8325 9 P 0 ;1
L 9.3325 1.8825 9.3325 1.8825 9 P 0 ;1
L 9.3325 1.9325 9.3325 1.9325 9 P 0 ;1
L 9.3325 1.9825 9.3325 1.9825 9 P 0 ;1
L 9.3325 2.0325 9.3325 2.0325 9 P 0 ;1
L 9.3325 2.0825 9.3325 2.0825 9 P 0 ;1
L 9.3325 2.1325 9.3325 2.1325 9 P 0 ;1
L 9.3325 2.1825 9.3325 2.1825 9 P 0 ;1
L 9.3325 2.2325 9.3325 2.2325 9 P 0 ;1
L 9.3325 2.2825 9.3325 2.2825 9 P 0 ;1
L 9.3325 2.3325 9.3325 2.3325 9 P 0 ;1
L 9.3325 2.3825 9.3325 2.3825 9 P 0 ;1
L 9.3325 2.4325 9.3325 2.4325 9 P 0 ;1
L 9.3325 2.4825 9.3325 2.4825 9 P 0 ;1
L 9.3325 2.5325 9.3325 2.5325 9 P 0 ;1
L 9.3325 2.5825 9.3325 2.5825 9 P 0 ;1
L 9.3325 2.6325 9.3325 2.6325 9 P 0 ;1
L 9.3325 2.6825 9.3325 2.6825 9 P 0 ;1
L 9.3325 2.7325 9.3325 2.7325 9 P 0 ;1
L 9.3325 2.7825 9.3325 2.7825 9 P 0 ;1
L 9.3325 2.8325 9.3325 2.8325 9 P 0 ;1
L 9.3325 2.8825 9.3325 2.8825 9 P 0 ;1
L 9.3325 2.9325 9.3325 2.9325 9 P 0 ;1
L 9.3325 2.9825 9.3325 2.9825 9 P 0 ;1
L 9.3325 3.0325 9.3325 3.0325 9 P 0 ;1
L 9.3325 3.0825 9.3325 3.0825 9 P 0 ;1
L 9.3325 3.1325 9.3325 3.1325 9 P 0 ;1
L 9.3325 3.1825 9.3325 3.1825 9 P 0 ;1
L 9.3325 3.2325 9.3325 3.2325 9 P 0 ;1
L 9.3325 3.2825 9.3325 3.2825 9 P 0 ;1
L 9.3325 3.3325 9.3325 3.3325 9 P 0 ;1
L 9.3325 3.3825 9.3325 3.3825 9 P 0 ;1
L 9.3325 3.4325 9.3325 3.4325 9 P 0 ;1
L 9.3325 3.4825 9.3325 3.4825 9 P 0 ;1
L 9.3325 3.5325 9.3325 3.5325 9 P 0 ;1
L 9.3325 3.5825 9.3325 3.5825 9 P 0 ;1
L 9.3325 3.6325 9.3325 3.6325 9 P 0 ;1
L 9.3325 3.6825 9.3325 3.6825 9 P 0 ;1
L 9.3325 3.7325 9.3325 3.7325 9 P 0 ;1
L 9.3325 3.7825 9.3325 3.7825 9 P 0 ;1
L 9.3325 3.8325 9.3325 3.8325 9 P 0 ;1
L 9.3325 3.8825 9.3325 3.8825 9 P 0 ;1
L 9.3325 3.9325 9.3325 3.9325 9 P 0 ;1
L 9.3325 3.9825 9.3325 3.9825 9 P 0 ;1
L 9.3325 4.0325 9.3325 4.0325 9 P 0 ;1
L 9.3325 4.0825 9.3325 4.0825 9 P 0 ;1
L 9.3325 4.1325 9.3325 4.1325 9 P 0 ;1
L 9.3325 4.1825 9.3325 4.1825 9 P 0 ;1
L 9.3325 4.2325 9.3325 4.2325 9 P 0 ;1
L 9.3325 4.2825 9.3325 4.2825 9 P 0 ;1
L 9.3325 4.3325 9.3325 4.3325 9 P 0 ;1
L 9.3325 4.3825 9.3325 4.3825 9 P 0 ;1
L 9.3325 4.4325 9.3325 4.4325 9 P 0 ;1
L 9.3325 4.4825 9.3325 4.4825 9 P 0 ;1
L 9.3325 4.5325 9.3325 4.5325 9 P 0 ;1
L 9.3325 5.2825 9.3325 5.2825 9 P 0 ;1
L 9.3325 5.3825 9.3325 5.3825 9 P 0 ;1
L 9.3325 5.4325 9.3325 5.4325 9 P 0 ;1
L 9.3325 5.4825 9.3325 5.4825 9 P 0 ;1
L 9.3325 5.5325 9.3325 5.5325 9 P 0 ;1
L 9.3325 5.5825 9.3325 5.5825 9 P 0 ;1
L 9.3325 5.6325 9.3325 5.6325 9 P 0 ;1
L 9.3325 5.6825 9.3325 5.6825 9 P 0 ;1
L 9.3325 5.7325 9.3325 5.7325 9 P 0 ;1
L 9.3325 5.7825 9.3325 5.7825 9 P 0 ;1
L 9.3325 5.8325 9.3325 5.8325 9 P 0 ;1
L 9.3325 5.8825 9.3325 5.8825 9 P 0 ;1
L 9.3825 0.1325 9.3825 0.1325 9 P 0 ;1
L 9.3825 0.1825 9.3825 0.1825 9 P 0 ;1
L 9.3825 0.5825 9.3825 0.5825 9 P 0 ;1
L 9.3825 0.6325 9.3825 0.6325 9 P 0 ;1
L 9.3825 0.8325 9.3825 0.8325 9 P 0 ;1
L 9.3825 0.8825 9.3825 0.8825 9 P 0 ;1
L 9.3825 0.9325 9.3825 0.9325 9 P 0 ;1
L 9.3825 0.9825 9.3825 0.9825 9 P 0 ;1
L 9.3825 1.0325 9.3825 1.0325 9 P 0 ;1
L 9.3825 1.0825 9.3825 1.0825 9 P 0 ;1
L 9.3825 1.1325 9.3825 1.1325 9 P 0 ;1
L 9.3825 1.1825 9.3825 1.1825 9 P 0 ;1
L 9.3825 1.2325 9.3825 1.2325 9 P 0 ;1
L 9.3825 1.2825 9.3825 1.2825 9 P 0 ;1
L 9.3825 1.3325 9.3825 1.3325 9 P 0 ;1
L 9.3825 1.3825 9.3825 1.3825 9 P 0 ;1
L 9.3825 1.4325 9.3825 1.4325 9 P 0 ;1
L 9.3825 1.4825 9.3825 1.4825 9 P 0 ;1
L 9.3825 1.5325 9.3825 1.5325 9 P 0 ;1
L 9.3825 1.5825 9.3825 1.5825 9 P 0 ;1
L 9.3825 1.6325 9.3825 1.6325 9 P 0 ;1
L 9.3825 1.6825 9.3825 1.6825 9 P 0 ;1
L 9.3825 1.7325 9.3825 1.7325 9 P 0 ;1
L 9.3825 1.7825 9.3825 1.7825 9 P 0 ;1
L 9.3825 1.8325 9.3825 1.8325 9 P 0 ;1
L 9.3825 1.8825 9.3825 1.8825 9 P 0 ;1
L 9.3825 1.9325 9.3825 1.9325 9 P 0 ;1
L 9.3825 1.9825 9.3825 1.9825 9 P 0 ;1
L 9.3825 2.0325 9.3825 2.0325 9 P 0 ;1
L 9.3825 2.0825 9.3825 2.0825 9 P 0 ;1
L 9.3825 2.1325 9.3825 2.1325 9 P 0 ;1
L 9.3825 2.1825 9.3825 2.1825 9 P 0 ;1
L 9.3825 2.2325 9.3825 2.2325 9 P 0 ;1
L 9.3825 2.2825 9.3825 2.2825 9 P 0 ;1
L 9.3825 2.3325 9.3825 2.3325 9 P 0 ;1
L 9.3825 2.3825 9.3825 2.3825 9 P 0 ;1
L 9.3825 2.4325 9.3825 2.4325 9 P 0 ;1
L 9.3825 2.4825 9.3825 2.4825 9 P 0 ;1
L 9.3825 2.5325 9.3825 2.5325 9 P 0 ;1
L 9.3825 2.5825 9.3825 2.5825 9 P 0 ;1
L 9.3825 2.6325 9.3825 2.6325 9 P 0 ;1
L 9.3825 2.6825 9.3825 2.6825 9 P 0 ;1
L 9.3825 2.7325 9.3825 2.7325 9 P 0 ;1
L 9.3825 2.7825 9.3825 2.7825 9 P 0 ;1
L 9.3825 2.8325 9.3825 2.8325 9 P 0 ;1
L 9.3825 2.8825 9.3825 2.8825 9 P 0 ;1
L 9.3825 2.9325 9.3825 2.9325 9 P 0 ;1
L 9.3825 2.9825 9.3825 2.9825 9 P 0 ;1
L 9.3825 3.0325 9.3825 3.0325 9 P 0 ;1
L 9.3825 3.0825 9.3825 3.0825 9 P 0 ;1
L 9.3825 3.1325 9.3825 3.1325 9 P 0 ;1
L 9.3825 3.1825 9.3825 3.1825 9 P 0 ;1
L 9.3825 3.2325 9.3825 3.2325 9 P 0 ;1
L 9.3825 3.2825 9.3825 3.2825 9 P 0 ;1
L 9.3825 3.3325 9.3825 3.3325 9 P 0 ;1
L 9.3825 3.3825 9.3825 3.3825 9 P 0 ;1
L 9.3825 3.4325 9.3825 3.4325 9 P 0 ;1
L 9.3825 3.4825 9.3825 3.4825 9 P 0 ;1
L 9.3825 3.5325 9.3825 3.5325 9 P 0 ;1
L 9.3825 3.5825 9.3825 3.5825 9 P 0 ;1
L 9.3825 3.6325 9.3825 3.6325 9 P 0 ;1
L 9.3825 3.6825 9.3825 3.6825 9 P 0 ;1
L 9.3825 3.7325 9.3825 3.7325 9 P 0 ;1
L 9.3825 3.7825 9.3825 3.7825 9 P 0 ;1
L 9.3825 3.8325 9.3825 3.8325 9 P 0 ;1
L 9.3825 3.8825 9.3825 3.8825 9 P 0 ;1
L 9.3825 3.9325 9.3825 3.9325 9 P 0 ;1
L 9.3825 3.9825 9.3825 3.9825 9 P 0 ;1
L 9.3825 4.0325 9.3825 4.0325 9 P 0 ;1
L 9.3825 4.0825 9.3825 4.0825 9 P 0 ;1
L 9.3825 4.1325 9.3825 4.1325 9 P 0 ;1
L 9.3825 4.1825 9.3825 4.1825 9 P 0 ;1
L 9.3825 4.2325 9.3825 4.2325 9 P 0 ;1
L 9.3825 4.2825 9.3825 4.2825 9 P 0 ;1
L 9.3825 4.3325 9.3825 4.3325 9 P 0 ;1
L 9.3825 4.3825 9.3825 4.3825 9 P 0 ;1
L 9.3825 4.4325 9.3825 4.4325 9 P 0 ;1
L 9.3825 4.4825 9.3825 4.4825 9 P 0 ;1
L 9.3825 4.5325 9.3825 4.5325 9 P 0 ;1
L 9.3825 5.4325 9.3825 5.4325 9 P 0 ;1
L 9.3825 5.4825 9.3825 5.4825 9 P 0 ;1
L 9.3825 5.5325 9.3825 5.5325 9 P 0 ;1
L 9.3825 5.5825 9.3825 5.5825 9 P 0 ;1
L 9.3825 5.6325 9.3825 5.6325 9 P 0 ;1
L 9.3825 5.6825 9.3825 5.6825 9 P 0 ;1
L 9.3825 5.7325 9.3825 5.7325 9 P 0 ;1
L 9.3825 5.7825 9.3825 5.7825 9 P 0 ;1
L 9.3825 5.8325 9.3825 5.8325 9 P 0 ;1
L 9.3825 5.8825 9.3825 5.8825 9 P 0 ;1
L 9.4325 0.1325 9.4325 0.1325 9 P 0 ;1
L 9.4325 0.1825 9.4325 0.1825 9 P 0 ;1
L 9.4325 0.5825 9.4325 0.5825 9 P 0 ;1
L 9.4325 0.6325 9.4325 0.6325 9 P 0 ;1
L 9.4325 0.9325 9.4325 0.9325 9 P 0 ;1
L 9.4325 0.9825 9.4325 0.9825 9 P 0 ;1
L 9.4325 1.0325 9.4325 1.0325 9 P 0 ;1
L 9.4325 1.0825 9.4325 1.0825 9 P 0 ;1
L 9.4325 1.1325 9.4325 1.1325 9 P 0 ;1
L 9.4325 1.1825 9.4325 1.1825 9 P 0 ;1
L 9.4325 1.2325 9.4325 1.2325 9 P 0 ;1
L 9.4325 1.2825 9.4325 1.2825 9 P 0 ;1
L 9.4325 1.3325 9.4325 1.3325 9 P 0 ;1
L 9.4325 1.3825 9.4325 1.3825 9 P 0 ;1
L 9.4325 1.4325 9.4325 1.4325 9 P 0 ;1
L 9.4325 1.4825 9.4325 1.4825 9 P 0 ;1
L 9.4325 1.5325 9.4325 1.5325 9 P 0 ;1
L 9.4325 1.5825 9.4325 1.5825 9 P 0 ;1
L 9.4325 1.6325 9.4325 1.6325 9 P 0 ;1
L 9.4325 1.6825 9.4325 1.6825 9 P 0 ;1
L 9.4325 1.7325 9.4325 1.7325 9 P 0 ;1
L 9.4325 1.7825 9.4325 1.7825 9 P 0 ;1
L 9.4325 1.8325 9.4325 1.8325 9 P 0 ;1
L 9.4325 1.8825 9.4325 1.8825 9 P 0 ;1
L 9.4325 1.9325 9.4325 1.9325 9 P 0 ;1
L 9.4325 1.9825 9.4325 1.9825 9 P 0 ;1
L 9.4325 2.0325 9.4325 2.0325 9 P 0 ;1
L 9.4325 2.0825 9.4325 2.0825 9 P 0 ;1
L 9.4325 2.1325 9.4325 2.1325 9 P 0 ;1
L 9.4325 2.1825 9.4325 2.1825 9 P 0 ;1
L 9.4325 2.2325 9.4325 2.2325 9 P 0 ;1
L 9.4325 2.2825 9.4325 2.2825 9 P 0 ;1
L 9.4325 2.3325 9.4325 2.3325 9 P 0 ;1
L 9.4325 2.3825 9.4325 2.3825 9 P 0 ;1
L 9.4325 2.4325 9.4325 2.4325 9 P 0 ;1
L 9.4325 2.4825 9.4325 2.4825 9 P 0 ;1
L 9.4325 2.5325 9.4325 2.5325 9 P 0 ;1
L 9.4325 2.5825 9.4325 2.5825 9 P 0 ;1
L 9.4325 2.6325 9.4325 2.6325 9 P 0 ;1
L 9.4325 2.6825 9.4325 2.6825 9 P 0 ;1
L 9.4325 2.7325 9.4325 2.7325 9 P 0 ;1
L 9.4325 2.7825 9.4325 2.7825 9 P 0 ;1
L 9.4325 2.8325 9.4325 2.8325 9 P 0 ;1
L 9.4325 2.8825 9.4325 2.8825 9 P 0 ;1
L 9.4325 2.9325 9.4325 2.9325 9 P 0 ;1
L 9.4325 2.9825 9.4325 2.9825 9 P 0 ;1
L 9.4325 3.0325 9.4325 3.0325 9 P 0 ;1
L 9.4325 3.0825 9.4325 3.0825 9 P 0 ;1
L 9.4325 3.1325 9.4325 3.1325 9 P 0 ;1
L 9.4325 3.1825 9.4325 3.1825 9 P 0 ;1
L 9.4325 3.2325 9.4325 3.2325 9 P 0 ;1
L 9.4325 3.2825 9.4325 3.2825 9 P 0 ;1
L 9.4325 3.3325 9.4325 3.3325 9 P 0 ;1
L 9.4325 3.3825 9.4325 3.3825 9 P 0 ;1
L 9.4325 3.4325 9.4325 3.4325 9 P 0 ;1
L 9.4325 3.4825 9.4325 3.4825 9 P 0 ;1
L 9.4325 3.5325 9.4325 3.5325 9 P 0 ;1
L 9.4325 3.5825 9.4325 3.5825 9 P 0 ;1
L 9.4325 3.6325 9.4325 3.6325 9 P 0 ;1
L 9.4325 3.6825 9.4325 3.6825 9 P 0 ;1
L 9.4325 3.7325 9.4325 3.7325 9 P 0 ;1
L 9.4325 3.7825 9.4325 3.7825 9 P 0 ;1
L 9.4325 3.8325 9.4325 3.8325 9 P 0 ;1
L 9.4325 3.8825 9.4325 3.8825 9 P 0 ;1
L 9.4325 3.9325 9.4325 3.9325 9 P 0 ;1
L 9.4325 3.9825 9.4325 3.9825 9 P 0 ;1
L 9.4325 4.0325 9.4325 4.0325 9 P 0 ;1
L 9.4325 4.0825 9.4325 4.0825 9 P 0 ;1
L 9.4325 4.1325 9.4325 4.1325 9 P 0 ;1
L 9.4325 4.1825 9.4325 4.1825 9 P 0 ;1
L 9.4325 4.2325 9.4325 4.2325 9 P 0 ;1
L 9.4325 4.2825 9.4325 4.2825 9 P 0 ;1
L 9.4325 4.3325 9.4325 4.3325 9 P 0 ;1
L 9.4325 4.3825 9.4325 4.3825 9 P 0 ;1
L 9.4325 4.4325 9.4325 4.4325 9 P 0 ;1
L 9.4325 4.4825 9.4325 4.4825 9 P 0 ;1
L 9.4325 5.4325 9.4325 5.4325 9 P 0 ;1
L 9.4325 5.4825 9.4325 5.4825 9 P 0 ;1
L 9.4325 5.5325 9.4325 5.5325 9 P 0 ;1
L 9.4325 5.5825 9.4325 5.5825 9 P 0 ;1
L 9.4325 5.6325 9.4325 5.6325 9 P 0 ;1
L 9.4325 5.6825 9.4325 5.6825 9 P 0 ;1
L 9.4325 5.7325 9.4325 5.7325 9 P 0 ;1
L 9.4325 5.7825 9.4325 5.7825 9 P 0 ;1
L 9.4325 5.8325 9.4325 5.8325 9 P 0 ;1
L 9.4325 5.8825 9.4325 5.8825 9 P 0 ;1
L 9.4825 0.1325 9.4825 0.1325 9 P 0 ;1
L 9.4825 0.1825 9.4825 0.1825 9 P 0 ;1
L 9.4825 0.2325 9.4825 0.2325 9 P 0 ;1
L 9.4825 0.5825 9.4825 0.5825 9 P 0 ;1
L 9.4825 0.6325 9.4825 0.6325 9 P 0 ;1
L 9.4825 0.9325 9.4825 0.9325 9 P 0 ;1
L 9.4825 0.9825 9.4825 0.9825 9 P 0 ;1
L 9.4825 1.0325 9.4825 1.0325 9 P 0 ;1
L 9.4825 1.0825 9.4825 1.0825 9 P 0 ;1
L 9.4825 1.1325 9.4825 1.1325 9 P 0 ;1
L 9.4825 1.1825 9.4825 1.1825 9 P 0 ;1
L 9.4825 1.2325 9.4825 1.2325 9 P 0 ;1
L 9.4825 1.2825 9.4825 1.2825 9 P 0 ;1
L 9.4825 1.3325 9.4825 1.3325 9 P 0 ;1
L 9.4825 1.3825 9.4825 1.3825 9 P 0 ;1
L 9.4825 1.4325 9.4825 1.4325 9 P 0 ;1
L 9.4825 1.4825 9.4825 1.4825 9 P 0 ;1
L 9.4825 1.5325 9.4825 1.5325 9 P 0 ;1
L 9.4825 1.5825 9.4825 1.5825 9 P 0 ;1
L 9.4825 1.6325 9.4825 1.6325 9 P 0 ;1
L 9.4825 1.6825 9.4825 1.6825 9 P 0 ;1
L 9.4825 1.7325 9.4825 1.7325 9 P 0 ;1
L 9.4825 1.7825 9.4825 1.7825 9 P 0 ;1
L 9.4825 1.8325 9.4825 1.8325 9 P 0 ;1
L 9.4825 1.8825 9.4825 1.8825 9 P 0 ;1
L 9.4825 1.9325 9.4825 1.9325 9 P 0 ;1
L 9.4825 1.9825 9.4825 1.9825 9 P 0 ;1
L 9.4825 2.0325 9.4825 2.0325 9 P 0 ;1
L 9.4825 2.0825 9.4825 2.0825 9 P 0 ;1
L 9.4825 2.1325 9.4825 2.1325 9 P 0 ;1
L 9.4825 2.1825 9.4825 2.1825 9 P 0 ;1
L 9.4825 2.2325 9.4825 2.2325 9 P 0 ;1
L 9.4825 2.2825 9.4825 2.2825 9 P 0 ;1
L 9.4825 2.3325 9.4825 2.3325 9 P 0 ;1
L 9.4825 2.3825 9.4825 2.3825 9 P 0 ;1
L 9.4825 2.4325 9.4825 2.4325 9 P 0 ;1
L 9.4825 2.4825 9.4825 2.4825 9 P 0 ;1
L 9.4825 2.5325 9.4825 2.5325 9 P 0 ;1
L 9.4825 2.5825 9.4825 2.5825 9 P 0 ;1
L 9.4825 2.6325 9.4825 2.6325 9 P 0 ;1
L 9.4825 2.6825 9.4825 2.6825 9 P 0 ;1
L 9.4825 2.7325 9.4825 2.7325 9 P 0 ;1
L 9.4825 2.7825 9.4825 2.7825 9 P 0 ;1
L 9.4825 2.8325 9.4825 2.8325 9 P 0 ;1
L 9.4825 2.8825 9.4825 2.8825 9 P 0 ;1
L 9.4825 2.9325 9.4825 2.9325 9 P 0 ;1
L 9.4825 2.9825 9.4825 2.9825 9 P 0 ;1
L 9.4825 3.0325 9.4825 3.0325 9 P 0 ;1
L 9.4825 3.0825 9.4825 3.0825 9 P 0 ;1
L 9.4825 3.1325 9.4825 3.1325 9 P 0 ;1
L 9.4825 3.1825 9.4825 3.1825 9 P 0 ;1
L 9.4825 3.2325 9.4825 3.2325 9 P 0 ;1
L 9.4825 3.2825 9.4825 3.2825 9 P 0 ;1
L 9.4825 3.3325 9.4825 3.3325 9 P 0 ;1
L 9.4825 3.3825 9.4825 3.3825 9 P 0 ;1
L 9.4825 3.4325 9.4825 3.4325 9 P 0 ;1
L 9.4825 3.4825 9.4825 3.4825 9 P 0 ;1
L 9.4825 3.5325 9.4825 3.5325 9 P 0 ;1
L 9.4825 3.5825 9.4825 3.5825 9 P 0 ;1
L 9.4825 3.6325 9.4825 3.6325 9 P 0 ;1
L 9.4825 3.6825 9.4825 3.6825 9 P 0 ;1
L 9.4825 3.7325 9.4825 3.7325 9 P 0 ;1
L 9.4825 3.7825 9.4825 3.7825 9 P 0 ;1
L 9.4825 3.8325 9.4825 3.8325 9 P 0 ;1
L 9.4825 3.8825 9.4825 3.8825 9 P 0 ;1
L 9.4825 3.9325 9.4825 3.9325 9 P 0 ;1
L 9.4825 3.9825 9.4825 3.9825 9 P 0 ;1
L 9.4825 4.0325 9.4825 4.0325 9 P 0 ;1
L 9.4825 4.0825 9.4825 4.0825 9 P 0 ;1
L 9.4825 4.1325 9.4825 4.1325 9 P 0 ;1
L 9.4825 4.1825 9.4825 4.1825 9 P 0 ;1
L 9.4825 4.2325 9.4825 4.2325 9 P 0 ;1
L 9.4825 4.2825 9.4825 4.2825 9 P 0 ;1
L 9.4825 4.3325 9.4825 4.3325 9 P 0 ;1
L 9.4825 4.3825 9.4825 4.3825 9 P 0 ;1
L 9.4825 4.4325 9.4825 4.4325 9 P 0 ;1
L 9.4825 4.4825 9.4825 4.4825 9 P 0 ;1
L 9.4825 5.3825 9.4825 5.3825 9 P 0 ;1
L 9.4825 5.4325 9.4825 5.4325 9 P 0 ;1
L 9.4825 5.4825 9.4825 5.4825 9 P 0 ;1
L 9.4825 5.5325 9.4825 5.5325 9 P 0 ;1
L 9.4825 5.5825 9.4825 5.5825 9 P 0 ;1
L 9.4825 5.6325 9.4825 5.6325 9 P 0 ;1
L 9.4825 5.6825 9.4825 5.6825 9 P 0 ;1
L 9.4825 5.7325 9.4825 5.7325 9 P 0 ;1
L 9.4825 5.7825 9.4825 5.7825 9 P 0 ;1
L 9.4825 5.8325 9.4825 5.8325 9 P 0 ;1
L 9.4825 5.8825 9.4825 5.8825 9 P 0 ;1
L 9.5325 0.1325 9.5325 0.1325 9 P 0 ;1
L 9.5325 0.1825 9.5325 0.1825 9 P 0 ;1
L 9.5325 0.4825 9.5325 0.4825 9 P 0 ;1
L 9.5325 0.5325 9.5325 0.5325 9 P 0 ;1
L 9.5325 0.5825 9.5325 0.5825 9 P 0 ;1
L 9.5325 0.6325 9.5325 0.6325 9 P 0 ;1
L 9.5325 0.8825 9.5325 0.8825 9 P 0 ;1
L 9.5325 0.9325 9.5325 0.9325 9 P 0 ;1
L 9.5325 0.9825 9.5325 0.9825 9 P 0 ;1
L 9.5325 1.0325 9.5325 1.0325 9 P 0 ;1
L 9.5325 1.0825 9.5325 1.0825 9 P 0 ;1
L 9.5325 1.1325 9.5325 1.1325 9 P 0 ;1
L 9.5325 1.1825 9.5325 1.1825 9 P 0 ;1
L 9.5325 1.2325 9.5325 1.2325 9 P 0 ;1
L 9.5325 1.2825 9.5325 1.2825 9 P 0 ;1
L 9.5325 1.3325 9.5325 1.3325 9 P 0 ;1
L 9.5325 1.3825 9.5325 1.3825 9 P 0 ;1
L 9.5325 1.4325 9.5325 1.4325 9 P 0 ;1
L 9.5325 1.4825 9.5325 1.4825 9 P 0 ;1
L 9.5325 1.5325 9.5325 1.5325 9 P 0 ;1
L 9.5325 1.5825 9.5325 1.5825 9 P 0 ;1
L 9.5325 1.6325 9.5325 1.6325 9 P 0 ;1
L 9.5325 1.6825 9.5325 1.6825 9 P 0 ;1
L 9.5325 1.7325 9.5325 1.7325 9 P 0 ;1
L 9.5325 1.7825 9.5325 1.7825 9 P 0 ;1
L 9.5325 1.8325 9.5325 1.8325 9 P 0 ;1
L 9.5325 1.8825 9.5325 1.8825 9 P 0 ;1
L 9.5325 1.9325 9.5325 1.9325 9 P 0 ;1
L 9.5325 1.9825 9.5325 1.9825 9 P 0 ;1
L 9.5325 2.0325 9.5325 2.0325 9 P 0 ;1
L 9.5325 2.0825 9.5325 2.0825 9 P 0 ;1
L 9.5325 2.1325 9.5325 2.1325 9 P 0 ;1
L 9.5325 2.1825 9.5325 2.1825 9 P 0 ;1
L 9.5325 2.2325 9.5325 2.2325 9 P 0 ;1
L 9.5325 2.2825 9.5325 2.2825 9 P 0 ;1
L 9.5325 2.3325 9.5325 2.3325 9 P 0 ;1
L 9.5325 2.3825 9.5325 2.3825 9 P 0 ;1
L 9.5325 2.4325 9.5325 2.4325 9 P 0 ;1
L 9.5325 2.4825 9.5325 2.4825 9 P 0 ;1
L 9.5325 2.5325 9.5325 2.5325 9 P 0 ;1
L 9.5325 2.5825 9.5325 2.5825 9 P 0 ;1
L 9.5325 2.6325 9.5325 2.6325 9 P 0 ;1
L 9.5325 2.6825 9.5325 2.6825 9 P 0 ;1
L 9.5325 2.7325 9.5325 2.7325 9 P 0 ;1
L 9.5325 2.7825 9.5325 2.7825 9 P 0 ;1
L 9.5325 2.8325 9.5325 2.8325 9 P 0 ;1
L 9.5325 2.8825 9.5325 2.8825 9 P 0 ;1
L 9.5325 2.9325 9.5325 2.9325 9 P 0 ;1
L 9.5325 2.9825 9.5325 2.9825 9 P 0 ;1
L 9.5325 3.0325 9.5325 3.0325 9 P 0 ;1
L 9.5325 3.0825 9.5325 3.0825 9 P 0 ;1
L 9.5325 3.1325 9.5325 3.1325 9 P 0 ;1
L 9.5325 3.1825 9.5325 3.1825 9 P 0 ;1
L 9.5325 3.2325 9.5325 3.2325 9 P 0 ;1
L 9.5325 3.2825 9.5325 3.2825 9 P 0 ;1
L 9.5325 3.3325 9.5325 3.3325 9 P 0 ;1
L 9.5325 3.3825 9.5325 3.3825 9 P 0 ;1
L 9.5325 3.4325 9.5325 3.4325 9 P 0 ;1
L 9.5325 3.4825 9.5325 3.4825 9 P 0 ;1
L 9.5325 3.5325 9.5325 3.5325 9 P 0 ;1
L 9.5325 3.5825 9.5325 3.5825 9 P 0 ;1
L 9.5325 3.6325 9.5325 3.6325 9 P 0 ;1
L 9.5325 3.6825 9.5325 3.6825 9 P 0 ;1
L 9.5325 3.7325 9.5325 3.7325 9 P 0 ;1
L 9.5325 3.7825 9.5325 3.7825 9 P 0 ;1
L 9.5325 3.8325 9.5325 3.8325 9 P 0 ;1
L 9.5325 3.8825 9.5325 3.8825 9 P 0 ;1
L 9.5325 3.9325 9.5325 3.9325 9 P 0 ;1
L 9.5325 3.9825 9.5325 3.9825 9 P 0 ;1
L 9.5325 4.0325 9.5325 4.0325 9 P 0 ;1
L 9.5325 4.0825 9.5325 4.0825 9 P 0 ;1
L 9.5325 4.1325 9.5325 4.1325 9 P 0 ;1
L 9.5325 4.1825 9.5325 4.1825 9 P 0 ;1
L 9.5325 4.2325 9.5325 4.2325 9 P 0 ;1
L 9.5325 4.2825 9.5325 4.2825 9 P 0 ;1
L 9.5325 4.3325 9.5325 4.3325 9 P 0 ;1
L 9.5325 4.3825 9.5325 4.3825 9 P 0 ;1
L 9.5325 4.4325 9.5325 4.4325 9 P 0 ;1
L 9.5325 4.4825 9.5325 4.4825 9 P 0 ;1
L 9.5325 5.3825 9.5325 5.3825 9 P 0 ;1
L 9.5325 5.4325 9.5325 5.4325 9 P 0 ;1
L 9.5325 5.4825 9.5325 5.4825 9 P 0 ;1
L 9.5325 5.5325 9.5325 5.5325 9 P 0 ;1
L 9.5325 5.5825 9.5325 5.5825 9 P 0 ;1
L 9.5325 5.6325 9.5325 5.6325 9 P 0 ;1
L 9.5325 5.6825 9.5325 5.6825 9 P 0 ;1
L 9.5325 5.7325 9.5325 5.7325 9 P 0 ;1
L 9.5325 5.7825 9.5325 5.7825 9 P 0 ;1
L 9.5325 5.8325 9.5325 5.8325 9 P 0 ;1
L 9.5325 5.8825 9.5325 5.8825 9 P 0 ;1
L 9.5825 0.1325 9.5825 0.1325 9 P 0 ;1
L 9.5825 0.1825 9.5825 0.1825 9 P 0 ;1
L 9.5825 0.4825 9.5825 0.4825 9 P 0 ;1
L 9.5825 0.5325 9.5825 0.5325 9 P 0 ;1
L 9.5825 0.5825 9.5825 0.5825 9 P 0 ;1
L 9.5825 0.6325 9.5825 0.6325 9 P 0 ;1
L 9.5825 0.8825 9.5825 0.8825 9 P 0 ;1
L 9.5825 0.9325 9.5825 0.9325 9 P 0 ;1
L 9.5825 0.9825 9.5825 0.9825 9 P 0 ;1
L 9.5825 1.0325 9.5825 1.0325 9 P 0 ;1
L 9.5825 1.0825 9.5825 1.0825 9 P 0 ;1
L 9.5825 1.1325 9.5825 1.1325 9 P 0 ;1
L 9.5825 1.1825 9.5825 1.1825 9 P 0 ;1
L 9.5825 1.2325 9.5825 1.2325 9 P 0 ;1
L 9.5825 1.2825 9.5825 1.2825 9 P 0 ;1
L 9.5825 1.3325 9.5825 1.3325 9 P 0 ;1
L 9.5825 1.3825 9.5825 1.3825 9 P 0 ;1
L 9.5825 1.4325 9.5825 1.4325 9 P 0 ;1
L 9.5825 1.4825 9.5825 1.4825 9 P 0 ;1
L 9.5825 1.5325 9.5825 1.5325 9 P 0 ;1
L 9.5825 1.5825 9.5825 1.5825 9 P 0 ;1
L 9.5825 1.6325 9.5825 1.6325 9 P 0 ;1
L 9.5825 1.6825 9.5825 1.6825 9 P 0 ;1
L 9.5825 1.7325 9.5825 1.7325 9 P 0 ;1
L 9.5825 1.7825 9.5825 1.7825 9 P 0 ;1
L 9.5825 1.8325 9.5825 1.8325 9 P 0 ;1
L 9.5825 1.8825 9.5825 1.8825 9 P 0 ;1
L 9.5825 1.9325 9.5825 1.9325 9 P 0 ;1
L 9.5825 1.9825 9.5825 1.9825 9 P 0 ;1
L 9.5825 2.0325 9.5825 2.0325 9 P 0 ;1
L 9.5825 2.0825 9.5825 2.0825 9 P 0 ;1
L 9.5825 2.1325 9.5825 2.1325 9 P 0 ;1
L 9.5825 2.1825 9.5825 2.1825 9 P 0 ;1
L 9.5825 2.2325 9.5825 2.2325 9 P 0 ;1
L 9.5825 2.2825 9.5825 2.2825 9 P 0 ;1
L 9.5825 2.3325 9.5825 2.3325 9 P 0 ;1
L 9.5825 2.3825 9.5825 2.3825 9 P 0 ;1
L 9.5825 2.4325 9.5825 2.4325 9 P 0 ;1
L 9.5825 2.4825 9.5825 2.4825 9 P 0 ;1
L 9.5825 2.5325 9.5825 2.5325 9 P 0 ;1
L 9.5825 2.5825 9.5825 2.5825 9 P 0 ;1
L 9.5825 2.6325 9.5825 2.6325 9 P 0 ;1
L 9.5825 2.6825 9.5825 2.6825 9 P 0 ;1
L 9.5825 2.7325 9.5825 2.7325 9 P 0 ;1
L 9.5825 2.7825 9.5825 2.7825 9 P 0 ;1
L 9.5825 2.8325 9.5825 2.8325 9 P 0 ;1
L 9.5825 2.8825 9.5825 2.8825 9 P 0 ;1
L 9.5825 2.9325 9.5825 2.9325 9 P 0 ;1
L 9.5825 2.9825 9.5825 2.9825 9 P 0 ;1
L 9.5825 3.0325 9.5825 3.0325 9 P 0 ;1
L 9.5825 3.0825 9.5825 3.0825 9 P 0 ;1
L 9.5825 3.1325 9.5825 3.1325 9 P 0 ;1
L 9.5825 3.1825 9.5825 3.1825 9 P 0 ;1
L 9.5825 3.2325 9.5825 3.2325 9 P 0 ;1
L 9.5825 3.2825 9.5825 3.2825 9 P 0 ;1
L 9.5825 3.3325 9.5825 3.3325 9 P 0 ;1
L 9.5825 3.3825 9.5825 3.3825 9 P 0 ;1
L 9.5825 3.4325 9.5825 3.4325 9 P 0 ;1
L 9.5825 3.4825 9.5825 3.4825 9 P 0 ;1
L 9.5825 3.5325 9.5825 3.5325 9 P 0 ;1
L 9.5825 3.5825 9.5825 3.5825 9 P 0 ;1
L 9.5825 3.6325 9.5825 3.6325 9 P 0 ;1
L 9.5825 3.6825 9.5825 3.6825 9 P 0 ;1
L 9.5825 3.7325 9.5825 3.7325 9 P 0 ;1
L 9.5825 3.7825 9.5825 3.7825 9 P 0 ;1
L 9.5825 3.8325 9.5825 3.8325 9 P 0 ;1
L 9.5825 3.8825 9.5825 3.8825 9 P 0 ;1
L 9.5825 3.9325 9.5825 3.9325 9 P 0 ;1
L 9.5825 3.9825 9.5825 3.9825 9 P 0 ;1
L 9.5825 4.0325 9.5825 4.0325 9 P 0 ;1
L 9.5825 4.0825 9.5825 4.0825 9 P 0 ;1
L 9.5825 4.1325 9.5825 4.1325 9 P 0 ;1
L 9.5825 4.1825 9.5825 4.1825 9 P 0 ;1
L 9.5825 4.2325 9.5825 4.2325 9 P 0 ;1
L 9.5825 4.2825 9.5825 4.2825 9 P 0 ;1
L 9.5825 4.3325 9.5825 4.3325 9 P 0 ;1
L 9.5825 4.3825 9.5825 4.3825 9 P 0 ;1
L 9.5825 4.4325 9.5825 4.4325 9 P 0 ;1
L 9.5825 4.4825 9.5825 4.4825 9 P 0 ;1
L 9.5825 4.5325 9.5825 4.5325 9 P 0 ;1
L 9.5825 4.5825 9.5825 4.5825 9 P 0 ;1
L 9.5825 5.2825 9.5825 5.2825 9 P 0 ;1
L 9.5825 5.3325 9.5825 5.3325 9 P 0 ;1
L 9.5825 5.3825 9.5825 5.3825 9 P 0 ;1
L 9.5825 5.4325 9.5825 5.4325 9 P 0 ;1
L 9.5825 5.4825 9.5825 5.4825 9 P 0 ;1
L 9.5825 5.5325 9.5825 5.5325 9 P 0 ;1
L 9.5825 5.5825 9.5825 5.5825 9 P 0 ;1
L 9.5825 5.6325 9.5825 5.6325 9 P 0 ;1
L 9.5825 5.6825 9.5825 5.6825 9 P 0 ;1
L 9.5825 5.7325 9.5825 5.7325 9 P 0 ;1
L 9.5825 5.7825 9.5825 5.7825 9 P 0 ;1
L 9.5825 5.8325 9.5825 5.8325 9 P 0 ;1
L 9.5825 5.8825 9.5825 5.8825 9 P 0 ;1
L 9.6325 0.1325 9.6325 0.1325 9 P 0 ;1
L 9.6325 0.1825 9.6325 0.1825 9 P 0 ;1
L 9.6325 0.2325 9.6325 0.2325 9 P 0 ;1
L 9.6325 0.3325 9.6325 0.3325 9 P 0 ;1
L 9.6325 0.4325 9.6325 0.4325 9 P 0 ;1
L 9.6325 0.4825 9.6325 0.4825 9 P 0 ;1
L 9.6325 0.5325 9.6325 0.5325 9 P 0 ;1
L 9.6325 0.5825 9.6325 0.5825 9 P 0 ;1
L 9.6325 0.8825 9.6325 0.8825 9 P 0 ;1
L 9.6325 0.9325 9.6325 0.9325 9 P 0 ;1
L 9.6325 0.9825 9.6325 0.9825 9 P 0 ;1
L 9.6325 1.0325 9.6325 1.0325 9 P 0 ;1
L 9.6325 1.0825 9.6325 1.0825 9 P 0 ;1
L 9.6325 1.1325 9.6325 1.1325 9 P 0 ;1
L 9.6325 1.1825 9.6325 1.1825 9 P 0 ;1
L 9.6325 1.2325 9.6325 1.2325 9 P 0 ;1
L 9.6325 1.2825 9.6325 1.2825 9 P 0 ;1
L 9.6325 1.3325 9.6325 1.3325 9 P 0 ;1
L 9.6325 1.3825 9.6325 1.3825 9 P 0 ;1
L 9.6325 1.4325 9.6325 1.4325 9 P 0 ;1
L 9.6325 1.4825 9.6325 1.4825 9 P 0 ;1
L 9.6325 1.5325 9.6325 1.5325 9 P 0 ;1
L 9.6325 1.5825 9.6325 1.5825 9 P 0 ;1
L 9.6325 1.6325 9.6325 1.6325 9 P 0 ;1
L 9.6325 1.6825 9.6325 1.6825 9 P 0 ;1
L 9.6325 1.7325 9.6325 1.7325 9 P 0 ;1
L 9.6325 1.7825 9.6325 1.7825 9 P 0 ;1
L 9.6325 1.8325 9.6325 1.8325 9 P 0 ;1
L 9.6325 1.8825 9.6325 1.8825 9 P 0 ;1
L 9.6325 1.9325 9.6325 1.9325 9 P 0 ;1
L 9.6325 1.9825 9.6325 1.9825 9 P 0 ;1
L 9.6325 2.0325 9.6325 2.0325 9 P 0 ;1
L 9.6325 2.0825 9.6325 2.0825 9 P 0 ;1
L 9.6325 2.1325 9.6325 2.1325 9 P 0 ;1
L 9.6325 2.1825 9.6325 2.1825 9 P 0 ;1
L 9.6325 2.2325 9.6325 2.2325 9 P 0 ;1
L 9.6325 2.2825 9.6325 2.2825 9 P 0 ;1
L 9.6325 2.3325 9.6325 2.3325 9 P 0 ;1
L 9.6325 2.3825 9.6325 2.3825 9 P 0 ;1
L 9.6325 2.4325 9.6325 2.4325 9 P 0 ;1
L 9.6325 2.4825 9.6325 2.4825 9 P 0 ;1
L 9.6325 2.5325 9.6325 2.5325 9 P 0 ;1
L 9.6325 2.5825 9.6325 2.5825 9 P 0 ;1
L 9.6325 2.6325 9.6325 2.6325 9 P 0 ;1
L 9.6325 2.6825 9.6325 2.6825 9 P 0 ;1
L 9.6325 2.7325 9.6325 2.7325 9 P 0 ;1
L 9.6325 2.7825 9.6325 2.7825 9 P 0 ;1
L 9.6325 2.8325 9.6325 2.8325 9 P 0 ;1
L 9.6325 2.8825 9.6325 2.8825 9 P 0 ;1
L 9.6325 2.9325 9.6325 2.9325 9 P 0 ;1
L 9.6325 2.9825 9.6325 2.9825 9 P 0 ;1
L 9.6325 3.0325 9.6325 3.0325 9 P 0 ;1
L 9.6325 3.0825 9.6325 3.0825 9 P 0 ;1
L 9.6325 3.1325 9.6325 3.1325 9 P 0 ;1
L 9.6325 3.1825 9.6325 3.1825 9 P 0 ;1
L 9.6325 3.2325 9.6325 3.2325 9 P 0 ;1
L 9.6325 3.2825 9.6325 3.2825 9 P 0 ;1
L 9.6325 3.3325 9.6325 3.3325 9 P 0 ;1
L 9.6325 3.3825 9.6325 3.3825 9 P 0 ;1
L 9.6325 3.4325 9.6325 3.4325 9 P 0 ;1
L 9.6325 3.4825 9.6325 3.4825 9 P 0 ;1
L 9.6325 3.5325 9.6325 3.5325 9 P 0 ;1
L 9.6325 3.5825 9.6325 3.5825 9 P 0 ;1
L 9.6325 3.6325 9.6325 3.6325 9 P 0 ;1
L 9.6325 3.6825 9.6325 3.6825 9 P 0 ;1
L 9.6325 3.7325 9.6325 3.7325 9 P 0 ;1
L 9.6325 3.7825 9.6325 3.7825 9 P 0 ;1
L 9.6325 3.8325 9.6325 3.8325 9 P 0 ;1
L 9.6325 3.8825 9.6325 3.8825 9 P 0 ;1
L 9.6325 3.9325 9.6325 3.9325 9 P 0 ;1
L 9.6325 3.9825 9.6325 3.9825 9 P 0 ;1
L 9.6325 4.0325 9.6325 4.0325 9 P 0 ;1
L 9.6325 4.0825 9.6325 4.0825 9 P 0 ;1
L 9.6325 4.1325 9.6325 4.1325 9 P 0 ;1
L 9.6325 4.1825 9.6325 4.1825 9 P 0 ;1
L 9.6325 4.2325 9.6325 4.2325 9 P 0 ;1
L 9.6325 4.2825 9.6325 4.2825 9 P 0 ;1
L 9.6325 4.3325 9.6325 4.3325 9 P 0 ;1
L 9.6325 4.3825 9.6325 4.3825 9 P 0 ;1
L 9.6325 4.4325 9.6325 4.4325 9 P 0 ;1
L 9.6325 4.4825 9.6325 4.4825 9 P 0 ;1
L 9.6325 4.5325 9.6325 4.5325 9 P 0 ;1
L 9.6325 4.5825 9.6325 4.5825 9 P 0 ;1
L 9.6325 5.2825 9.6325 5.2825 9 P 0 ;1
L 9.6325 5.3325 9.6325 5.3325 9 P 0 ;1
L 9.6325 5.3825 9.6325 5.3825 9 P 0 ;1
L 9.6325 5.4325 9.6325 5.4325 9 P 0 ;1
L 9.6325 5.4825 9.6325 5.4825 9 P 0 ;1
L 9.6325 5.5325 9.6325 5.5325 9 P 0 ;1
L 9.6325 5.5825 9.6325 5.5825 9 P 0 ;1
L 9.6325 5.6325 9.6325 5.6325 9 P 0 ;1
L 9.6325 5.6825 9.6325 5.6825 9 P 0 ;1
L 9.6325 5.7325 9.6325 5.7325 9 P 0 ;1
L 9.6325 5.7825 9.6325 5.7825 9 P 0 ;1
L 9.6325 5.8325 9.6325 5.8325 9 P 0 ;1
L 9.6325 5.8825 9.6325 5.8825 9 P 0 ;1
L 9.6825 0.1325 9.6825 0.1325 9 P 0 ;1
L 9.6825 0.1825 9.6825 0.1825 9 P 0 ;1
L 9.6825 0.2325 9.6825 0.2325 9 P 0 ;1
L 9.6825 0.2825 9.6825 0.2825 9 P 0 ;1
L 9.6825 0.3325 9.6825 0.3325 9 P 0 ;1
L 9.6825 0.3825 9.6825 0.3825 9 P 0 ;1
L 9.6825 0.4325 9.6825 0.4325 9 P 0 ;1
L 9.6825 0.4825 9.6825 0.4825 9 P 0 ;1
L 9.6825 0.5325 9.6825 0.5325 9 P 0 ;1
L 9.6825 0.5825 9.6825 0.5825 9 P 0 ;1
L 9.6825 0.6325 9.6825 0.6325 9 P 0 ;1
L 9.6825 0.8825 9.6825 0.8825 9 P 0 ;1
L 9.6825 0.9325 9.6825 0.9325 9 P 0 ;1
L 9.6825 0.9825 9.6825 0.9825 9 P 0 ;1
L 9.6825 1.0325 9.6825 1.0325 9 P 0 ;1
L 9.6825 1.0825 9.6825 1.0825 9 P 0 ;1
L 9.6825 1.1325 9.6825 1.1325 9 P 0 ;1
L 9.6825 1.1825 9.6825 1.1825 9 P 0 ;1
L 9.6825 1.2325 9.6825 1.2325 9 P 0 ;1
L 9.6825 1.2825 9.6825 1.2825 9 P 0 ;1
L 9.6825 1.3325 9.6825 1.3325 9 P 0 ;1
L 9.6825 1.3825 9.6825 1.3825 9 P 0 ;1
L 9.6825 1.4325 9.6825 1.4325 9 P 0 ;1
L 9.6825 1.4825 9.6825 1.4825 9 P 0 ;1
L 9.6825 1.5325 9.6825 1.5325 9 P 0 ;1
L 9.6825 1.5825 9.6825 1.5825 9 P 0 ;1
L 9.6825 1.6325 9.6825 1.6325 9 P 0 ;1
L 9.6825 1.6825 9.6825 1.6825 9 P 0 ;1
L 9.6825 1.7325 9.6825 1.7325 9 P 0 ;1
L 9.6825 1.7825 9.6825 1.7825 9 P 0 ;1
L 9.6825 1.8325 9.6825 1.8325 9 P 0 ;1
L 9.6825 1.8825 9.6825 1.8825 9 P 0 ;1
L 9.6825 1.9325 9.6825 1.9325 9 P 0 ;1
L 9.6825 1.9825 9.6825 1.9825 9 P 0 ;1
L 9.6825 2.0325 9.6825 2.0325 9 P 0 ;1
L 9.6825 2.0825 9.6825 2.0825 9 P 0 ;1
L 9.6825 2.1325 9.6825 2.1325 9 P 0 ;1
L 9.6825 2.1825 9.6825 2.1825 9 P 0 ;1
L 9.6825 2.2325 9.6825 2.2325 9 P 0 ;1
L 9.6825 2.2825 9.6825 2.2825 9 P 0 ;1
L 9.6825 2.3325 9.6825 2.3325 9 P 0 ;1
L 9.6825 2.3825 9.6825 2.3825 9 P 0 ;1
L 9.6825 2.4325 9.6825 2.4325 9 P 0 ;1
L 9.6825 2.4825 9.6825 2.4825 9 P 0 ;1
L 9.6825 2.5325 9.6825 2.5325 9 P 0 ;1
L 9.6825 2.5825 9.6825 2.5825 9 P 0 ;1
L 9.6825 2.6325 9.6825 2.6325 9 P 0 ;1
L 9.6825 2.6825 9.6825 2.6825 9 P 0 ;1
L 9.6825 2.7325 9.6825 2.7325 9 P 0 ;1
L 9.6825 2.7825 9.6825 2.7825 9 P 0 ;1
L 9.6825 2.8325 9.6825 2.8325 9 P 0 ;1
L 9.6825 2.8825 9.6825 2.8825 9 P 0 ;1
L 9.6825 2.9325 9.6825 2.9325 9 P 0 ;1
L 9.6825 2.9825 9.6825 2.9825 9 P 0 ;1
L 9.6825 3.0325 9.6825 3.0325 9 P 0 ;1
L 9.6825 3.0825 9.6825 3.0825 9 P 0 ;1
L 9.6825 3.1325 9.6825 3.1325 9 P 0 ;1
L 9.6825 3.1825 9.6825 3.1825 9 P 0 ;1
L 9.6825 3.2325 9.6825 3.2325 9 P 0 ;1
L 9.6825 3.2825 9.6825 3.2825 9 P 0 ;1
L 9.6825 3.3325 9.6825 3.3325 9 P 0 ;1
L 9.6825 3.3825 9.6825 3.3825 9 P 0 ;1
L 9.6825 3.4325 9.6825 3.4325 9 P 0 ;1
L 9.6825 3.4825 9.6825 3.4825 9 P 0 ;1
L 9.6825 3.5325 9.6825 3.5325 9 P 0 ;1
L 9.6825 3.5825 9.6825 3.5825 9 P 0 ;1
L 9.6825 3.6325 9.6825 3.6325 9 P 0 ;1
L 9.6825 3.6825 9.6825 3.6825 9 P 0 ;1
L 9.6825 3.7325 9.6825 3.7325 9 P 0 ;1
L 9.6825 3.7825 9.6825 3.7825 9 P 0 ;1
L 9.6825 3.8325 9.6825 3.8325 9 P 0 ;1
L 9.6825 3.8825 9.6825 3.8825 9 P 0 ;1
L 9.6825 3.9325 9.6825 3.9325 9 P 0 ;1
L 9.6825 3.9825 9.6825 3.9825 9 P 0 ;1
L 9.6825 4.0325 9.6825 4.0325 9 P 0 ;1
L 9.6825 4.0825 9.6825 4.0825 9 P 0 ;1
L 9.6825 4.1325 9.6825 4.1325 9 P 0 ;1
L 9.6825 4.1825 9.6825 4.1825 9 P 0 ;1
L 9.6825 4.2325 9.6825 4.2325 9 P 0 ;1
L 9.6825 4.2825 9.6825 4.2825 9 P 0 ;1
L 9.6825 4.3325 9.6825 4.3325 9 P 0 ;1
L 9.6825 4.3825 9.6825 4.3825 9 P 0 ;1
L 9.6825 4.4325 9.6825 4.4325 9 P 0 ;1
L 9.6825 4.4825 9.6825 4.4825 9 P 0 ;1
L 9.6825 4.5325 9.6825 4.5325 9 P 0 ;1
L 9.6825 4.5825 9.6825 4.5825 9 P 0 ;1
L 9.6825 4.6325 9.6825 4.6325 9 P 0 ;1
L 9.6825 4.6825 9.6825 4.6825 9 P 0 ;1
L 9.6825 4.8325 9.6825 4.8325 9 P 0 ;1
L 9.6825 4.8825 9.6825 4.8825 9 P 0 ;1
L 9.6825 4.9825 9.6825 4.9825 9 P 0 ;1
L 9.6825 5.1325 9.6825 5.1325 9 P 0 ;1
L 9.6825 5.1825 9.6825 5.1825 9 P 0 ;1
L 9.6825 5.2325 9.6825 5.2325 9 P 0 ;1
L 9.6825 5.2825 9.6825 5.2825 9 P 0 ;1
L 9.6825 5.3325 9.6825 5.3325 9 P 0 ;1
L 9.6825 5.3825 9.6825 5.3825 9 P 0 ;1
L 9.6825 5.4325 9.6825 5.4325 9 P 0 ;1
L 9.6825 5.4825 9.6825 5.4825 9 P 0 ;1
L 9.6825 5.5325 9.6825 5.5325 9 P 0 ;1
L 9.6825 5.5825 9.6825 5.5825 9 P 0 ;1
L 9.6825 5.6325 9.6825 5.6325 9 P 0 ;1
L 9.6825 5.6825 9.6825 5.6825 9 P 0 ;1
L 9.6825 5.7325 9.6825 5.7325 9 P 0 ;1
L 9.6825 5.7825 9.6825 5.7825 9 P 0 ;1
L 9.6825 5.8325 9.6825 5.8325 9 P 0 ;1
L 9.6825 5.8825 9.6825 5.8825 9 P 0 ;1
L 9.7325 0.1325 9.7325 0.1325 9 P 0 ;1
L 9.7325 0.1825 9.7325 0.1825 9 P 0 ;1
L 9.7325 0.2325 9.7325 0.2325 9 P 0 ;1
L 9.7325 0.2825 9.7325 0.2825 9 P 0 ;1
L 9.7325 0.3325 9.7325 0.3325 9 P 0 ;1
L 9.7325 0.3825 9.7325 0.3825 9 P 0 ;1
L 9.7325 0.4325 9.7325 0.4325 9 P 0 ;1
L 9.7325 0.4825 9.7325 0.4825 9 P 0 ;1
L 9.7325 0.5325 9.7325 0.5325 9 P 0 ;1
L 9.7325 0.5825 9.7325 0.5825 9 P 0 ;1
L 9.7325 0.6325 9.7325 0.6325 9 P 0 ;1
L 9.7325 0.6825 9.7325 0.6825 9 P 0 ;1
L 9.7325 0.7325 9.7325 0.7325 9 P 0 ;1
L 9.7325 0.7825 9.7325 0.7825 9 P 0 ;1
L 9.7325 0.8325 9.7325 0.8325 9 P 0 ;1
L 9.7325 0.8825 9.7325 0.8825 9 P 0 ;1
L 9.7325 0.9325 9.7325 0.9325 9 P 0 ;1
L 9.7325 0.9825 9.7325 0.9825 9 P 0 ;1
L 9.7325 1.0325 9.7325 1.0325 9 P 0 ;1
L 9.7325 1.0825 9.7325 1.0825 9 P 0 ;1
L 9.7325 1.1325 9.7325 1.1325 9 P 0 ;1
L 9.7325 1.1825 9.7325 1.1825 9 P 0 ;1
L 9.7325 1.2325 9.7325 1.2325 9 P 0 ;1
L 9.7325 1.2825 9.7325 1.2825 9 P 0 ;1
L 9.7325 1.3325 9.7325 1.3325 9 P 0 ;1
L 9.7325 1.3825 9.7325 1.3825 9 P 0 ;1
L 9.7325 1.4325 9.7325 1.4325 9 P 0 ;1
L 9.7325 1.4825 9.7325 1.4825 9 P 0 ;1
L 9.7325 1.5325 9.7325 1.5325 9 P 0 ;1
L 9.7325 1.5825 9.7325 1.5825 9 P 0 ;1
L 9.7325 1.6325 9.7325 1.6325 9 P 0 ;1
L 9.7325 1.6825 9.7325 1.6825 9 P 0 ;1
L 9.7325 1.7325 9.7325 1.7325 9 P 0 ;1
L 9.7325 1.7825 9.7325 1.7825 9 P 0 ;1
L 9.7325 1.8325 9.7325 1.8325 9 P 0 ;1
L 9.7325 1.8825 9.7325 1.8825 9 P 0 ;1
L 9.7325 1.9325 9.7325 1.9325 9 P 0 ;1
L 9.7325 1.9825 9.7325 1.9825 9 P 0 ;1
L 9.7325 2.0325 9.7325 2.0325 9 P 0 ;1
L 9.7325 2.0825 9.7325 2.0825 9 P 0 ;1
L 9.7325 2.1325 9.7325 2.1325 9 P 0 ;1
L 9.7325 2.1825 9.7325 2.1825 9 P 0 ;1
L 9.7325 2.2325 9.7325 2.2325 9 P 0 ;1
L 9.7325 2.2825 9.7325 2.2825 9 P 0 ;1
L 9.7325 2.3325 9.7325 2.3325 9 P 0 ;1
L 9.7325 2.3825 9.7325 2.3825 9 P 0 ;1
L 9.7325 2.4325 9.7325 2.4325 9 P 0 ;1
L 9.7325 2.4825 9.7325 2.4825 9 P 0 ;1
L 9.7325 2.5325 9.7325 2.5325 9 P 0 ;1
L 9.7325 2.5825 9.7325 2.5825 9 P 0 ;1
L 9.7325 2.6325 9.7325 2.6325 9 P 0 ;1
L 9.7325 2.6825 9.7325 2.6825 9 P 0 ;1
L 9.7325 2.7325 9.7325 2.7325 9 P 0 ;1
L 9.7325 2.7825 9.7325 2.7825 9 P 0 ;1
L 9.7325 2.8325 9.7325 2.8325 9 P 0 ;1
L 9.7325 2.8825 9.7325 2.8825 9 P 0 ;1
L 9.7325 2.9325 9.7325 2.9325 9 P 0 ;1
L 9.7325 2.9825 9.7325 2.9825 9 P 0 ;1
L 9.7325 3.0325 9.7325 3.0325 9 P 0 ;1
L 9.7325 3.0825 9.7325 3.0825 9 P 0 ;1
L 9.7325 3.1325 9.7325 3.1325 9 P 0 ;1
L 9.7325 3.1825 9.7325 3.1825 9 P 0 ;1
L 9.7325 3.2325 9.7325 3.2325 9 P 0 ;1
L 9.7325 3.2825 9.7325 3.2825 9 P 0 ;1
L 9.7325 3.3325 9.7325 3.3325 9 P 0 ;1
L 9.7325 3.3825 9.7325 3.3825 9 P 0 ;1
L 9.7325 3.4325 9.7325 3.4325 9 P 0 ;1
L 9.7325 3.4825 9.7325 3.4825 9 P 0 ;1
L 9.7325 3.5325 9.7325 3.5325 9 P 0 ;1
L 9.7325 3.5825 9.7325 3.5825 9 P 0 ;1
L 9.7325 3.6325 9.7325 3.6325 9 P 0 ;1
L 9.7325 3.6825 9.7325 3.6825 9 P 0 ;1
L 9.7325 3.7325 9.7325 3.7325 9 P 0 ;1
L 9.7325 3.7825 9.7325 3.7825 9 P 0 ;1
L 9.7325 3.8325 9.7325 3.8325 9 P 0 ;1
L 9.7325 3.8825 9.7325 3.8825 9 P 0 ;1
L 9.7325 3.9325 9.7325 3.9325 9 P 0 ;1
L 9.7325 3.9825 9.7325 3.9825 9 P 0 ;1
L 9.7325 4.0325 9.7325 4.0325 9 P 0 ;1
L 9.7325 4.0825 9.7325 4.0825 9 P 0 ;1
L 9.7325 4.1325 9.7325 4.1325 9 P 0 ;1
L 9.7325 4.1825 9.7325 4.1825 9 P 0 ;1
L 9.7325 4.2325 9.7325 4.2325 9 P 0 ;1
L 9.7325 4.2825 9.7325 4.2825 9 P 0 ;1
L 9.7325 4.3325 9.7325 4.3325 9 P 0 ;1
L 9.7325 4.3825 9.7325 4.3825 9 P 0 ;1
L 9.7325 4.4325 9.7325 4.4325 9 P 0 ;1
L 9.7325 4.4825 9.7325 4.4825 9 P 0 ;1
L 9.7325 4.5325 9.7325 4.5325 9 P 0 ;1
L 9.7325 4.5825 9.7325 4.5825 9 P 0 ;1
L 9.7325 4.6325 9.7325 4.6325 9 P 0 ;1
L 9.7325 4.6825 9.7325 4.6825 9 P 0 ;1
L 9.7325 4.7325 9.7325 4.7325 9 P 0 ;1
L 9.7325 4.7825 9.7325 4.7825 9 P 0 ;1
L 9.7325 4.8325 9.7325 4.8325 9 P 0 ;1
L 9.7325 4.8825 9.7325 4.8825 9 P 0 ;1
L 9.7325 4.9325 9.7325 4.9325 9 P 0 ;1
L 9.7325 4.9825 9.7325 4.9825 9 P 0 ;1
L 9.7325 5.0325 9.7325 5.0325 9 P 0 ;1
L 9.7325 5.0825 9.7325 5.0825 9 P 0 ;1
L 9.7325 5.1325 9.7325 5.1325 9 P 0 ;1
L 9.7325 5.1825 9.7325 5.1825 9 P 0 ;1
L 9.7325 5.2325 9.7325 5.2325 9 P 0 ;1
L 9.7325 5.2825 9.7325 5.2825 9 P 0 ;1
L 9.7325 5.3325 9.7325 5.3325 9 P 0 ;1
L 9.7325 5.3825 9.7325 5.3825 9 P 0 ;1
L 9.7325 5.4325 9.7325 5.4325 9 P 0 ;1
L 9.7325 5.4825 9.7325 5.4825 9 P 0 ;1
L 9.7325 5.5325 9.7325 5.5325 9 P 0 ;1
L 9.7325 5.5825 9.7325 5.5825 9 P 0 ;1
L 9.7325 5.6325 9.7325 5.6325 9 P 0 ;1
L 9.7325 5.6825 9.7325 5.6825 9 P 0 ;1
L 9.7325 5.7325 9.7325 5.7325 9 P 0 ;1
L 9.7325 5.7825 9.7325 5.7825 9 P 0 ;1
L 9.7325 5.8325 9.7325 5.8325 9 P 0 ;1
L 9.7325 5.8825 9.7325 5.8825 9 P 0 ;1
L 9.7825 0.1325 9.7825 0.1325 9 P 0 ;1
L 9.7825 0.1825 9.7825 0.1825 9 P 0 ;1
L 9.7825 0.2325 9.7825 0.2325 9 P 0 ;1
L 9.7825 0.2825 9.7825 0.2825 9 P 0 ;1
L 9.7825 0.3325 9.7825 0.3325 9 P 0 ;1
L 9.7825 0.3825 9.7825 0.3825 9 P 0 ;1
L 9.7825 0.4325 9.7825 0.4325 9 P 0 ;1
L 9.7825 0.4825 9.7825 0.4825 9 P 0 ;1
L 9.7825 0.5325 9.7825 0.5325 9 P 0 ;1
L 9.7825 0.5825 9.7825 0.5825 9 P 0 ;1
L 9.7825 0.6325 9.7825 0.6325 9 P 0 ;1
L 9.7825 0.6825 9.7825 0.6825 9 P 0 ;1
L 9.7825 0.7325 9.7825 0.7325 9 P 0 ;1
L 9.7825 0.7825 9.7825 0.7825 9 P 0 ;1
L 9.7825 0.8325 9.7825 0.8325 9 P 0 ;1
L 9.7825 0.8825 9.7825 0.8825 9 P 0 ;1
L 9.7825 0.9325 9.7825 0.9325 9 P 0 ;1
L 9.7825 0.9825 9.7825 0.9825 9 P 0 ;1
L 9.7825 1.0325 9.7825 1.0325 9 P 0 ;1
L 9.7825 1.0825 9.7825 1.0825 9 P 0 ;1
L 9.7825 1.1325 9.7825 1.1325 9 P 0 ;1
L 9.7825 1.1825 9.7825 1.1825 9 P 0 ;1
L 9.7825 1.2325 9.7825 1.2325 9 P 0 ;1
L 9.7825 1.2825 9.7825 1.2825 9 P 0 ;1
L 9.7825 1.3325 9.7825 1.3325 9 P 0 ;1
L 9.7825 1.3825 9.7825 1.3825 9 P 0 ;1
L 9.7825 1.4325 9.7825 1.4325 9 P 0 ;1
L 9.7825 1.4825 9.7825 1.4825 9 P 0 ;1
L 9.7825 1.5325 9.7825 1.5325 9 P 0 ;1
L 9.7825 1.5825 9.7825 1.5825 9 P 0 ;1
L 9.7825 1.6325 9.7825 1.6325 9 P 0 ;1
L 9.7825 1.6825 9.7825 1.6825 9 P 0 ;1
L 9.7825 1.7325 9.7825 1.7325 9 P 0 ;1
L 9.7825 1.7825 9.7825 1.7825 9 P 0 ;1
L 9.7825 1.8325 9.7825 1.8325 9 P 0 ;1
L 9.7825 1.8825 9.7825 1.8825 9 P 0 ;1
L 9.7825 1.9325 9.7825 1.9325 9 P 0 ;1
L 9.7825 1.9825 9.7825 1.9825 9 P 0 ;1
L 9.7825 2.0325 9.7825 2.0325 9 P 0 ;1
L 9.7825 2.0825 9.7825 2.0825 9 P 0 ;1
L 9.7825 2.1325 9.7825 2.1325 9 P 0 ;1
L 9.7825 2.1825 9.7825 2.1825 9 P 0 ;1
L 9.7825 2.2325 9.7825 2.2325 9 P 0 ;1
L 9.7825 2.2825 9.7825 2.2825 9 P 0 ;1
L 9.7825 2.3325 9.7825 2.3325 9 P 0 ;1
L 9.7825 2.3825 9.7825 2.3825 9 P 0 ;1
L 9.7825 2.4325 9.7825 2.4325 9 P 0 ;1
L 9.7825 2.4825 9.7825 2.4825 9 P 0 ;1
L 9.7825 2.5325 9.7825 2.5325 9 P 0 ;1
L 9.7825 2.5825 9.7825 2.5825 9 P 0 ;1
L 9.7825 2.6325 9.7825 2.6325 9 P 0 ;1
L 9.7825 2.6825 9.7825 2.6825 9 P 0 ;1
L 9.7825 2.7325 9.7825 2.7325 9 P 0 ;1
L 9.7825 2.7825 9.7825 2.7825 9 P 0 ;1
L 9.7825 2.8325 9.7825 2.8325 9 P 0 ;1
L 9.7825 2.8825 9.7825 2.8825 9 P 0 ;1
L 9.7825 2.9325 9.7825 2.9325 9 P 0 ;1
L 9.7825 2.9825 9.7825 2.9825 9 P 0 ;1
L 9.7825 3.0325 9.7825 3.0325 9 P 0 ;1
L 9.7825 3.0825 9.7825 3.0825 9 P 0 ;1
L 9.7825 3.1325 9.7825 3.1325 9 P 0 ;1
L 9.7825 3.1825 9.7825 3.1825 9 P 0 ;1
L 9.7825 3.2325 9.7825 3.2325 9 P 0 ;1
L 9.7825 3.2825 9.7825 3.2825 9 P 0 ;1
L 9.7825 3.3325 9.7825 3.3325 9 P 0 ;1
L 9.7825 3.3825 9.7825 3.3825 9 P 0 ;1
L 9.7825 3.4325 9.7825 3.4325 9 P 0 ;1
L 9.7825 3.4825 9.7825 3.4825 9 P 0 ;1
L 9.7825 3.5325 9.7825 3.5325 9 P 0 ;1
L 9.7825 3.5825 9.7825 3.5825 9 P 0 ;1
L 9.7825 3.6325 9.7825 3.6325 9 P 0 ;1
L 9.7825 3.6825 9.7825 3.6825 9 P 0 ;1
L 9.7825 3.7325 9.7825 3.7325 9 P 0 ;1
L 9.7825 3.7825 9.7825 3.7825 9 P 0 ;1
L 9.7825 3.8325 9.7825 3.8325 9 P 0 ;1
L 9.7825 3.8825 9.7825 3.8825 9 P 0 ;1
L 9.7825 3.9325 9.7825 3.9325 9 P 0 ;1
L 9.7825 3.9825 9.7825 3.9825 9 P 0 ;1
L 9.7825 4.0325 9.7825 4.0325 9 P 0 ;1
L 9.7825 4.0825 9.7825 4.0825 9 P 0 ;1
L 9.7825 4.1325 9.7825 4.1325 9 P 0 ;1
L 9.7825 4.1825 9.7825 4.1825 9 P 0 ;1
L 9.7825 4.2325 9.7825 4.2325 9 P 0 ;1
L 9.7825 4.2825 9.7825 4.2825 9 P 0 ;1
L 9.7825 4.3325 9.7825 4.3325 9 P 0 ;1
L 9.7825 4.3825 9.7825 4.3825 9 P 0 ;1
L 9.7825 4.4325 9.7825 4.4325 9 P 0 ;1
L 9.7825 4.4825 9.7825 4.4825 9 P 0 ;1
L 9.7825 4.5325 9.7825 4.5325 9 P 0 ;1
L 9.7825 4.5825 9.7825 4.5825 9 P 0 ;1
L 9.7825 4.6325 9.7825 4.6325 9 P 0 ;1
L 9.7825 4.6825 9.7825 4.6825 9 P 0 ;1
L 9.7825 4.7325 9.7825 4.7325 9 P 0 ;1
L 9.7825 4.7825 9.7825 4.7825 9 P 0 ;1
L 9.7825 4.8325 9.7825 4.8325 9 P 0 ;1
L 9.7825 4.8825 9.7825 4.8825 9 P 0 ;1
L 9.7825 4.9325 9.7825 4.9325 9 P 0 ;1
L 9.7825 4.9825 9.7825 4.9825 9 P 0 ;1
L 9.7825 5.0325 9.7825 5.0325 9 P 0 ;1
L 9.7825 5.0825 9.7825 5.0825 9 P 0 ;1
L 9.7825 5.1325 9.7825 5.1325 9 P 0 ;1
L 9.7825 5.1825 9.7825 5.1825 9 P 0 ;1
L 9.7825 5.2325 9.7825 5.2325 9 P 0 ;1
L 9.7825 5.2825 9.7825 5.2825 9 P 0 ;1
L 9.7825 5.3325 9.7825 5.3325 9 P 0 ;1
L 9.7825 5.3825 9.7825 5.3825 9 P 0 ;1
L 9.7825 5.4325 9.7825 5.4325 9 P 0 ;1
L 9.7825 5.4825 9.7825 5.4825 9 P 0 ;1
L 9.7825 5.5325 9.7825 5.5325 9 P 0 ;1
L 9.7825 5.5825 9.7825 5.5825 9 P 0 ;1
L 9.7825 5.6325 9.7825 5.6325 9 P 0 ;1
L 9.7825 5.6825 9.7825 5.6825 9 P 0 ;1
L 9.7825 5.7325 9.7825 5.7325 9 P 0 ;1
L 9.7825 5.7825 9.7825 5.7825 9 P 0 ;1
L 9.7825 5.8325 9.7825 5.8325 9 P 0 ;1
L 9.7825 5.8825 9.7825 5.8825 9 P 0 ;1
L 9.8325 0.1325 9.8325 0.1325 9 P 0 ;1
L 9.8325 0.1825 9.8325 0.1825 9 P 0 ;1
L 9.8325 0.2325 9.8325 0.2325 9 P 0 ;1
L 9.8325 0.2825 9.8325 0.2825 9 P 0 ;1
L 9.8325 0.3325 9.8325 0.3325 9 P 0 ;1
L 9.8325 0.3825 9.8325 0.3825 9 P 0 ;1
L 9.8325 0.4325 9.8325 0.4325 9 P 0 ;1
L 9.8325 0.4825 9.8325 0.4825 9 P 0 ;1
L 9.8325 0.5325 9.8325 0.5325 9 P 0 ;1
L 9.8325 0.5825 9.8325 0.5825 9 P 0 ;1
L 9.8325 0.6325 9.8325 0.6325 9 P 0 ;1
L 9.8325 0.6825 9.8325 0.6825 9 P 0 ;1
L 9.8325 0.7325 9.8325 0.7325 9 P 0 ;1
L 9.8325 0.7825 9.8325 0.7825 9 P 0 ;1
L 9.8325 0.8325 9.8325 0.8325 9 P 0 ;1
L 9.8325 0.8825 9.8325 0.8825 9 P 0 ;1
L 9.8325 0.9325 9.8325 0.9325 9 P 0 ;1
L 9.8325 0.9825 9.8325 0.9825 9 P 0 ;1
L 9.8325 1.0325 9.8325 1.0325 9 P 0 ;1
L 9.8325 1.0825 9.8325 1.0825 9 P 0 ;1
L 9.8325 1.1325 9.8325 1.1325 9 P 0 ;1
L 9.8325 1.1825 9.8325 1.1825 9 P 0 ;1
L 9.8325 1.2325 9.8325 1.2325 9 P 0 ;1
L 9.8325 1.2825 9.8325 1.2825 9 P 0 ;1
L 9.8325 1.3325 9.8325 1.3325 9 P 0 ;1
L 9.8325 1.3825 9.8325 1.3825 9 P 0 ;1
L 9.8325 1.4325 9.8325 1.4325 9 P 0 ;1
L 9.8325 1.4825 9.8325 1.4825 9 P 0 ;1
L 9.8325 1.5325 9.8325 1.5325 9 P 0 ;1
L 9.8325 1.5825 9.8325 1.5825 9 P 0 ;1
L 9.8325 1.6325 9.8325 1.6325 9 P 0 ;1
L 9.8325 1.6825 9.8325 1.6825 9 P 0 ;1
L 9.8325 1.7325 9.8325 1.7325 9 P 0 ;1
L 9.8325 1.7825 9.8325 1.7825 9 P 0 ;1
L 9.8325 1.8325 9.8325 1.8325 9 P 0 ;1
L 9.8325 1.8825 9.8325 1.8825 9 P 0 ;1
L 9.8325 1.9325 9.8325 1.9325 9 P 0 ;1
L 9.8325 1.9825 9.8325 1.9825 9 P 0 ;1
L 9.8325 2.0325 9.8325 2.0325 9 P 0 ;1
L 9.8325 2.0825 9.8325 2.0825 9 P 0 ;1
L 9.8325 2.1325 9.8325 2.1325 9 P 0 ;1
L 9.8325 2.1825 9.8325 2.1825 9 P 0 ;1
L 9.8325 2.2325 9.8325 2.2325 9 P 0 ;1
L 9.8325 2.2825 9.8325 2.2825 9 P 0 ;1
L 9.8325 2.3325 9.8325 2.3325 9 P 0 ;1
L 9.8325 2.3825 9.8325 2.3825 9 P 0 ;1
L 9.8325 2.4325 9.8325 2.4325 9 P 0 ;1
L 9.8325 2.4825 9.8325 2.4825 9 P 0 ;1
L 9.8325 2.5325 9.8325 2.5325 9 P 0 ;1
L 9.8325 2.5825 9.8325 2.5825 9 P 0 ;1
L 9.8325 2.6325 9.8325 2.6325 9 P 0 ;1
L 9.8325 2.6825 9.8325 2.6825 9 P 0 ;1
L 9.8325 2.7325 9.8325 2.7325 9 P 0 ;1
L 9.8325 2.7825 9.8325 2.7825 9 P 0 ;1
L 9.8325 2.8325 9.8325 2.8325 9 P 0 ;1
L 9.8325 2.8825 9.8325 2.8825 9 P 0 ;1
L 9.8325 2.9325 9.8325 2.9325 9 P 0 ;1
L 9.8325 2.9825 9.8325 2.9825 9 P 0 ;1
L 9.8325 3.0325 9.8325 3.0325 9 P 0 ;1
L 9.8325 3.0825 9.8325 3.0825 9 P 0 ;1
L 9.8325 3.1325 9.8325 3.1325 9 P 0 ;1
L 9.8325 3.1825 9.8325 3.1825 9 P 0 ;1
L 9.8325 3.2325 9.8325 3.2325 9 P 0 ;1
L 9.8325 3.2825 9.8325 3.2825 9 P 0 ;1
L 9.8325 3.3325 9.8325 3.3325 9 P 0 ;1
L 9.8325 3.3825 9.8325 3.3825 9 P 0 ;1
L 9.8325 3.4325 9.8325 3.4325 9 P 0 ;1
L 9.8325 3.4825 9.8325 3.4825 9 P 0 ;1
L 9.8325 3.5325 9.8325 3.5325 9 P 0 ;1
L 9.8325 3.5825 9.8325 3.5825 9 P 0 ;1
L 9.8325 3.6325 9.8325 3.6325 9 P 0 ;1
L 9.8325 3.6825 9.8325 3.6825 9 P 0 ;1
L 9.8325 3.7325 9.8325 3.7325 9 P 0 ;1
L 9.8325 3.7825 9.8325 3.7825 9 P 0 ;1
L 9.8325 3.8325 9.8325 3.8325 9 P 0 ;1
L 9.8325 3.8825 9.8325 3.8825 9 P 0 ;1
L 9.8325 3.9325 9.8325 3.9325 9 P 0 ;1
L 9.8325 3.9825 9.8325 3.9825 9 P 0 ;1
L 9.8325 4.0325 9.8325 4.0325 9 P 0 ;1
L 9.8325 4.0825 9.8325 4.0825 9 P 0 ;1
L 9.8325 4.1325 9.8325 4.1325 9 P 0 ;1
L 9.8325 4.1825 9.8325 4.1825 9 P 0 ;1
L 9.8325 4.2325 9.8325 4.2325 9 P 0 ;1
L 9.8325 4.2825 9.8325 4.2825 9 P 0 ;1
L 9.8325 4.3325 9.8325 4.3325 9 P 0 ;1
L 9.8325 4.3825 9.8325 4.3825 9 P 0 ;1
L 9.8325 4.4825 9.8325 4.4825 9 P 0 ;1
L 9.8325 4.5325 9.8325 4.5325 9 P 0 ;1
L 9.8325 4.5825 9.8325 4.5825 9 P 0 ;1
L 9.8325 4.6325 9.8325 4.6325 9 P 0 ;1
L 9.8325 4.6825 9.8325 4.6825 9 P 0 ;1
L 9.8325 4.7325 9.8325 4.7325 9 P 0 ;1
L 9.8325 4.7825 9.8325 4.7825 9 P 0 ;1
L 9.8325 4.8325 9.8325 4.8325 9 P 0 ;1
L 9.8325 4.8825 9.8325 4.8825 9 P 0 ;1
L 9.8325 4.9325 9.8325 4.9325 9 P 0 ;1
L 9.8325 4.9825 9.8325 4.9825 9 P 0 ;1
L 9.8325 5.0325 9.8325 5.0325 9 P 0 ;1
L 9.8325 5.0825 9.8325 5.0825 9 P 0 ;1
L 9.8325 5.1325 9.8325 5.1325 9 P 0 ;1
L 9.8325 5.1825 9.8325 5.1825 9 P 0 ;1
L 9.8325 5.2325 9.8325 5.2325 9 P 0 ;1
L 9.8325 5.2825 9.8325 5.2825 9 P 0 ;1
L 9.8325 5.3325 9.8325 5.3325 9 P 0 ;1
L 9.8325 5.3825 9.8325 5.3825 9 P 0 ;1
L 9.8325 5.4325 9.8325 5.4325 9 P 0 ;1
L 9.8325 5.4825 9.8325 5.4825 9 P 0 ;1
L 9.8325 5.5325 9.8325 5.5325 9 P 0 ;1
L 9.8325 5.5825 9.8325 5.5825 9 P 0 ;1
L 9.8325 5.6325 9.8325 5.6325 9 P 0 ;1
L 9.8325 5.6825 9.8325 5.6825 9 P 0 ;1
L 9.8325 5.7325 9.8325 5.7325 9 P 0 ;1
L 9.8325 5.7825 9.8325 5.7825 9 P 0 ;1
L 9.8325 5.8325 9.8325 5.8325 9 P 0 ;1
L 9.8325 5.8825 9.8325 5.8825 9 P 0 ;1
L 9.8825 0.1325 9.8825 0.1325 9 P 0 ;1
L 9.8825 0.1825 9.8825 0.1825 9 P 0 ;1
L 9.8825 0.2325 9.8825 0.2325 9 P 0 ;1
L 9.8825 0.2825 9.8825 0.2825 9 P 0 ;1
L 9.8825 0.3325 9.8825 0.3325 9 P 0 ;1
L 9.8825 0.3825 9.8825 0.3825 9 P 0 ;1
L 9.8825 0.4325 9.8825 0.4325 9 P 0 ;1
L 9.8825 0.4825 9.8825 0.4825 9 P 0 ;1
L 9.8825 0.5325 9.8825 0.5325 9 P 0 ;1
L 9.8825 0.5825 9.8825 0.5825 9 P 0 ;1
L 9.8825 0.6325 9.8825 0.6325 9 P 0 ;1
L 9.8825 0.6825 9.8825 0.6825 9 P 0 ;1
L 9.8825 0.7325 9.8825 0.7325 9 P 0 ;1
L 9.8825 0.7825 9.8825 0.7825 9 P 0 ;1
L 9.8825 0.8325 9.8825 0.8325 9 P 0 ;1
L 9.8825 0.8825 9.8825 0.8825 9 P 0 ;1
L 9.8825 0.9325 9.8825 0.9325 9 P 0 ;1
L 9.8825 0.9825 9.8825 0.9825 9 P 0 ;1
L 9.8825 1.0325 9.8825 1.0325 9 P 0 ;1
L 9.8825 1.0825 9.8825 1.0825 9 P 0 ;1
L 9.8825 1.1325 9.8825 1.1325 9 P 0 ;1
L 9.8825 1.1825 9.8825 1.1825 9 P 0 ;1
L 9.8825 1.2325 9.8825 1.2325 9 P 0 ;1
L 9.8825 1.2825 9.8825 1.2825 9 P 0 ;1
L 9.8825 1.3325 9.8825 1.3325 9 P 0 ;1
L 9.8825 1.3825 9.8825 1.3825 9 P 0 ;1
L 9.8825 1.4325 9.8825 1.4325 9 P 0 ;1
L 9.8825 1.4825 9.8825 1.4825 9 P 0 ;1
L 9.8825 1.5325 9.8825 1.5325 9 P 0 ;1
L 9.8825 1.5825 9.8825 1.5825 9 P 0 ;1
L 9.8825 1.6325 9.8825 1.6325 9 P 0 ;1
L 9.8825 1.6825 9.8825 1.6825 9 P 0 ;1
L 9.8825 1.7325 9.8825 1.7325 9 P 0 ;1
L 9.8825 1.7825 9.8825 1.7825 9 P 0 ;1
L 9.8825 1.8325 9.8825 1.8325 9 P 0 ;1
L 9.8825 1.8825 9.8825 1.8825 9 P 0 ;1
L 9.8825 1.9325 9.8825 1.9325 9 P 0 ;1
L 9.8825 1.9825 9.8825 1.9825 9 P 0 ;1
L 9.8825 2.0325 9.8825 2.0325 9 P 0 ;1
L 9.8825 2.0825 9.8825 2.0825 9 P 0 ;1
L 9.8825 2.1325 9.8825 2.1325 9 P 0 ;1
L 9.8825 2.1825 9.8825 2.1825 9 P 0 ;1
L 9.8825 2.2325 9.8825 2.2325 9 P 0 ;1
L 9.8825 2.2825 9.8825 2.2825 9 P 0 ;1
L 9.8825 2.3325 9.8825 2.3325 9 P 0 ;1
L 9.8825 2.3825 9.8825 2.3825 9 P 0 ;1
L 9.8825 2.4325 9.8825 2.4325 9 P 0 ;1
L 9.8825 2.4825 9.8825 2.4825 9 P 0 ;1
L 9.8825 2.5325 9.8825 2.5325 9 P 0 ;1
L 9.8825 2.5825 9.8825 2.5825 9 P 0 ;1
L 9.8825 2.6325 9.8825 2.6325 9 P 0 ;1
L 9.8825 2.6825 9.8825 2.6825 9 P 0 ;1
L 9.8825 2.7325 9.8825 2.7325 9 P 0 ;1
L 9.8825 2.7825 9.8825 2.7825 9 P 0 ;1
L 9.8825 2.8325 9.8825 2.8325 9 P 0 ;1
L 9.8825 2.8825 9.8825 2.8825 9 P 0 ;1
L 9.8825 2.9325 9.8825 2.9325 9 P 0 ;1
L 9.8825 2.9825 9.8825 2.9825 9 P 0 ;1
L 9.8825 3.0325 9.8825 3.0325 9 P 0 ;1
L 9.8825 3.0825 9.8825 3.0825 9 P 0 ;1
L 9.8825 3.1325 9.8825 3.1325 9 P 0 ;1
L 9.8825 3.1825 9.8825 3.1825 9 P 0 ;1
L 9.8825 3.2325 9.8825 3.2325 9 P 0 ;1
L 9.8825 3.2825 9.8825 3.2825 9 P 0 ;1
L 9.8825 3.3325 9.8825 3.3325 9 P 0 ;1
L 9.8825 3.3825 9.8825 3.3825 9 P 0 ;1
L 9.8825 3.4325 9.8825 3.4325 9 P 0 ;1
L 9.8825 3.4825 9.8825 3.4825 9 P 0 ;1
L 9.8825 3.5325 9.8825 3.5325 9 P 0 ;1
L 9.8825 3.5825 9.8825 3.5825 9 P 0 ;1
L 9.8825 3.6325 9.8825 3.6325 9 P 0 ;1
L 9.8825 3.6825 9.8825 3.6825 9 P 0 ;1
L 9.8825 3.7325 9.8825 3.7325 9 P 0 ;1
L 9.8825 3.7825 9.8825 3.7825 9 P 0 ;1
L 9.8825 3.8325 9.8825 3.8325 9 P 0 ;1
L 9.8825 3.8825 9.8825 3.8825 9 P 0 ;1
L 9.8825 3.9325 9.8825 3.9325 9 P 0 ;1
L 9.8825 3.9825 9.8825 3.9825 9 P 0 ;1
L 9.8825 4.0325 9.8825 4.0325 9 P 0 ;1
L 9.8825 4.0825 9.8825 4.0825 9 P 0 ;1
L 9.8825 4.1325 9.8825 4.1325 9 P 0 ;1
L 9.8825 4.1825 9.8825 4.1825 9 P 0 ;1
L 9.8825 4.2325 9.8825 4.2325 9 P 0 ;1
L 9.8825 4.2825 9.8825 4.2825 9 P 0 ;1
L 9.8825 4.3325 9.8825 4.3325 9 P 0 ;1
L 9.8825 4.5325 9.8825 4.5325 9 P 0 ;1
L 9.8825 4.5825 9.8825 4.5825 9 P 0 ;1
L 9.8825 4.7825 9.8825 4.7825 9 P 0 ;1
L 9.8825 4.8325 9.8825 4.8325 9 P 0 ;1
L 9.8825 4.8825 9.8825 4.8825 9 P 0 ;1
L 9.8825 4.9325 9.8825 4.9325 9 P 0 ;1
L 9.8825 4.9825 9.8825 4.9825 9 P 0 ;1
L 9.8825 5.0325 9.8825 5.0325 9 P 0 ;1
L 9.8825 5.0825 9.8825 5.0825 9 P 0 ;1
L 9.8825 5.1325 9.8825 5.1325 9 P 0 ;1
L 9.8825 5.1825 9.8825 5.1825 9 P 0 ;1
L 9.8825 5.2325 9.8825 5.2325 9 P 0 ;1
L 9.8825 5.2825 9.8825 5.2825 9 P 0 ;1
L 9.8825 5.3325 9.8825 5.3325 9 P 0 ;1
L 9.8825 5.3825 9.8825 5.3825 9 P 0 ;1
L 9.8825 5.4325 9.8825 5.4325 9 P 0 ;1
L 9.8825 5.4825 9.8825 5.4825 9 P 0 ;1
L 9.8825 5.5325 9.8825 5.5325 9 P 0 ;1
L 9.8825 5.5825 9.8825 5.5825 9 P 0 ;1
L 9.8825 5.6325 9.8825 5.6325 9 P 0 ;1
L 9.8825 5.6825 9.8825 5.6825 9 P 0 ;1
L 9.8825 5.7325 9.8825 5.7325 9 P 0 ;1
L 9.8825 5.7825 9.8825 5.7825 9 P 0 ;1
L 9.8825 5.8325 9.8825 5.8325 9 P 0 ;1
L 9.8825 5.8825 9.8825 5.8825 9 P 0 ;1
L 9.9325 0.1325 9.9325 0.1325 9 P 0 ;1
L 9.9325 0.1825 9.9325 0.1825 9 P 0 ;1
L 9.9325 0.2325 9.9325 0.2325 9 P 0 ;1
L 9.9325 0.2825 9.9325 0.2825 9 P 0 ;1
L 9.9325 0.3325 9.9325 0.3325 9 P 0 ;1
L 9.9325 0.3825 9.9325 0.3825 9 P 0 ;1
L 9.9325 0.4325 9.9325 0.4325 9 P 0 ;1
L 9.9325 0.4825 9.9325 0.4825 9 P 0 ;1
L 9.9325 0.5325 9.9325 0.5325 9 P 0 ;1
L 9.9325 0.5825 9.9325 0.5825 9 P 0 ;1
L 9.9325 0.6325 9.9325 0.6325 9 P 0 ;1
L 9.9325 0.6825 9.9325 0.6825 9 P 0 ;1
L 9.9325 0.7325 9.9325 0.7325 9 P 0 ;1
L 9.9325 0.7825 9.9325 0.7825 9 P 0 ;1
L 9.9325 0.8325 9.9325 0.8325 9 P 0 ;1
L 9.9325 0.8825 9.9325 0.8825 9 P 0 ;1
L 9.9325 0.9325 9.9325 0.9325 9 P 0 ;1
L 9.9325 0.9825 9.9325 0.9825 9 P 0 ;1
L 9.9325 1.0325 9.9325 1.0325 9 P 0 ;1
L 9.9325 1.0825 9.9325 1.0825 9 P 0 ;1
L 9.9325 1.1325 9.9325 1.1325 9 P 0 ;1
L 9.9325 1.1825 9.9325 1.1825 9 P 0 ;1
L 9.9325 1.2325 9.9325 1.2325 9 P 0 ;1
L 9.9325 1.2825 9.9325 1.2825 9 P 0 ;1
L 9.9325 1.3325 9.9325 1.3325 9 P 0 ;1
L 9.9325 1.3825 9.9325 1.3825 9 P 0 ;1
L 9.9325 1.4325 9.9325 1.4325 9 P 0 ;1
L 9.9325 1.4825 9.9325 1.4825 9 P 0 ;1
L 9.9325 1.5325 9.9325 1.5325 9 P 0 ;1
L 9.9325 1.5825 9.9325 1.5825 9 P 0 ;1
L 9.9325 1.6325 9.9325 1.6325 9 P 0 ;1
L 9.9325 1.6825 9.9325 1.6825 9 P 0 ;1
L 9.9325 1.7325 9.9325 1.7325 9 P 0 ;1
L 9.9325 1.7825 9.9325 1.7825 9 P 0 ;1
L 9.9325 1.8325 9.9325 1.8325 9 P 0 ;1
L 9.9325 1.8825 9.9325 1.8825 9 P 0 ;1
L 9.9325 1.9325 9.9325 1.9325 9 P 0 ;1
L 9.9325 1.9825 9.9325 1.9825 9 P 0 ;1
L 9.9325 2.0325 9.9325 2.0325 9 P 0 ;1
L 9.9325 2.0825 9.9325 2.0825 9 P 0 ;1
L 9.9325 2.1325 9.9325 2.1325 9 P 0 ;1
L 9.9325 2.7325 9.9325 2.7325 9 P 0 ;1
L 9.9325 2.7825 9.9325 2.7825 9 P 0 ;1
L 9.9325 3.0325 9.9325 3.0325 9 P 0 ;1
L 9.9325 3.0825 9.9325 3.0825 9 P 0 ;1
L 9.9325 3.1325 9.9325 3.1325 9 P 0 ;1
L 9.9325 3.1825 9.9325 3.1825 9 P 0 ;1
L 9.9325 3.2325 9.9325 3.2325 9 P 0 ;1
L 9.9325 3.2825 9.9325 3.2825 9 P 0 ;1
L 9.9325 3.3325 9.9325 3.3325 9 P 0 ;1
L 9.9325 3.3825 9.9325 3.3825 9 P 0 ;1
L 9.9325 3.4325 9.9325 3.4325 9 P 0 ;1
L 9.9325 3.4825 9.9325 3.4825 9 P 0 ;1
L 9.9325 3.5325 9.9325 3.5325 9 P 0 ;1
L 9.9325 3.5825 9.9325 3.5825 9 P 0 ;1
L 9.9325 3.6325 9.9325 3.6325 9 P 0 ;1
L 9.9325 3.6825 9.9325 3.6825 9 P 0 ;1
L 9.9325 3.7325 9.9325 3.7325 9 P 0 ;1
L 9.9325 3.7825 9.9325 3.7825 9 P 0 ;1
L 9.9325 3.8325 9.9325 3.8325 9 P 0 ;1
L 9.9325 3.8825 9.9325 3.8825 9 P 0 ;1
L 9.9325 3.9325 9.9325 3.9325 9 P 0 ;1
L 9.9325 3.9825 9.9325 3.9825 9 P 0 ;1
L 9.9325 4.0325 9.9325 4.0325 9 P 0 ;1
L 9.9325 4.0825 9.9325 4.0825 9 P 0 ;1
L 9.9325 4.1325 9.9325 4.1325 9 P 0 ;1
L 9.9325 4.1825 9.9325 4.1825 9 P 0 ;1
L 9.9325 4.2325 9.9325 4.2325 9 P 0 ;1
L 9.9325 4.2825 9.9325 4.2825 9 P 0 ;1
L 9.9325 4.3325 9.9325 4.3325 9 P 0 ;1
L 9.9325 4.5825 9.9325 4.5825 9 P 0 ;1
L 9.9325 4.7825 9.9325 4.7825 9 P 0 ;1
L 9.9325 4.8325 9.9325 4.8325 9 P 0 ;1
L 9.9325 4.8825 9.9325 4.8825 9 P 0 ;1
L 9.9325 4.9325 9.9325 4.9325 9 P 0 ;1
L 9.9325 4.9825 9.9325 4.9825 9 P 0 ;1
L 9.9325 5.0325 9.9325 5.0325 9 P 0 ;1
L 9.9325 5.0825 9.9325 5.0825 9 P 0 ;1
L 9.9325 5.1325 9.9325 5.1325 9 P 0 ;1
L 9.9325 5.1825 9.9325 5.1825 9 P 0 ;1
L 9.9325 5.2325 9.9325 5.2325 9 P 0 ;1
L 9.9325 5.2825 9.9325 5.2825 9 P 0 ;1
L 9.9325 5.3325 9.9325 5.3325 9 P 0 ;1
L 9.9325 5.3825 9.9325 5.3825 9 P 0 ;1
L 9.9325 5.4325 9.9325 5.4325 9 P 0 ;1
L 9.9325 5.4825 9.9325 5.4825 9 P 0 ;1
L 9.9325 5.5325 9.9325 5.5325 9 P 0 ;1
L 9.9325 5.5825 9.9325 5.5825 9 P 0 ;1
L 9.9325 5.6325 9.9325 5.6325 9 P 0 ;1
L 9.9325 5.6825 9.9325 5.6825 9 P 0 ;1
L 9.9325 5.7325 9.9325 5.7325 9 P 0 ;1
L 9.9325 5.7825 9.9325 5.7825 9 P 0 ;1
L 9.9325 5.8325 9.9325 5.8325 9 P 0 ;1
L 9.9325 5.8825 9.9325 5.8825 9 P 0 ;1
L 9.9825 0.1325 9.9825 0.1325 9 P 0 ;1
L 9.9825 0.1825 9.9825 0.1825 9 P 0 ;1
L 9.9825 0.2325 9.9825 0.2325 9 P 0 ;1
L 9.9825 0.2825 9.9825 0.2825 9 P 0 ;1
L 9.9825 0.3325 9.9825 0.3325 9 P 0 ;1
L 9.9825 0.3825 9.9825 0.3825 9 P 0 ;1
L 9.9825 0.4325 9.9825 0.4325 9 P 0 ;1
L 9.9825 0.4825 9.9825 0.4825 9 P 0 ;1
L 9.9825 0.5325 9.9825 0.5325 9 P 0 ;1
L 9.9825 0.5825 9.9825 0.5825 9 P 0 ;1
L 9.9825 0.6325 9.9825 0.6325 9 P 0 ;1
L 9.9825 0.6825 9.9825 0.6825 9 P 0 ;1
L 9.9825 0.7325 9.9825 0.7325 9 P 0 ;1
L 9.9825 0.7825 9.9825 0.7825 9 P 0 ;1
L 9.9825 0.8325 9.9825 0.8325 9 P 0 ;1
L 9.9825 0.8825 9.9825 0.8825 9 P 0 ;1
L 9.9825 0.9325 9.9825 0.9325 9 P 0 ;1
L 9.9825 0.9825 9.9825 0.9825 9 P 0 ;1
L 9.9825 1.0325 9.9825 1.0325 9 P 0 ;1
L 9.9825 1.0825 9.9825 1.0825 9 P 0 ;1
L 9.9825 1.1325 9.9825 1.1325 9 P 0 ;1
L 9.9825 1.1825 9.9825 1.1825 9 P 0 ;1
L 9.9825 1.2325 9.9825 1.2325 9 P 0 ;1
L 9.9825 1.2825 9.9825 1.2825 9 P 0 ;1
L 9.9825 1.3325 9.9825 1.3325 9 P 0 ;1
L 9.9825 1.3825 9.9825 1.3825 9 P 0 ;1
L 9.9825 1.4325 9.9825 1.4325 9 P 0 ;1
L 9.9825 1.4825 9.9825 1.4825 9 P 0 ;1
L 9.9825 1.5325 9.9825 1.5325 9 P 0 ;1
L 9.9825 1.5825 9.9825 1.5825 9 P 0 ;1
L 9.9825 1.6325 9.9825 1.6325 9 P 0 ;1
L 9.9825 1.6825 9.9825 1.6825 9 P 0 ;1
L 9.9825 1.7325 9.9825 1.7325 9 P 0 ;1
L 9.9825 1.7825 9.9825 1.7825 9 P 0 ;1
L 9.9825 1.8325 9.9825 1.8325 9 P 0 ;1
L 9.9825 1.8825 9.9825 1.8825 9 P 0 ;1
L 9.9825 1.9325 9.9825 1.9325 9 P 0 ;1
L 9.9825 1.9825 9.9825 1.9825 9 P 0 ;1
L 9.9825 2.0325 9.9825 2.0325 9 P 0 ;1
L 9.9825 2.0825 9.9825 2.0825 9 P 0 ;1
L 9.9825 2.7825 9.9825 2.7825 9 P 0 ;1
L 9.9825 3.0325 9.9825 3.0325 9 P 0 ;1
L 9.9825 3.0825 9.9825 3.0825 9 P 0 ;1
L 9.9825 3.1325 9.9825 3.1325 9 P 0 ;1
L 9.9825 3.1825 9.9825 3.1825 9 P 0 ;1
L 9.9825 3.2325 9.9825 3.2325 9 P 0 ;1
L 9.9825 3.2825 9.9825 3.2825 9 P 0 ;1
L 9.9825 3.3325 9.9825 3.3325 9 P 0 ;1
L 9.9825 3.3825 9.9825 3.3825 9 P 0 ;1
L 9.9825 3.4325 9.9825 3.4325 9 P 0 ;1
L 9.9825 3.4825 9.9825 3.4825 9 P 0 ;1
L 9.9825 3.5325 9.9825 3.5325 9 P 0 ;1
L 9.9825 3.5825 9.9825 3.5825 9 P 0 ;1
L 9.9825 3.6325 9.9825 3.6325 9 P 0 ;1
L 9.9825 3.6825 9.9825 3.6825 9 P 0 ;1
L 9.9825 3.7325 9.9825 3.7325 9 P 0 ;1
L 9.9825 3.7825 9.9825 3.7825 9 P 0 ;1
L 9.9825 3.8325 9.9825 3.8325 9 P 0 ;1
L 9.9825 3.8825 9.9825 3.8825 9 P 0 ;1
L 9.9825 3.9325 9.9825 3.9325 9 P 0 ;1
L 9.9825 3.9825 9.9825 3.9825 9 P 0 ;1
L 9.9825 4.0325 9.9825 4.0325 9 P 0 ;1
L 9.9825 4.0825 9.9825 4.0825 9 P 0 ;1
L 9.9825 4.1325 9.9825 4.1325 9 P 0 ;1
L 9.9825 4.1825 9.9825 4.1825 9 P 0 ;1
L 9.9825 4.2325 9.9825 4.2325 9 P 0 ;1
L 9.9825 4.2825 9.9825 4.2825 9 P 0 ;1
L 9.9825 4.3325 9.9825 4.3325 9 P 0 ;1
L 9.9825 4.3825 9.9825 4.3825 9 P 0 ;1
L 9.9825 4.7825 9.9825 4.7825 9 P 0 ;1
L 9.9825 4.8325 9.9825 4.8325 9 P 0 ;1
L 9.9825 4.8825 9.9825 4.8825 9 P 0 ;1
L 9.9825 4.9325 9.9825 4.9325 9 P 0 ;1
L 9.9825 4.9825 9.9825 4.9825 9 P 0 ;1
L 9.9825 5.0325 9.9825 5.0325 9 P 0 ;1
L 9.9825 5.0825 9.9825 5.0825 9 P 0 ;1
L 9.9825 5.1325 9.9825 5.1325 9 P 0 ;1
L 9.9825 5.1825 9.9825 5.1825 9 P 0 ;1
L 9.9825 5.2325 9.9825 5.2325 9 P 0 ;1
L 9.9825 5.2825 9.9825 5.2825 9 P 0 ;1
L 9.9825 5.6325 9.9825 5.6325 9 P 0 ;1
L 9.9825 5.6825 9.9825 5.6825 9 P 0 ;1
L 9.9825 5.7325 9.9825 5.7325 9 P 0 ;1
L 9.9825 5.7825 9.9825 5.7825 9 P 0 ;1
L 9.9825 5.8325 9.9825 5.8325 9 P 0 ;1
L 9.9825 5.8825 9.9825 5.8825 9 P 0 ;1
L 10.0325 0.1325 10.0325 0.1325 9 P 0 ;1
L 10.0325 0.1825 10.0325 0.1825 9 P 0 ;1
L 10.0325 0.2325 10.0325 0.2325 9 P 0 ;1
L 10.0325 0.2825 10.0325 0.2825 9 P 0 ;1
L 10.0325 0.3325 10.0325 0.3325 9 P 0 ;1
L 10.0325 0.3825 10.0325 0.3825 9 P 0 ;1
L 10.0325 0.4325 10.0325 0.4325 9 P 0 ;1
L 10.0325 0.4825 10.0325 0.4825 9 P 0 ;1
L 10.0325 0.5325 10.0325 0.5325 9 P 0 ;1
L 10.0325 0.5825 10.0325 0.5825 9 P 0 ;1
L 10.0325 0.6325 10.0325 0.6325 9 P 0 ;1
L 10.0325 0.6825 10.0325 0.6825 9 P 0 ;1
L 10.0325 0.7325 10.0325 0.7325 9 P 0 ;1
L 10.0325 0.7825 10.0325 0.7825 9 P 0 ;1
L 10.0325 0.8325 10.0325 0.8325 9 P 0 ;1
L 10.0325 0.8825 10.0325 0.8825 9 P 0 ;1
L 10.0325 0.9325 10.0325 0.9325 9 P 0 ;1
L 10.0325 0.9825 10.0325 0.9825 9 P 0 ;1
L 10.0325 1.0325 10.0325 1.0325 9 P 0 ;1
L 10.0325 1.0825 10.0325 1.0825 9 P 0 ;1
L 10.0325 1.1325 10.0325 1.1325 9 P 0 ;1
L 10.0325 1.1825 10.0325 1.1825 9 P 0 ;1
L 10.0325 1.2325 10.0325 1.2325 9 P 0 ;1
L 10.0325 1.2825 10.0325 1.2825 9 P 0 ;1
L 10.0325 1.3325 10.0325 1.3325 9 P 0 ;1
L 10.0325 1.3825 10.0325 1.3825 9 P 0 ;1
L 10.0325 1.4325 10.0325 1.4325 9 P 0 ;1
L 10.0325 1.4825 10.0325 1.4825 9 P 0 ;1
L 10.0325 1.5325 10.0325 1.5325 9 P 0 ;1
L 10.0325 1.5825 10.0325 1.5825 9 P 0 ;1
L 10.0325 1.6325 10.0325 1.6325 9 P 0 ;1
L 10.0325 1.6825 10.0325 1.6825 9 P 0 ;1
L 10.0325 1.7325 10.0325 1.7325 9 P 0 ;1
L 10.0325 1.7825 10.0325 1.7825 9 P 0 ;1
L 10.0325 1.8325 10.0325 1.8325 9 P 0 ;1
L 10.0325 1.8825 10.0325 1.8825 9 P 0 ;1
L 10.0325 1.9325 10.0325 1.9325 9 P 0 ;1
L 10.0325 3.0325 10.0325 3.0325 9 P 0 ;1
L 10.0325 3.0825 10.0325 3.0825 9 P 0 ;1
L 10.0325 3.1325 10.0325 3.1325 9 P 0 ;1
L 10.0325 3.1825 10.0325 3.1825 9 P 0 ;1
L 10.0325 3.2325 10.0325 3.2325 9 P 0 ;1
L 10.0325 3.2825 10.0325 3.2825 9 P 0 ;1
L 10.0325 3.3325 10.0325 3.3325 9 P 0 ;1
L 10.0325 3.3825 10.0325 3.3825 9 P 0 ;1
L 10.0325 3.4325 10.0325 3.4325 9 P 0 ;1
L 10.0325 3.4825 10.0325 3.4825 9 P 0 ;1
L 10.0325 3.5325 10.0325 3.5325 9 P 0 ;1
L 10.0325 3.5825 10.0325 3.5825 9 P 0 ;1
L 10.0325 3.6325 10.0325 3.6325 9 P 0 ;1
L 10.0325 3.6825 10.0325 3.6825 9 P 0 ;1
L 10.0325 3.7325 10.0325 3.7325 9 P 0 ;1
L 10.0325 3.7825 10.0325 3.7825 9 P 0 ;1
L 10.0325 3.8325 10.0325 3.8325 9 P 0 ;1
L 10.0325 3.8825 10.0325 3.8825 9 P 0 ;1
L 10.0325 3.9325 10.0325 3.9325 9 P 0 ;1
L 10.0325 3.9825 10.0325 3.9825 9 P 0 ;1
L 10.0325 4.0325 10.0325 4.0325 9 P 0 ;1
L 10.0325 4.0825 10.0325 4.0825 9 P 0 ;1
L 10.0325 4.1325 10.0325 4.1325 9 P 0 ;1
L 10.0325 4.1825 10.0325 4.1825 9 P 0 ;1
L 10.0325 4.2325 10.0325 4.2325 9 P 0 ;1
L 10.0325 4.2825 10.0325 4.2825 9 P 0 ;1
L 10.0325 4.3325 10.0325 4.3325 9 P 0 ;1
L 10.0325 4.3825 10.0325 4.3825 9 P 0 ;1
L 10.0325 4.7325 10.0325 4.7325 9 P 0 ;1
L 10.0325 4.7825 10.0325 4.7825 9 P 0 ;1
L 10.0325 4.8325 10.0325 4.8325 9 P 0 ;1
L 10.0325 4.8825 10.0325 4.8825 9 P 0 ;1
L 10.0325 4.9325 10.0325 4.9325 9 P 0 ;1
L 10.0325 4.9825 10.0325 4.9825 9 P 0 ;1
L 10.0325 5.0325 10.0325 5.0325 9 P 0 ;1
L 10.0325 5.0825 10.0325 5.0825 9 P 0 ;1
L 10.0325 5.1325 10.0325 5.1325 9 P 0 ;1
L 10.0325 5.1825 10.0325 5.1825 9 P 0 ;1
L 10.0325 5.2325 10.0325 5.2325 9 P 0 ;1
L 10.0325 5.6825 10.0325 5.6825 9 P 0 ;1
L 10.0325 5.7325 10.0325 5.7325 9 P 0 ;1
L 10.0325 5.7825 10.0325 5.7825 9 P 0 ;1
L 10.0325 5.8325 10.0325 5.8325 9 P 0 ;1
L 10.0325 5.8825 10.0325 5.8825 9 P 0 ;1
L 10.0825 0.1325 10.0825 0.1325 9 P 0 ;1
L 10.0825 0.1825 10.0825 0.1825 9 P 0 ;1
L 10.0825 0.2325 10.0825 0.2325 9 P 0 ;1
L 10.0825 0.2825 10.0825 0.2825 9 P 0 ;1
L 10.0825 0.3325 10.0825 0.3325 9 P 0 ;1
L 10.0825 0.3825 10.0825 0.3825 9 P 0 ;1
L 10.0825 0.4325 10.0825 0.4325 9 P 0 ;1
L 10.0825 0.4825 10.0825 0.4825 9 P 0 ;1
L 10.0825 0.5325 10.0825 0.5325 9 P 0 ;1
L 10.0825 0.5825 10.0825 0.5825 9 P 0 ;1
L 10.0825 0.6325 10.0825 0.6325 9 P 0 ;1
L 10.0825 0.6825 10.0825 0.6825 9 P 0 ;1
L 10.0825 0.7325 10.0825 0.7325 9 P 0 ;1
L 10.0825 0.7825 10.0825 0.7825 9 P 0 ;1
L 10.0825 0.8325 10.0825 0.8325 9 P 0 ;1
L 10.0825 0.8825 10.0825 0.8825 9 P 0 ;1
L 10.0825 0.9325 10.0825 0.9325 9 P 0 ;1
L 10.0825 0.9825 10.0825 0.9825 9 P 0 ;1
L 10.0825 1.0325 10.0825 1.0325 9 P 0 ;1
L 10.0825 1.0825 10.0825 1.0825 9 P 0 ;1
L 10.0825 1.1325 10.0825 1.1325 9 P 0 ;1
L 10.0825 1.1825 10.0825 1.1825 9 P 0 ;1
L 10.0825 1.2325 10.0825 1.2325 9 P 0 ;1
L 10.0825 1.2825 10.0825 1.2825 9 P 0 ;1
L 10.0825 1.3325 10.0825 1.3325 9 P 0 ;1
L 10.0825 1.3825 10.0825 1.3825 9 P 0 ;1
L 10.0825 1.4325 10.0825 1.4325 9 P 0 ;1
L 10.0825 1.4825 10.0825 1.4825 9 P 0 ;1
L 10.0825 1.5325 10.0825 1.5325 9 P 0 ;1
L 10.0825 1.5825 10.0825 1.5825 9 P 0 ;1
L 10.0825 1.6325 10.0825 1.6325 9 P 0 ;1
L 10.0825 1.6825 10.0825 1.6825 9 P 0 ;1
L 10.0825 1.7325 10.0825 1.7325 9 P 0 ;1
L 10.0825 1.7825 10.0825 1.7825 9 P 0 ;1
L 10.0825 1.8325 10.0825 1.8325 9 P 0 ;1
L 10.0825 1.8825 10.0825 1.8825 9 P 0 ;1
L 10.0825 1.9325 10.0825 1.9325 9 P 0 ;1
L 10.0825 3.0325 10.0825 3.0325 9 P 0 ;1
L 10.0825 3.0825 10.0825 3.0825 9 P 0 ;1
L 10.0825 3.1325 10.0825 3.1325 9 P 0 ;1
L 10.0825 3.1825 10.0825 3.1825 9 P 0 ;1
L 10.0825 3.2325 10.0825 3.2325 9 P 0 ;1
L 10.0825 3.2825 10.0825 3.2825 9 P 0 ;1
L 10.0825 3.3325 10.0825 3.3325 9 P 0 ;1
L 10.0825 3.3825 10.0825 3.3825 9 P 0 ;1
L 10.0825 3.4325 10.0825 3.4325 9 P 0 ;1
L 10.0825 3.4825 10.0825 3.4825 9 P 0 ;1
L 10.0825 3.5325 10.0825 3.5325 9 P 0 ;1
L 10.0825 3.5825 10.0825 3.5825 9 P 0 ;1
L 10.0825 3.6325 10.0825 3.6325 9 P 0 ;1
L 10.0825 3.6825 10.0825 3.6825 9 P 0 ;1
L 10.0825 3.7325 10.0825 3.7325 9 P 0 ;1
L 10.0825 3.7825 10.0825 3.7825 9 P 0 ;1
L 10.0825 3.8325 10.0825 3.8325 9 P 0 ;1
L 10.0825 3.8825 10.0825 3.8825 9 P 0 ;1
L 10.0825 3.9325 10.0825 3.9325 9 P 0 ;1
L 10.0825 3.9825 10.0825 3.9825 9 P 0 ;1
L 10.0825 4.0325 10.0825 4.0325 9 P 0 ;1
L 10.0825 4.0825 10.0825 4.0825 9 P 0 ;1
L 10.0825 4.1325 10.0825 4.1325 9 P 0 ;1
L 10.0825 4.1825 10.0825 4.1825 9 P 0 ;1
L 10.0825 4.2325 10.0825 4.2325 9 P 0 ;1
L 10.0825 4.2825 10.0825 4.2825 9 P 0 ;1
L 10.0825 4.3325 10.0825 4.3325 9 P 0 ;1
L 10.0825 4.3825 10.0825 4.3825 9 P 0 ;1
L 10.0825 4.4325 10.0825 4.4325 9 P 0 ;1
L 10.0825 4.6825 10.0825 4.6825 9 P 0 ;1
L 10.0825 4.7325 10.0825 4.7325 9 P 0 ;1
L 10.0825 4.7825 10.0825 4.7825 9 P 0 ;1
L 10.0825 4.8325 10.0825 4.8325 9 P 0 ;1
L 10.0825 4.8825 10.0825 4.8825 9 P 0 ;1
L 10.0825 4.9325 10.0825 4.9325 9 P 0 ;1
L 10.0825 4.9825 10.0825 4.9825 9 P 0 ;1
L 10.0825 5.0325 10.0825 5.0325 9 P 0 ;1
L 10.0825 5.0825 10.0825 5.0825 9 P 0 ;1
L 10.0825 5.1325 10.0825 5.1325 9 P 0 ;1
L 10.0825 5.1825 10.0825 5.1825 9 P 0 ;1
L 10.0825 5.7325 10.0825 5.7325 9 P 0 ;1
L 10.0825 5.7825 10.0825 5.7825 9 P 0 ;1
L 10.0825 5.8325 10.0825 5.8325 9 P 0 ;1
L 10.0825 5.8825 10.0825 5.8825 9 P 0 ;1
L 10.1325 0.1325 10.1325 0.1325 9 P 0 ;1
L 10.1325 0.1825 10.1325 0.1825 9 P 0 ;1
L 10.1325 0.2325 10.1325 0.2325 9 P 0 ;1
L 10.1325 0.2825 10.1325 0.2825 9 P 0 ;1
L 10.1325 0.3325 10.1325 0.3325 9 P 0 ;1
L 10.1325 0.3825 10.1325 0.3825 9 P 0 ;1
L 10.1325 0.4325 10.1325 0.4325 9 P 0 ;1
L 10.1325 0.4825 10.1325 0.4825 9 P 0 ;1
L 10.1325 0.5325 10.1325 0.5325 9 P 0 ;1
L 10.1325 0.5825 10.1325 0.5825 9 P 0 ;1
L 10.1325 0.6325 10.1325 0.6325 9 P 0 ;1
L 10.1325 0.6825 10.1325 0.6825 9 P 0 ;1
L 10.1325 0.7325 10.1325 0.7325 9 P 0 ;1
L 10.1325 0.7825 10.1325 0.7825 9 P 0 ;1
L 10.1325 0.8325 10.1325 0.8325 9 P 0 ;1
L 10.1325 0.8825 10.1325 0.8825 9 P 0 ;1
L 10.1325 0.9325 10.1325 0.9325 9 P 0 ;1
L 10.1325 0.9825 10.1325 0.9825 9 P 0 ;1
L 10.1325 1.0325 10.1325 1.0325 9 P 0 ;1
L 10.1325 1.0825 10.1325 1.0825 9 P 0 ;1
L 10.1325 1.1325 10.1325 1.1325 9 P 0 ;1
L 10.1325 1.1825 10.1325 1.1825 9 P 0 ;1
L 10.1325 1.2325 10.1325 1.2325 9 P 0 ;1
L 10.1325 1.2825 10.1325 1.2825 9 P 0 ;1
L 10.1325 1.3325 10.1325 1.3325 9 P 0 ;1
L 10.1325 1.3825 10.1325 1.3825 9 P 0 ;1
L 10.1325 1.4325 10.1325 1.4325 9 P 0 ;1
L 10.1325 1.4825 10.1325 1.4825 9 P 0 ;1
L 10.1325 1.5325 10.1325 1.5325 9 P 0 ;1
L 10.1325 1.5825 10.1325 1.5825 9 P 0 ;1
L 10.1325 1.6325 10.1325 1.6325 9 P 0 ;1
L 10.1325 1.6825 10.1325 1.6825 9 P 0 ;1
L 10.1325 1.7325 10.1325 1.7325 9 P 0 ;1
L 10.1325 1.7825 10.1325 1.7825 9 P 0 ;1
L 10.1325 1.8325 10.1325 1.8325 9 P 0 ;1
L 10.1325 1.8825 10.1325 1.8825 9 P 0 ;1
L 10.1325 2.9825 10.1325 2.9825 9 P 0 ;1
L 10.1325 3.0325 10.1325 3.0325 9 P 0 ;1
L 10.1325 3.0825 10.1325 3.0825 9 P 0 ;1
L 10.1325 3.1325 10.1325 3.1325 9 P 0 ;1
L 10.1325 3.1825 10.1325 3.1825 9 P 0 ;1
L 10.1325 3.2325 10.1325 3.2325 9 P 0 ;1
L 10.1325 3.2825 10.1325 3.2825 9 P 0 ;1
L 10.1325 3.3325 10.1325 3.3325 9 P 0 ;1
L 10.1325 3.3825 10.1325 3.3825 9 P 0 ;1
L 10.1325 3.4325 10.1325 3.4325 9 P 0 ;1
L 10.1325 3.4825 10.1325 3.4825 9 P 0 ;1
L 10.1325 3.5325 10.1325 3.5325 9 P 0 ;1
L 10.1325 3.5825 10.1325 3.5825 9 P 0 ;1
L 10.1325 3.6325 10.1325 3.6325 9 P 0 ;1
L 10.1325 3.6825 10.1325 3.6825 9 P 0 ;1
L 10.1325 3.7325 10.1325 3.7325 9 P 0 ;1
L 10.1325 3.7825 10.1325 3.7825 9 P 0 ;1
L 10.1325 3.8325 10.1325 3.8325 9 P 0 ;1
L 10.1325 3.8825 10.1325 3.8825 9 P 0 ;1
L 10.1325 3.9325 10.1325 3.9325 9 P 0 ;1
L 10.1325 3.9825 10.1325 3.9825 9 P 0 ;1
L 10.1325 4.0325 10.1325 4.0325 9 P 0 ;1
L 10.1325 4.0825 10.1325 4.0825 9 P 0 ;1
L 10.1325 4.1325 10.1325 4.1325 9 P 0 ;1
L 10.1325 4.1825 10.1325 4.1825 9 P 0 ;1
L 10.1325 4.2325 10.1325 4.2325 9 P 0 ;1
L 10.1325 4.2825 10.1325 4.2825 9 P 0 ;1
L 10.1325 4.3325 10.1325 4.3325 9 P 0 ;1
L 10.1325 4.3825 10.1325 4.3825 9 P 0 ;1
L 10.1325 4.4325 10.1325 4.4325 9 P 0 ;1
L 10.1325 4.4825 10.1325 4.4825 9 P 0 ;1
L 10.1325 4.5325 10.1325 4.5325 9 P 0 ;1
L 10.1325 4.5825 10.1325 4.5825 9 P 0 ;1
L 10.1325 4.6325 10.1325 4.6325 9 P 0 ;1
L 10.1325 4.6825 10.1325 4.6825 9 P 0 ;1
L 10.1325 4.7325 10.1325 4.7325 9 P 0 ;1
L 10.1325 4.7825 10.1325 4.7825 9 P 0 ;1
L 10.1325 4.8325 10.1325 4.8325 9 P 0 ;1
L 10.1325 4.8825 10.1325 4.8825 9 P 0 ;1
L 10.1325 4.9325 10.1325 4.9325 9 P 0 ;1
L 10.1325 4.9825 10.1325 4.9825 9 P 0 ;1
L 10.1325 5.0325 10.1325 5.0325 9 P 0 ;1
L 10.1325 5.0825 10.1325 5.0825 9 P 0 ;1
L 10.1325 5.1325 10.1325 5.1325 9 P 0 ;1
L 10.1325 5.1825 10.1325 5.1825 9 P 0 ;1
L 10.1325 5.7325 10.1325 5.7325 9 P 0 ;1
L 10.1325 5.7825 10.1325 5.7825 9 P 0 ;1
L 10.1325 5.8325 10.1325 5.8325 9 P 0 ;1
L 10.1325 5.8825 10.1325 5.8825 9 P 0 ;1
L 10.1825 0.1325 10.1825 0.1325 9 P 0 ;1
L 10.1825 0.1825 10.1825 0.1825 9 P 0 ;1
L 10.1825 0.2325 10.1825 0.2325 9 P 0 ;1
L 10.1825 0.2825 10.1825 0.2825 9 P 0 ;1
L 10.1825 0.3325 10.1825 0.3325 9 P 0 ;1
L 10.1825 0.3825 10.1825 0.3825 9 P 0 ;1
L 10.1825 0.4325 10.1825 0.4325 9 P 0 ;1
L 10.1825 0.4825 10.1825 0.4825 9 P 0 ;1
L 10.1825 0.5325 10.1825 0.5325 9 P 0 ;1
L 10.1825 0.5825 10.1825 0.5825 9 P 0 ;1
L 10.1825 0.6325 10.1825 0.6325 9 P 0 ;1
L 10.1825 0.6825 10.1825 0.6825 9 P 0 ;1
L 10.1825 0.7325 10.1825 0.7325 9 P 0 ;1
L 10.1825 0.7825 10.1825 0.7825 9 P 0 ;1
L 10.1825 0.8325 10.1825 0.8325 9 P 0 ;1
L 10.1825 0.8825 10.1825 0.8825 9 P 0 ;1
L 10.1825 0.9325 10.1825 0.9325 9 P 0 ;1
L 10.1825 0.9825 10.1825 0.9825 9 P 0 ;1
L 10.1825 1.0325 10.1825 1.0325 9 P 0 ;1
L 10.1825 1.0825 10.1825 1.0825 9 P 0 ;1
L 10.1825 1.1325 10.1825 1.1325 9 P 0 ;1
L 10.1825 1.1825 10.1825 1.1825 9 P 0 ;1
L 10.1825 1.2325 10.1825 1.2325 9 P 0 ;1
L 10.1825 1.2825 10.1825 1.2825 9 P 0 ;1
L 10.1825 1.3325 10.1825 1.3325 9 P 0 ;1
L 10.1825 1.3825 10.1825 1.3825 9 P 0 ;1
L 10.1825 1.4325 10.1825 1.4325 9 P 0 ;1
L 10.1825 1.4825 10.1825 1.4825 9 P 0 ;1
L 10.1825 1.5325 10.1825 1.5325 9 P 0 ;1
L 10.1825 1.5825 10.1825 1.5825 9 P 0 ;1
L 10.1825 1.6325 10.1825 1.6325 9 P 0 ;1
L 10.1825 1.6825 10.1825 1.6825 9 P 0 ;1
L 10.1825 1.7325 10.1825 1.7325 9 P 0 ;1
L 10.1825 1.7825 10.1825 1.7825 9 P 0 ;1
L 10.1825 1.8325 10.1825 1.8325 9 P 0 ;1
L 10.1825 2.9325 10.1825 2.9325 9 P 0 ;1
L 10.1825 2.9825 10.1825 2.9825 9 P 0 ;1
L 10.1825 3.0325 10.1825 3.0325 9 P 0 ;1
L 10.1825 3.0825 10.1825 3.0825 9 P 0 ;1
L 10.1825 3.1325 10.1825 3.1325 9 P 0 ;1
L 10.1825 3.1825 10.1825 3.1825 9 P 0 ;1
L 10.1825 3.2325 10.1825 3.2325 9 P 0 ;1
L 10.1825 3.2825 10.1825 3.2825 9 P 0 ;1
L 10.1825 3.3325 10.1825 3.3325 9 P 0 ;1
L 10.1825 3.3825 10.1825 3.3825 9 P 0 ;1
L 10.1825 3.4325 10.1825 3.4325 9 P 0 ;1
L 10.1825 3.4825 10.1825 3.4825 9 P 0 ;1
L 10.1825 3.5325 10.1825 3.5325 9 P 0 ;1
L 10.1825 3.5825 10.1825 3.5825 9 P 0 ;1
L 10.1825 3.6325 10.1825 3.6325 9 P 0 ;1
L 10.1825 3.6825 10.1825 3.6825 9 P 0 ;1
L 10.1825 3.7325 10.1825 3.7325 9 P 0 ;1
L 10.1825 3.7825 10.1825 3.7825 9 P 0 ;1
L 10.1825 3.8325 10.1825 3.8325 9 P 0 ;1
L 10.1825 3.8825 10.1825 3.8825 9 P 0 ;1
L 10.1825 3.9325 10.1825 3.9325 9 P 0 ;1
L 10.1825 3.9825 10.1825 3.9825 9 P 0 ;1
L 10.1825 4.0325 10.1825 4.0325 9 P 0 ;1
L 10.1825 4.0825 10.1825 4.0825 9 P 0 ;1
L 10.1825 4.1325 10.1825 4.1325 9 P 0 ;1
L 10.1825 4.1825 10.1825 4.1825 9 P 0 ;1
L 10.1825 4.2325 10.1825 4.2325 9 P 0 ;1
L 10.1825 4.2825 10.1825 4.2825 9 P 0 ;1
L 10.1825 4.3325 10.1825 4.3325 9 P 0 ;1
L 10.1825 4.3825 10.1825 4.3825 9 P 0 ;1
L 10.1825 4.4325 10.1825 4.4325 9 P 0 ;1
L 10.1825 4.4825 10.1825 4.4825 9 P 0 ;1
L 10.1825 4.5325 10.1825 4.5325 9 P 0 ;1
L 10.1825 4.5825 10.1825 4.5825 9 P 0 ;1
L 10.1825 4.6325 10.1825 4.6325 9 P 0 ;1
L 10.1825 4.6825 10.1825 4.6825 9 P 0 ;1
L 10.1825 4.7325 10.1825 4.7325 9 P 0 ;1
L 10.1825 4.7825 10.1825 4.7825 9 P 0 ;1
L 10.1825 4.8325 10.1825 4.8325 9 P 0 ;1
L 10.1825 4.8825 10.1825 4.8825 9 P 0 ;1
L 10.1825 4.9325 10.1825 4.9325 9 P 0 ;1
L 10.1825 4.9825 10.1825 4.9825 9 P 0 ;1
L 10.1825 5.0325 10.1825 5.0325 9 P 0 ;1
L 10.1825 5.0825 10.1825 5.0825 9 P 0 ;1
L 10.1825 5.1325 10.1825 5.1325 9 P 0 ;1
L 10.1825 5.7325 10.1825 5.7325 9 P 0 ;1
L 10.1825 5.7825 10.1825 5.7825 9 P 0 ;1
L 10.1825 5.8325 10.1825 5.8325 9 P 0 ;1
L 10.1825 5.8825 10.1825 5.8825 9 P 0 ;1
L 10.2325 0.1325 10.2325 0.1325 9 P 0 ;1
L 10.2325 0.1825 10.2325 0.1825 9 P 0 ;1
L 10.2325 0.2325 10.2325 0.2325 9 P 0 ;1
L 10.2325 0.2825 10.2325 0.2825 9 P 0 ;1
L 10.2325 0.3325 10.2325 0.3325 9 P 0 ;1
L 10.2325 0.3825 10.2325 0.3825 9 P 0 ;1
L 10.2325 0.4325 10.2325 0.4325 9 P 0 ;1
L 10.2325 0.4825 10.2325 0.4825 9 P 0 ;1
L 10.2325 0.5325 10.2325 0.5325 9 P 0 ;1
L 10.2325 0.5825 10.2325 0.5825 9 P 0 ;1
L 10.2325 0.6325 10.2325 0.6325 9 P 0 ;1
L 10.2325 0.6825 10.2325 0.6825 9 P 0 ;1
L 10.2325 0.7325 10.2325 0.7325 9 P 0 ;1
L 10.2325 0.7825 10.2325 0.7825 9 P 0 ;1
L 10.2325 0.8325 10.2325 0.8325 9 P 0 ;1
L 10.2325 0.8825 10.2325 0.8825 9 P 0 ;1
L 10.2325 0.9325 10.2325 0.9325 9 P 0 ;1
L 10.2325 0.9825 10.2325 0.9825 9 P 0 ;1
L 10.2325 1.0325 10.2325 1.0325 9 P 0 ;1
L 10.2325 1.0825 10.2325 1.0825 9 P 0 ;1
L 10.2325 1.1325 10.2325 1.1325 9 P 0 ;1
L 10.2325 1.1825 10.2325 1.1825 9 P 0 ;1
L 10.2325 1.2325 10.2325 1.2325 9 P 0 ;1
L 10.2325 1.2825 10.2325 1.2825 9 P 0 ;1
L 10.2325 1.3325 10.2325 1.3325 9 P 0 ;1
L 10.2325 1.3825 10.2325 1.3825 9 P 0 ;1
L 10.2325 1.4325 10.2325 1.4325 9 P 0 ;1
L 10.2325 1.4825 10.2325 1.4825 9 P 0 ;1
L 10.2325 1.5325 10.2325 1.5325 9 P 0 ;1
L 10.2325 1.5825 10.2325 1.5825 9 P 0 ;1
L 10.2325 2.0825 10.2325 2.0825 9 P 0 ;1
L 10.2325 2.1325 10.2325 2.1325 9 P 0 ;1
L 10.2325 2.1825 10.2325 2.1825 9 P 0 ;1
L 10.2325 2.2325 10.2325 2.2325 9 P 0 ;1
L 10.2325 2.2825 10.2325 2.2825 9 P 0 ;1
L 10.2325 2.3325 10.2325 2.3325 9 P 0 ;1
L 10.2325 2.3825 10.2325 2.3825 9 P 0 ;1
L 10.2325 2.4325 10.2325 2.4325 9 P 0 ;1
L 10.2325 2.4825 10.2325 2.4825 9 P 0 ;1
L 10.2325 2.5325 10.2325 2.5325 9 P 0 ;1
L 10.2325 2.5825 10.2325 2.5825 9 P 0 ;1
L 10.2325 2.6325 10.2325 2.6325 9 P 0 ;1
L 10.2325 2.6825 10.2325 2.6825 9 P 0 ;1
L 10.2325 2.7325 10.2325 2.7325 9 P 0 ;1
L 10.2325 2.8825 10.2325 2.8825 9 P 0 ;1
L 10.2325 2.9325 10.2325 2.9325 9 P 0 ;1
L 10.2325 2.9825 10.2325 2.9825 9 P 0 ;1
L 10.2325 3.0325 10.2325 3.0325 9 P 0 ;1
L 10.2325 3.0825 10.2325 3.0825 9 P 0 ;1
L 10.2325 3.1325 10.2325 3.1325 9 P 0 ;1
L 10.2325 3.1825 10.2325 3.1825 9 P 0 ;1
L 10.2325 5.7325 10.2325 5.7325 9 P 0 ;1
L 10.2325 5.7825 10.2325 5.7825 9 P 0 ;1
L 10.2325 5.8325 10.2325 5.8325 9 P 0 ;1
L 10.2325 5.8825 10.2325 5.8825 9 P 0 ;1
L 10.2825 0.1325 10.2825 0.1325 9 P 0 ;1
L 10.2825 0.1825 10.2825 0.1825 9 P 0 ;1
L 10.2825 0.2325 10.2825 0.2325 9 P 0 ;1
L 10.2825 0.2825 10.2825 0.2825 9 P 0 ;1
L 10.2825 0.3325 10.2825 0.3325 9 P 0 ;1
L 10.2825 0.3825 10.2825 0.3825 9 P 0 ;1
L 10.2825 0.4325 10.2825 0.4325 9 P 0 ;1
L 10.2825 0.4825 10.2825 0.4825 9 P 0 ;1
L 10.2825 0.5325 10.2825 0.5325 9 P 0 ;1
L 10.2825 0.5825 10.2825 0.5825 9 P 0 ;1
L 10.2825 0.6325 10.2825 0.6325 9 P 0 ;1
L 10.2825 0.6825 10.2825 0.6825 9 P 0 ;1
L 10.2825 0.7325 10.2825 0.7325 9 P 0 ;1
L 10.2825 0.7825 10.2825 0.7825 9 P 0 ;1
L 10.2825 0.8325 10.2825 0.8325 9 P 0 ;1
L 10.2825 0.8825 10.2825 0.8825 9 P 0 ;1
L 10.2825 0.9325 10.2825 0.9325 9 P 0 ;1
L 10.2825 0.9825 10.2825 0.9825 9 P 0 ;1
L 10.2825 1.0325 10.2825 1.0325 9 P 0 ;1
L 10.2825 1.0825 10.2825 1.0825 9 P 0 ;1
L 10.2825 1.1325 10.2825 1.1325 9 P 0 ;1
L 10.2825 1.1825 10.2825 1.1825 9 P 0 ;1
L 10.2825 1.2325 10.2825 1.2325 9 P 0 ;1
L 10.2825 1.2825 10.2825 1.2825 9 P 0 ;1
L 10.2825 1.3325 10.2825 1.3325 9 P 0 ;1
L 10.2825 1.3825 10.2825 1.3825 9 P 0 ;1
L 10.2825 1.4325 10.2825 1.4325 9 P 0 ;1
L 10.2825 1.4825 10.2825 1.4825 9 P 0 ;1
L 10.2825 2.0825 10.2825 2.0825 9 P 0 ;1
L 10.2825 2.1325 10.2825 2.1325 9 P 0 ;1
L 10.2825 2.1825 10.2825 2.1825 9 P 0 ;1
L 10.2825 2.2325 10.2825 2.2325 9 P 0 ;1
L 10.2825 2.2825 10.2825 2.2825 9 P 0 ;1
L 10.2825 2.3325 10.2825 2.3325 9 P 0 ;1
L 10.2825 2.3825 10.2825 2.3825 9 P 0 ;1
L 10.2825 2.4325 10.2825 2.4325 9 P 0 ;1
L 10.2825 2.4825 10.2825 2.4825 9 P 0 ;1
L 10.2825 2.5325 10.2825 2.5325 9 P 0 ;1
L 10.2825 2.5825 10.2825 2.5825 9 P 0 ;1
L 10.2825 2.6325 10.2825 2.6325 9 P 0 ;1
L 10.2825 2.6825 10.2825 2.6825 9 P 0 ;1
L 10.2825 2.7325 10.2825 2.7325 9 P 0 ;1
L 10.2825 2.7825 10.2825 2.7825 9 P 0 ;1
L 10.2825 2.8325 10.2825 2.8325 9 P 0 ;1
L 10.2825 2.8825 10.2825 2.8825 9 P 0 ;1
L 10.2825 2.9325 10.2825 2.9325 9 P 0 ;1
L 10.2825 2.9825 10.2825 2.9825 9 P 0 ;1
L 10.2825 3.0325 10.2825 3.0325 9 P 0 ;1
L 10.2825 3.0825 10.2825 3.0825 9 P 0 ;1
L 10.2825 3.1325 10.2825 3.1325 9 P 0 ;1
L 10.2825 5.7325 10.2825 5.7325 9 P 0 ;1
L 10.2825 5.7825 10.2825 5.7825 9 P 0 ;1
L 10.2825 5.8325 10.2825 5.8325 9 P 0 ;1
L 10.2825 5.8825 10.2825 5.8825 9 P 0 ;1
L 10.3325 0.1325 10.3325 0.1325 9 P 0 ;1
L 10.3325 0.1825 10.3325 0.1825 9 P 0 ;1
L 10.3325 0.2325 10.3325 0.2325 9 P 0 ;1
L 10.3325 0.2825 10.3325 0.2825 9 P 0 ;1
L 10.3325 0.3325 10.3325 0.3325 9 P 0 ;1
L 10.3325 0.3825 10.3325 0.3825 9 P 0 ;1
L 10.3325 0.4325 10.3325 0.4325 9 P 0 ;1
L 10.3325 0.4825 10.3325 0.4825 9 P 0 ;1
L 10.3325 0.5325 10.3325 0.5325 9 P 0 ;1
L 10.3325 0.5825 10.3325 0.5825 9 P 0 ;1
L 10.3325 0.6325 10.3325 0.6325 9 P 0 ;1
L 10.3325 0.6825 10.3325 0.6825 9 P 0 ;1
L 10.3325 0.7325 10.3325 0.7325 9 P 0 ;1
L 10.3325 0.7825 10.3325 0.7825 9 P 0 ;1
L 10.3325 0.8325 10.3325 0.8325 9 P 0 ;1
L 10.3325 0.8825 10.3325 0.8825 9 P 0 ;1
L 10.3325 0.9325 10.3325 0.9325 9 P 0 ;1
L 10.3325 0.9825 10.3325 0.9825 9 P 0 ;1
L 10.3325 1.0325 10.3325 1.0325 9 P 0 ;1
L 10.3325 1.0825 10.3325 1.0825 9 P 0 ;1
L 10.3325 1.1325 10.3325 1.1325 9 P 0 ;1
L 10.3325 1.1825 10.3325 1.1825 9 P 0 ;1
L 10.3325 1.2325 10.3325 1.2325 9 P 0 ;1
L 10.3325 1.3825 10.3325 1.3825 9 P 0 ;1
L 10.3325 2.0325 10.3325 2.0325 9 P 0 ;1
L 10.3325 2.0825 10.3325 2.0825 9 P 0 ;1
L 10.3325 2.1325 10.3325 2.1325 9 P 0 ;1
L 10.3325 2.1825 10.3325 2.1825 9 P 0 ;1
L 10.3325 2.2325 10.3325 2.2325 9 P 0 ;1
L 10.3325 2.2825 10.3325 2.2825 9 P 0 ;1
L 10.3325 2.3325 10.3325 2.3325 9 P 0 ;1
L 10.3325 2.3825 10.3325 2.3825 9 P 0 ;1
L 10.3325 2.4325 10.3325 2.4325 9 P 0 ;1
L 10.3325 2.4825 10.3325 2.4825 9 P 0 ;1
L 10.3325 2.5325 10.3325 2.5325 9 P 0 ;1
L 10.3325 2.5825 10.3325 2.5825 9 P 0 ;1
L 10.3325 2.6325 10.3325 2.6325 9 P 0 ;1
L 10.3325 2.6825 10.3325 2.6825 9 P 0 ;1
L 10.3325 2.7325 10.3325 2.7325 9 P 0 ;1
L 10.3325 2.7825 10.3325 2.7825 9 P 0 ;1
L 10.3325 2.8325 10.3325 2.8325 9 P 0 ;1
L 10.3325 2.8825 10.3325 2.8825 9 P 0 ;1
L 10.3325 2.9325 10.3325 2.9325 9 P 0 ;1
L 10.3325 2.9825 10.3325 2.9825 9 P 0 ;1
L 10.3325 3.0325 10.3325 3.0325 9 P 0 ;1
L 10.3325 3.0825 10.3325 3.0825 9 P 0 ;1
L 10.3325 5.7325 10.3325 5.7325 9 P 0 ;1
L 10.3325 5.7825 10.3325 5.7825 9 P 0 ;1
L 10.3325 5.8325 10.3325 5.8325 9 P 0 ;1
L 10.3325 5.8825 10.3325 5.8825 9 P 0 ;1
L 10.3825 0.1325 10.3825 0.1325 9 P 0 ;1
L 10.3825 0.1825 10.3825 0.1825 9 P 0 ;1
L 10.3825 0.2325 10.3825 0.2325 9 P 0 ;1
L 10.3825 0.2825 10.3825 0.2825 9 P 0 ;1
L 10.3825 0.3325 10.3825 0.3325 9 P 0 ;1
L 10.3825 0.3825 10.3825 0.3825 9 P 0 ;1
L 10.3825 0.4325 10.3825 0.4325 9 P 0 ;1
L 10.3825 0.4825 10.3825 0.4825 9 P 0 ;1
L 10.3825 0.5325 10.3825 0.5325 9 P 0 ;1
L 10.3825 0.5825 10.3825 0.5825 9 P 0 ;1
L 10.3825 0.6325 10.3825 0.6325 9 P 0 ;1
L 10.3825 0.6825 10.3825 0.6825 9 P 0 ;1
L 10.3825 0.7325 10.3825 0.7325 9 P 0 ;1
L 10.3825 0.7825 10.3825 0.7825 9 P 0 ;1
L 10.3825 0.8325 10.3825 0.8325 9 P 0 ;1
L 10.3825 0.8825 10.3825 0.8825 9 P 0 ;1
L 10.3825 0.9325 10.3825 0.9325 9 P 0 ;1
L 10.3825 0.9825 10.3825 0.9825 9 P 0 ;1
L 10.3825 1.0325 10.3825 1.0325 9 P 0 ;1
L 10.3825 1.0825 10.3825 1.0825 9 P 0 ;1
L 10.3825 1.1325 10.3825 1.1325 9 P 0 ;1
L 10.3825 1.1825 10.3825 1.1825 9 P 0 ;1
L 10.3825 1.6325 10.3825 1.6325 9 P 0 ;1
L 10.3825 1.6825 10.3825 1.6825 9 P 0 ;1
L 10.3825 1.7325 10.3825 1.7325 9 P 0 ;1
L 10.3825 1.7825 10.3825 1.7825 9 P 0 ;1
L 10.3825 1.8325 10.3825 1.8325 9 P 0 ;1
L 10.3825 1.8825 10.3825 1.8825 9 P 0 ;1
L 10.3825 1.9325 10.3825 1.9325 9 P 0 ;1
L 10.3825 1.9825 10.3825 1.9825 9 P 0 ;1
L 10.3825 2.0325 10.3825 2.0325 9 P 0 ;1
L 10.3825 2.0825 10.3825 2.0825 9 P 0 ;1
L 10.3825 2.1325 10.3825 2.1325 9 P 0 ;1
L 10.3825 2.1825 10.3825 2.1825 9 P 0 ;1
L 10.3825 2.2325 10.3825 2.2325 9 P 0 ;1
L 10.3825 2.2825 10.3825 2.2825 9 P 0 ;1
L 10.3825 2.3325 10.3825 2.3325 9 P 0 ;1
L 10.3825 2.3825 10.3825 2.3825 9 P 0 ;1
L 10.3825 2.4325 10.3825 2.4325 9 P 0 ;1
L 10.3825 2.4825 10.3825 2.4825 9 P 0 ;1
L 10.3825 2.5325 10.3825 2.5325 9 P 0 ;1
L 10.3825 2.5825 10.3825 2.5825 9 P 0 ;1
L 10.3825 2.6325 10.3825 2.6325 9 P 0 ;1
L 10.3825 2.6825 10.3825 2.6825 9 P 0 ;1
L 10.3825 2.7325 10.3825 2.7325 9 P 0 ;1
L 10.3825 2.7825 10.3825 2.7825 9 P 0 ;1
L 10.3825 2.8325 10.3825 2.8325 9 P 0 ;1
L 10.3825 2.8825 10.3825 2.8825 9 P 0 ;1
L 10.3825 2.9325 10.3825 2.9325 9 P 0 ;1
L 10.3825 2.9825 10.3825 2.9825 9 P 0 ;1
L 10.3825 3.0325 10.3825 3.0325 9 P 0 ;1
L 10.3825 5.2325 10.3825 5.2325 9 P 0 ;1
L 10.3825 5.6825 10.3825 5.6825 9 P 0 ;1
L 10.3825 5.7325 10.3825 5.7325 9 P 0 ;1
L 10.3825 5.7825 10.3825 5.7825 9 P 0 ;1
L 10.3825 5.8325 10.3825 5.8325 9 P 0 ;1
L 10.3825 5.8825 10.3825 5.8825 9 P 0 ;1
L 10.4325 0.1325 10.4325 0.1325 9 P 0 ;1
L 10.4325 0.1825 10.4325 0.1825 9 P 0 ;1
L 10.4325 0.2325 10.4325 0.2325 9 P 0 ;1
L 10.4325 0.2825 10.4325 0.2825 9 P 0 ;1
L 10.4325 0.3325 10.4325 0.3325 9 P 0 ;1
L 10.4325 0.3825 10.4325 0.3825 9 P 0 ;1
L 10.4325 0.4325 10.4325 0.4325 9 P 0 ;1
L 10.4325 0.4825 10.4325 0.4825 9 P 0 ;1
L 10.4325 0.5325 10.4325 0.5325 9 P 0 ;1
L 10.4325 0.5825 10.4325 0.5825 9 P 0 ;1
L 10.4325 0.6325 10.4325 0.6325 9 P 0 ;1
L 10.4325 0.6825 10.4325 0.6825 9 P 0 ;1
L 10.4325 0.7325 10.4325 0.7325 9 P 0 ;1
L 10.4325 0.7825 10.4325 0.7825 9 P 0 ;1
L 10.4325 0.8325 10.4325 0.8325 9 P 0 ;1
L 10.4325 0.8825 10.4325 0.8825 9 P 0 ;1
L 10.4325 0.9325 10.4325 0.9325 9 P 0 ;1
L 10.4325 0.9825 10.4325 0.9825 9 P 0 ;1
L 10.4325 1.0325 10.4325 1.0325 9 P 0 ;1
L 10.4325 1.0825 10.4325 1.0825 9 P 0 ;1
L 10.4325 1.1325 10.4325 1.1325 9 P 0 ;1
L 10.4325 1.1825 10.4325 1.1825 9 P 0 ;1
L 10.4325 1.6325 10.4325 1.6325 9 P 0 ;1
L 10.4325 1.6825 10.4325 1.6825 9 P 0 ;1
L 10.4325 1.7325 10.4325 1.7325 9 P 0 ;1
L 10.4325 1.7825 10.4325 1.7825 9 P 0 ;1
L 10.4325 1.8325 10.4325 1.8325 9 P 0 ;1
L 10.4325 1.8825 10.4325 1.8825 9 P 0 ;1
L 10.4325 1.9325 10.4325 1.9325 9 P 0 ;1
L 10.4325 1.9825 10.4325 1.9825 9 P 0 ;1
L 10.4325 2.0325 10.4325 2.0325 9 P 0 ;1
L 10.4325 2.0825 10.4325 2.0825 9 P 0 ;1
L 10.4325 2.1325 10.4325 2.1325 9 P 0 ;1
L 10.4325 2.1825 10.4325 2.1825 9 P 0 ;1
L 10.4325 2.2325 10.4325 2.2325 9 P 0 ;1
L 10.4325 2.2825 10.4325 2.2825 9 P 0 ;1
L 10.4325 2.3325 10.4325 2.3325 9 P 0 ;1
L 10.4325 2.3825 10.4325 2.3825 9 P 0 ;1
L 10.4325 2.4325 10.4325 2.4325 9 P 0 ;1
L 10.4325 2.4825 10.4325 2.4825 9 P 0 ;1
L 10.4325 2.5325 10.4325 2.5325 9 P 0 ;1
L 10.4325 2.5825 10.4325 2.5825 9 P 0 ;1
L 10.4325 2.6325 10.4325 2.6325 9 P 0 ;1
L 10.4325 2.6825 10.4325 2.6825 9 P 0 ;1
L 10.4325 2.7325 10.4325 2.7325 9 P 0 ;1
L 10.4325 2.7825 10.4325 2.7825 9 P 0 ;1
L 10.4325 2.8325 10.4325 2.8325 9 P 0 ;1
L 10.4325 2.8825 10.4325 2.8825 9 P 0 ;1
L 10.4325 2.9325 10.4325 2.9325 9 P 0 ;1
L 10.4325 2.9825 10.4325 2.9825 9 P 0 ;1
L 10.4325 5.6325 10.4325 5.6325 9 P 0 ;1
L 10.4325 5.6825 10.4325 5.6825 9 P 0 ;1
L 10.4325 5.7325 10.4325 5.7325 9 P 0 ;1
L 10.4325 5.7825 10.4325 5.7825 9 P 0 ;1
L 10.4325 5.8325 10.4325 5.8325 9 P 0 ;1
L 10.4325 5.8825 10.4325 5.8825 9 P 0 ;1
L 10.4825 0.1325 10.4825 0.1325 9 P 0 ;1
L 10.4825 0.1825 10.4825 0.1825 9 P 0 ;1
L 10.4825 0.2325 10.4825 0.2325 9 P 0 ;1
L 10.4825 0.2825 10.4825 0.2825 9 P 0 ;1
L 10.4825 0.3325 10.4825 0.3325 9 P 0 ;1
L 10.4825 0.3825 10.4825 0.3825 9 P 0 ;1
L 10.4825 0.4325 10.4825 0.4325 9 P 0 ;1
L 10.4825 0.4825 10.4825 0.4825 9 P 0 ;1
L 10.4825 0.5325 10.4825 0.5325 9 P 0 ;1
L 10.4825 0.5825 10.4825 0.5825 9 P 0 ;1
L 10.4825 0.6325 10.4825 0.6325 9 P 0 ;1
L 10.4825 0.6825 10.4825 0.6825 9 P 0 ;1
L 10.4825 0.7325 10.4825 0.7325 9 P 0 ;1
L 10.4825 0.7825 10.4825 0.7825 9 P 0 ;1
L 10.4825 0.8325 10.4825 0.8325 9 P 0 ;1
L 10.4825 0.8825 10.4825 0.8825 9 P 0 ;1
L 10.4825 0.9325 10.4825 0.9325 9 P 0 ;1
L 10.4825 0.9825 10.4825 0.9825 9 P 0 ;1
L 10.4825 1.0325 10.4825 1.0325 9 P 0 ;1
L 10.4825 1.0825 10.4825 1.0825 9 P 0 ;1
L 10.4825 1.1325 10.4825 1.1325 9 P 0 ;1
L 10.4825 1.1825 10.4825 1.1825 9 P 0 ;1
L 10.4825 1.5825 10.4825 1.5825 9 P 0 ;1
L 10.4825 1.6325 10.4825 1.6325 9 P 0 ;1
L 10.4825 1.6825 10.4825 1.6825 9 P 0 ;1
L 10.4825 1.7325 10.4825 1.7325 9 P 0 ;1
L 10.4825 1.7825 10.4825 1.7825 9 P 0 ;1
L 10.4825 1.8325 10.4825 1.8325 9 P 0 ;1
L 10.4825 1.8825 10.4825 1.8825 9 P 0 ;1
L 10.4825 1.9325 10.4825 1.9325 9 P 0 ;1
L 10.4825 1.9825 10.4825 1.9825 9 P 0 ;1
L 10.4825 2.0325 10.4825 2.0325 9 P 0 ;1
L 10.4825 2.0825 10.4825 2.0825 9 P 0 ;1
L 10.4825 2.1325 10.4825 2.1325 9 P 0 ;1
L 10.4825 2.1825 10.4825 2.1825 9 P 0 ;1
L 10.4825 2.2325 10.4825 2.2325 9 P 0 ;1
L 10.4825 2.2825 10.4825 2.2825 9 P 0 ;1
L 10.4825 2.3325 10.4825 2.3325 9 P 0 ;1
L 10.4825 2.3825 10.4825 2.3825 9 P 0 ;1
L 10.4825 2.4325 10.4825 2.4325 9 P 0 ;1
L 10.4825 2.4825 10.4825 2.4825 9 P 0 ;1
L 10.4825 2.5325 10.4825 2.5325 9 P 0 ;1
L 10.4825 2.5825 10.4825 2.5825 9 P 0 ;1
L 10.4825 2.6325 10.4825 2.6325 9 P 0 ;1
L 10.4825 2.6825 10.4825 2.6825 9 P 0 ;1
L 10.4825 2.7325 10.4825 2.7325 9 P 0 ;1
L 10.4825 2.7825 10.4825 2.7825 9 P 0 ;1
L 10.4825 2.8325 10.4825 2.8325 9 P 0 ;1
L 10.4825 2.8825 10.4825 2.8825 9 P 0 ;1
L 10.4825 2.9325 10.4825 2.9325 9 P 0 ;1
L 10.4825 5.4325 10.4825 5.4325 9 P 0 ;1
L 10.4825 5.4825 10.4825 5.4825 9 P 0 ;1
L 10.4825 5.5325 10.4825 5.5325 9 P 0 ;1
L 10.4825 5.5825 10.4825 5.5825 9 P 0 ;1
L 10.4825 5.6325 10.4825 5.6325 9 P 0 ;1
L 10.4825 5.6825 10.4825 5.6825 9 P 0 ;1
L 10.4825 5.7325 10.4825 5.7325 9 P 0 ;1
L 10.4825 5.7825 10.4825 5.7825 9 P 0 ;1
L 10.4825 5.8325 10.4825 5.8325 9 P 0 ;1
L 10.4825 5.8825 10.4825 5.8825 9 P 0 ;1
L 10.5325 0.1325 10.5325 0.1325 9 P 0 ;1
L 10.5325 0.1825 10.5325 0.1825 9 P 0 ;1
L 10.5325 0.2325 10.5325 0.2325 9 P 0 ;1
L 10.5325 0.2825 10.5325 0.2825 9 P 0 ;1
L 10.5325 0.3325 10.5325 0.3325 9 P 0 ;1
L 10.5325 0.3825 10.5325 0.3825 9 P 0 ;1
L 10.5325 0.4325 10.5325 0.4325 9 P 0 ;1
L 10.5325 0.4825 10.5325 0.4825 9 P 0 ;1
L 10.5325 0.5325 10.5325 0.5325 9 P 0 ;1
L 10.5325 0.5825 10.5325 0.5825 9 P 0 ;1
L 10.5325 0.6325 10.5325 0.6325 9 P 0 ;1
L 10.5325 0.6825 10.5325 0.6825 9 P 0 ;1
L 10.5325 0.7325 10.5325 0.7325 9 P 0 ;1
L 10.5325 0.7825 10.5325 0.7825 9 P 0 ;1
L 10.5325 0.8325 10.5325 0.8325 9 P 0 ;1
L 10.5325 0.8825 10.5325 0.8825 9 P 0 ;1
L 10.5325 0.9325 10.5325 0.9325 9 P 0 ;1
L 10.5325 0.9825 10.5325 0.9825 9 P 0 ;1
L 10.5325 1.0325 10.5325 1.0325 9 P 0 ;1
L 10.5325 1.0825 10.5325 1.0825 9 P 0 ;1
L 10.5325 1.1325 10.5325 1.1325 9 P 0 ;1
L 10.5325 1.1825 10.5325 1.1825 9 P 0 ;1
L 10.5325 1.2325 10.5325 1.2325 9 P 0 ;1
L 10.5325 1.2825 10.5325 1.2825 9 P 0 ;1
L 10.5325 1.3325 10.5325 1.3325 9 P 0 ;1
L 10.5325 1.5325 10.5325 1.5325 9 P 0 ;1
L 10.5325 1.5825 10.5325 1.5825 9 P 0 ;1
L 10.5325 1.6325 10.5325 1.6325 9 P 0 ;1
L 10.5325 1.6825 10.5325 1.6825 9 P 0 ;1
L 10.5325 1.7325 10.5325 1.7325 9 P 0 ;1
L 10.5325 1.7825 10.5325 1.7825 9 P 0 ;1
L 10.5825 0.1325 10.5825 0.1325 9 P 0 ;1
L 10.5825 0.1825 10.5825 0.1825 9 P 0 ;1
L 10.5825 0.2325 10.5825 0.2325 9 P 0 ;1
L 10.5825 0.2825 10.5825 0.2825 9 P 0 ;1
L 10.5825 0.3325 10.5825 0.3325 9 P 0 ;1
L 10.5825 0.3825 10.5825 0.3825 9 P 0 ;1
L 10.5825 0.4325 10.5825 0.4325 9 P 0 ;1
L 10.5825 0.4825 10.5825 0.4825 9 P 0 ;1
L 10.5825 0.5325 10.5825 0.5325 9 P 0 ;1
L 10.5825 0.5825 10.5825 0.5825 9 P 0 ;1
L 10.5825 0.6325 10.5825 0.6325 9 P 0 ;1
L 10.5825 0.6825 10.5825 0.6825 9 P 0 ;1
L 10.5825 0.7325 10.5825 0.7325 9 P 0 ;1
L 10.5825 0.7825 10.5825 0.7825 9 P 0 ;1
L 10.5825 0.8325 10.5825 0.8325 9 P 0 ;1
L 10.5825 0.8825 10.5825 0.8825 9 P 0 ;1
L 10.5825 0.9325 10.5825 0.9325 9 P 0 ;1
L 10.5825 0.9825 10.5825 0.9825 9 P 0 ;1
L 10.5825 1.0325 10.5825 1.0325 9 P 0 ;1
L 10.5825 1.0825 10.5825 1.0825 9 P 0 ;1
L 10.5825 1.1325 10.5825 1.1325 9 P 0 ;1
L 10.5825 1.1825 10.5825 1.1825 9 P 0 ;1
L 10.5825 1.2325 10.5825 1.2325 9 P 0 ;1
L 10.5825 1.2825 10.5825 1.2825 9 P 0 ;1
L 10.5825 1.3325 10.5825 1.3325 9 P 0 ;1
L 10.5825 1.3825 10.5825 1.3825 9 P 0 ;1
L 10.5825 1.4325 10.5825 1.4325 9 P 0 ;1
L 10.5825 1.4825 10.5825 1.4825 9 P 0 ;1
L 10.5825 1.5325 10.5825 1.5325 9 P 0 ;1
L 10.5825 1.5825 10.5825 1.5825 9 P 0 ;1
L 10.5825 1.6325 10.5825 1.6325 9 P 0 ;1
L 10.5825 1.6825 10.5825 1.6825 9 P 0 ;1
L 10.5825 1.7325 10.5825 1.7325 9 P 0 ;1
L 10.5825 1.7825 10.5825 1.7825 9 P 0 ;1
L 10.6325 0.1325 10.6325 0.1325 9 P 0 ;1
L 10.6325 0.1825 10.6325 0.1825 9 P 0 ;1
L 10.6325 0.2325 10.6325 0.2325 9 P 0 ;1
L 10.6325 0.2825 10.6325 0.2825 9 P 0 ;1
L 10.6325 0.3325 10.6325 0.3325 9 P 0 ;1
L 10.6325 0.3825 10.6325 0.3825 9 P 0 ;1
L 10.6325 0.4325 10.6325 0.4325 9 P 0 ;1
L 10.6325 0.4825 10.6325 0.4825 9 P 0 ;1
L 10.6325 0.5325 10.6325 0.5325 9 P 0 ;1
L 10.6325 0.5825 10.6325 0.5825 9 P 0 ;1
L 10.6325 0.6325 10.6325 0.6325 9 P 0 ;1
L 10.6325 0.6825 10.6325 0.6825 9 P 0 ;1
L 10.6325 0.7325 10.6325 0.7325 9 P 0 ;1
L 10.6325 0.7825 10.6325 0.7825 9 P 0 ;1
L 10.6325 0.8325 10.6325 0.8325 9 P 0 ;1
L 10.6325 0.8825 10.6325 0.8825 9 P 0 ;1
L 10.6325 0.9325 10.6325 0.9325 9 P 0 ;1
L 10.6325 0.9825 10.6325 0.9825 9 P 0 ;1
L 10.6325 1.0325 10.6325 1.0325 9 P 0 ;1
L 10.6325 1.0825 10.6325 1.0825 9 P 0 ;1
L 10.6325 1.1325 10.6325 1.1325 9 P 0 ;1
L 10.6325 1.1825 10.6325 1.1825 9 P 0 ;1
L 10.6325 1.2325 10.6325 1.2325 9 P 0 ;1
L 10.6325 1.2825 10.6325 1.2825 9 P 0 ;1
L 10.6325 1.3325 10.6325 1.3325 9 P 0 ;1
L 10.6325 1.3825 10.6325 1.3825 9 P 0 ;1
L 10.6325 1.4325 10.6325 1.4325 9 P 0 ;1
L 10.6325 1.5825 10.6325 1.5825 9 P 0 ;1
L 10.6325 1.6325 10.6325 1.6325 9 P 0 ;1
L 10.6325 1.6825 10.6325 1.6825 9 P 0 ;1
L 10.6325 1.7325 10.6325 1.7325 9 P 0 ;1
L 10.6325 1.7825 10.6325 1.7825 9 P 0 ;1
L 10.6825 0.1325 10.6825 0.1325 9 P 0 ;1
L 10.6825 0.1825 10.6825 0.1825 9 P 0 ;1
L 10.6825 0.2325 10.6825 0.2325 9 P 0 ;1
L 10.6825 0.2825 10.6825 0.2825 9 P 0 ;1
L 10.6825 0.3325 10.6825 0.3325 9 P 0 ;1
L 10.6825 0.3825 10.6825 0.3825 9 P 0 ;1
L 10.6825 0.4325 10.6825 0.4325 9 P 0 ;1
L 10.6825 0.4825 10.6825 0.4825 9 P 0 ;1
L 10.6825 0.5325 10.6825 0.5325 9 P 0 ;1
L 10.6825 0.5825 10.6825 0.5825 9 P 0 ;1
L 10.6825 0.6325 10.6825 0.6325 9 P 0 ;1
L 10.6825 0.6825 10.6825 0.6825 9 P 0 ;1
L 10.6825 0.7325 10.6825 0.7325 9 P 0 ;1
L 10.6825 0.7825 10.6825 0.7825 9 P 0 ;1
L 10.6825 0.8325 10.6825 0.8325 9 P 0 ;1
L 10.6825 0.8825 10.6825 0.8825 9 P 0 ;1
L 10.6825 0.9325 10.6825 0.9325 9 P 0 ;1
L 10.6825 0.9825 10.6825 0.9825 9 P 0 ;1
L 10.6825 1.0325 10.6825 1.0325 9 P 0 ;1
L 10.6825 1.0825 10.6825 1.0825 9 P 0 ;1
L 10.6825 1.1325 10.6825 1.1325 9 P 0 ;1
L 10.6825 1.1825 10.6825 1.1825 9 P 0 ;1
L 10.6825 1.2325 10.6825 1.2325 9 P 0 ;1
L 10.6825 1.2825 10.6825 1.2825 9 P 0 ;1
L 10.6825 1.3325 10.6825 1.3325 9 P 0 ;1
L 10.6825 1.6825 10.6825 1.6825 9 P 0 ;1
L 10.6825 1.7325 10.6825 1.7325 9 P 0 ;1
L 10.6825 1.7825 10.6825 1.7825 9 P 0 ;1
L 10.7325 0.1325 10.7325 0.1325 9 P 0 ;1
L 10.7325 0.1825 10.7325 0.1825 9 P 0 ;1
L 10.7325 0.2325 10.7325 0.2325 9 P 0 ;1
L 10.7325 0.2825 10.7325 0.2825 9 P 0 ;1
L 10.7325 0.3325 10.7325 0.3325 9 P 0 ;1
L 10.7325 0.3825 10.7325 0.3825 9 P 0 ;1
L 10.7325 0.4325 10.7325 0.4325 9 P 0 ;1
L 10.7325 0.4825 10.7325 0.4825 9 P 0 ;1
L 10.7325 0.5325 10.7325 0.5325 9 P 0 ;1
L 10.7325 0.5825 10.7325 0.5825 9 P 0 ;1
L 10.7325 0.6325 10.7325 0.6325 9 P 0 ;1
L 10.7325 0.6825 10.7325 0.6825 9 P 0 ;1
L 10.7325 0.7325 10.7325 0.7325 9 P 0 ;1
L 10.7325 0.7825 10.7325 0.7825 9 P 0 ;1
L 10.7325 0.8325 10.7325 0.8325 9 P 0 ;1
L 10.7325 0.8825 10.7325 0.8825 9 P 0 ;1
L 10.7325 0.9325 10.7325 0.9325 9 P 0 ;1
L 10.7325 0.9825 10.7325 0.9825 9 P 0 ;1
L 10.7325 1.0325 10.7325 1.0325 9 P 0 ;1
L 10.7325 1.0825 10.7325 1.0825 9 P 0 ;1
L 10.7325 1.1325 10.7325 1.1325 9 P 0 ;1
L 10.7325 1.1825 10.7325 1.1825 9 P 0 ;1
L 10.7325 1.2325 10.7325 1.2325 9 P 0 ;1
L 10.7325 1.2825 10.7325 1.2825 9 P 0 ;1
L 10.7325 1.3325 10.7325 1.3325 9 P 0 ;1
L 10.7325 1.6825 10.7325 1.6825 9 P 0 ;1
L 10.7325 1.7325 10.7325 1.7325 9 P 0 ;1
L 10.7325 1.7825 10.7325 1.7825 9 P 0 ;1
L 10.7825 0.1325 10.7825 0.1325 9 P 0 ;1
L 10.7825 0.1825 10.7825 0.1825 9 P 0 ;1
L 10.7825 0.2325 10.7825 0.2325 9 P 0 ;1
L 10.7825 0.2825 10.7825 0.2825 9 P 0 ;1
L 10.7825 0.3325 10.7825 0.3325 9 P 0 ;1
L 10.7825 0.3825 10.7825 0.3825 9 P 0 ;1
L 10.7825 0.4325 10.7825 0.4325 9 P 0 ;1
L 10.7825 0.4825 10.7825 0.4825 9 P 0 ;1
L 10.7825 0.5325 10.7825 0.5325 9 P 0 ;1
L 10.7825 0.5825 10.7825 0.5825 9 P 0 ;1
L 10.7825 0.6325 10.7825 0.6325 9 P 0 ;1
L 10.7825 0.6825 10.7825 0.6825 9 P 0 ;1
L 10.7825 0.7325 10.7825 0.7325 9 P 0 ;1
L 10.7825 0.7825 10.7825 0.7825 9 P 0 ;1
L 10.7825 0.8325 10.7825 0.8325 9 P 0 ;1
L 10.7825 0.8825 10.7825 0.8825 9 P 0 ;1
L 10.7825 0.9325 10.7825 0.9325 9 P 0 ;1
L 10.7825 0.9825 10.7825 0.9825 9 P 0 ;1
L 10.7825 1.0325 10.7825 1.0325 9 P 0 ;1
L 10.7825 1.0825 10.7825 1.0825 9 P 0 ;1
L 10.7825 1.1325 10.7825 1.1325 9 P 0 ;1
L 10.7825 1.1825 10.7825 1.1825 9 P 0 ;1
L 10.7825 1.2325 10.7825 1.2325 9 P 0 ;1
L 10.7825 1.2825 10.7825 1.2825 9 P 0 ;1
L 10.7825 1.7325 10.7825 1.7325 9 P 0 ;1
L 10.7825 1.7825 10.7825 1.7825 9 P 0 ;1
L 10.8325 0.1325 10.8325 0.1325 9 P 0 ;1
L 10.8325 0.1825 10.8325 0.1825 9 P 0 ;1
L 10.8325 0.2325 10.8325 0.2325 9 P 0 ;1
L 10.8325 0.2825 10.8325 0.2825 9 P 0 ;1
L 10.8325 0.3325 10.8325 0.3325 9 P 0 ;1
L 10.8325 0.3825 10.8325 0.3825 9 P 0 ;1
L 10.8325 0.4325 10.8325 0.4325 9 P 0 ;1
L 10.8325 0.4825 10.8325 0.4825 9 P 0 ;1
L 10.8325 0.5325 10.8325 0.5325 9 P 0 ;1
L 10.8325 0.5825 10.8325 0.5825 9 P 0 ;1
L 10.8325 0.6325 10.8325 0.6325 9 P 0 ;1
L 10.8325 0.6825 10.8325 0.6825 9 P 0 ;1
L 10.8325 0.7325 10.8325 0.7325 9 P 0 ;1
L 10.8325 0.7825 10.8325 0.7825 9 P 0 ;1
L 10.8325 0.8325 10.8325 0.8325 9 P 0 ;1
L 10.8325 0.8825 10.8325 0.8825 9 P 0 ;1
L 10.8325 0.9325 10.8325 0.9325 9 P 0 ;1
L 10.8325 0.9825 10.8325 0.9825 9 P 0 ;1
L 10.8325 1.0325 10.8325 1.0325 9 P 0 ;1
L 10.8325 1.0825 10.8325 1.0825 9 P 0 ;1
L 10.8325 1.1325 10.8325 1.1325 9 P 0 ;1
L 10.8325 1.1825 10.8325 1.1825 9 P 0 ;1
L 10.8325 1.2325 10.8325 1.2325 9 P 0 ;1
L 10.8325 1.2825 10.8325 1.2825 9 P 0 ;1
L 10.8325 1.7325 10.8325 1.7325 9 P 0 ;1
L 10.8325 1.7825 10.8325 1.7825 9 P 0 ;1
L 10.8825 0.1325 10.8825 0.1325 9 P 0 ;1
L 10.8825 0.1825 10.8825 0.1825 9 P 0 ;1
L 10.8825 0.2325 10.8825 0.2325 9 P 0 ;1
L 10.8825 0.2825 10.8825 0.2825 9 P 0 ;1
L 10.8825 0.3325 10.8825 0.3325 9 P 0 ;1
L 10.8825 0.3825 10.8825 0.3825 9 P 0 ;1
L 10.8825 0.4325 10.8825 0.4325 9 P 0 ;1
L 10.8825 0.4825 10.8825 0.4825 9 P 0 ;1
L 10.8825 0.5325 10.8825 0.5325 9 P 0 ;1
L 10.8825 0.5825 10.8825 0.5825 9 P 0 ;1
L 10.8825 0.6325 10.8825 0.6325 9 P 0 ;1
L 10.8825 0.6825 10.8825 0.6825 9 P 0 ;1
L 10.8825 0.7325 10.8825 0.7325 9 P 0 ;1
L 10.8825 0.7825 10.8825 0.7825 9 P 0 ;1
L 10.8825 0.8325 10.8825 0.8325 9 P 0 ;1
L 10.8825 0.8825 10.8825 0.8825 9 P 0 ;1
L 10.8825 0.9325 10.8825 0.9325 9 P 0 ;1
L 10.8825 0.9825 10.8825 0.9825 9 P 0 ;1
L 10.8825 1.0325 10.8825 1.0325 9 P 0 ;1
L 10.8825 1.0825 10.8825 1.0825 9 P 0 ;1
L 10.8825 1.1325 10.8825 1.1325 9 P 0 ;1
L 10.8825 1.1825 10.8825 1.1825 9 P 0 ;1
L 10.8825 1.2325 10.8825 1.2325 9 P 0 ;1
L 10.8825 1.2825 10.8825 1.2825 9 P 0 ;1
L 10.8825 1.7325 10.8825 1.7325 9 P 0 ;1
L 10.8825 1.7825 10.8825 1.7825 9 P 0 ;1
L 10.9325 0.1325 10.9325 0.1325 9 P 0 ;1
L 10.9325 0.1825 10.9325 0.1825 9 P 0 ;1
L 10.9325 0.2325 10.9325 0.2325 9 P 0 ;1
L 10.9325 0.2825 10.9325 0.2825 9 P 0 ;1
L 10.9325 0.3325 10.9325 0.3325 9 P 0 ;1
L 10.9325 0.3825 10.9325 0.3825 9 P 0 ;1
L 10.9325 0.4325 10.9325 0.4325 9 P 0 ;1
L 10.9325 0.4825 10.9325 0.4825 9 P 0 ;1
L 10.9325 0.5325 10.9325 0.5325 9 P 0 ;1
L 10.9325 0.5825 10.9325 0.5825 9 P 0 ;1
L 10.9325 0.6325 10.9325 0.6325 9 P 0 ;1
L 10.9325 0.6825 10.9325 0.6825 9 P 0 ;1
L 10.9325 0.7325 10.9325 0.7325 9 P 0 ;1
L 10.9325 0.7825 10.9325 0.7825 9 P 0 ;1
L 10.9325 0.8325 10.9325 0.8325 9 P 0 ;1
L 10.9325 0.8825 10.9325 0.8825 9 P 0 ;1
L 10.9325 0.9325 10.9325 0.9325 9 P 0 ;1
L 10.9325 0.9825 10.9325 0.9825 9 P 0 ;1
L 10.9325 1.0325 10.9325 1.0325 9 P 0 ;1
L 10.9325 1.0825 10.9325 1.0825 9 P 0 ;1
L 10.9325 1.1325 10.9325 1.1325 9 P 0 ;1
L 10.9325 1.1825 10.9325 1.1825 9 P 0 ;1
L 10.9325 1.2325 10.9325 1.2325 9 P 0 ;1
L 10.9325 1.2825 10.9325 1.2825 9 P 0 ;1
L 10.9325 1.3325 10.9325 1.3325 9 P 0 ;1
L 10.9325 1.6825 10.9325 1.6825 9 P 0 ;1
L 10.9325 1.7325 10.9325 1.7325 9 P 0 ;1
L 10.9325 1.7825 10.9325 1.7825 9 P 0 ;1
L 10.9825 0.1325 10.9825 0.1325 9 P 0 ;1
L 10.9825 0.1825 10.9825 0.1825 9 P 0 ;1
L 10.9825 0.2325 10.9825 0.2325 9 P 0 ;1
L 10.9825 0.2825 10.9825 0.2825 9 P 0 ;1
L 10.9825 0.3325 10.9825 0.3325 9 P 0 ;1
L 10.9825 0.3825 10.9825 0.3825 9 P 0 ;1
L 10.9825 0.4325 10.9825 0.4325 9 P 0 ;1
L 10.9825 0.4825 10.9825 0.4825 9 P 0 ;1
L 10.9825 0.5325 10.9825 0.5325 9 P 0 ;1
L 10.9825 0.5825 10.9825 0.5825 9 P 0 ;1
L 10.9825 0.6325 10.9825 0.6325 9 P 0 ;1
L 10.9825 0.6825 10.9825 0.6825 9 P 0 ;1
L 10.9825 0.7325 10.9825 0.7325 9 P 0 ;1
L 10.9825 0.7825 10.9825 0.7825 9 P 0 ;1
L 10.9825 0.8325 10.9825 0.8325 9 P 0 ;1
L 10.9825 0.8825 10.9825 0.8825 9 P 0 ;1
L 10.9825 0.9325 10.9825 0.9325 9 P 0 ;1
L 10.9825 0.9825 10.9825 0.9825 9 P 0 ;1
L 10.9825 1.0325 10.9825 1.0325 9 P 0 ;1
L 10.9825 1.0825 10.9825 1.0825 9 P 0 ;1
L 10.9825 1.1325 10.9825 1.1325 9 P 0 ;1
L 10.9825 1.1825 10.9825 1.1825 9 P 0 ;1
L 10.9825 1.2325 10.9825 1.2325 9 P 0 ;1
L 10.9825 1.2825 10.9825 1.2825 9 P 0 ;1
L 10.9825 1.3325 10.9825 1.3325 9 P 0 ;1
L 10.9825 1.6825 10.9825 1.6825 9 P 0 ;1
L 10.9825 1.7325 10.9825 1.7325 9 P 0 ;1
L 10.9825 1.7825 10.9825 1.7825 9 P 0 ;1
L 11.0325 0.1325 11.0325 0.1325 9 P 0 ;1
L 11.0325 0.1825 11.0325 0.1825 9 P 0 ;1
L 11.0325 0.2325 11.0325 0.2325 9 P 0 ;1
L 11.0325 0.2825 11.0325 0.2825 9 P 0 ;1
L 11.0325 0.3325 11.0325 0.3325 9 P 0 ;1
L 11.0325 0.3825 11.0325 0.3825 9 P 0 ;1
L 11.0325 0.4325 11.0325 0.4325 9 P 0 ;1
L 11.0325 0.4825 11.0325 0.4825 9 P 0 ;1
L 11.0325 0.5325 11.0325 0.5325 9 P 0 ;1
L 11.0325 0.5825 11.0325 0.5825 9 P 0 ;1
L 11.0325 0.6325 11.0325 0.6325 9 P 0 ;1
L 11.0325 0.6825 11.0325 0.6825 9 P 0 ;1
L 11.0325 0.7325 11.0325 0.7325 9 P 0 ;1
L 11.0325 0.7825 11.0325 0.7825 9 P 0 ;1
L 11.0325 0.8325 11.0325 0.8325 9 P 0 ;1
L 11.0325 0.8825 11.0325 0.8825 9 P 0 ;1
L 11.0325 0.9325 11.0325 0.9325 9 P 0 ;1
L 11.0325 0.9825 11.0325 0.9825 9 P 0 ;1
L 11.0325 1.0325 11.0325 1.0325 9 P 0 ;1
L 11.0325 1.0825 11.0325 1.0825 9 P 0 ;1
L 11.0325 1.1325 11.0325 1.1325 9 P 0 ;1
L 11.0325 1.1825 11.0325 1.1825 9 P 0 ;1
L 11.0325 1.2325 11.0325 1.2325 9 P 0 ;1
L 11.0325 1.2825 11.0325 1.2825 9 P 0 ;1
L 11.0325 1.3325 11.0325 1.3325 9 P 0 ;1
L 11.0325 1.3825 11.0325 1.3825 9 P 0 ;1
L 11.0325 1.4325 11.0325 1.4325 9 P 0 ;1
L 11.0325 1.5825 11.0325 1.5825 9 P 0 ;1
L 11.0325 1.6325 11.0325 1.6325 9 P 0 ;1
L 11.0325 1.6825 11.0325 1.6825 9 P 0 ;1
L 11.0325 1.7325 11.0325 1.7325 9 P 0 ;1
L 11.0325 1.7825 11.0325 1.7825 9 P 0 ;1
L 11.0825 0.1325 11.0825 0.1325 9 P 0 ;1
L 11.0825 0.1825 11.0825 0.1825 9 P 0 ;1
L 11.0825 0.2325 11.0825 0.2325 9 P 0 ;1
L 11.0825 0.2825 11.0825 0.2825 9 P 0 ;1
L 11.0825 0.3325 11.0825 0.3325 9 P 0 ;1
L 11.0825 0.3825 11.0825 0.3825 9 P 0 ;1
L 11.0825 0.4325 11.0825 0.4325 9 P 0 ;1
L 11.0825 0.4825 11.0825 0.4825 9 P 0 ;1
L 11.0825 0.5325 11.0825 0.5325 9 P 0 ;1
L 11.0825 0.5825 11.0825 0.5825 9 P 0 ;1
L 11.0825 0.6325 11.0825 0.6325 9 P 0 ;1
L 11.0825 0.6825 11.0825 0.6825 9 P 0 ;1
L 11.0825 0.7325 11.0825 0.7325 9 P 0 ;1
L 11.0825 0.7825 11.0825 0.7825 9 P 0 ;1
L 11.0825 0.8325 11.0825 0.8325 9 P 0 ;1
L 11.0825 0.8825 11.0825 0.8825 9 P 0 ;1
L 11.0825 0.9325 11.0825 0.9325 9 P 0 ;1
L 11.0825 0.9825 11.0825 0.9825 9 P 0 ;1
L 11.0825 1.0325 11.0825 1.0325 9 P 0 ;1
L 11.0825 1.0825 11.0825 1.0825 9 P 0 ;1
L 11.0825 1.1325 11.0825 1.1325 9 P 0 ;1
L 11.0825 1.1825 11.0825 1.1825 9 P 0 ;1
L 11.0825 1.2325 11.0825 1.2325 9 P 0 ;1
L 11.0825 1.2825 11.0825 1.2825 9 P 0 ;1
L 11.0825 1.3325 11.0825 1.3325 9 P 0 ;1
L 11.0825 1.3825 11.0825 1.3825 9 P 0 ;1
L 11.0825 1.4325 11.0825 1.4325 9 P 0 ;1
L 11.0825 1.4825 11.0825 1.4825 9 P 0 ;1
L 11.0825 1.5325 11.0825 1.5325 9 P 0 ;1
L 11.0825 1.5825 11.0825 1.5825 9 P 0 ;1
L 11.0825 1.6325 11.0825 1.6325 9 P 0 ;1
L 11.0825 1.6825 11.0825 1.6825 9 P 0 ;1
L 11.0825 1.7325 11.0825 1.7325 9 P 0 ;1
L 11.0825 1.7825 11.0825 1.7825 9 P 0 ;1
L 11.1325 0.1325 11.1325 0.1325 9 P 0 ;1
L 11.1325 0.1825 11.1325 0.1825 9 P 0 ;1
L 11.1325 0.2325 11.1325 0.2325 9 P 0 ;1
L 11.1325 0.2825 11.1325 0.2825 9 P 0 ;1
L 11.1325 0.3325 11.1325 0.3325 9 P 0 ;1
L 11.1325 0.3825 11.1325 0.3825 9 P 0 ;1
L 11.1325 0.4325 11.1325 0.4325 9 P 0 ;1
L 11.1325 0.4825 11.1325 0.4825 9 P 0 ;1
L 11.1325 0.5325 11.1325 0.5325 9 P 0 ;1
L 11.1325 0.5825 11.1325 0.5825 9 P 0 ;1
L 11.1325 0.6325 11.1325 0.6325 9 P 0 ;1
L 11.1325 0.6825 11.1325 0.6825 9 P 0 ;1
L 11.1325 0.7325 11.1325 0.7325 9 P 0 ;1
L 11.1325 0.7825 11.1325 0.7825 9 P 0 ;1
L 11.1325 0.8325 11.1325 0.8325 9 P 0 ;1
L 11.1325 0.8825 11.1325 0.8825 9 P 0 ;1
L 11.1325 0.9325 11.1325 0.9325 9 P 0 ;1
L 11.1325 0.9825 11.1325 0.9825 9 P 0 ;1
L 11.1325 1.0325 11.1325 1.0325 9 P 0 ;1
L 11.1325 1.0825 11.1325 1.0825 9 P 0 ;1
L 11.1325 1.1325 11.1325 1.1325 9 P 0 ;1
L 11.1325 1.1825 11.1325 1.1825 9 P 0 ;1
L 11.1325 1.2325 11.1325 1.2325 9 P 0 ;1
L 11.1325 1.2825 11.1325 1.2825 9 P 0 ;1
L 11.1325 1.3325 11.1325 1.3325 9 P 0 ;1
L 11.1325 1.3825 11.1325 1.3825 9 P 0 ;1
L 11.1325 1.4325 11.1325 1.4325 9 P 0 ;1
L 11.1325 1.4825 11.1325 1.4825 9 P 0 ;1
L 11.1325 1.5325 11.1325 1.5325 9 P 0 ;1
L 11.1325 1.5825 11.1325 1.5825 9 P 0 ;1
L 11.1325 1.6325 11.1325 1.6325 9 P 0 ;1
L 11.1325 1.6825 11.1325 1.6825 9 P 0 ;1
L 11.1325 1.7325 11.1325 1.7325 9 P 0 ;1
L 11.1325 1.7825 11.1325 1.7825 9 P 0 ;1
L 11.1825 0.1325 11.1825 0.1325 9 P 0 ;1
L 11.1825 0.1825 11.1825 0.1825 9 P 0 ;1
L 11.1825 0.2325 11.1825 0.2325 9 P 0 ;1
L 11.1825 0.2825 11.1825 0.2825 9 P 0 ;1
L 11.1825 0.3325 11.1825 0.3325 9 P 0 ;1
L 11.1825 0.3825 11.1825 0.3825 9 P 0 ;1
L 11.1825 0.4325 11.1825 0.4325 9 P 0 ;1
L 11.1825 0.4825 11.1825 0.4825 9 P 0 ;1
L 11.1825 0.5325 11.1825 0.5325 9 P 0 ;1
L 11.1825 0.5825 11.1825 0.5825 9 P 0 ;1
L 11.1825 0.6325 11.1825 0.6325 9 P 0 ;1
L 11.1825 0.6825 11.1825 0.6825 9 P 0 ;1
L 11.1825 0.7325 11.1825 0.7325 9 P 0 ;1
L 11.1825 0.7825 11.1825 0.7825 9 P 0 ;1
L 11.1825 0.8325 11.1825 0.8325 9 P 0 ;1
L 11.1825 0.8825 11.1825 0.8825 9 P 0 ;1
L 11.1825 0.9325 11.1825 0.9325 9 P 0 ;1
L 11.1825 0.9825 11.1825 0.9825 9 P 0 ;1
L 11.1825 1.0325 11.1825 1.0325 9 P 0 ;1
L 11.1825 1.0825 11.1825 1.0825 9 P 0 ;1
L 11.1825 1.1325 11.1825 1.1325 9 P 0 ;1
L 11.1825 1.1825 11.1825 1.1825 9 P 0 ;1
L 11.1825 1.2325 11.1825 1.2325 9 P 0 ;1
L 11.1825 1.2825 11.1825 1.2825 9 P 0 ;1
L 11.1825 1.3325 11.1825 1.3325 9 P 0 ;1
L 11.1825 1.3825 11.1825 1.3825 9 P 0 ;1
L 11.1825 1.4325 11.1825 1.4325 9 P 0 ;1
L 11.1825 1.4825 11.1825 1.4825 9 P 0 ;1
L 11.1825 1.5325 11.1825 1.5325 9 P 0 ;1
L 11.1825 1.5825 11.1825 1.5825 9 P 0 ;1
L 11.1825 1.6325 11.1825 1.6325 9 P 0 ;1
L 11.1825 1.6825 11.1825 1.6825 9 P 0 ;1
L 11.1825 1.7325 11.1825 1.7325 9 P 0 ;1
L 11.1825 1.7825 11.1825 1.7825 9 P 0 ;1
L 11.1825 1.8325 11.1825 1.8325 9 P 0 ;1
L 11.1825 1.8825 11.1825 1.8825 9 P 0 ;1
L 11.1825 1.9325 11.1825 1.9325 9 P 0 ;1
L 11.1825 1.9825 11.1825 1.9825 9 P 0 ;1
L 11.1825 2.0325 11.1825 2.0325 9 P 0 ;1
L 11.1825 2.0825 11.1825 2.0825 9 P 0 ;1
L 11.1825 2.1325 11.1825 2.1325 9 P 0 ;1
L 11.1825 2.1825 11.1825 2.1825 9 P 0 ;1
L 11.1825 2.2325 11.1825 2.2325 9 P 0 ;1
L 11.1825 2.2825 11.1825 2.2825 9 P 0 ;1
L 11.1825 2.3325 11.1825 2.3325 9 P 0 ;1
L 11.1825 2.3825 11.1825 2.3825 9 P 0 ;1
L 11.1825 2.4325 11.1825 2.4325 9 P 0 ;1
L 11.1825 2.4825 11.1825 2.4825 9 P 0 ;1
L 11.1825 2.5325 11.1825 2.5325 9 P 0 ;1
L 11.1825 2.5825 11.1825 2.5825 9 P 0 ;1
L 11.1825 2.6325 11.1825 2.6325 9 P 0 ;1
L 11.1825 2.6825 11.1825 2.6825 9 P 0 ;1
L 11.1825 2.7325 11.1825 2.7325 9 P 0 ;1
L 11.2325 0.1325 11.2325 0.1325 9 P 0 ;1
L 11.2325 0.1825 11.2325 0.1825 9 P 0 ;1
L 11.2325 0.2325 11.2325 0.2325 9 P 0 ;1
L 11.2325 0.2825 11.2325 0.2825 9 P 0 ;1
L 11.2325 0.3325 11.2325 0.3325 9 P 0 ;1
L 11.2325 0.3825 11.2325 0.3825 9 P 0 ;1
L 11.2325 0.4325 11.2325 0.4325 9 P 0 ;1
L 11.2325 0.4825 11.2325 0.4825 9 P 0 ;1
L 11.2325 0.5325 11.2325 0.5325 9 P 0 ;1
L 11.2325 0.5825 11.2325 0.5825 9 P 0 ;1
L 11.2325 0.6325 11.2325 0.6325 9 P 0 ;1
L 11.2325 0.6825 11.2325 0.6825 9 P 0 ;1
L 11.2325 0.7325 11.2325 0.7325 9 P 0 ;1
L 11.2325 0.7825 11.2325 0.7825 9 P 0 ;1
L 11.2325 0.8325 11.2325 0.8325 9 P 0 ;1
L 11.2325 0.8825 11.2325 0.8825 9 P 0 ;1
L 11.2325 0.9325 11.2325 0.9325 9 P 0 ;1
L 11.2325 0.9825 11.2325 0.9825 9 P 0 ;1
L 11.2325 1.0325 11.2325 1.0325 9 P 0 ;1
L 11.2325 1.0825 11.2325 1.0825 9 P 0 ;1
L 11.2325 1.1325 11.2325 1.1325 9 P 0 ;1
L 11.2325 1.1825 11.2325 1.1825 9 P 0 ;1
L 11.2325 1.2325 11.2325 1.2325 9 P 0 ;1
L 11.2325 1.2825 11.2325 1.2825 9 P 0 ;1
L 11.2325 1.3325 11.2325 1.3325 9 P 0 ;1
L 11.2325 1.3825 11.2325 1.3825 9 P 0 ;1
L 11.2325 1.4325 11.2325 1.4325 9 P 0 ;1
L 11.2325 1.4825 11.2325 1.4825 9 P 0 ;1
L 11.2325 1.5325 11.2325 1.5325 9 P 0 ;1
L 11.2325 1.5825 11.2325 1.5825 9 P 0 ;1
L 11.2325 1.6325 11.2325 1.6325 9 P 0 ;1
L 11.2325 1.6825 11.2325 1.6825 9 P 0 ;1
L 11.2325 1.7325 11.2325 1.7325 9 P 0 ;1
L 11.2325 1.7825 11.2325 1.7825 9 P 0 ;1
L 11.2325 1.8325 11.2325 1.8325 9 P 0 ;1
L 11.2325 1.8825 11.2325 1.8825 9 P 0 ;1
L 11.2325 1.9325 11.2325 1.9325 9 P 0 ;1
L 11.2325 1.9825 11.2325 1.9825 9 P 0 ;1
L 11.2325 2.0325 11.2325 2.0325 9 P 0 ;1
L 11.2325 2.0825 11.2325 2.0825 9 P 0 ;1
L 11.2325 2.1325 11.2325 2.1325 9 P 0 ;1
L 11.2325 2.1825 11.2325 2.1825 9 P 0 ;1
L 11.2325 2.2325 11.2325 2.2325 9 P 0 ;1
L 11.2325 2.2825 11.2325 2.2825 9 P 0 ;1
L 11.2325 2.3325 11.2325 2.3325 9 P 0 ;1
L 11.2325 2.3825 11.2325 2.3825 9 P 0 ;1
L 11.2325 2.4325 11.2325 2.4325 9 P 0 ;1
L 11.2325 2.4825 11.2325 2.4825 9 P 0 ;1
L 11.2325 2.5325 11.2325 2.5325 9 P 0 ;1
L 11.2325 2.5825 11.2325 2.5825 9 P 0 ;1
L 11.2325 2.6325 11.2325 2.6325 9 P 0 ;1
L 11.2325 2.6825 11.2325 2.6825 9 P 0 ;1
L 11.2325 2.7325 11.2325 2.7325 9 P 0 ;1
L 11.2325 2.7825 11.2325 2.7825 9 P 0 ;1
L 11.2325 2.8325 11.2325 2.8325 9 P 0 ;1
L 11.2825 0.1325 11.2825 0.1325 9 P 0 ;1
L 11.2825 0.1825 11.2825 0.1825 9 P 0 ;1
L 11.2825 0.2325 11.2825 0.2325 9 P 0 ;1
L 11.2825 0.2825 11.2825 0.2825 9 P 0 ;1
L 11.2825 0.3325 11.2825 0.3325 9 P 0 ;1
L 11.2825 0.3825 11.2825 0.3825 9 P 0 ;1
L 11.2825 0.4325 11.2825 0.4325 9 P 0 ;1
L 11.2825 0.4825 11.2825 0.4825 9 P 0 ;1
L 11.2825 0.5325 11.2825 0.5325 9 P 0 ;1
L 11.2825 0.5825 11.2825 0.5825 9 P 0 ;1
L 11.2825 0.6325 11.2825 0.6325 9 P 0 ;1
L 11.2825 0.6825 11.2825 0.6825 9 P 0 ;1
L 11.2825 0.7325 11.2825 0.7325 9 P 0 ;1
L 11.2825 0.7825 11.2825 0.7825 9 P 0 ;1
L 11.2825 0.8325 11.2825 0.8325 9 P 0 ;1
L 11.2825 0.8825 11.2825 0.8825 9 P 0 ;1
L 11.2825 0.9325 11.2825 0.9325 9 P 0 ;1
L 11.2825 0.9825 11.2825 0.9825 9 P 0 ;1
L 11.2825 1.0325 11.2825 1.0325 9 P 0 ;1
L 11.2825 1.0825 11.2825 1.0825 9 P 0 ;1
L 11.2825 1.1325 11.2825 1.1325 9 P 0 ;1
L 11.2825 1.1825 11.2825 1.1825 9 P 0 ;1
L 11.2825 1.2325 11.2825 1.2325 9 P 0 ;1
L 11.2825 1.2825 11.2825 1.2825 9 P 0 ;1
L 11.2825 1.3325 11.2825 1.3325 9 P 0 ;1
L 11.2825 1.3825 11.2825 1.3825 9 P 0 ;1
L 11.2825 1.4325 11.2825 1.4325 9 P 0 ;1
L 11.2825 1.4825 11.2825 1.4825 9 P 0 ;1
L 11.2825 1.5325 11.2825 1.5325 9 P 0 ;1
L 11.2825 1.5825 11.2825 1.5825 9 P 0 ;1
L 11.2825 1.6325 11.2825 1.6325 9 P 0 ;1
L 11.2825 1.6825 11.2825 1.6825 9 P 0 ;1
L 11.2825 1.7325 11.2825 1.7325 9 P 0 ;1
L 11.2825 1.7825 11.2825 1.7825 9 P 0 ;1
L 11.2825 1.8325 11.2825 1.8325 9 P 0 ;1
L 11.2825 1.8825 11.2825 1.8825 9 P 0 ;1
L 11.2825 1.9325 11.2825 1.9325 9 P 0 ;1
L 11.2825 1.9825 11.2825 1.9825 9 P 0 ;1
L 11.2825 2.0325 11.2825 2.0325 9 P 0 ;1
L 11.2825 2.0825 11.2825 2.0825 9 P 0 ;1
L 11.2825 2.1325 11.2825 2.1325 9 P 0 ;1
L 11.2825 2.1825 11.2825 2.1825 9 P 0 ;1
L 11.2825 2.2325 11.2825 2.2325 9 P 0 ;1
L 11.2825 2.2825 11.2825 2.2825 9 P 0 ;1
L 11.2825 2.3325 11.2825 2.3325 9 P 0 ;1
L 11.2825 2.3825 11.2825 2.3825 9 P 0 ;1
L 11.2825 2.4325 11.2825 2.4325 9 P 0 ;1
L 11.2825 2.4825 11.2825 2.4825 9 P 0 ;1
L 11.2825 2.5325 11.2825 2.5325 9 P 0 ;1
L 11.2825 2.5825 11.2825 2.5825 9 P 0 ;1
L 11.2825 2.6325 11.2825 2.6325 9 P 0 ;1
L 11.2825 2.6825 11.2825 2.6825 9 P 0 ;1
L 11.2825 2.7325 11.2825 2.7325 9 P 0 ;1
L 11.2825 2.7825 11.2825 2.7825 9 P 0 ;1
L 11.2825 2.8325 11.2825 2.8325 9 P 0 ;1
L 11.2825 3.3825 11.2825 3.3825 9 P 0 ;1
L 11.2825 3.4325 11.2825 3.4325 9 P 0 ;1
L 11.2825 3.4825 11.2825 3.4825 9 P 0 ;1
L 11.2825 3.5325 11.2825 3.5325 9 P 0 ;1
L 11.2825 3.5825 11.2825 3.5825 9 P 0 ;1
L 11.2825 3.6325 11.2825 3.6325 9 P 0 ;1
L 11.2825 3.6825 11.2825 3.6825 9 P 0 ;1
L 11.2825 3.7325 11.2825 3.7325 9 P 0 ;1
L 11.2825 3.7825 11.2825 3.7825 9 P 0 ;1
L 11.2825 3.8325 11.2825 3.8325 9 P 0 ;1
L 11.2825 3.8825 11.2825 3.8825 9 P 0 ;1
L 11.2825 3.9325 11.2825 3.9325 9 P 0 ;1
L 11.2825 3.9825 11.2825 3.9825 9 P 0 ;1
L 11.2825 4.0325 11.2825 4.0325 9 P 0 ;1
L 11.2825 4.0825 11.2825 4.0825 9 P 0 ;1
L 11.2825 4.1325 11.2825 4.1325 9 P 0 ;1
L 11.2825 4.1825 11.2825 4.1825 9 P 0 ;1
L 11.2825 4.2325 11.2825 4.2325 9 P 0 ;1
L 11.2825 4.2825 11.2825 4.2825 9 P 0 ;1
L 11.2825 4.3325 11.2825 4.3325 9 P 0 ;1
L 11.2825 4.3825 11.2825 4.3825 9 P 0 ;1
L 11.2825 4.4325 11.2825 4.4325 9 P 0 ;1
L 11.2825 4.4825 11.2825 4.4825 9 P 0 ;1
L 11.2825 4.5325 11.2825 4.5325 9 P 0 ;1
L 11.2825 4.5825 11.2825 4.5825 9 P 0 ;1
L 11.2825 4.6325 11.2825 4.6325 9 P 0 ;1
L 11.2825 4.6825 11.2825 4.6825 9 P 0 ;1
L 11.3325 0.1325 11.3325 0.1325 9 P 0 ;1
L 11.3325 0.1825 11.3325 0.1825 9 P 0 ;1
L 11.3325 0.2325 11.3325 0.2325 9 P 0 ;1
L 11.3325 0.2825 11.3325 0.2825 9 P 0 ;1
L 11.3325 0.3325 11.3325 0.3325 9 P 0 ;1
L 11.3325 0.3825 11.3325 0.3825 9 P 0 ;1
L 11.3325 0.4325 11.3325 0.4325 9 P 0 ;1
L 11.3325 0.4825 11.3325 0.4825 9 P 0 ;1
L 11.3325 0.5325 11.3325 0.5325 9 P 0 ;1
L 11.3325 0.5825 11.3325 0.5825 9 P 0 ;1
L 11.3325 0.6325 11.3325 0.6325 9 P 0 ;1
L 11.3325 0.6825 11.3325 0.6825 9 P 0 ;1
L 11.3325 0.7325 11.3325 0.7325 9 P 0 ;1
L 11.3325 0.7825 11.3325 0.7825 9 P 0 ;1
L 11.3325 0.8325 11.3325 0.8325 9 P 0 ;1
L 11.3325 0.8825 11.3325 0.8825 9 P 0 ;1
L 11.3325 0.9325 11.3325 0.9325 9 P 0 ;1
L 11.3325 0.9825 11.3325 0.9825 9 P 0 ;1
L 11.3325 1.0325 11.3325 1.0325 9 P 0 ;1
L 11.3325 1.0825 11.3325 1.0825 9 P 0 ;1
L 11.3325 1.1325 11.3325 1.1325 9 P 0 ;1
L 11.3325 1.1825 11.3325 1.1825 9 P 0 ;1
L 11.3325 1.2325 11.3325 1.2325 9 P 0 ;1
L 11.3325 1.2825 11.3325 1.2825 9 P 0 ;1
L 11.3325 1.3325 11.3325 1.3325 9 P 0 ;1
L 11.3325 1.3825 11.3325 1.3825 9 P 0 ;1
L 11.3325 1.4325 11.3325 1.4325 9 P 0 ;1
L 11.3325 1.4825 11.3325 1.4825 9 P 0 ;1
L 11.3325 1.5325 11.3325 1.5325 9 P 0 ;1
L 11.3325 1.5825 11.3325 1.5825 9 P 0 ;1
L 11.3325 1.6325 11.3325 1.6325 9 P 0 ;1
L 11.3325 1.6825 11.3325 1.6825 9 P 0 ;1
L 11.3325 1.7325 11.3325 1.7325 9 P 0 ;1
L 11.3325 1.7825 11.3325 1.7825 9 P 0 ;1
L 11.3325 1.8325 11.3325 1.8325 9 P 0 ;1
L 11.3325 1.8825 11.3325 1.8825 9 P 0 ;1
L 11.3325 1.9325 11.3325 1.9325 9 P 0 ;1
L 11.3325 1.9825 11.3325 1.9825 9 P 0 ;1
L 11.3325 2.0325 11.3325 2.0325 9 P 0 ;1
L 11.3325 2.0825 11.3325 2.0825 9 P 0 ;1
L 11.3325 2.1325 11.3325 2.1325 9 P 0 ;1
L 11.3325 2.1825 11.3325 2.1825 9 P 0 ;1
L 11.3325 2.2325 11.3325 2.2325 9 P 0 ;1
L 11.3325 2.2825 11.3325 2.2825 9 P 0 ;1
L 11.3325 2.3325 11.3325 2.3325 9 P 0 ;1
L 11.3325 2.3825 11.3325 2.3825 9 P 0 ;1
L 11.3325 2.4325 11.3325 2.4325 9 P 0 ;1
L 11.3325 2.4825 11.3325 2.4825 9 P 0 ;1
L 11.3325 2.5325 11.3325 2.5325 9 P 0 ;1
L 11.3325 2.5825 11.3325 2.5825 9 P 0 ;1
L 11.3325 2.6325 11.3325 2.6325 9 P 0 ;1
L 11.3325 3.3825 11.3325 3.3825 9 P 0 ;1
L 11.3325 3.4325 11.3325 3.4325 9 P 0 ;1
L 11.3325 3.4825 11.3325 3.4825 9 P 0 ;1
L 11.3325 3.5325 11.3325 3.5325 9 P 0 ;1
L 11.3325 3.5825 11.3325 3.5825 9 P 0 ;1
L 11.3325 3.6325 11.3325 3.6325 9 P 0 ;1
L 11.3325 3.6825 11.3325 3.6825 9 P 0 ;1
L 11.3325 3.7325 11.3325 3.7325 9 P 0 ;1
L 11.3325 3.7825 11.3325 3.7825 9 P 0 ;1
L 11.3325 3.8325 11.3325 3.8325 9 P 0 ;1
L 11.3325 3.8825 11.3325 3.8825 9 P 0 ;1
L 11.3325 3.9325 11.3325 3.9325 9 P 0 ;1
L 11.3325 3.9825 11.3325 3.9825 9 P 0 ;1
L 11.3325 4.0325 11.3325 4.0325 9 P 0 ;1
L 11.3325 4.0825 11.3325 4.0825 9 P 0 ;1
L 11.3325 4.1325 11.3325 4.1325 9 P 0 ;1
L 11.3325 4.1825 11.3325 4.1825 9 P 0 ;1
L 11.3325 4.2325 11.3325 4.2325 9 P 0 ;1
L 11.3325 4.2825 11.3325 4.2825 9 P 0 ;1
L 11.3325 4.3325 11.3325 4.3325 9 P 0 ;1
L 11.3325 4.3825 11.3325 4.3825 9 P 0 ;1
L 11.3325 4.4325 11.3325 4.4325 9 P 0 ;1
L 11.3325 4.4825 11.3325 4.4825 9 P 0 ;1
L 11.3325 4.5325 11.3325 4.5325 9 P 0 ;1
L 11.3325 4.5825 11.3325 4.5825 9 P 0 ;1
L 11.3325 4.6325 11.3325 4.6325 9 P 0 ;1
L 11.3325 4.6825 11.3325 4.6825 9 P 0 ;1
L 11.3825 0.1325 11.3825 0.1325 9 P 0 ;1
L 11.3825 0.1825 11.3825 0.1825 9 P 0 ;1
L 11.3825 0.2325 11.3825 0.2325 9 P 0 ;1
L 11.3825 0.2825 11.3825 0.2825 9 P 0 ;1
L 11.3825 0.3325 11.3825 0.3325 9 P 0 ;1
L 11.3825 0.3825 11.3825 0.3825 9 P 0 ;1
L 11.3825 0.4325 11.3825 0.4325 9 P 0 ;1
L 11.3825 0.4825 11.3825 0.4825 9 P 0 ;1
L 11.3825 0.5325 11.3825 0.5325 9 P 0 ;1
L 11.3825 0.5825 11.3825 0.5825 9 P 0 ;1
L 11.3825 0.6325 11.3825 0.6325 9 P 0 ;1
L 11.3825 0.6825 11.3825 0.6825 9 P 0 ;1
L 11.3825 0.7325 11.3825 0.7325 9 P 0 ;1
L 11.3825 0.7825 11.3825 0.7825 9 P 0 ;1
L 11.3825 0.8325 11.3825 0.8325 9 P 0 ;1
L 11.3825 0.8825 11.3825 0.8825 9 P 0 ;1
L 11.3825 0.9325 11.3825 0.9325 9 P 0 ;1
L 11.3825 0.9825 11.3825 0.9825 9 P 0 ;1
L 11.3825 1.0325 11.3825 1.0325 9 P 0 ;1
L 11.3825 1.0825 11.3825 1.0825 9 P 0 ;1
L 11.3825 1.1325 11.3825 1.1325 9 P 0 ;1
L 11.3825 1.1825 11.3825 1.1825 9 P 0 ;1
L 11.3825 1.2325 11.3825 1.2325 9 P 0 ;1
L 11.3825 1.2825 11.3825 1.2825 9 P 0 ;1
L 11.3825 1.3325 11.3825 1.3325 9 P 0 ;1
L 11.3825 1.3825 11.3825 1.3825 9 P 0 ;1
L 11.3825 1.4325 11.3825 1.4325 9 P 0 ;1
L 11.3825 1.4825 11.3825 1.4825 9 P 0 ;1
L 11.3825 1.5325 11.3825 1.5325 9 P 0 ;1
L 11.3825 1.5825 11.3825 1.5825 9 P 0 ;1
L 11.3825 1.6325 11.3825 1.6325 9 P 0 ;1
L 11.3825 1.6825 11.3825 1.6825 9 P 0 ;1
L 11.3825 1.7325 11.3825 1.7325 9 P 0 ;1
L 11.3825 1.7825 11.3825 1.7825 9 P 0 ;1
L 11.3825 1.8325 11.3825 1.8325 9 P 0 ;1
L 11.3825 1.8825 11.3825 1.8825 9 P 0 ;1
L 11.3825 1.9325 11.3825 1.9325 9 P 0 ;1
L 11.3825 1.9825 11.3825 1.9825 9 P 0 ;1
L 11.3825 2.0325 11.3825 2.0325 9 P 0 ;1
L 11.3825 2.0825 11.3825 2.0825 9 P 0 ;1
L 11.3825 2.1325 11.3825 2.1325 9 P 0 ;1
L 11.3825 2.1825 11.3825 2.1825 9 P 0 ;1
L 11.3825 2.2325 11.3825 2.2325 9 P 0 ;1
L 11.3825 2.2825 11.3825 2.2825 9 P 0 ;1
L 11.3825 2.3325 11.3825 2.3325 9 P 0 ;1
L 11.3825 2.3825 11.3825 2.3825 9 P 0 ;1
L 11.3825 2.4325 11.3825 2.4325 9 P 0 ;1
L 11.3825 2.4825 11.3825 2.4825 9 P 0 ;1
L 11.3825 2.5325 11.3825 2.5325 9 P 0 ;1
L 11.3825 2.5825 11.3825 2.5825 9 P 0 ;1
L 11.3825 2.6325 11.3825 2.6325 9 P 0 ;1
L 11.3825 2.8825 11.3825 2.8825 9 P 0 ;1
L 11.3825 3.3825 11.3825 3.3825 9 P 0 ;1
L 11.3825 3.4325 11.3825 3.4325 9 P 0 ;1
L 11.3825 3.4825 11.3825 3.4825 9 P 0 ;1
L 11.3825 3.5325 11.3825 3.5325 9 P 0 ;1
L 11.3825 3.5825 11.3825 3.5825 9 P 0 ;1
L 11.3825 3.6325 11.3825 3.6325 9 P 0 ;1
L 11.3825 3.6825 11.3825 3.6825 9 P 0 ;1
L 11.3825 3.7325 11.3825 3.7325 9 P 0 ;1
L 11.3825 3.7825 11.3825 3.7825 9 P 0 ;1
L 11.3825 3.8325 11.3825 3.8325 9 P 0 ;1
L 11.3825 3.8825 11.3825 3.8825 9 P 0 ;1
L 11.3825 3.9325 11.3825 3.9325 9 P 0 ;1
L 11.3825 3.9825 11.3825 3.9825 9 P 0 ;1
L 11.3825 4.0325 11.3825 4.0325 9 P 0 ;1
L 11.3825 4.0825 11.3825 4.0825 9 P 0 ;1
L 11.3825 4.1325 11.3825 4.1325 9 P 0 ;1
L 11.3825 4.1825 11.3825 4.1825 9 P 0 ;1
L 11.3825 4.2325 11.3825 4.2325 9 P 0 ;1
L 11.3825 4.2825 11.3825 4.2825 9 P 0 ;1
L 11.3825 4.3325 11.3825 4.3325 9 P 0 ;1
L 11.3825 4.3825 11.3825 4.3825 9 P 0 ;1
L 11.3825 4.4325 11.3825 4.4325 9 P 0 ;1
L 11.3825 4.4825 11.3825 4.4825 9 P 0 ;1
L 11.3825 4.5325 11.3825 4.5325 9 P 0 ;1
L 11.3825 4.5825 11.3825 4.5825 9 P 0 ;1
L 11.3825 4.6325 11.3825 4.6325 9 P 0 ;1
L 11.3825 4.6825 11.3825 4.6825 9 P 0 ;1
L 11.4325 0.1325 11.4325 0.1325 9 P 0 ;1
L 11.4325 0.1825 11.4325 0.1825 9 P 0 ;1
L 11.4325 0.2325 11.4325 0.2325 9 P 0 ;1
L 11.4325 0.2825 11.4325 0.2825 9 P 0 ;1
L 11.4325 0.3325 11.4325 0.3325 9 P 0 ;1
L 11.4325 0.3825 11.4325 0.3825 9 P 0 ;1
L 11.4325 0.4325 11.4325 0.4325 9 P 0 ;1
L 11.4325 0.4825 11.4325 0.4825 9 P 0 ;1
L 11.4325 0.5325 11.4325 0.5325 9 P 0 ;1
L 11.4325 0.5825 11.4325 0.5825 9 P 0 ;1
L 11.4325 0.6325 11.4325 0.6325 9 P 0 ;1
L 11.4325 0.6825 11.4325 0.6825 9 P 0 ;1
L 11.4325 0.7325 11.4325 0.7325 9 P 0 ;1
L 11.4325 0.7825 11.4325 0.7825 9 P 0 ;1
L 11.4325 0.8325 11.4325 0.8325 9 P 0 ;1
L 11.4325 0.8825 11.4325 0.8825 9 P 0 ;1
L 11.4325 0.9325 11.4325 0.9325 9 P 0 ;1
L 11.4325 0.9825 11.4325 0.9825 9 P 0 ;1
L 11.4325 1.0325 11.4325 1.0325 9 P 0 ;1
L 11.4325 1.0825 11.4325 1.0825 9 P 0 ;1
L 11.4325 1.1325 11.4325 1.1325 9 P 0 ;1
L 11.4325 1.1825 11.4325 1.1825 9 P 0 ;1
L 11.4325 1.2325 11.4325 1.2325 9 P 0 ;1
L 11.4325 1.2825 11.4325 1.2825 9 P 0 ;1
L 11.4325 1.3325 11.4325 1.3325 9 P 0 ;1
L 11.4325 2.1825 11.4325 2.1825 9 P 0 ;1
L 11.4325 2.2325 11.4325 2.2325 9 P 0 ;1
L 11.4325 2.2825 11.4325 2.2825 9 P 0 ;1
L 11.4325 3.3825 11.4325 3.3825 9 P 0 ;1
L 11.4325 3.4325 11.4325 3.4325 9 P 0 ;1
L 11.4325 3.4825 11.4325 3.4825 9 P 0 ;1
L 11.4325 3.5325 11.4325 3.5325 9 P 0 ;1
L 11.4325 3.5825 11.4325 3.5825 9 P 0 ;1
L 11.4325 3.6325 11.4325 3.6325 9 P 0 ;1
L 11.4325 3.6825 11.4325 3.6825 9 P 0 ;1
L 11.4325 3.7325 11.4325 3.7325 9 P 0 ;1
L 11.4325 3.7825 11.4325 3.7825 9 P 0 ;1
L 11.4325 3.8325 11.4325 3.8325 9 P 0 ;1
L 11.4325 3.8825 11.4325 3.8825 9 P 0 ;1
L 11.4325 3.9325 11.4325 3.9325 9 P 0 ;1
L 11.4325 3.9825 11.4325 3.9825 9 P 0 ;1
L 11.4325 4.0325 11.4325 4.0325 9 P 0 ;1
L 11.4325 4.0825 11.4325 4.0825 9 P 0 ;1
L 11.4325 4.1325 11.4325 4.1325 9 P 0 ;1
L 11.4325 4.1825 11.4325 4.1825 9 P 0 ;1
L 11.4325 4.2325 11.4325 4.2325 9 P 0 ;1
L 11.4325 4.2825 11.4325 4.2825 9 P 0 ;1
L 11.4325 4.3325 11.4325 4.3325 9 P 0 ;1
L 11.4325 4.3825 11.4325 4.3825 9 P 0 ;1
L 11.4325 4.4325 11.4325 4.4325 9 P 0 ;1
L 11.4325 4.4825 11.4325 4.4825 9 P 0 ;1
L 11.4325 4.5325 11.4325 4.5325 9 P 0 ;1
L 11.4325 4.5825 11.4325 4.5825 9 P 0 ;1
L 11.4325 4.6325 11.4325 4.6325 9 P 0 ;1
L 11.4325 4.6825 11.4325 4.6825 9 P 0 ;1
L 11.4825 0.1325 11.4825 0.1325 9 P 0 ;1
L 11.4825 0.1825 11.4825 0.1825 9 P 0 ;1
L 11.4825 0.2325 11.4825 0.2325 9 P 0 ;1
L 11.4825 0.2825 11.4825 0.2825 9 P 0 ;1
L 11.4825 0.3325 11.4825 0.3325 9 P 0 ;1
L 11.4825 0.3825 11.4825 0.3825 9 P 0 ;1
L 11.4825 0.4325 11.4825 0.4325 9 P 0 ;1
L 11.4825 0.4825 11.4825 0.4825 9 P 0 ;1
L 11.4825 0.5325 11.4825 0.5325 9 P 0 ;1
L 11.4825 0.5825 11.4825 0.5825 9 P 0 ;1
L 11.4825 0.6325 11.4825 0.6325 9 P 0 ;1
L 11.4825 0.6825 11.4825 0.6825 9 P 0 ;1
L 11.4825 0.7325 11.4825 0.7325 9 P 0 ;1
L 11.4825 0.7825 11.4825 0.7825 9 P 0 ;1
L 11.4825 0.8325 11.4825 0.8325 9 P 0 ;1
L 11.4825 0.8825 11.4825 0.8825 9 P 0 ;1
L 11.4825 0.9325 11.4825 0.9325 9 P 0 ;1
L 11.4825 0.9825 11.4825 0.9825 9 P 0 ;1
L 11.4825 1.0325 11.4825 1.0325 9 P 0 ;1
L 11.4825 1.0825 11.4825 1.0825 9 P 0 ;1
L 11.4825 1.1325 11.4825 1.1325 9 P 0 ;1
L 11.4825 1.1825 11.4825 1.1825 9 P 0 ;1
L 11.4825 1.2325 11.4825 1.2325 9 P 0 ;1
L 11.4825 1.2825 11.4825 1.2825 9 P 0 ;1
L 11.4825 2.1825 11.4825 2.1825 9 P 0 ;1
L 11.4825 2.2325 11.4825 2.2325 9 P 0 ;1
L 11.4825 2.2825 11.4825 2.2825 9 P 0 ;1
L 11.4825 3.3825 11.4825 3.3825 9 P 0 ;1
L 11.4825 3.4325 11.4825 3.4325 9 P 0 ;1
L 11.4825 3.4825 11.4825 3.4825 9 P 0 ;1
L 11.4825 3.5325 11.4825 3.5325 9 P 0 ;1
L 11.4825 3.5825 11.4825 3.5825 9 P 0 ;1
L 11.4825 3.6325 11.4825 3.6325 9 P 0 ;1
L 11.4825 3.6825 11.4825 3.6825 9 P 0 ;1
L 11.4825 3.7325 11.4825 3.7325 9 P 0 ;1
L 11.4825 3.7825 11.4825 3.7825 9 P 0 ;1
L 11.4825 3.8325 11.4825 3.8325 9 P 0 ;1
L 11.4825 3.8825 11.4825 3.8825 9 P 0 ;1
L 11.4825 3.9325 11.4825 3.9325 9 P 0 ;1
L 11.4825 3.9825 11.4825 3.9825 9 P 0 ;1
L 11.4825 4.0325 11.4825 4.0325 9 P 0 ;1
L 11.4825 4.0825 11.4825 4.0825 9 P 0 ;1
L 11.4825 4.1325 11.4825 4.1325 9 P 0 ;1
L 11.4825 4.1825 11.4825 4.1825 9 P 0 ;1
L 11.4825 4.2325 11.4825 4.2325 9 P 0 ;1
L 11.4825 4.2825 11.4825 4.2825 9 P 0 ;1
L 11.4825 4.3325 11.4825 4.3325 9 P 0 ;1
L 11.4825 4.3825 11.4825 4.3825 9 P 0 ;1
L 11.4825 4.4325 11.4825 4.4325 9 P 0 ;1
L 11.4825 4.4825 11.4825 4.4825 9 P 0 ;1
L 11.4825 4.5325 11.4825 4.5325 9 P 0 ;1
L 11.4825 4.5825 11.4825 4.5825 9 P 0 ;1
L 11.4825 4.6325 11.4825 4.6325 9 P 0 ;1
L 11.4825 4.6825 11.4825 4.6825 9 P 0 ;1
L 11.5325 0.1325 11.5325 0.1325 9 P 0 ;1
L 11.5325 0.1825 11.5325 0.1825 9 P 0 ;1
L 11.5325 0.2325 11.5325 0.2325 9 P 0 ;1
L 11.5325 0.2825 11.5325 0.2825 9 P 0 ;1
L 11.5325 0.3325 11.5325 0.3325 9 P 0 ;1
L 11.5325 0.3825 11.5325 0.3825 9 P 0 ;1
L 11.5325 0.4325 11.5325 0.4325 9 P 0 ;1
L 11.5325 0.4825 11.5325 0.4825 9 P 0 ;1
L 11.5325 0.5325 11.5325 0.5325 9 P 0 ;1
L 11.5325 0.5825 11.5325 0.5825 9 P 0 ;1
L 11.5325 0.6325 11.5325 0.6325 9 P 0 ;1
L 11.5325 0.6825 11.5325 0.6825 9 P 0 ;1
L 11.5325 0.7325 11.5325 0.7325 9 P 0 ;1
L 11.5325 0.7825 11.5325 0.7825 9 P 0 ;1
L 11.5325 0.8325 11.5325 0.8325 9 P 0 ;1
L 11.5325 0.8825 11.5325 0.8825 9 P 0 ;1
L 11.5325 0.9325 11.5325 0.9325 9 P 0 ;1
L 11.5325 0.9825 11.5325 0.9825 9 P 0 ;1
L 11.5325 1.0325 11.5325 1.0325 9 P 0 ;1
L 11.5325 1.0825 11.5325 1.0825 9 P 0 ;1
L 11.5325 1.1325 11.5325 1.1325 9 P 0 ;1
L 11.5325 1.1825 11.5325 1.1825 9 P 0 ;1
L 11.5325 1.2325 11.5325 1.2325 9 P 0 ;1
L 11.5325 1.2825 11.5325 1.2825 9 P 0 ;1
L 11.5325 2.2825 11.5325 2.2825 9 P 0 ;1
L 11.5325 2.9825 11.5325 2.9825 9 P 0 ;1
L 11.5325 3.0325 11.5325 3.0325 9 P 0 ;1
L 11.5325 3.0825 11.5325 3.0825 9 P 0 ;1
L 11.5325 3.1325 11.5325 3.1325 9 P 0 ;1
L 11.5325 3.1825 11.5325 3.1825 9 P 0 ;1
L 11.5325 3.2325 11.5325 3.2325 9 P 0 ;1
L 11.5325 3.2825 11.5325 3.2825 9 P 0 ;1
L 11.5325 3.3325 11.5325 3.3325 9 P 0 ;1
L 11.5325 3.3825 11.5325 3.3825 9 P 0 ;1
L 11.5325 3.4325 11.5325 3.4325 9 P 0 ;1
L 11.5325 3.4825 11.5325 3.4825 9 P 0 ;1
L 11.5325 3.5325 11.5325 3.5325 9 P 0 ;1
L 11.5325 3.5825 11.5325 3.5825 9 P 0 ;1
L 11.5325 3.6325 11.5325 3.6325 9 P 0 ;1
L 11.5325 3.6825 11.5325 3.6825 9 P 0 ;1
L 11.5325 3.7325 11.5325 3.7325 9 P 0 ;1
L 11.5325 3.7825 11.5325 3.7825 9 P 0 ;1
L 11.5325 3.8325 11.5325 3.8325 9 P 0 ;1
L 11.5325 3.8825 11.5325 3.8825 9 P 0 ;1
L 11.5325 3.9325 11.5325 3.9325 9 P 0 ;1
L 11.5325 3.9825 11.5325 3.9825 9 P 0 ;1
L 11.5325 4.0325 11.5325 4.0325 9 P 0 ;1
L 11.5325 4.0825 11.5325 4.0825 9 P 0 ;1
L 11.5325 4.1325 11.5325 4.1325 9 P 0 ;1
L 11.5325 4.1825 11.5325 4.1825 9 P 0 ;1
L 11.5325 4.2325 11.5325 4.2325 9 P 0 ;1
L 11.5325 4.2825 11.5325 4.2825 9 P 0 ;1
L 11.5325 4.3325 11.5325 4.3325 9 P 0 ;1
L 11.5325 4.3825 11.5325 4.3825 9 P 0 ;1
L 11.5325 4.4325 11.5325 4.4325 9 P 0 ;1
L 11.5325 4.4825 11.5325 4.4825 9 P 0 ;1
L 11.5325 4.5325 11.5325 4.5325 9 P 0 ;1
L 11.5325 4.5825 11.5325 4.5825 9 P 0 ;1
L 11.5325 4.6325 11.5325 4.6325 9 P 0 ;1
L 11.5325 4.6825 11.5325 4.6825 9 P 0 ;1
L 11.5825 0.1325 11.5825 0.1325 9 P 0 ;1
L 11.5825 0.1825 11.5825 0.1825 9 P 0 ;1
L 11.5825 0.2325 11.5825 0.2325 9 P 0 ;1
L 11.5825 0.2825 11.5825 0.2825 9 P 0 ;1
L 11.5825 0.3325 11.5825 0.3325 9 P 0 ;1
L 11.5825 0.3825 11.5825 0.3825 9 P 0 ;1
L 11.5825 0.4325 11.5825 0.4325 9 P 0 ;1
L 11.5825 0.4825 11.5825 0.4825 9 P 0 ;1
L 11.5825 0.5325 11.5825 0.5325 9 P 0 ;1
L 11.5825 0.5825 11.5825 0.5825 9 P 0 ;1
L 11.5825 0.6325 11.5825 0.6325 9 P 0 ;1
L 11.5825 0.6825 11.5825 0.6825 9 P 0 ;1
L 11.5825 0.7325 11.5825 0.7325 9 P 0 ;1
L 11.5825 0.7825 11.5825 0.7825 9 P 0 ;1
L 11.5825 0.8325 11.5825 0.8325 9 P 0 ;1
L 11.5825 0.8825 11.5825 0.8825 9 P 0 ;1
L 11.5825 0.9325 11.5825 0.9325 9 P 0 ;1
L 11.5825 0.9825 11.5825 0.9825 9 P 0 ;1
L 11.5825 1.0325 11.5825 1.0325 9 P 0 ;1
L 11.5825 1.0825 11.5825 1.0825 9 P 0 ;1
L 11.5825 1.1325 11.5825 1.1325 9 P 0 ;1
L 11.5825 1.1825 11.5825 1.1825 9 P 0 ;1
L 11.5825 1.2325 11.5825 1.2325 9 P 0 ;1
L 11.5825 1.2825 11.5825 1.2825 9 P 0 ;1
L 11.5825 1.3325 11.5825 1.3325 9 P 0 ;1
L 11.5825 3.0325 11.5825 3.0325 9 P 0 ;1
L 11.5825 3.0825 11.5825 3.0825 9 P 0 ;1
L 11.5825 3.1325 11.5825 3.1325 9 P 0 ;1
L 11.5825 3.1825 11.5825 3.1825 9 P 0 ;1
L 11.5825 3.2325 11.5825 3.2325 9 P 0 ;1
L 11.5825 3.2825 11.5825 3.2825 9 P 0 ;1
L 11.5825 3.3325 11.5825 3.3325 9 P 0 ;1
L 11.5825 3.3825 11.5825 3.3825 9 P 0 ;1
L 11.5825 3.4325 11.5825 3.4325 9 P 0 ;1
L 11.5825 3.4825 11.5825 3.4825 9 P 0 ;1
L 11.5825 3.5325 11.5825 3.5325 9 P 0 ;1
L 11.5825 3.5825 11.5825 3.5825 9 P 0 ;1
L 11.5825 3.6325 11.5825 3.6325 9 P 0 ;1
L 11.5825 3.6825 11.5825 3.6825 9 P 0 ;1
L 11.5825 3.7325 11.5825 3.7325 9 P 0 ;1
L 11.5825 3.7825 11.5825 3.7825 9 P 0 ;1
L 11.5825 3.8325 11.5825 3.8325 9 P 0 ;1
L 11.5825 3.8825 11.5825 3.8825 9 P 0 ;1
L 11.5825 3.9325 11.5825 3.9325 9 P 0 ;1
L 11.5825 3.9825 11.5825 3.9825 9 P 0 ;1
L 11.5825 4.0325 11.5825 4.0325 9 P 0 ;1
L 11.5825 4.0825 11.5825 4.0825 9 P 0 ;1
L 11.5825 4.1325 11.5825 4.1325 9 P 0 ;1
L 11.5825 4.1825 11.5825 4.1825 9 P 0 ;1
L 11.5825 4.2325 11.5825 4.2325 9 P 0 ;1
L 11.5825 4.2825 11.5825 4.2825 9 P 0 ;1
L 11.5825 4.3325 11.5825 4.3325 9 P 0 ;1
L 11.5825 4.3825 11.5825 4.3825 9 P 0 ;1
L 11.5825 4.4325 11.5825 4.4325 9 P 0 ;1
L 11.5825 4.4825 11.5825 4.4825 9 P 0 ;1
L 11.5825 4.5325 11.5825 4.5325 9 P 0 ;1
L 11.5825 4.5825 11.5825 4.5825 9 P 0 ;1
L 11.5825 4.6325 11.5825 4.6325 9 P 0 ;1
L 11.5825 4.6825 11.5825 4.6825 9 P 0 ;1
L 11.6325 0.1325 11.6325 0.1325 9 P 0 ;1
L 11.6325 0.1825 11.6325 0.1825 9 P 0 ;1
L 11.6325 0.2325 11.6325 0.2325 9 P 0 ;1
L 11.6325 0.2825 11.6325 0.2825 9 P 0 ;1
L 11.6325 0.3325 11.6325 0.3325 9 P 0 ;1
L 11.6325 0.3825 11.6325 0.3825 9 P 0 ;1
L 11.6325 0.4325 11.6325 0.4325 9 P 0 ;1
L 11.6325 0.4825 11.6325 0.4825 9 P 0 ;1
L 11.6325 0.5325 11.6325 0.5325 9 P 0 ;1
L 11.6325 0.5825 11.6325 0.5825 9 P 0 ;1
L 11.6325 0.6325 11.6325 0.6325 9 P 0 ;1
L 11.6325 0.6825 11.6325 0.6825 9 P 0 ;1
L 11.6325 0.7325 11.6325 0.7325 9 P 0 ;1
L 11.6325 0.7825 11.6325 0.7825 9 P 0 ;1
L 11.6325 0.8325 11.6325 0.8325 9 P 0 ;1
L 11.6325 0.8825 11.6325 0.8825 9 P 0 ;1
L 11.6325 0.9325 11.6325 0.9325 9 P 0 ;1
L 11.6325 0.9825 11.6325 0.9825 9 P 0 ;1
L 11.6325 1.0325 11.6325 1.0325 9 P 0 ;1
L 11.6325 1.0825 11.6325 1.0825 9 P 0 ;1
L 11.6325 1.1325 11.6325 1.1325 9 P 0 ;1
L 11.6325 1.1825 11.6325 1.1825 9 P 0 ;1
L 11.6325 1.2325 11.6325 1.2325 9 P 0 ;1
L 11.6325 1.2825 11.6325 1.2825 9 P 0 ;1
L 11.6325 1.3325 11.6325 1.3325 9 P 0 ;1
L 11.6325 1.3825 11.6325 1.3825 9 P 0 ;1
L 11.6325 2.9825 11.6325 2.9825 9 P 0 ;1
L 11.6325 3.0325 11.6325 3.0325 9 P 0 ;1
L 11.6325 3.0825 11.6325 3.0825 9 P 0 ;1
L 11.6325 3.1325 11.6325 3.1325 9 P 0 ;1
L 11.6325 3.1825 11.6325 3.1825 9 P 0 ;1
L 11.6325 3.2325 11.6325 3.2325 9 P 0 ;1
L 11.6325 3.2825 11.6325 3.2825 9 P 0 ;1
L 11.6325 3.3325 11.6325 3.3325 9 P 0 ;1
L 11.6325 3.3825 11.6325 3.3825 9 P 0 ;1
L 11.6325 3.4325 11.6325 3.4325 9 P 0 ;1
L 11.6325 3.4825 11.6325 3.4825 9 P 0 ;1
L 11.6325 3.5325 11.6325 3.5325 9 P 0 ;1
L 11.6325 3.5825 11.6325 3.5825 9 P 0 ;1
L 11.6325 3.6325 11.6325 3.6325 9 P 0 ;1
L 11.6325 3.6825 11.6325 3.6825 9 P 0 ;1
L 11.6325 3.7325 11.6325 3.7325 9 P 0 ;1
L 11.6325 3.7825 11.6325 3.7825 9 P 0 ;1
L 11.6325 3.8325 11.6325 3.8325 9 P 0 ;1
L 11.6325 3.8825 11.6325 3.8825 9 P 0 ;1
L 11.6325 3.9325 11.6325 3.9325 9 P 0 ;1
L 11.6325 3.9825 11.6325 3.9825 9 P 0 ;1
L 11.6325 4.0325 11.6325 4.0325 9 P 0 ;1
L 11.6325 4.0825 11.6325 4.0825 9 P 0 ;1
L 11.6325 4.1325 11.6325 4.1325 9 P 0 ;1
L 11.6325 4.1825 11.6325 4.1825 9 P 0 ;1
L 11.6325 4.2325 11.6325 4.2325 9 P 0 ;1
L 11.6325 4.2825 11.6325 4.2825 9 P 0 ;1
L 11.6325 4.3325 11.6325 4.3325 9 P 0 ;1
L 11.6325 4.3825 11.6325 4.3825 9 P 0 ;1
L 11.6325 4.4325 11.6325 4.4325 9 P 0 ;1
L 11.6325 4.4825 11.6325 4.4825 9 P 0 ;1
L 11.6325 4.5325 11.6325 4.5325 9 P 0 ;1
L 11.6325 4.5825 11.6325 4.5825 9 P 0 ;1
L 11.6325 4.6325 11.6325 4.6325 9 P 0 ;1
L 11.6325 4.6825 11.6325 4.6825 9 P 0 ;1
L 11.6825 0.1325 11.6825 0.1325 9 P 0 ;1
L 11.6825 0.1825 11.6825 0.1825 9 P 0 ;1
L 11.6825 0.2325 11.6825 0.2325 9 P 0 ;1
L 11.6825 0.2825 11.6825 0.2825 9 P 0 ;1
L 11.6825 0.3325 11.6825 0.3325 9 P 0 ;1
L 11.6825 0.3825 11.6825 0.3825 9 P 0 ;1
L 11.6825 0.4325 11.6825 0.4325 9 P 0 ;1
L 11.6825 0.4825 11.6825 0.4825 9 P 0 ;1
L 11.6825 0.5325 11.6825 0.5325 9 P 0 ;1
L 11.6825 0.5825 11.6825 0.5825 9 P 0 ;1
L 11.6825 0.6325 11.6825 0.6325 9 P 0 ;1
L 11.6825 0.6825 11.6825 0.6825 9 P 0 ;1
L 11.6825 0.7325 11.6825 0.7325 9 P 0 ;1
L 11.6825 0.7825 11.6825 0.7825 9 P 0 ;1
L 11.6825 0.8325 11.6825 0.8325 9 P 0 ;1
L 11.6825 0.8825 11.6825 0.8825 9 P 0 ;1
L 11.6825 0.9325 11.6825 0.9325 9 P 0 ;1
L 11.6825 0.9825 11.6825 0.9825 9 P 0 ;1
L 11.6825 1.0325 11.6825 1.0325 9 P 0 ;1
L 11.6825 1.0825 11.6825 1.0825 9 P 0 ;1
L 11.6825 1.1325 11.6825 1.1325 9 P 0 ;1
L 11.6825 1.1825 11.6825 1.1825 9 P 0 ;1
L 11.6825 1.2325 11.6825 1.2325 9 P 0 ;1
L 11.6825 1.2825 11.6825 1.2825 9 P 0 ;1
L 11.6825 1.3325 11.6825 1.3325 9 P 0 ;1
L 11.6825 1.3825 11.6825 1.3825 9 P 0 ;1
L 11.6825 2.9325 11.6825 2.9325 9 P 0 ;1
L 11.6825 2.9825 11.6825 2.9825 9 P 0 ;1
L 11.6825 3.0325 11.6825 3.0325 9 P 0 ;1
L 11.6825 3.0825 11.6825 3.0825 9 P 0 ;1
L 11.6825 3.1325 11.6825 3.1325 9 P 0 ;1
L 11.6825 3.1825 11.6825 3.1825 9 P 0 ;1
L 11.6825 3.2325 11.6825 3.2325 9 P 0 ;1
L 11.6825 3.2825 11.6825 3.2825 9 P 0 ;1
L 11.6825 3.3325 11.6825 3.3325 9 P 0 ;1
L 11.6825 3.3825 11.6825 3.3825 9 P 0 ;1
L 11.6825 3.4325 11.6825 3.4325 9 P 0 ;1
L 11.6825 3.4825 11.6825 3.4825 9 P 0 ;1
L 11.6825 3.5325 11.6825 3.5325 9 P 0 ;1
L 11.6825 3.5825 11.6825 3.5825 9 P 0 ;1
L 11.6825 3.6325 11.6825 3.6325 9 P 0 ;1
L 11.6825 3.6825 11.6825 3.6825 9 P 0 ;1
L 11.6825 3.7325 11.6825 3.7325 9 P 0 ;1
L 11.6825 3.7825 11.6825 3.7825 9 P 0 ;1
L 11.6825 3.8325 11.6825 3.8325 9 P 0 ;1
L 11.6825 3.8825 11.6825 3.8825 9 P 0 ;1
L 11.6825 3.9325 11.6825 3.9325 9 P 0 ;1
L 11.6825 3.9825 11.6825 3.9825 9 P 0 ;1
L 11.6825 4.0325 11.6825 4.0325 9 P 0 ;1
L 11.6825 4.0825 11.6825 4.0825 9 P 0 ;1
L 11.6825 4.1325 11.6825 4.1325 9 P 0 ;1
L 11.6825 4.1825 11.6825 4.1825 9 P 0 ;1
L 11.6825 4.2325 11.6825 4.2325 9 P 0 ;1
L 11.6825 4.2825 11.6825 4.2825 9 P 0 ;1
L 11.6825 4.3325 11.6825 4.3325 9 P 0 ;1
L 11.6825 4.3825 11.6825 4.3825 9 P 0 ;1
L 11.6825 4.4325 11.6825 4.4325 9 P 0 ;1
L 11.6825 4.4825 11.6825 4.4825 9 P 0 ;1
L 11.6825 4.5325 11.6825 4.5325 9 P 0 ;1
L 11.6825 4.5825 11.6825 4.5825 9 P 0 ;1
L 11.6825 4.6325 11.6825 4.6325 9 P 0 ;1
L 11.6825 4.6825 11.6825 4.6825 9 P 0 ;1
L 11.7325 0.1325 11.7325 0.1325 9 P 0 ;1
L 11.7325 0.1825 11.7325 0.1825 9 P 0 ;1
L 11.7325 0.2325 11.7325 0.2325 9 P 0 ;1
L 11.7325 0.2825 11.7325 0.2825 9 P 0 ;1
L 11.7325 0.3325 11.7325 0.3325 9 P 0 ;1
L 11.7325 0.3825 11.7325 0.3825 9 P 0 ;1
L 11.7325 0.4325 11.7325 0.4325 9 P 0 ;1
L 11.7325 0.4825 11.7325 0.4825 9 P 0 ;1
L 11.7325 0.5325 11.7325 0.5325 9 P 0 ;1
L 11.7325 0.5825 11.7325 0.5825 9 P 0 ;1
L 11.7325 0.6325 11.7325 0.6325 9 P 0 ;1
L 11.7325 0.6825 11.7325 0.6825 9 P 0 ;1
L 11.7325 0.7325 11.7325 0.7325 9 P 0 ;1
L 11.7325 0.7825 11.7325 0.7825 9 P 0 ;1
L 11.7325 0.8325 11.7325 0.8325 9 P 0 ;1
L 11.7325 0.8825 11.7325 0.8825 9 P 0 ;1
L 11.7325 0.9325 11.7325 0.9325 9 P 0 ;1
L 11.7325 0.9825 11.7325 0.9825 9 P 0 ;1
L 11.7325 1.0325 11.7325 1.0325 9 P 0 ;1
L 11.7325 1.0825 11.7325 1.0825 9 P 0 ;1
L 11.7325 1.1325 11.7325 1.1325 9 P 0 ;1
L 11.7325 1.1825 11.7325 1.1825 9 P 0 ;1
L 11.7325 1.2325 11.7325 1.2325 9 P 0 ;1
L 11.7325 1.2825 11.7325 1.2825 9 P 0 ;1
L 11.7325 1.3325 11.7325 1.3325 9 P 0 ;1
L 11.7325 1.3825 11.7325 1.3825 9 P 0 ;1
L 11.7325 2.9325 11.7325 2.9325 9 P 0 ;1
L 11.7325 2.9825 11.7325 2.9825 9 P 0 ;1
L 11.7325 3.0325 11.7325 3.0325 9 P 0 ;1
L 11.7325 3.0825 11.7325 3.0825 9 P 0 ;1
L 11.7325 3.1325 11.7325 3.1325 9 P 0 ;1
L 11.7325 3.1825 11.7325 3.1825 9 P 0 ;1
L 11.7325 3.2325 11.7325 3.2325 9 P 0 ;1
L 11.7325 3.2825 11.7325 3.2825 9 P 0 ;1
L 11.7325 3.3325 11.7325 3.3325 9 P 0 ;1
L 11.7325 3.3825 11.7325 3.3825 9 P 0 ;1
L 11.7325 3.4325 11.7325 3.4325 9 P 0 ;1
L 11.7325 3.4825 11.7325 3.4825 9 P 0 ;1
L 11.7325 3.5325 11.7325 3.5325 9 P 0 ;1
L 11.7325 3.5825 11.7325 3.5825 9 P 0 ;1
L 11.7325 3.6325 11.7325 3.6325 9 P 0 ;1
L 11.7325 3.6825 11.7325 3.6825 9 P 0 ;1
L 11.7325 3.7325 11.7325 3.7325 9 P 0 ;1
L 11.7325 3.7825 11.7325 3.7825 9 P 0 ;1
L 11.7325 3.8325 11.7325 3.8325 9 P 0 ;1
L 11.7325 3.8825 11.7325 3.8825 9 P 0 ;1
L 11.7325 3.9325 11.7325 3.9325 9 P 0 ;1
L 11.7325 3.9825 11.7325 3.9825 9 P 0 ;1
L 11.7325 4.0325 11.7325 4.0325 9 P 0 ;1
L 11.7325 4.0825 11.7325 4.0825 9 P 0 ;1
L 11.7325 4.1325 11.7325 4.1325 9 P 0 ;1
L 11.7325 4.1825 11.7325 4.1825 9 P 0 ;1
L 11.7325 4.2325 11.7325 4.2325 9 P 0 ;1
L 11.7325 4.2825 11.7325 4.2825 9 P 0 ;1
L 11.7325 4.3325 11.7325 4.3325 9 P 0 ;1
L 11.7325 4.3825 11.7325 4.3825 9 P 0 ;1
L 11.7325 4.4325 11.7325 4.4325 9 P 0 ;1
L 11.7325 4.4825 11.7325 4.4825 9 P 0 ;1
L 11.7325 4.5325 11.7325 4.5325 9 P 0 ;1
L 11.7325 4.5825 11.7325 4.5825 9 P 0 ;1
L 11.7325 4.6325 11.7325 4.6325 9 P 0 ;1
L 11.7325 4.6825 11.7325 4.6825 9 P 0 ;1
L 11.7325 4.7325 11.7325 4.7325 9 P 0 ;1
L 11.7825 0.1325 11.7825 0.1325 9 P 0 ;1
L 11.7825 0.1825 11.7825 0.1825 9 P 0 ;1
L 11.7825 0.2325 11.7825 0.2325 9 P 0 ;1
L 11.7825 0.2825 11.7825 0.2825 9 P 0 ;1
L 11.7825 0.3325 11.7825 0.3325 9 P 0 ;1
L 11.7825 0.3825 11.7825 0.3825 9 P 0 ;1
L 11.7825 0.4325 11.7825 0.4325 9 P 0 ;1
L 11.7825 0.4825 11.7825 0.4825 9 P 0 ;1
L 11.7825 0.5325 11.7825 0.5325 9 P 0 ;1
L 11.7825 0.5825 11.7825 0.5825 9 P 0 ;1
L 11.7825 0.6325 11.7825 0.6325 9 P 0 ;1
L 11.7825 0.6825 11.7825 0.6825 9 P 0 ;1
L 11.7825 0.7325 11.7825 0.7325 9 P 0 ;1
L 11.7825 0.7825 11.7825 0.7825 9 P 0 ;1
L 11.7825 0.8325 11.7825 0.8325 9 P 0 ;1
L 11.7825 0.8825 11.7825 0.8825 9 P 0 ;1
L 11.7825 0.9325 11.7825 0.9325 9 P 0 ;1
L 11.7825 0.9825 11.7825 0.9825 9 P 0 ;1
L 11.7825 1.0325 11.7825 1.0325 9 P 0 ;1
L 11.7825 1.0825 11.7825 1.0825 9 P 0 ;1
L 11.7825 1.1325 11.7825 1.1325 9 P 0 ;1
L 11.7825 1.1825 11.7825 1.1825 9 P 0 ;1
L 11.7825 1.2325 11.7825 1.2325 9 P 0 ;1
L 11.7825 1.2825 11.7825 1.2825 9 P 0 ;1
L 11.7825 1.3325 11.7825 1.3325 9 P 0 ;1
L 11.7825 1.3825 11.7825 1.3825 9 P 0 ;1
L 11.7825 2.9325 11.7825 2.9325 9 P 0 ;1
L 11.7825 2.9825 11.7825 2.9825 9 P 0 ;1
L 11.7825 3.0325 11.7825 3.0325 9 P 0 ;1
L 11.7825 3.0825 11.7825 3.0825 9 P 0 ;1
L 11.7825 3.1325 11.7825 3.1325 9 P 0 ;1
L 11.7825 3.1825 11.7825 3.1825 9 P 0 ;1
L 11.7825 3.2325 11.7825 3.2325 9 P 0 ;1
L 11.7825 3.2825 11.7825 3.2825 9 P 0 ;1
L 11.7825 3.3325 11.7825 3.3325 9 P 0 ;1
L 11.7825 3.3825 11.7825 3.3825 9 P 0 ;1
L 11.7825 3.4325 11.7825 3.4325 9 P 0 ;1
L 11.7825 3.4825 11.7825 3.4825 9 P 0 ;1
L 11.7825 3.5325 11.7825 3.5325 9 P 0 ;1
L 11.7825 3.5825 11.7825 3.5825 9 P 0 ;1
L 11.7825 3.6325 11.7825 3.6325 9 P 0 ;1
L 11.7825 3.6825 11.7825 3.6825 9 P 0 ;1
L 11.7825 3.7325 11.7825 3.7325 9 P 0 ;1
L 11.7825 3.7825 11.7825 3.7825 9 P 0 ;1
L 11.7825 3.8325 11.7825 3.8325 9 P 0 ;1
L 11.7825 3.8825 11.7825 3.8825 9 P 0 ;1
L 11.7825 3.9325 11.7825 3.9325 9 P 0 ;1
L 11.7825 3.9825 11.7825 3.9825 9 P 0 ;1
L 11.7825 4.0325 11.7825 4.0325 9 P 0 ;1
L 11.7825 4.0825 11.7825 4.0825 9 P 0 ;1
L 11.7825 4.1325 11.7825 4.1325 9 P 0 ;1
L 11.7825 4.1825 11.7825 4.1825 9 P 0 ;1
L 11.7825 4.2325 11.7825 4.2325 9 P 0 ;1
L 11.7825 4.2825 11.7825 4.2825 9 P 0 ;1
L 11.7825 4.3325 11.7825 4.3325 9 P 0 ;1
L 11.7825 4.3825 11.7825 4.3825 9 P 0 ;1
L 11.7825 4.4325 11.7825 4.4325 9 P 0 ;1
L 11.7825 4.4825 11.7825 4.4825 9 P 0 ;1
L 11.7825 4.5325 11.7825 4.5325 9 P 0 ;1
L 11.7825 4.5825 11.7825 4.5825 9 P 0 ;1
L 11.7825 4.6325 11.7825 4.6325 9 P 0 ;1
L 11.7825 4.6825 11.7825 4.6825 9 P 0 ;1
L 11.7825 4.7325 11.7825 4.7325 9 P 0 ;1
L 11.8325 0.1325 11.8325 0.1325 9 P 0 ;1
L 11.8325 0.1825 11.8325 0.1825 9 P 0 ;1
L 11.8325 0.2325 11.8325 0.2325 9 P 0 ;1
L 11.8325 0.2825 11.8325 0.2825 9 P 0 ;1
L 11.8325 0.3325 11.8325 0.3325 9 P 0 ;1
L 11.8325 0.3825 11.8325 0.3825 9 P 0 ;1
L 11.8325 0.4325 11.8325 0.4325 9 P 0 ;1
L 11.8325 0.4825 11.8325 0.4825 9 P 0 ;1
L 11.8325 0.5325 11.8325 0.5325 9 P 0 ;1
L 11.8325 0.5825 11.8325 0.5825 9 P 0 ;1
L 11.8325 0.6325 11.8325 0.6325 9 P 0 ;1
L 11.8325 0.6825 11.8325 0.6825 9 P 0 ;1
L 11.8325 0.7325 11.8325 0.7325 9 P 0 ;1
L 11.8325 0.7825 11.8325 0.7825 9 P 0 ;1
L 11.8325 0.8325 11.8325 0.8325 9 P 0 ;1
L 11.8325 0.8825 11.8325 0.8825 9 P 0 ;1
L 11.8325 0.9325 11.8325 0.9325 9 P 0 ;1
L 11.8325 0.9825 11.8325 0.9825 9 P 0 ;1
L 11.8325 1.0325 11.8325 1.0325 9 P 0 ;1
L 11.8325 1.0825 11.8325 1.0825 9 P 0 ;1
L 11.8325 1.1325 11.8325 1.1325 9 P 0 ;1
L 11.8325 1.1825 11.8325 1.1825 9 P 0 ;1
L 11.8325 1.2325 11.8325 1.2325 9 P 0 ;1
L 11.8325 1.2825 11.8325 1.2825 9 P 0 ;1
L 11.8325 1.3325 11.8325 1.3325 9 P 0 ;1
L 11.8325 1.3825 11.8325 1.3825 9 P 0 ;1
L 11.8325 1.4325 11.8325 1.4325 9 P 0 ;1
L 11.8325 2.9325 11.8325 2.9325 9 P 0 ;1
L 11.8325 2.9825 11.8325 2.9825 9 P 0 ;1
L 11.8325 3.0325 11.8325 3.0325 9 P 0 ;1
L 11.8325 3.0825 11.8325 3.0825 9 P 0 ;1
L 11.8325 3.1325 11.8325 3.1325 9 P 0 ;1
L 11.8325 3.1825 11.8325 3.1825 9 P 0 ;1
L 11.8325 3.2325 11.8325 3.2325 9 P 0 ;1
L 11.8325 3.2825 11.8325 3.2825 9 P 0 ;1
L 11.8325 3.3325 11.8325 3.3325 9 P 0 ;1
L 11.8325 3.3825 11.8325 3.3825 9 P 0 ;1
L 11.8325 3.4325 11.8325 3.4325 9 P 0 ;1
L 11.8325 3.4825 11.8325 3.4825 9 P 0 ;1
L 11.8325 3.5325 11.8325 3.5325 9 P 0 ;1
L 11.8325 3.5825 11.8325 3.5825 9 P 0 ;1
L 11.8325 3.6325 11.8325 3.6325 9 P 0 ;1
L 11.8325 3.6825 11.8325 3.6825 9 P 0 ;1
L 11.8325 3.7325 11.8325 3.7325 9 P 0 ;1
L 11.8325 3.7825 11.8325 3.7825 9 P 0 ;1
L 11.8325 3.8325 11.8325 3.8325 9 P 0 ;1
L 11.8325 3.8825 11.8325 3.8825 9 P 0 ;1
L 11.8325 3.9325 11.8325 3.9325 9 P 0 ;1
L 11.8325 3.9825 11.8325 3.9825 9 P 0 ;1
L 11.8325 4.0325 11.8325 4.0325 9 P 0 ;1
L 11.8325 4.0825 11.8325 4.0825 9 P 0 ;1
L 11.8325 4.1325 11.8325 4.1325 9 P 0 ;1
L 11.8325 4.1825 11.8325 4.1825 9 P 0 ;1
L 11.8325 4.2325 11.8325 4.2325 9 P 0 ;1
L 11.8325 4.2825 11.8325 4.2825 9 P 0 ;1
L 11.8325 4.3325 11.8325 4.3325 9 P 0 ;1
L 11.8325 4.5325 11.8325 4.5325 9 P 0 ;1
L 11.8325 4.5825 11.8325 4.5825 9 P 0 ;1
L 11.8325 4.6325 11.8325 4.6325 9 P 0 ;1
L 11.8325 4.6825 11.8325 4.6825 9 P 0 ;1
L 11.8325 4.7325 11.8325 4.7325 9 P 0 ;1
L 11.8825 0.1325 11.8825 0.1325 9 P 0 ;1
L 11.8825 0.1825 11.8825 0.1825 9 P 0 ;1
L 11.8825 0.2325 11.8825 0.2325 9 P 0 ;1
L 11.8825 0.2825 11.8825 0.2825 9 P 0 ;1
L 11.8825 0.3325 11.8825 0.3325 9 P 0 ;1
L 11.8825 0.3825 11.8825 0.3825 9 P 0 ;1
L 11.8825 0.4325 11.8825 0.4325 9 P 0 ;1
L 11.8825 0.4825 11.8825 0.4825 9 P 0 ;1
L 11.8825 0.5325 11.8825 0.5325 9 P 0 ;1
L 11.8825 0.5825 11.8825 0.5825 9 P 0 ;1
L 11.8825 0.6325 11.8825 0.6325 9 P 0 ;1
L 11.8825 0.6825 11.8825 0.6825 9 P 0 ;1
L 11.8825 0.7325 11.8825 0.7325 9 P 0 ;1
L 11.8825 0.7825 11.8825 0.7825 9 P 0 ;1
L 11.8825 0.8325 11.8825 0.8325 9 P 0 ;1
L 11.8825 0.8825 11.8825 0.8825 9 P 0 ;1
L 11.8825 0.9325 11.8825 0.9325 9 P 0 ;1
L 11.8825 0.9825 11.8825 0.9825 9 P 0 ;1
L 11.8825 1.0325 11.8825 1.0325 9 P 0 ;1
L 11.8825 1.0825 11.8825 1.0825 9 P 0 ;1
L 11.8825 1.1325 11.8825 1.1325 9 P 0 ;1
L 11.8825 1.1825 11.8825 1.1825 9 P 0 ;1
L 11.8825 1.2325 11.8825 1.2325 9 P 0 ;1
L 11.8825 1.2825 11.8825 1.2825 9 P 0 ;1
L 11.8825 1.3325 11.8825 1.3325 9 P 0 ;1
L 11.8825 2.9825 11.8825 2.9825 9 P 0 ;1
L 11.8825 3.0325 11.8825 3.0325 9 P 0 ;1
L 11.8825 3.0825 11.8825 3.0825 9 P 0 ;1
L 11.8825 3.1325 11.8825 3.1325 9 P 0 ;1
L 11.8825 3.1825 11.8825 3.1825 9 P 0 ;1
L 11.8825 3.2325 11.8825 3.2325 9 P 0 ;1
L 11.8825 3.2825 11.8825 3.2825 9 P 0 ;1
L 11.8825 3.3325 11.8825 3.3325 9 P 0 ;1
L 11.8825 3.3825 11.8825 3.3825 9 P 0 ;1
L 11.8825 3.4325 11.8825 3.4325 9 P 0 ;1
L 11.8825 3.4825 11.8825 3.4825 9 P 0 ;1
L 11.8825 3.5325 11.8825 3.5325 9 P 0 ;1
L 11.8825 3.5825 11.8825 3.5825 9 P 0 ;1
L 11.8825 3.6325 11.8825 3.6325 9 P 0 ;1
L 11.8825 3.6825 11.8825 3.6825 9 P 0 ;1
L 11.8825 3.7325 11.8825 3.7325 9 P 0 ;1
L 11.8825 3.7825 11.8825 3.7825 9 P 0 ;1
L 11.8825 3.8325 11.8825 3.8325 9 P 0 ;1
L 11.8825 3.8825 11.8825 3.8825 9 P 0 ;1
L 11.8825 3.9325 11.8825 3.9325 9 P 0 ;1
L 11.8825 3.9825 11.8825 3.9825 9 P 0 ;1
L 11.8825 4.0325 11.8825 4.0325 9 P 0 ;1
L 11.8825 4.0825 11.8825 4.0825 9 P 0 ;1
L 11.8825 4.1325 11.8825 4.1325 9 P 0 ;1
L 11.8825 4.1825 11.8825 4.1825 9 P 0 ;1
L 11.8825 4.2325 11.8825 4.2325 9 P 0 ;1
L 11.8825 4.2825 11.8825 4.2825 9 P 0 ;1
L 11.8825 4.3325 11.8825 4.3325 9 P 0 ;1
L 11.8825 4.5325 11.8825 4.5325 9 P 0 ;1
L 11.8825 4.5825 11.8825 4.5825 9 P 0 ;1
L 11.8825 4.6325 11.8825 4.6325 9 P 0 ;1
L 11.8825 4.6825 11.8825 4.6825 9 P 0 ;1
L 11.8825 4.7325 11.8825 4.7325 9 P 0 ;1
L 11.9325 0.1325 11.9325 0.1325 9 P 0 ;1
L 11.9325 0.1825 11.9325 0.1825 9 P 0 ;1
L 11.9325 0.2325 11.9325 0.2325 9 P 0 ;1
L 11.9325 0.2825 11.9325 0.2825 9 P 0 ;1
L 11.9325 0.3325 11.9325 0.3325 9 P 0 ;1
L 11.9325 0.3825 11.9325 0.3825 9 P 0 ;1
L 11.9325 0.4325 11.9325 0.4325 9 P 0 ;1
L 11.9325 0.4825 11.9325 0.4825 9 P 0 ;1
L 11.9325 0.5325 11.9325 0.5325 9 P 0 ;1
L 11.9325 0.5825 11.9325 0.5825 9 P 0 ;1
L 11.9325 0.6325 11.9325 0.6325 9 P 0 ;1
L 11.9325 0.6825 11.9325 0.6825 9 P 0 ;1
L 11.9325 0.7325 11.9325 0.7325 9 P 0 ;1
L 11.9325 0.7825 11.9325 0.7825 9 P 0 ;1
L 11.9325 0.8325 11.9325 0.8325 9 P 0 ;1
L 11.9325 0.8825 11.9325 0.8825 9 P 0 ;1
L 11.9325 0.9325 11.9325 0.9325 9 P 0 ;1
L 11.9325 0.9825 11.9325 0.9825 9 P 0 ;1
L 11.9325 1.0325 11.9325 1.0325 9 P 0 ;1
L 11.9325 1.0825 11.9325 1.0825 9 P 0 ;1
L 11.9325 1.1325 11.9325 1.1325 9 P 0 ;1
L 11.9325 1.1825 11.9325 1.1825 9 P 0 ;1
L 11.9325 1.2325 11.9325 1.2325 9 P 0 ;1
L 11.9325 3.0825 11.9325 3.0825 9 P 0 ;1
L 11.9325 3.1325 11.9325 3.1325 9 P 0 ;1
L 11.9325 3.1825 11.9325 3.1825 9 P 0 ;1
L 11.9325 3.2325 11.9325 3.2325 9 P 0 ;1
L 11.9325 3.2825 11.9325 3.2825 9 P 0 ;1
L 11.9325 3.3325 11.9325 3.3325 9 P 0 ;1
L 11.9325 3.3825 11.9325 3.3825 9 P 0 ;1
L 11.9325 3.4325 11.9325 3.4325 9 P 0 ;1
L 11.9325 3.4825 11.9325 3.4825 9 P 0 ;1
L 11.9325 3.5325 11.9325 3.5325 9 P 0 ;1
L 11.9325 3.5825 11.9325 3.5825 9 P 0 ;1
L 11.9325 3.6325 11.9325 3.6325 9 P 0 ;1
L 11.9325 3.6825 11.9325 3.6825 9 P 0 ;1
L 11.9325 3.7325 11.9325 3.7325 9 P 0 ;1
L 11.9325 3.7825 11.9325 3.7825 9 P 0 ;1
L 11.9325 3.8325 11.9325 3.8325 9 P 0 ;1
L 11.9325 3.8825 11.9325 3.8825 9 P 0 ;1
L 11.9325 3.9325 11.9325 3.9325 9 P 0 ;1
L 11.9325 3.9825 11.9325 3.9825 9 P 0 ;1
L 11.9325 4.0325 11.9325 4.0325 9 P 0 ;1
L 11.9325 4.0825 11.9325 4.0825 9 P 0 ;1
L 11.9325 4.1325 11.9325 4.1325 9 P 0 ;1
L 11.9325 4.2825 11.9325 4.2825 9 P 0 ;1
L 11.9325 4.3325 11.9325 4.3325 9 P 0 ;1
L 11.9325 4.3825 11.9325 4.3825 9 P 0 ;1
L 11.9325 4.5325 11.9325 4.5325 9 P 0 ;1
L 11.9325 4.5825 11.9325 4.5825 9 P 0 ;1
L 11.9325 4.6325 11.9325 4.6325 9 P 0 ;1
L 11.9325 4.6825 11.9325 4.6825 9 P 0 ;1
L 11.9325 4.7325 11.9325 4.7325 9 P 0 ;1
L 11.9825 0.1325 11.9825 0.1325 9 P 0 ;1
L 11.9825 0.1825 11.9825 0.1825 9 P 0 ;1
L 11.9825 0.2325 11.9825 0.2325 9 P 0 ;1
L 11.9825 0.2825 11.9825 0.2825 9 P 0 ;1
L 11.9825 0.3325 11.9825 0.3325 9 P 0 ;1
L 11.9825 0.3825 11.9825 0.3825 9 P 0 ;1
L 11.9825 0.4325 11.9825 0.4325 9 P 0 ;1
L 11.9825 0.4825 11.9825 0.4825 9 P 0 ;1
L 11.9825 0.5325 11.9825 0.5325 9 P 0 ;1
L 11.9825 0.5825 11.9825 0.5825 9 P 0 ;1
L 11.9825 0.6325 11.9825 0.6325 9 P 0 ;1
L 11.9825 0.6825 11.9825 0.6825 9 P 0 ;1
L 11.9825 0.7325 11.9825 0.7325 9 P 0 ;1
L 11.9825 0.7825 11.9825 0.7825 9 P 0 ;1
L 11.9825 0.8325 11.9825 0.8325 9 P 0 ;1
L 11.9825 0.8825 11.9825 0.8825 9 P 0 ;1
L 11.9825 0.9325 11.9825 0.9325 9 P 0 ;1
L 11.9825 0.9825 11.9825 0.9825 9 P 0 ;1
L 11.9825 1.0325 11.9825 1.0325 9 P 0 ;1
L 11.9825 1.0825 11.9825 1.0825 9 P 0 ;1
L 11.9825 1.1325 11.9825 1.1325 9 P 0 ;1
L 11.9825 1.1825 11.9825 1.1825 9 P 0 ;1
L 11.9825 1.2325 11.9825 1.2325 9 P 0 ;1
L 11.9825 1.6825 11.9825 1.6825 9 P 0 ;1
L 11.9825 1.7325 11.9825 1.7325 9 P 0 ;1
L 11.9825 3.1325 11.9825 3.1325 9 P 0 ;1
L 11.9825 3.1825 11.9825 3.1825 9 P 0 ;1
L 11.9825 3.2325 11.9825 3.2325 9 P 0 ;1
L 11.9825 3.2825 11.9825 3.2825 9 P 0 ;1
L 11.9825 3.3325 11.9825 3.3325 9 P 0 ;1
L 11.9825 3.3825 11.9825 3.3825 9 P 0 ;1
L 11.9825 3.4325 11.9825 3.4325 9 P 0 ;1
L 11.9825 3.4825 11.9825 3.4825 9 P 0 ;1
L 11.9825 3.5325 11.9825 3.5325 9 P 0 ;1
L 11.9825 3.5825 11.9825 3.5825 9 P 0 ;1
L 11.9825 3.6325 11.9825 3.6325 9 P 0 ;1
L 11.9825 3.6825 11.9825 3.6825 9 P 0 ;1
L 11.9825 3.7325 11.9825 3.7325 9 P 0 ;1
L 11.9825 3.7825 11.9825 3.7825 9 P 0 ;1
L 11.9825 3.8325 11.9825 3.8325 9 P 0 ;1
L 11.9825 3.8825 11.9825 3.8825 9 P 0 ;1
L 11.9825 3.9325 11.9825 3.9325 9 P 0 ;1
L 11.9825 3.9825 11.9825 3.9825 9 P 0 ;1
L 11.9825 4.0325 11.9825 4.0325 9 P 0 ;1
L 11.9825 4.3825 11.9825 4.3825 9 P 0 ;1
L 11.9825 4.4325 11.9825 4.4325 9 P 0 ;1
L 11.9825 4.4825 11.9825 4.4825 9 P 0 ;1
L 11.9825 4.5325 11.9825 4.5325 9 P 0 ;1
L 11.9825 4.5825 11.9825 4.5825 9 P 0 ;1
L 11.9825 4.6325 11.9825 4.6325 9 P 0 ;1
L 11.9825 4.6825 11.9825 4.6825 9 P 0 ;1
L 11.9825 4.7325 11.9825 4.7325 9 P 0 ;1
L 12.0325 0.1325 12.0325 0.1325 9 P 0 ;1
L 12.0325 0.1825 12.0325 0.1825 9 P 0 ;1
L 12.0325 0.2325 12.0325 0.2325 9 P 0 ;1
L 12.0325 0.2825 12.0325 0.2825 9 P 0 ;1
L 12.0325 0.3325 12.0325 0.3325 9 P 0 ;1
L 12.0325 0.3825 12.0325 0.3825 9 P 0 ;1
L 12.0325 0.4325 12.0325 0.4325 9 P 0 ;1
L 12.0325 0.4825 12.0325 0.4825 9 P 0 ;1
L 12.0325 0.5325 12.0325 0.5325 9 P 0 ;1
L 12.0325 0.5825 12.0325 0.5825 9 P 0 ;1
L 12.0325 0.6325 12.0325 0.6325 9 P 0 ;1
L 12.0325 0.6825 12.0325 0.6825 9 P 0 ;1
L 12.0325 0.7325 12.0325 0.7325 9 P 0 ;1
L 12.0325 0.7825 12.0325 0.7825 9 P 0 ;1
L 12.0325 0.8325 12.0325 0.8325 9 P 0 ;1
L 12.0325 0.8825 12.0325 0.8825 9 P 0 ;1
L 12.0325 0.9325 12.0325 0.9325 9 P 0 ;1
L 12.0325 0.9825 12.0325 0.9825 9 P 0 ;1
L 12.0325 1.0325 12.0325 1.0325 9 P 0 ;1
L 12.0325 1.0825 12.0325 1.0825 9 P 0 ;1
L 12.0325 1.1325 12.0325 1.1325 9 P 0 ;1
L 12.0325 1.1825 12.0325 1.1825 9 P 0 ;1
L 12.0325 1.7325 12.0325 1.7325 9 P 0 ;1
L 12.0325 3.2325 12.0325 3.2325 9 P 0 ;1
L 12.0325 3.2825 12.0325 3.2825 9 P 0 ;1
L 12.0325 3.3325 12.0325 3.3325 9 P 0 ;1
L 12.0325 3.3825 12.0325 3.3825 9 P 0 ;1
L 12.0325 3.4325 12.0325 3.4325 9 P 0 ;1
L 12.0325 3.4825 12.0325 3.4825 9 P 0 ;1
L 12.0325 3.5325 12.0325 3.5325 9 P 0 ;1
L 12.0325 3.5825 12.0325 3.5825 9 P 0 ;1
L 12.0325 3.6325 12.0325 3.6325 9 P 0 ;1
L 12.0325 3.6825 12.0325 3.6825 9 P 0 ;1
L 12.0325 3.7325 12.0325 3.7325 9 P 0 ;1
L 12.0325 3.7825 12.0325 3.7825 9 P 0 ;1
L 12.0325 3.8325 12.0325 3.8325 9 P 0 ;1
L 12.0325 3.8825 12.0325 3.8825 9 P 0 ;1
L 12.0325 3.9325 12.0325 3.9325 9 P 0 ;1
L 12.0325 3.9825 12.0325 3.9825 9 P 0 ;1
L 12.0325 4.0325 12.0325 4.0325 9 P 0 ;1
L 12.0325 4.3825 12.0325 4.3825 9 P 0 ;1
L 12.0325 4.4325 12.0325 4.4325 9 P 0 ;1
L 12.0325 4.4825 12.0325 4.4825 9 P 0 ;1
L 12.0325 4.5325 12.0325 4.5325 9 P 0 ;1
L 12.0325 4.5825 12.0325 4.5825 9 P 0 ;1
L 12.0325 4.6325 12.0325 4.6325 9 P 0 ;1
L 12.0325 4.6825 12.0325 4.6825 9 P 0 ;1
L 12.0325 4.7325 12.0325 4.7325 9 P 0 ;1
L 12.0825 0.1325 12.0825 0.1325 9 P 0 ;1
L 12.0825 0.1825 12.0825 0.1825 9 P 0 ;1
L 12.0825 0.2325 12.0825 0.2325 9 P 0 ;1
L 12.0825 0.2825 12.0825 0.2825 9 P 0 ;1
L 12.0825 0.3325 12.0825 0.3325 9 P 0 ;1
L 12.0825 0.3825 12.0825 0.3825 9 P 0 ;1
L 12.0825 0.4325 12.0825 0.4325 9 P 0 ;1
L 12.0825 0.4825 12.0825 0.4825 9 P 0 ;1
L 12.0825 0.5325 12.0825 0.5325 9 P 0 ;1
L 12.0825 0.5825 12.0825 0.5825 9 P 0 ;1
L 12.0825 0.6325 12.0825 0.6325 9 P 0 ;1
L 12.0825 0.6825 12.0825 0.6825 9 P 0 ;1
L 12.0825 0.7325 12.0825 0.7325 9 P 0 ;1
L 12.0825 0.7825 12.0825 0.7825 9 P 0 ;1
L 12.0825 0.8325 12.0825 0.8325 9 P 0 ;1
L 12.0825 0.8825 12.0825 0.8825 9 P 0 ;1
L 12.0825 0.9325 12.0825 0.9325 9 P 0 ;1
L 12.0825 0.9825 12.0825 0.9825 9 P 0 ;1
L 12.0825 1.0325 12.0825 1.0325 9 P 0 ;1
L 12.0825 1.0825 12.0825 1.0825 9 P 0 ;1
L 12.0825 1.1325 12.0825 1.1325 9 P 0 ;1
L 12.0825 1.1825 12.0825 1.1825 9 P 0 ;1
L 12.0825 1.7325 12.0825 1.7325 9 P 0 ;1
L 12.0825 1.7825 12.0825 1.7825 9 P 0 ;1
L 12.0825 2.7325 12.0825 2.7325 9 P 0 ;1
L 12.0825 2.7825 12.0825 2.7825 9 P 0 ;1
L 12.0825 3.2825 12.0825 3.2825 9 P 0 ;1
L 12.0825 3.3325 12.0825 3.3325 9 P 0 ;1
L 12.0825 3.3825 12.0825 3.3825 9 P 0 ;1
L 12.0825 3.4325 12.0825 3.4325 9 P 0 ;1
L 12.0825 3.4825 12.0825 3.4825 9 P 0 ;1
L 12.0825 3.5325 12.0825 3.5325 9 P 0 ;1
L 12.0825 3.5825 12.0825 3.5825 9 P 0 ;1
L 12.0825 3.6325 12.0825 3.6325 9 P 0 ;1
L 12.0825 3.6825 12.0825 3.6825 9 P 0 ;1
L 12.0825 3.7325 12.0825 3.7325 9 P 0 ;1
L 12.0825 3.7825 12.0825 3.7825 9 P 0 ;1
L 12.0825 3.8325 12.0825 3.8325 9 P 0 ;1
L 12.0825 3.8825 12.0825 3.8825 9 P 0 ;1
L 12.0825 3.9325 12.0825 3.9325 9 P 0 ;1
L 12.0825 3.9825 12.0825 3.9825 9 P 0 ;1
L 12.0825 4.4325 12.0825 4.4325 9 P 0 ;1
L 12.0825 4.4825 12.0825 4.4825 9 P 0 ;1
L 12.0825 4.5325 12.0825 4.5325 9 P 0 ;1
L 12.0825 4.5825 12.0825 4.5825 9 P 0 ;1
L 12.0825 4.6325 12.0825 4.6325 9 P 0 ;1
L 12.0825 4.6825 12.0825 4.6825 9 P 0 ;1
L 12.0825 4.7325 12.0825 4.7325 9 P 0 ;1
L 12.0825 4.7825 12.0825 4.7825 9 P 0 ;1
L 12.0825 4.8325 12.0825 4.8325 9 P 0 ;1
L 12.1325 0.1325 12.1325 0.1325 9 P 0 ;1
L 12.1325 0.1825 12.1325 0.1825 9 P 0 ;1
L 12.1325 0.2325 12.1325 0.2325 9 P 0 ;1
L 12.1325 0.2825 12.1325 0.2825 9 P 0 ;1
L 12.1325 0.3325 12.1325 0.3325 9 P 0 ;1
L 12.1325 0.3825 12.1325 0.3825 9 P 0 ;1
L 12.1325 0.4325 12.1325 0.4325 9 P 0 ;1
L 12.1325 0.4825 12.1325 0.4825 9 P 0 ;1
L 12.1325 0.5325 12.1325 0.5325 9 P 0 ;1
L 12.1325 0.5825 12.1325 0.5825 9 P 0 ;1
L 12.1325 0.6325 12.1325 0.6325 9 P 0 ;1
L 12.1325 0.6825 12.1325 0.6825 9 P 0 ;1
L 12.1325 0.7325 12.1325 0.7325 9 P 0 ;1
L 12.1325 0.7825 12.1325 0.7825 9 P 0 ;1
L 12.1325 0.8325 12.1325 0.8325 9 P 0 ;1
L 12.1325 0.8825 12.1325 0.8825 9 P 0 ;1
L 12.1325 0.9325 12.1325 0.9325 9 P 0 ;1
L 12.1325 0.9825 12.1325 0.9825 9 P 0 ;1
L 12.1325 1.0325 12.1325 1.0325 9 P 0 ;1
L 12.1325 1.0825 12.1325 1.0825 9 P 0 ;1
L 12.1325 1.1325 12.1325 1.1325 9 P 0 ;1
L 12.1325 1.1825 12.1325 1.1825 9 P 0 ;1
L 12.1325 1.7825 12.1325 1.7825 9 P 0 ;1
L 12.1325 1.8325 12.1325 1.8325 9 P 0 ;1
L 12.1325 3.4825 12.1325 3.4825 9 P 0 ;1
L 12.1325 3.5325 12.1325 3.5325 9 P 0 ;1
L 12.1325 3.5825 12.1325 3.5825 9 P 0 ;1
L 12.1325 3.6325 12.1325 3.6325 9 P 0 ;1
L 12.1325 3.6825 12.1325 3.6825 9 P 0 ;1
L 12.1325 3.7325 12.1325 3.7325 9 P 0 ;1
L 12.1325 3.7825 12.1325 3.7825 9 P 0 ;1
L 12.1325 3.8325 12.1325 3.8325 9 P 0 ;1
L 12.1325 3.8825 12.1325 3.8825 9 P 0 ;1
L 12.1325 3.9325 12.1325 3.9325 9 P 0 ;1
L 12.1325 3.9825 12.1325 3.9825 9 P 0 ;1
L 12.1325 4.4325 12.1325 4.4325 9 P 0 ;1
L 12.1325 4.4825 12.1325 4.4825 9 P 0 ;1
L 12.1325 4.5325 12.1325 4.5325 9 P 0 ;1
L 12.1325 4.5825 12.1325 4.5825 9 P 0 ;1
L 12.1325 4.6325 12.1325 4.6325 9 P 0 ;1
L 12.1325 4.6825 12.1325 4.6825 9 P 0 ;1
L 12.1325 4.7325 12.1325 4.7325 9 P 0 ;1
L 12.1325 4.7825 12.1325 4.7825 9 P 0 ;1
L 12.1325 4.8325 12.1325 4.8325 9 P 0 ;1
L 12.1825 0.1325 12.1825 0.1325 9 P 0 ;1
L 12.1825 0.1825 12.1825 0.1825 9 P 0 ;1
L 12.1825 0.4325 12.1825 0.4325 9 P 0 ;1
L 12.1825 0.4825 12.1825 0.4825 9 P 0 ;1
L 12.1825 0.5325 12.1825 0.5325 9 P 0 ;1
L 12.1825 0.5825 12.1825 0.5825 9 P 0 ;1
L 12.1825 0.6325 12.1825 0.6325 9 P 0 ;1
L 12.1825 0.6825 12.1825 0.6825 9 P 0 ;1
L 12.1825 0.7325 12.1825 0.7325 9 P 0 ;1
L 12.1825 0.7825 12.1825 0.7825 9 P 0 ;1
L 12.1825 0.8325 12.1825 0.8325 9 P 0 ;1
L 12.1825 0.8825 12.1825 0.8825 9 P 0 ;1
L 12.1825 0.9325 12.1825 0.9325 9 P 0 ;1
L 12.1825 0.9825 12.1825 0.9825 9 P 0 ;1
L 12.1825 1.0325 12.1825 1.0325 9 P 0 ;1
L 12.1825 1.0825 12.1825 1.0825 9 P 0 ;1
L 12.1825 1.1325 12.1825 1.1325 9 P 0 ;1
L 12.1825 1.1825 12.1825 1.1825 9 P 0 ;1
L 12.1825 1.7325 12.1825 1.7325 9 P 0 ;1
L 12.1825 1.7825 12.1825 1.7825 9 P 0 ;1
L 12.1825 1.8325 12.1825 1.8325 9 P 0 ;1
L 12.1825 1.8825 12.1825 1.8825 9 P 0 ;1
L 12.1825 3.7825 12.1825 3.7825 9 P 0 ;1
L 12.1825 3.8325 12.1825 3.8325 9 P 0 ;1
L 12.1825 3.8825 12.1825 3.8825 9 P 0 ;1
L 12.1825 3.9325 12.1825 3.9325 9 P 0 ;1
L 12.1825 3.9825 12.1825 3.9825 9 P 0 ;1
L 12.1825 4.4325 12.1825 4.4325 9 P 0 ;1
L 12.1825 4.4825 12.1825 4.4825 9 P 0 ;1
L 12.1825 4.5325 12.1825 4.5325 9 P 0 ;1
L 12.1825 4.5825 12.1825 4.5825 9 P 0 ;1
L 12.1825 4.6325 12.1825 4.6325 9 P 0 ;1
L 12.1825 4.6825 12.1825 4.6825 9 P 0 ;1
L 12.1825 4.7325 12.1825 4.7325 9 P 0 ;1
L 12.1825 4.7825 12.1825 4.7825 9 P 0 ;1
L 12.1825 4.8325 12.1825 4.8325 9 P 0 ;1
L 12.2325 0.1325 12.2325 0.1325 9 P 0 ;1
L 12.2325 0.4325 12.2325 0.4325 9 P 0 ;1
L 12.2325 0.4825 12.2325 0.4825 9 P 0 ;1
L 12.2325 0.5325 12.2325 0.5325 9 P 0 ;1
L 12.2325 0.5825 12.2325 0.5825 9 P 0 ;1
L 12.2325 0.6325 12.2325 0.6325 9 P 0 ;1
L 12.2325 0.6825 12.2325 0.6825 9 P 0 ;1
L 12.2325 0.7325 12.2325 0.7325 9 P 0 ;1
L 12.2325 0.7825 12.2325 0.7825 9 P 0 ;1
L 12.2325 0.8325 12.2325 0.8325 9 P 0 ;1
L 12.2325 0.8825 12.2325 0.8825 9 P 0 ;1
L 12.2325 0.9325 12.2325 0.9325 9 P 0 ;1
L 12.2325 0.9825 12.2325 0.9825 9 P 0 ;1
L 12.2325 1.0325 12.2325 1.0325 9 P 0 ;1
L 12.2325 1.0825 12.2325 1.0825 9 P 0 ;1
L 12.2325 1.1325 12.2325 1.1325 9 P 0 ;1
L 12.2325 1.1825 12.2325 1.1825 9 P 0 ;1
L 12.2325 1.7325 12.2325 1.7325 9 P 0 ;1
L 12.2325 1.7825 12.2325 1.7825 9 P 0 ;1
L 12.2325 1.8325 12.2325 1.8325 9 P 0 ;1
L 12.2325 1.8825 12.2325 1.8825 9 P 0 ;1
L 12.2325 1.9325 12.2325 1.9325 9 P 0 ;1
L 12.2325 4.0325 12.2325 4.0325 9 P 0 ;1
L 12.2325 4.3825 12.2325 4.3825 9 P 0 ;1
L 12.2325 4.4325 12.2325 4.4325 9 P 0 ;1
L 12.2325 4.4825 12.2325 4.4825 9 P 0 ;1
L 12.2325 4.5325 12.2325 4.5325 9 P 0 ;1
L 12.2325 4.5825 12.2325 4.5825 9 P 0 ;1
L 12.2325 4.6325 12.2325 4.6325 9 P 0 ;1
L 12.2325 4.6825 12.2325 4.6825 9 P 0 ;1
L 12.2325 4.7325 12.2325 4.7325 9 P 0 ;1
L 12.2325 4.7825 12.2325 4.7825 9 P 0 ;1
L 12.2325 4.8325 12.2325 4.8325 9 P 0 ;1
L 12.2825 0.1325 12.2825 0.1325 9 P 0 ;1
L 12.2825 0.4325 12.2825 0.4325 9 P 0 ;1
L 12.2825 0.4825 12.2825 0.4825 9 P 0 ;1
L 12.2825 0.5325 12.2825 0.5325 9 P 0 ;1
L 12.2825 0.5825 12.2825 0.5825 9 P 0 ;1
L 12.2825 0.6325 12.2825 0.6325 9 P 0 ;1
L 12.2825 0.6825 12.2825 0.6825 9 P 0 ;1
L 12.2825 0.7325 12.2825 0.7325 9 P 0 ;1
L 12.2825 0.7825 12.2825 0.7825 9 P 0 ;1
L 12.2825 0.8325 12.2825 0.8325 9 P 0 ;1
L 12.2825 0.8825 12.2825 0.8825 9 P 0 ;1
L 12.2825 0.9325 12.2825 0.9325 9 P 0 ;1
L 12.2825 0.9825 12.2825 0.9825 9 P 0 ;1
L 12.2825 1.0325 12.2825 1.0325 9 P 0 ;1
L 12.2825 1.0825 12.2825 1.0825 9 P 0 ;1
L 12.2825 1.1325 12.2825 1.1325 9 P 0 ;1
L 12.2825 1.1825 12.2825 1.1825 9 P 0 ;1
L 12.2825 1.2325 12.2825 1.2325 9 P 0 ;1
L 12.2825 1.6825 12.2825 1.6825 9 P 0 ;1
L 12.2825 1.7325 12.2825 1.7325 9 P 0 ;1
L 12.2825 1.7825 12.2825 1.7825 9 P 0 ;1
L 12.2825 1.8325 12.2825 1.8325 9 P 0 ;1
L 12.2825 1.8825 12.2825 1.8825 9 P 0 ;1
L 12.2825 1.9325 12.2825 1.9325 9 P 0 ;1
L 12.2825 1.9825 12.2825 1.9825 9 P 0 ;1
L 12.2825 4.3825 12.2825 4.3825 9 P 0 ;1
L 12.2825 4.4325 12.2825 4.4325 9 P 0 ;1
L 12.2825 4.4825 12.2825 4.4825 9 P 0 ;1
L 12.2825 4.5325 12.2825 4.5325 9 P 0 ;1
L 12.2825 4.5825 12.2825 4.5825 9 P 0 ;1
L 12.2825 4.6325 12.2825 4.6325 9 P 0 ;1
L 12.2825 4.6825 12.2825 4.6825 9 P 0 ;1
L 12.2825 4.7325 12.2825 4.7325 9 P 0 ;1
L 12.2825 4.7825 12.2825 4.7825 9 P 0 ;1
L 12.2825 4.8325 12.2825 4.8325 9 P 0 ;1
L 12.3325 0.1325 12.3325 0.1325 9 P 0 ;1
L 12.3325 0.4325 12.3325 0.4325 9 P 0 ;1
L 12.3325 0.4825 12.3325 0.4825 9 P 0 ;1
L 12.3325 0.5325 12.3325 0.5325 9 P 0 ;1
L 12.3325 0.5825 12.3325 0.5825 9 P 0 ;1
L 12.3325 0.6325 12.3325 0.6325 9 P 0 ;1
L 12.3325 0.6825 12.3325 0.6825 9 P 0 ;1
L 12.3325 0.7325 12.3325 0.7325 9 P 0 ;1
L 12.3325 0.7825 12.3325 0.7825 9 P 0 ;1
L 12.3325 0.8325 12.3325 0.8325 9 P 0 ;1
L 12.3325 0.8825 12.3325 0.8825 9 P 0 ;1
L 12.3325 0.9325 12.3325 0.9325 9 P 0 ;1
L 12.3325 0.9825 12.3325 0.9825 9 P 0 ;1
L 12.3325 1.0325 12.3325 1.0325 9 P 0 ;1
L 12.3325 1.0825 12.3325 1.0825 9 P 0 ;1
L 12.3325 1.1325 12.3325 1.1325 9 P 0 ;1
L 12.3325 1.1825 12.3325 1.1825 9 P 0 ;1
L 12.3325 1.2325 12.3325 1.2325 9 P 0 ;1
L 12.3325 1.2825 12.3325 1.2825 9 P 0 ;1
L 12.3325 1.9325 12.3325 1.9325 9 P 0 ;1
L 12.3325 1.9825 12.3325 1.9825 9 P 0 ;1
L 12.3325 4.4825 12.3325 4.4825 9 P 0 ;1
L 12.3325 4.5325 12.3325 4.5325 9 P 0 ;1
L 12.3325 4.5825 12.3325 4.5825 9 P 0 ;1
L 12.3325 4.6325 12.3325 4.6325 9 P 0 ;1
L 12.3325 4.6825 12.3325 4.6825 9 P 0 ;1
L 12.3325 4.7325 12.3325 4.7325 9 P 0 ;1
L 12.3325 4.7825 12.3325 4.7825 9 P 0 ;1
L 12.3325 4.8325 12.3325 4.8325 9 P 0 ;1
L 12.3325 4.8825 12.3325 4.8825 9 P 0 ;1
L 12.3325 4.9325 12.3325 4.9325 9 P 0 ;1
L 12.3325 4.9825 12.3325 4.9825 9 P 0 ;1
L 12.3825 0.1325 12.3825 0.1325 9 P 0 ;1
L 12.3825 0.1825 12.3825 0.1825 9 P 0 ;1
L 12.3825 0.3825 12.3825 0.3825 9 P 0 ;1
L 12.3825 0.4325 12.3825 0.4325 9 P 0 ;1
L 12.3825 0.4825 12.3825 0.4825 9 P 0 ;1
L 12.3825 0.5325 12.3825 0.5325 9 P 0 ;1
L 12.3825 0.5825 12.3825 0.5825 9 P 0 ;1
L 12.3825 0.6325 12.3825 0.6325 9 P 0 ;1
L 12.3825 0.6825 12.3825 0.6825 9 P 0 ;1
L 12.3825 0.7325 12.3825 0.7325 9 P 0 ;1
L 12.3825 0.7825 12.3825 0.7825 9 P 0 ;1
L 12.3825 0.8325 12.3825 0.8325 9 P 0 ;1
L 12.3825 0.8825 12.3825 0.8825 9 P 0 ;1
L 12.3825 0.9325 12.3825 0.9325 9 P 0 ;1
L 12.3825 0.9825 12.3825 0.9825 9 P 0 ;1
L 12.3825 1.0325 12.3825 1.0325 9 P 0 ;1
L 12.3825 1.0825 12.3825 1.0825 9 P 0 ;1
L 12.3825 1.1325 12.3825 1.1325 9 P 0 ;1
L 12.3825 1.1825 12.3825 1.1825 9 P 0 ;1
L 12.3825 1.2325 12.3825 1.2325 9 P 0 ;1
L 12.3825 1.2825 12.3825 1.2825 9 P 0 ;1
L 12.3825 1.3325 12.3825 1.3325 9 P 0 ;1
L 12.3825 2.0325 12.3825 2.0325 9 P 0 ;1
L 12.3825 4.5825 12.3825 4.5825 9 P 0 ;1
L 12.3825 4.6325 12.3825 4.6325 9 P 0 ;1
L 12.3825 4.6825 12.3825 4.6825 9 P 0 ;1
L 12.3825 4.7325 12.3825 4.7325 9 P 0 ;1
L 12.3825 4.7825 12.3825 4.7825 9 P 0 ;1
L 12.3825 4.8325 12.3825 4.8325 9 P 0 ;1
L 12.3825 4.8825 12.3825 4.8825 9 P 0 ;1
L 12.3825 4.9325 12.3825 4.9325 9 P 0 ;1
L 12.3825 4.9825 12.3825 4.9825 9 P 0 ;1
L 12.3825 5.0325 12.3825 5.0325 9 P 0 ;1
L 12.4325 0.1325 12.4325 0.1325 9 P 0 ;1
L 12.4325 0.1825 12.4325 0.1825 9 P 0 ;1
L 12.4325 0.2325 12.4325 0.2325 9 P 0 ;1
L 12.4325 0.2825 12.4325 0.2825 9 P 0 ;1
L 12.4325 0.3325 12.4325 0.3325 9 P 0 ;1
L 12.4325 0.3825 12.4325 0.3825 9 P 0 ;1
L 12.4325 0.4325 12.4325 0.4325 9 P 0 ;1
L 12.4325 0.4825 12.4325 0.4825 9 P 0 ;1
L 12.4325 0.5325 12.4325 0.5325 9 P 0 ;1
L 12.4325 0.5825 12.4325 0.5825 9 P 0 ;1
L 12.4325 0.6325 12.4325 0.6325 9 P 0 ;1
L 12.4325 0.6825 12.4325 0.6825 9 P 0 ;1
L 12.4325 0.7325 12.4325 0.7325 9 P 0 ;1
L 12.4325 0.7825 12.4325 0.7825 9 P 0 ;1
L 12.4325 0.8325 12.4325 0.8325 9 P 0 ;1
L 12.4325 0.8825 12.4325 0.8825 9 P 0 ;1
L 12.4325 0.9325 12.4325 0.9325 9 P 0 ;1
L 12.4325 0.9825 12.4325 0.9825 9 P 0 ;1
L 12.4325 1.0325 12.4325 1.0325 9 P 0 ;1
L 12.4325 1.0825 12.4325 1.0825 9 P 0 ;1
L 12.4325 1.1325 12.4325 1.1325 9 P 0 ;1
L 12.4325 1.1825 12.4325 1.1825 9 P 0 ;1
L 12.4325 1.2325 12.4325 1.2325 9 P 0 ;1
L 12.4325 1.2825 12.4325 1.2825 9 P 0 ;1
L 12.4325 1.3325 12.4325 1.3325 9 P 0 ;1
L 12.4325 1.3825 12.4325 1.3825 9 P 0 ;1
L 12.4325 2.0825 12.4325 2.0825 9 P 0 ;1
L 12.4325 4.5825 12.4325 4.5825 9 P 0 ;1
L 12.4325 4.6325 12.4325 4.6325 9 P 0 ;1
L 12.4325 4.6825 12.4325 4.6825 9 P 0 ;1
L 12.4325 4.7325 12.4325 4.7325 9 P 0 ;1
L 12.4325 4.7825 12.4325 4.7825 9 P 0 ;1
L 12.4325 4.8325 12.4325 4.8325 9 P 0 ;1
L 12.4325 4.8825 12.4325 4.8825 9 P 0 ;1
L 12.4325 4.9325 12.4325 4.9325 9 P 0 ;1
L 12.4325 4.9825 12.4325 4.9825 9 P 0 ;1
L 12.4325 5.0325 12.4325 5.0325 9 P 0 ;1
L 12.4325 5.0825 12.4325 5.0825 9 P 0 ;1
L 12.4825 0.1325 12.4825 0.1325 9 P 0 ;1
L 12.4825 0.1825 12.4825 0.1825 9 P 0 ;1
L 12.4825 0.2325 12.4825 0.2325 9 P 0 ;1
L 12.4825 0.2825 12.4825 0.2825 9 P 0 ;1
L 12.4825 0.3325 12.4825 0.3325 9 P 0 ;1
L 12.4825 0.3825 12.4825 0.3825 9 P 0 ;1
L 12.4825 0.4325 12.4825 0.4325 9 P 0 ;1
L 12.4825 0.4825 12.4825 0.4825 9 P 0 ;1
L 12.4825 0.5325 12.4825 0.5325 9 P 0 ;1
L 12.4825 0.5825 12.4825 0.5825 9 P 0 ;1
L 12.4825 0.6325 12.4825 0.6325 9 P 0 ;1
L 12.4825 0.6825 12.4825 0.6825 9 P 0 ;1
L 12.4825 0.7825 12.4825 0.7825 9 P 0 ;1
L 12.4825 0.8325 12.4825 0.8325 9 P 0 ;1
L 12.4825 0.8825 12.4825 0.8825 9 P 0 ;1
L 12.4825 0.9325 12.4825 0.9325 9 P 0 ;1
L 12.4825 0.9825 12.4825 0.9825 9 P 0 ;1
L 12.4825 1.0325 12.4825 1.0325 9 P 0 ;1
L 12.4825 1.0825 12.4825 1.0825 9 P 0 ;1
L 12.4825 1.1325 12.4825 1.1325 9 P 0 ;1
L 12.4825 1.1825 12.4825 1.1825 9 P 0 ;1
L 12.4825 1.2325 12.4825 1.2325 9 P 0 ;1
L 12.4825 1.2825 12.4825 1.2825 9 P 0 ;1
L 12.4825 1.3325 12.4825 1.3325 9 P 0 ;1
L 12.4825 1.7825 12.4825 1.7825 9 P 0 ;1
L 12.4825 1.8325 12.4825 1.8325 9 P 0 ;1
L 12.4825 4.7325 12.4825 4.7325 9 P 0 ;1
L 12.4825 4.7825 12.4825 4.7825 9 P 0 ;1
L 12.4825 4.8325 12.4825 4.8325 9 P 0 ;1
L 12.4825 4.8825 12.4825 4.8825 9 P 0 ;1
L 12.4825 4.9325 12.4825 4.9325 9 P 0 ;1
L 12.4825 4.9825 12.4825 4.9825 9 P 0 ;1
L 12.4825 5.0325 12.4825 5.0325 9 P 0 ;1
L 12.4825 5.0825 12.4825 5.0825 9 P 0 ;1
L 12.5325 0.1325 12.5325 0.1325 9 P 0 ;1
L 12.5325 0.1825 12.5325 0.1825 9 P 0 ;1
L 12.5325 0.2325 12.5325 0.2325 9 P 0 ;1
L 12.5325 0.2825 12.5325 0.2825 9 P 0 ;1
L 12.5325 0.3325 12.5325 0.3325 9 P 0 ;1
L 12.5325 0.3825 12.5325 0.3825 9 P 0 ;1
L 12.5325 0.4325 12.5325 0.4325 9 P 0 ;1
L 12.5325 0.4825 12.5325 0.4825 9 P 0 ;1
L 12.5325 0.5325 12.5325 0.5325 9 P 0 ;1
L 12.5325 0.5825 12.5325 0.5825 9 P 0 ;1
L 12.5325 0.8825 12.5325 0.8825 9 P 0 ;1
L 12.5325 0.9325 12.5325 0.9325 9 P 0 ;1
L 12.5325 0.9825 12.5325 0.9825 9 P 0 ;1
L 12.5325 1.0325 12.5325 1.0325 9 P 0 ;1
L 12.5325 1.0825 12.5325 1.0825 9 P 0 ;1
L 12.5325 1.1325 12.5325 1.1325 9 P 0 ;1
L 12.5325 1.1825 12.5325 1.1825 9 P 0 ;1
L 12.5325 1.2325 12.5325 1.2325 9 P 0 ;1
L 12.5325 1.2825 12.5325 1.2825 9 P 0 ;1
L 12.5325 4.7325 12.5325 4.7325 9 P 0 ;1
L 12.5325 4.7825 12.5325 4.7825 9 P 0 ;1
L 12.5325 4.8325 12.5325 4.8325 9 P 0 ;1
L 12.5325 4.8825 12.5325 4.8825 9 P 0 ;1
L 12.5325 4.9325 12.5325 4.9325 9 P 0 ;1
L 12.5325 4.9825 12.5325 4.9825 9 P 0 ;1
L 12.5825 0.1325 12.5825 0.1325 9 P 0 ;1
L 12.5825 0.1825 12.5825 0.1825 9 P 0 ;1
L 12.5825 0.2325 12.5825 0.2325 9 P 0 ;1
L 12.5825 0.2825 12.5825 0.2825 9 P 0 ;1
L 12.5825 0.3325 12.5825 0.3325 9 P 0 ;1
L 12.5825 1.0825 12.5825 1.0825 9 P 0 ;1
L 12.5825 1.1325 12.5825 1.1325 9 P 0 ;1
L 12.5825 1.1825 12.5825 1.1825 9 P 0 ;1
L 12.5825 1.2325 12.5825 1.2325 9 P 0 ;1
L 12.5825 1.2825 12.5825 1.2825 9 P 0 ;1
L 12.5825 4.7825 12.5825 4.7825 9 P 0 ;1
L 12.5825 4.8325 12.5825 4.8325 9 P 0 ;1
L 12.5825 4.9825 12.5825 4.9825 9 P 0 ;1
L 12.6325 0.1325 12.6325 0.1325 9 P 0 ;1
L 12.6325 0.1825 12.6325 0.1825 9 P 0 ;1
L 12.6325 0.2325 12.6325 0.2325 9 P 0 ;1
L 12.6325 0.2825 12.6325 0.2825 9 P 0 ;1
L 12.6325 1.1325 12.6325 1.1325 9 P 0 ;1
L 12.6325 1.1825 12.6325 1.1825 9 P 0 ;1
L 12.6325 1.2325 12.6325 1.2325 9 P 0 ;1
L 12.6325 1.2825 12.6325 1.2825 9 P 0 ;1
L 12.6325 5.5825 12.6325 5.5825 9 P 0 ;1
L 12.6325 5.6325 12.6325 5.6325 9 P 0 ;1
L 12.6325 5.6825 12.6325 5.6825 9 P 0 ;1
L 12.6325 5.7325 12.6325 5.7325 9 P 0 ;1
L 12.6325 5.7825 12.6325 5.7825 9 P 0 ;1
L 12.6325 5.8325 12.6325 5.8325 9 P 0 ;1
L 12.6325 5.8825 12.6325 5.8825 9 P 0 ;1
L 12.6825 0.1325 12.6825 0.1325 9 P 0 ;1
L 12.6825 0.1825 12.6825 0.1825 9 P 0 ;1
L 12.6825 0.2325 12.6825 0.2325 9 P 0 ;1
L 12.6825 0.2825 12.6825 0.2825 9 P 0 ;1
L 12.6825 1.1325 12.6825 1.1325 9 P 0 ;1
L 12.6825 1.1825 12.6825 1.1825 9 P 0 ;1
L 12.6825 1.2325 12.6825 1.2325 9 P 0 ;1
L 12.6825 1.2825 12.6825 1.2825 9 P 0 ;1
L 12.6825 5.5825 12.6825 5.5825 9 P 0 ;1
L 12.6825 5.6325 12.6825 5.6325 9 P 0 ;1
L 12.6825 5.6825 12.6825 5.6825 9 P 0 ;1
L 12.6825 5.7325 12.6825 5.7325 9 P 0 ;1
L 12.6825 5.7825 12.6825 5.7825 9 P 0 ;1
L 12.6825 5.8325 12.6825 5.8325 9 P 0 ;1
L 12.6825 5.8825 12.6825 5.8825 9 P 0 ;1
L 12.7325 0.1325 12.7325 0.1325 9 P 0 ;1
L 12.7325 0.1825 12.7325 0.1825 9 P 0 ;1
L 12.7325 0.2325 12.7325 0.2325 9 P 0 ;1
L 12.7325 0.2825 12.7325 0.2825 9 P 0 ;1
L 12.7325 1.1325 12.7325 1.1325 9 P 0 ;1
L 12.7325 1.1825 12.7325 1.1825 9 P 0 ;1
L 12.7325 1.2325 12.7325 1.2325 9 P 0 ;1
L 12.7325 1.2825 12.7325 1.2825 9 P 0 ;1
L 12.7325 5.5825 12.7325 5.5825 9 P 0 ;1
L 12.7325 5.6325 12.7325 5.6325 9 P 0 ;1
L 12.7325 5.6825 12.7325 5.6825 9 P 0 ;1
L 12.7325 5.7325 12.7325 5.7325 9 P 0 ;1
L 12.7325 5.7825 12.7325 5.7825 9 P 0 ;1
L 12.7325 5.8325 12.7325 5.8325 9 P 0 ;1
L 12.7325 5.8825 12.7325 5.8825 9 P 0 ;1
L 12.7825 0.1325 12.7825 0.1325 9 P 0 ;1
L 12.7825 0.1825 12.7825 0.1825 9 P 0 ;1
L 12.7825 0.2325 12.7825 0.2325 9 P 0 ;1
L 12.7825 0.2825 12.7825 0.2825 9 P 0 ;1
L 12.7825 0.3325 12.7825 0.3325 9 P 0 ;1
L 12.7825 1.0825 12.7825 1.0825 9 P 0 ;1
L 12.7825 1.1325 12.7825 1.1325 9 P 0 ;1
L 12.7825 1.1825 12.7825 1.1825 9 P 0 ;1
L 12.7825 1.2325 12.7825 1.2325 9 P 0 ;1
L 12.7825 1.2825 12.7825 1.2825 9 P 0 ;1
L 12.7825 4.8325 12.7825 4.8325 9 P 0 ;1
L 12.7825 5.5325 12.7825 5.5325 9 P 0 ;1
L 12.7825 5.5825 12.7825 5.5825 9 P 0 ;1
L 12.7825 5.6325 12.7825 5.6325 9 P 0 ;1
L 12.7825 5.6825 12.7825 5.6825 9 P 0 ;1
L 12.7825 5.7325 12.7825 5.7325 9 P 0 ;1
L 12.7825 5.7825 12.7825 5.7825 9 P 0 ;1
L 12.7825 5.8325 12.7825 5.8325 9 P 0 ;1
L 12.7825 5.8825 12.7825 5.8825 9 P 0 ;1

### steps/drc/layers/l11/features
#
#Feature symbol names
#
$0 r2
$1 r5
$2 r6
$3 r15
$4 r20
$5 r28
$6 r30
$7 r32
$8 r33
$9 r40
$10 r50
$11 r57.09
$12 r78.74
$13 r86.61
$14 r90.55
$15 r100
$16 r131.89
$17 r137.8
$18 r161.42
$19 r168.31
$20 r173.23
$21 r181.1
$22 r204.72
$23 r224.41
$24 r440.94
$25 null
$26 oval236.22x177.17
$27 thr61.02x49.21x45x4x15.75
$28 thr96.46x76.77x45x4x19.69

#
#Feature attribute names
#
@0 .nomenclature
@1 .geometry

#
#Feature attribute text strings
#
&0 TPB30V20D10AT28BPM
&1 C1_11P0_7
&2 C1_11P0_7TP
&3 V17D8AT30SM11
&4 V20D10AT28SM14
&5 C2_5N
&6 S1_11P0_7TP
&7 S1_11P0_7
&8 V20D10AT28PG
&9 C1_17P0_76TPM
&10 C1_9P1_4
&11 S1_9P1_4
&12 SP-8C5_2P0_254
&13 SP-9C5_7P0_254
&14 C3_175N-A
&15 C10N
&16 C3_3N
&17 C4_5N-B
&18 C4N-B
&19 C3_5N
&20 O5X3_5N
&21 C3N
&22 C1_3N
&23 C2_35N
&24 C1N

#
#Layer features
#
P 7.785 4.45 5 P 0 0;1=0
P 7.835 4.45 5 P 0 0;1=0
P 1.8 4.485 5 P 0 0;1=0
P 1.86 4.485 5 P 0 0;1=0
P 0.27165 1.72835 11 P 0 0;1=1
P 0.17323002 2.12205 11 P 0 0;1=1
P 12.73621004 1.76771998 11 P 0 0;1=1
P 12.81495 2.59448996 11 P 0 0;1=1
P 12.63778996 2.16141998 11 P 0 0;1=1
P 0.725 -0.25 11 P 0 0;1=2
P 0.875 -0.25 11 P 0 0;1=2
P 1.065 6.26 11 P 0 0;1=2
P 1.065 6.36 11 P 0 0;1=2
P 1.29 6.26 11 P 0 0;1=2
P 1.29 6.36 11 P 0 0;1=2
P 1.515 6.26 11 P 0 0;1=2
P 1.515 6.36 11 P 0 0;1=2
P 0.84 6.26 11 P 0 0;1=2
P 0.84 6.36 11 P 0 0;1=2
P 1.74 6.26 11 P 0 0;1=2
P 1.74 6.36 11 P 0 0;1=2
P 2.09606004 3.56615 6 P 0 0;1=3
P 8.1 3.56615 6 P 0 0;1=3
P 12.55905 3.38188996 11 P 0 0;1=1
P 12.81495 4.64173996 11 P 0 0;1=1
P 12.81495 1.88583002 11 P 0 0;1=1
P 0.35038996 4.60236998 11 P 0 0;1=1
P 0.35038996 2.55511998 11 P 0 0;1=1
P 0.35038996 1.84646004 11 P 0 0;1=1
P 0.09448996 3.34251998 11 P 0 0;1=1
P 6.385 5.03 5 P 0 0;1=4
P 12.68701998 0.97243996 17 P 0 0;1=5
P 0.22245 0.93306998 17 P 0 0;1=5
P 12.68701004 4.91338002 17 P 0 0;1=5
P 3.94 4.545 5 P 0 0;1=0
P 4.91 5.375 5 P 0 0;1=4
P 1.08 5.85 5 P 0 0;1=0
P 3.6817 5.74 5 P 0 0;1=4
P 10.07 2.928 5 P 0 0;1=4
P 4.105 4.985 5 P 0 0;1=0
P 4.125 2.725 5 P 0 0;1=4
P 4.02 4.355 5 P 0 0;1=0
P 1.16 5.85 5 P 0 0;1=0
P 3.815 5.815 5 P 0 0;1=4
P 1.19 6.36 27 P 0 3;1=6
P 1.19 6.26 27 P 0 3;1=6
P 1.415 6.36 27 P 0 3;1=6
P 1.415 6.26 27 P 0 3;1=6
P 1.64 6.36 27 P 0 3;1=6
P 1.64 6.26 27 P 0 3;1=6
P 0.965 6.26 27 P 0 3;1=6
P 0.965 6.36 27 P 0 3;1=6
P 0.74 6.26 27 P 0 3;1=6
P 0.74 6.36 27 P 0 3;1=6
P 12.63778996 1.37401998 11 P 0 0;1=7
P 0.17323002 1.33465 11 P 0 0;1=7
P 6.501 5.017 5 P 0 0;1=0
P 7.425 3.43 5 P 0 0;1=0
P 7.445 1.705 5 P 0 0;1=4
P 11.03661004 3.81615 6 P 0 0;1=3
P 11.135 2.845 5 P 0 0;1=4
P 11.03661004 2.16615 6 P 0 0;1=3
P 3.8899 4.765 5 P 0 0;1=0
P 4.93268002 2.41615 6 P 0 0;1=3
P 4.93268002 2.46615 6 P 0 0;1=3
P 7.2926 5.04351004 5 P 0 0;1=0
P 7.2426 5.04351004 5 P 0 0;1=0
P 3.45646004 5.3 5 P 0 0;1=0
P 1.28906004 5.04351004 5 P 0 0;1=0
P 1.23906004 5.04351004 5 P 0 0;1=0
P 9.46 5.3 5 P 0 0;1=0
P 4.68268002 2.36615 6 P 0 0;1=3
P 0.27165 4.01181004 11 P 0 0;1=1
P 4.58268002 2.36615 6 P 0 0;1=3
P 0.27165 4.16928996 11 P 0 0;1=1
P 4.63268002 2.41615 6 P 0 0;1=3
P 0.27165 4.32676998 11 P 0 0;1=1
P 4.73268002 2.26615 6 P 0 0;1=3
P 0.27165 3.38188996 11 P 0 0;1=1
P 4.73268002 2.41615 6 P 0 0;1=3
P 0.27165 4.48425 11 P 0 0;1=1
P 4.68268002 2.21615 6 P 0 0;1=3
P 0.27165 3.53936998 11 P 0 0;1=1
P 4.63268002 2.26615 6 P 0 0;1=3
P 0.27165 3.85433002 11 P 0 0;1=1
P 4.58268002 2.06615 6 P 0 0;1=3
P 0.35038996 3.02756004 11 P 0 0;1=1
P 4.58268002 2.11615 6 P 0 0;1=3
P 0.27165 2.98818996 11 P 0 0;1=1
P 4.63268002 1.86615 6 P 0 0;1=3
P 0.35038996 2.3189 11 P 0 0;1=1
P 4.58268002 1.96615 6 P 0 0;1=3
P 0.27165 2.43701004 11 P 0 0;1=1
P 4.68268002 2.06615 6 P 0 0;1=3
P 0.35038996 3.18503996 11 P 0 0;1=1
P 4.58268002 1.91615 6 P 0 0;1=3
P 0.35038996 2.47638002 11 P 0 0;1=1
P 0.27165 2.27953002 11 P 0 0;1=1
P 4.63268002 1.91615 6 P 0 0;1=3
P 5.42048002 1.7396 6 P 0 0;1=3
P 0.09448996 2.55511998 11 P 0 0;1=1
P 4.68268002 2.11615 6 P 0 0;1=3
P 0.27165 3.14566998 11 P 0 0;1=1
P 5.42048002 1.7796 6 P 0 0;1=3
P 0.17323002 2.51575 11 P 0 0;1=1
P 4.68268002 1.91615 6 P 0 0;1=3
P 0.35038996 2.16141998 11 P 0 0;1=1
P 4.68268002 1.96615 6 P 0 0;1=3
P 0.27165 2.12205 11 P 0 0;1=1
P 5.57531004 2.0878 6 P 0 0;1=3
P 0.09448996 3.1063 11 P 0 0;1=1
P 5.57531004 2.1278 6 P 0 0;1=3
P 0.17323002 3.06693002 11 P 0 0;1=1
P 5.57531004 2.2232 6 P 0 0;1=3
P 0.17323002 3.46063002 11 P 0 0;1=1
P 5.57531004 2.2632 6 P 0 0;1=3
P 0.09448996 3.42126004 11 P 0 0;1=1
P 5.42048002 2.4662 6 P 0 0;1=3
P 0.09448996 4.05118002 11 P 0 0;1=1
P 5.57531004 2.3986 6 P 0 0;1=3
P 0.09448996 3.8937 11 P 0 0;1=1
P 5.57531004 2.673 6 P 0 0;1=3
P 0.09448996 4.36613996 11 P 0 0;1=1
P 5.57531004 1.9869 6 P 0 0;1=3
P 0.17323002 2.75196998 11 P 0 0;1=1
P 5.57531004 2.4978 6 P 0 0;1=3
P 0.17323002 4.24803002 11 P 0 0;1=1
P 5.57531004 1.6718 6 P 0 0;1=3
P 0.17323002 2.20078996 11 P 0 0;1=1
P 5.57531004 2.633 6 P 0 0;1=3
P 0.17323002 4.40551004 11 P 0 0;1=1
P 5.57531004 1.7118 6 P 0 0;1=3
P 0.09448996 2.24016004 11 P 0 0;1=1
P 5.57531004 2.5378 6 P 0 0;1=3
P 0.09448996 4.20866004 11 P 0 0;1=1
P 5.42048002 1.6433 6 P 0 0;1=3
P 0.09448996 2.39763996 11 P 0 0;1=1
P 5.42048002 2.6054 6 P 0 0;1=3
P 0.09448996 4.52361998 11 P 0 0;1=1
P 5.42048002 1.87835 6 P 0 0;1=3
P 0.09448996 2.94881998 11 P 0 0;1=1
P 5.57531004 2.3586 6 P 0 0;1=3
P 0.17323002 3.93306998 11 P 0 0;1=1
P 5.42048002 1.6033 6 P 0 0;1=3
P 0.17323002 2.35826998 11 P 0 0;1=1
P 5.42048002 2.4262 6 P 0 0;1=3
P 0.17323002 4.09055 11 P 0 0;1=1
P 5.42048002 1.91835 6 P 0 0;1=3
P 0.17323002 2.90945 11 P 0 0;1=1
P 5.42048002 2.0547 6 P 0 0;1=3
P 0.17323002 3.22441004 11 P 0 0;1=1
P 5.57531004 1.9469 6 P 0 0;1=3
P 0.09448996 2.79133996 11 P 0 0;1=1
P 5.42048002 2.0147 6 P 0 0;1=3
P 0.09448996 3.26378002 11 P 0 0;1=1
P 5.57531004 1.8508 6 P 0 0;1=3
P 0.09448996 2.00393996 11 P 0 0;1=1
P 5.57531004 1.8108 6 P 0 0;1=3
P 0.17323002 2.04331004 11 P 0 0;1=1
P 0.35038996 3.97243996 11 P 0 0;1=1
P 4.68268002 2.41615 6 P 0 0;1=3
P 4.73268002 2.46615 6 P 0 0;1=3
P 0.35038996 4.44488002 11 P 0 0;1=1
P 4.63268002 2.46615 6 P 0 0;1=3
P 0.35038996 4.2874 11 P 0 0;1=1
P 0.35038996 4.12991998 11 P 0 0;1=1
P 4.58268002 2.41615 6 P 0 0;1=3
P 4.68268002 2.26615 6 P 0 0;1=3
P 0.35038996 3.5 11 P 0 0;1=1
P 5.42048002 2.1554 6 P 0 0;1=3
P 0.17323002 3.77558996 11 P 0 0;1=1
P 4.73268002 2.31615 6 P 0 0;1=3
P 0.35038996 3.34251998 11 P 0 0;1=1
P 4.63268002 2.31615 6 P 0 0;1=3
P 0.35038996 3.81496004 11 P 0 0;1=1
P 4.58268002 2.26615 6 P 0 0;1=3
P 0.35038996 3.65748002 11 P 0 0;1=1
P 5.42048002 2.5654 6 P 0 0;1=3
P 0.17323002 4.563 11 P 0 0;1=1
P 5.42048002 2.1954 6 P 0 0;1=3
P 0.09448996 3.73621998 11 P 0 0;1=1
P 0.09448996 3.57873996 11 P 0 0;1=1
P 5.42048002 2.3308 6 P 0 0;1=3
P 0.17323002 3.61811004 11 P 0 0;1=1
P 5.42048002 2.2908 6 P 0 0;1=3
P 0.35038996 1.9252 11 P 0 0;1=1
P 4.73268002 1.91615 6 P 0 0;1=3
P 4.73268002 1.86615 6 P 0 0;1=3
P 0.27165 1.96456998 11 P 0 0;1=1
P 4.58268002 2.21615 6 P 0 0;1=3
P 0.27165 3.69685 11 P 0 0;1=1
P 4.73268002 2.06615 6 P 0 0;1=3
P 0.27165 2.67323002 11 P 0 0;1=1
P 4.73268002 2.01615 6 P 0 0;1=3
P 0.35038996 2.7126 11 P 0 0;1=1
P 4.63268002 2.01615 6 P 0 0;1=3
P 0.35038996 2.87008002 11 P 0 0;1=1
P 4.63268002 2.06615 6 P 0 0;1=3
P 0.27165 2.83071004 11 P 0 0;1=1
P 6.785 4.725 5 P 0 0;1=4
P 6.785 4.685 5 P 0 0;1=4
P 6.74018996 4.765 5 P 0 0;1=4
P 6.74 4.805 5 P 0 0;1=0
P 6.785 4.845 5 P 0 0;1=4
P 6.785 4.805 5 P 0 0;1=4
P 6.785 4.765 5 P 0 0;1=4
P 6.74 4.845 5 P 0 0;1=4
P 6.65 5.055 5 P 0 0;1=0
P 6.49205 5.09705 5 P 0 0;1=0
P 6.495 4.9328 5 P 0 0;1=0
P 6.55118996 5.04705 5 P 0 0;1=0
P 6.78 4.94705 5 P 0 0;1=0
P 6.755 4.89705 5 P 0 0;1=0
P 6.74 4.987 5 P 0 0;1=0
P 12.73621004 2.08268002 11 P 0 0;1=1
P 12.73621004 2.63386004 11 P 0 0;1=1
P 12.81495 3.30315 11 P 0 0;1=1
P 12.73621004 4.60236998 11 P 0 0;1=1
P 12.55905 1.96456998 11 P 0 0;1=1
P 12.63778996 1.9252 11 P 0 0;1=1
P 0.09448996 1.9252 11 P 0 0;1=1
P 0.17323002 1.88583002 11 P 0 0;1=1
P 0.27165 2.04331004 11 P 0 0;1=1
P 0.27165 4.563 11 P 0 0;1=1
P 0.35038996 3.26378002 11 P 0 0;1=1
P 0.27165 2.59448996 11 P 0 0;1=1
P 0.17323002 1.72835 11 P 0 0;1=1
P 5.03268002 1.91615 6 P 0 0;1=3
P 1.025 -0.25 11 P 0 0;1=2
P 1.175 -0.25 11 P 0 0;1=2
P 1.325 -0.25 11 P 0 0;1=2
P 5.03268002 2.06615 6 P 0 0;1=3
P 12.63778996 4.12991998 11 P 0 0;1=1
P 11.53316004 2.372 6 P 0 0;1=3
P 5.08268002 2.26615 6 P 0 0;1=3
P 11.53316004 1.892 6 P 0 0;1=3
P 12.55905 3.30315 11 P 0 0;1=1
P 12.81495 2.51575 11 P 0 0;1=1
P 10.58661004 1.91615 6 P 0 0;1=3
P 10.26 1.66445 6 P 0 0;1=3
P 11.03998996 4.8431 5 P 0 0;1=4
P 11.08498996 4.8431 5 P 0 0;1=4
P 11.13498996 4.8431 5 P 0 0;1=4
P 11.17998996 4.8431 5 P 0 0;1=4
P 11.17998996 4.8031 5 P 0 0;1=4
P 11.17998996 4.7581 5 P 0 0;1=4
P 11.17998996 4.7131 5 P 0 0;1=4
P 11.17998996 4.6731 5 P 0 0;1=4
P 11.03998996 4.6731 5 P 0 0;1=4
P 11.08498996 4.6731 5 P 0 0;1=4
P 11.13498996 4.6731 5 P 0 0;1=4
P 11.03998996 4.7131 5 P 0 0;1=4
P 11.03998996 4.8031 5 P 0 0;1=4
P 11.03998996 4.7581 5 P 0 0;1=4
P 10.81998996 4.6631 5 P 0 0;1=4
P 10.85998996 4.6631 5 P 0 0;1=4
P 10.65998996 4.6631 5 P 0 0;1=4
P 10.69998996 4.6631 5 P 0 0;1=4
P 10.81998996 4.7031 5 P 0 0;1=4
P 10.81998996 4.8381 5 P 0 0;1=4
P 10.81998996 4.7931 5 P 0 0;1=4
P 10.81998996 4.7481 5 P 0 0;1=4
P 10.85998996 4.7031 5 P 0 0;1=4
P 10.85998996 4.8381 5 P 0 0;1=4
P 10.85998996 4.7931 5 P 0 0;1=4
P 10.85998996 4.7481 5 P 0 0;1=4
P 10.65998996 4.7031 5 P 0 0;1=4
P 10.65998996 4.8381 5 P 0 0;1=4
P 10.65998996 4.7931 5 P 0 0;1=4
P 10.65998996 4.7481 5 P 0 0;1=4
P 10.69998996 4.7031 5 P 0 0;1=4
P 10.69998996 4.8381 5 P 0 0;1=4
P 10.69998996 4.7931 5 P 0 0;1=4
P 10.69998996 4.7481 5 P 0 0;1=4
P 10.77998996 4.6431 5 P 0 0;1=4
P 10.73498996 4.6431 5 P 0 0;1=4
P 10.73998996 4.8381 5 P 0 0;1=4
P 10.77998996 4.8381 5 P 0 0;1=4
P 10.30998996 4.6631 5 P 0 0;1=4
P 10.26998996 4.6631 5 P 0 0;1=4
P 10.34498996 4.6431 5 P 0 0;1=4
P 10.38998996 4.6431 5 P 0 0;1=4
P 10.42998996 4.6631 5 P 0 0;1=4
P 10.46998996 4.6631 5 P 0 0;1=4
P 10.30998996 4.7481 5 P 0 0;1=4
P 10.30998996 4.7931 5 P 0 0;1=4
P 10.30998996 4.7031 5 P 0 0;1=4
P 10.26998996 4.7481 5 P 0 0;1=4
P 10.26998996 4.7931 5 P 0 0;1=4
P 10.26998996 4.7031 5 P 0 0;1=4
P 10.26998996 4.8381 5 P 0 0;1=4
P 10.30998996 4.8381 5 P 0 0;1=4
P 10.38998996 4.8381 5 P 0 0;1=4
P 10.34998996 4.8381 5 P 0 0;1=4
P 10.46998996 4.8381 5 P 0 0;1=4
P 10.42998996 4.8381 5 P 0 0;1=4
P 10.42998996 4.7031 5 P 0 0;1=4
P 10.42998996 4.7931 5 P 0 0;1=4
P 10.42998996 4.7481 5 P 0 0;1=4
P 10.46998996 4.7031 5 P 0 0;1=4
P 10.46998996 4.7931 5 P 0 0;1=4
P 10.46998996 4.7481 5 P 0 0;1=4
P 10.58661004 3.16615 6 P 0 0;1=3
P 10.63661004 3.01615 6 P 0 0;1=3
P 10.58661004 3.11615 6 P 0 0;1=3
P 10.58661004 3.01615 6 P 0 0;1=3
P 10.63661004 3.11615 6 P 0 0;1=3
P 10.63661004 2.96615 6 P 0 0;1=3
P 10.58661004 2.96615 6 P 0 0;1=3
P 10.58661004 3.41615 6 P 0 0;1=3
P 10.63661004 3.16615 6 P 0 0;1=3
P 10.63661004 3.26615 6 P 0 0;1=3
P 10.58661004 3.31615 6 P 0 0;1=3
P 10.58661004 3.26615 6 P 0 0;1=3
P 10.63661004 3.31615 6 P 0 0;1=3
P 10.63661004 3.56615 6 P 0 0;1=3
P 10.63661004 3.61615 6 P 0 0;1=3
P 10.58661004 3.56615 6 P 0 0;1=3
P 10.58661004 3.61615 6 P 0 0;1=3
P 10.63661004 3.46615 6 P 0 0;1=3
P 10.63661004 3.41615 6 P 0 0;1=3
P 10.58661004 3.46615 6 P 0 0;1=3
P 10.63661004 3.86615 6 P 0 0;1=3
P 10.63661004 3.76615 6 P 0 0;1=3
P 10.58661004 3.86615 6 P 0 0;1=3
P 10.58661004 3.76615 6 P 0 0;1=3
P 10.63661004 3.71615 6 P 0 0;1=3
P 10.58661004 3.71615 6 P 0 0;1=3
P 10.88661004 2.96615 6 P 0 0;1=3
P 10.83661004 2.96615 6 P 0 0;1=3
P 10.88661004 3.01615 6 P 0 0;1=3
P 10.83661004 3.01615 6 P 0 0;1=3
P 10.88661004 3.11615 6 P 0 0;1=3
P 10.83661004 3.11615 6 P 0 0;1=3
P 10.83661004 3.16615 6 P 0 0;1=3
P 10.78661004 3.16615 6 P 0 0;1=3
P 10.68661004 3.16615 6 P 0 0;1=3
P 10.73661004 3.16615 6 P 0 0;1=3
P 10.78661004 3.01615 6 P 0 0;1=3
P 10.78661004 3.11615 6 P 0 0;1=3
P 10.73661004 3.01615 6 P 0 0;1=3
P 10.73661004 3.11615 6 P 0 0;1=3
P 10.68661004 3.01615 6 P 0 0;1=3
P 10.68661004 3.11615 6 P 0 0;1=3
P 10.78661004 2.96615 6 P 0 0;1=3
P 10.73661004 2.96615 6 P 0 0;1=3
P 10.68661004 2.96615 6 P 0 0;1=3
P 10.88661004 3.16615 6 P 0 0;1=3
P 10.88661004 3.26615 6 P 0 0;1=3
P 10.83661004 3.26615 6 P 0 0;1=3
P 10.83661004 3.31615 6 P 0 0;1=3
P 10.88661004 3.31615 6 P 0 0;1=3
P 10.83661004 3.41615 6 P 0 0;1=3
P 10.78661004 3.41615 6 P 0 0;1=3
P 10.68661004 3.41615 6 P 0 0;1=3
P 10.73661004 3.41615 6 P 0 0;1=3
P 10.78661004 3.31615 6 P 0 0;1=3
P 10.78661004 3.26615 6 P 0 0;1=3
P 10.68661004 3.31615 6 P 0 0;1=3
P 10.68661004 3.26615 6 P 0 0;1=3
P 10.73661004 3.26615 6 P 0 0;1=3
P 10.73661004 3.31615 6 P 0 0;1=3
P 10.88661004 3.41615 6 P 0 0;1=3
P 10.83661004 3.46615 6 P 0 0;1=3
P 10.88661004 3.46615 6 P 0 0;1=3
P 10.83661004 3.56615 6 P 0 0;1=3
P 10.88661004 3.56615 6 P 0 0;1=3
P 10.83661004 3.61615 6 P 0 0;1=3
P 10.88661004 3.61615 6 P 0 0;1=3
P 10.78661004 3.56615 6 P 0 0;1=3
P 10.78661004 3.61615 6 P 0 0;1=3
P 10.68661004 3.61615 6 P 0 0;1=3
P 10.68661004 3.56615 6 P 0 0;1=3
P 10.73661004 3.61615 6 P 0 0;1=3
P 10.73661004 3.56615 6 P 0 0;1=3
P 10.78661004 3.46615 6 P 0 0;1=3
P 10.73661004 3.46615 6 P 0 0;1=3
P 10.68661004 3.46615 6 P 0 0;1=3
P 10.83661004 3.71615 6 P 0 0;1=3
P 10.88661004 3.71615 6 P 0 0;1=3
P 10.83661004 3.76615 6 P 0 0;1=3
P 10.88661004 3.76615 6 P 0 0;1=3
P 10.83661004 3.86615 6 P 0 0;1=3
P 10.88661004 3.86615 6 P 0 0;1=3
P 10.78661004 3.86615 6 P 0 0;1=3
P 10.78661004 3.76615 6 P 0 0;1=3
P 10.68661004 3.86615 6 P 0 0;1=3
P 10.68661004 3.76615 6 P 0 0;1=3
P 10.73661004 3.86615 6 P 0 0;1=3
P 10.73661004 3.76615 6 P 0 0;1=3
P 10.78661004 3.71615 6 P 0 0;1=3
P 10.68661004 3.71615 6 P 0 0;1=3
P 10.73661004 3.71615 6 P 0 0;1=3
P 11.03661004 2.96615 6 P 0 0;1=3
P 10.93661004 2.96615 6 P 0 0;1=3
P 10.98661004 2.96615 6 P 0 0;1=3
P 11.03661004 3.01615 6 P 0 0;1=3
P 10.93661004 3.01615 6 P 0 0;1=3
P 10.98661004 3.01615 6 P 0 0;1=3
P 11.03661004 3.11615 6 P 0 0;1=3
P 10.93661004 3.11615 6 P 0 0;1=3
P 10.98661004 3.11615 6 P 0 0;1=3
P 11.03661004 3.16615 6 P 0 0;1=3
P 10.93661004 3.16615 6 P 0 0;1=3
P 10.98661004 3.16615 6 P 0 0;1=3
P 11.03661004 3.26615 6 P 0 0;1=3
P 10.93661004 3.26615 6 P 0 0;1=3
P 10.98661004 3.26615 6 P 0 0;1=3
P 10.98661004 3.31615 6 P 0 0;1=3
P 10.93661004 3.31615 6 P 0 0;1=3
P 11.03661004 3.31615 6 P 0 0;1=3
P 10.98661004 3.41615 6 P 0 0;1=3
P 10.93661004 3.41615 6 P 0 0;1=3
P 11.03661004 3.41615 6 P 0 0;1=3
P 10.98661004 3.46615 6 P 0 0;1=3
P 10.93661004 3.46615 6 P 0 0;1=3
P 11.03661004 3.46615 6 P 0 0;1=3
P 10.98661004 3.56615 6 P 0 0;1=3
P 10.93661004 3.56615 6 P 0 0;1=3
P 11.03661004 3.56615 6 P 0 0;1=3
P 10.98661004 3.61615 6 P 0 0;1=3
P 10.93661004 3.61615 6 P 0 0;1=3
P 11.03661004 3.61615 6 P 0 0;1=3
P 10.98661004 3.71615 6 P 0 0;1=3
P 10.93661004 3.71615 6 P 0 0;1=3
P 11.03661004 3.71615 6 P 0 0;1=3
P 10.98661004 3.76615 6 P 0 0;1=3
P 10.93661004 3.76615 6 P 0 0;1=3
P 11.03661004 3.76615 6 P 0 0;1=3
P 10.98661004 3.86615 6 P 0 0;1=3
P 10.93661004 3.86615 6 P 0 0;1=3
P 11.03661004 3.86615 6 P 0 0;1=3
P 5.08268002 2.06615 6 P 0 0;1=3
P 10.58661004 2.36615 6 P 0 0;1=3
P 9.975 2.4709 6 P 0 0;1=3
P 12.73621004 4.20866004 11 P 0 0;1=1
P 11.08661004 2.36615 6 P 0 0;1=3
P 5.08268002 2.11615 6 P 0 0;1=3
P 11.08661004 2.41615 6 P 0 0;1=3
P 12.73621004 2.47638002 11 P 0 0;1=1
P 10.58661004 1.96615 6 P 0 0;1=3
P 10.26 1.70445 6 P 0 0;1=3
P 10.98661004 2.41615 6 P 0 0;1=3
P 8.5 3.76615 6 P 0 0;1=3
P 9.35271004 5.1035 6 P 0 0;1=3
P 4.98268002 2.06615 6 P 0 0;1=3
P 8.5 3.81615 6 P 0 0;1=3
P 9.31271004 5.1035 6 P 0 0;1=3
P 12.55905 2.59448996 11 P 0 0;1=1
P 11.53316004 1.572 6 P 0 0;1=3
P 4.98268002 2.11615 6 P 0 0;1=3
P 10.98661004 2.36615 6 P 0 0;1=3
P 8.5 3.61615 6 P 0 0;1=3
P 9.56531004 5.14 6 P 0 0;1=3
P 4.93268002 2.01615 6 P 0 0;1=3
P 11.53316004 1.412 6 P 0 0;1=3
P 12.63778996 2.39763996 11 P 0 0;1=1
P 8.5 3.66615 6 P 0 0;1=3
P 9.52531004 5.14 6 P 0 0;1=3
P 12.73621004 2.87008002 11 P 0 0;1=1
P 10.63661004 2.06615 6 P 0 0;1=3
P 10.225 1.96645 6 P 0 0;1=3
P 11.53316004 1.452 6 P 0 0;1=3
P 12.55905 2.43701004 11 P 0 0;1=1
P 8.35 3.66615 6 P 0 0;1=3
P 9.56531004 4.71973002 6 P 0 0;1=3
P 4.93268002 2.06615 6 P 0 0;1=3
P 8.35 3.71615 6 P 0 0;1=3
P 9.52531004 4.71973002 6 P 0 0;1=3
P 11.83316004 2.212 6 P 0 0;1=3
P 12.63778996 3.65748002 11 P 0 0;1=1
P 12.73621004 3.02756004 11 P 0 0;1=1
P 10.58661004 2.11615 6 P 0 0;1=3
P 10.09 2.05655 6 P 0 0;1=3
P 11.53316004 1.932 6 P 0 0;1=3
P 12.63778996 3.26378002 11 P 0 0;1=1
P 8.74578996 5.14 6 P 0 0;1=3
P 8.05 3.61615 6 P 0 0;1=3
P 12.81495 4.01181004 11 P 0 0;1=1
P 10.09 2.57845 6 P 0 0;1=3
P 10.68661004 2.41615 6 P 0 0;1=3
P 11.73316004 1.492 6 P 0 0;1=3
P 12.63778996 2.24016004 11 P 0 0;1=1
P 8.78578996 5.14 6 P 0 0;1=3
P 8.05 3.66615 6 P 0 0;1=3
P 12.73621004 2.7126 11 P 0 0;1=1
P 10.73661004 2.06615 6 P 0 0;1=3
P 10.26025 1.86845 6 P 0 0;1=3
P 11.03661004 2.46615 6 P 0 0;1=3
P 8.15 3.61615 6 P 0 0;1=3
P 8.88441004 5.17001998 6 P 0 0;1=3
P 12.55905 4.09055 11 P 0 0;1=1
P 11.53316004 2.412 6 P 0 0;1=3
P 11.03661004 2.51615 6 P 0 0;1=3
P 8.15 3.66615 6 P 0 0;1=3
P 8.92441004 5.17001998 6 P 0 0;1=3
P 1.057 5.027 5 P 0 0;1=0
P 12.73621004 3.18503996 11 P 0 0;1=1
P 10.68661004 2.11615 6 P 0 0;1=3
P 10.09 2.17095 6 P 0 0;1=3
P 11.78316004 1.692 6 P 0 0;1=3
P 12.55905 2.04331004 11 P 0 0;1=1
P 12.81495 2.90945 11 P 0 0;1=1
P 10.63661004 2.01615 6 P 0 0;1=3
P 10.225 1.92645 6 P 0 0;1=3
P 11.78316004 1.652 6 P 0 0;1=3
P 12.63778996 2.08268002 11 P 0 0;1=1
P 1.122 5.417 5 P 0 0;1=4
P 5.855 0.925 5 P 0 0;1=4
P 3.88 4.545 5 P 0 0;1=0
P 0.96555 5.78055 5 P 0 0;1=0
P 4.07 4.625 5 P 0 0;1=4
P 10.58661004 2.71615 6 P 0 0;1=3
P 9.91 4.433 5 P 0 0;1=0
P 9.995 2.936 5 P 0 0;1=4
P 11.83316004 2.252 6 P 0 0;1=3
P 12.55905 3.61811004 11 P 0 0;1=1
P 12.81495 3.06693002 11 P 0 0;1=1
P 10.58661004 2.06615 6 P 0 0;1=3
P 10.09 2.01655 6 P 0 0;1=3
P 8.1 3.81615 6 P 0 0;1=3
P 9.10011004 5.0535 6 P 0 0;1=3
P 8.1 3.86615 6 P 0 0;1=3
P 9.14011004 5.0535 6 P 0 0;1=3
P 3.9599 5.395 5 P 0 0;1=0
P 0.88681004 5.78181004 5 P 0 0;1=4
P 12.73621004 2.3189 11 P 0 0;1=1
P 10.63661004 1.91615 6 P 0 0;1=3
P 10.38371998 1.49328002 6 P 0 0;1=3
P 8.35 3.81615 6 P 0 0;1=3
P 9.28185 5.22001998 6 P 0 0;1=3
P 0.72933002 5.463 5 P 0 0;1=0
P 11.53316004 2.572 6 P 0 0;1=3
P 12.55905 4.56298996 11 P 0 0;1=1
P 8.35 3.86615 6 P 0 0;1=3
P 9.24185 5.22001998 6 P 0 0;1=3
P 4.125 2.682 5 P 0 0;1=4
P 3.94 4.42 5 P 0 0;1=0
P 5.03 5.4 5 P 0 0;1=4
P 4.58268002 2.71615 6 P 0 0;1=3
P 8.45 3.81615 6 P 0 0;1=3
P 9.21098002 4.78291998 6 P 0 0;1=3
P 8.45 3.86615 6 P 0 0;1=3
P 9.17098002 4.78291998 6 P 0 0;1=3
P 3.75998996 0.24001004 5 P 0 0;1=0
P 9.55795 0.26133996 5 P 0 0;1=0
P 3.71203002 0.77535 5 P 0 0;1=4
P 3.70998996 0.7 5 P 0 0;1=4
P 9.50795 0.72133002 5 P 0 0;1=4
P 9.46795 0.82631998 5 P 0 0;1=4
P 4.02893002 2.59336998 5 P 0 0;1=4
P 11.395 2.725 5 P 0 0;1=0
P 11.395 2.8 5 P 0 0;1=4
P 11.58613002 2.905 5 P 0 0;1=4
P 11.58613002 2.785 5 P 0 0;1=4
P 1.33906004 4.60351004 5 P 0 0;1=0
P 3.67 4.45 5 P 0 0;1=4
P 3.72 4.545 5 P 0 0;1=4
P 5.37968996 2.8 5 P 0 0;1=4
P 5.387 2.725 5 P 0 0;1=0
P 5.5822 2.785 5 P 0 0;1=4
P 5.5822 2.905 5 P 0 0;1=4
P 7.2426 4.69351004 5 P 0 0;1=4
P 7.2926 4.60351004 5 P 0 0;1=4
P 9.98 4.51 5 P 0 0;1=4
P 10.07286004 2.82336998 5 P 0 0;1=4
P 10.03 4.61 5 P 0 0;1=4
P 1.23906004 4.69351004 5 P 0 0;1=4
P 3.89 4.655 5 P 0 0;1=4
P 3.9899 4.765 5 P 0 0;1=4
P 4.1049 4.86 5 P 0 0;1=4
P 4.0599 5.395 5 P 0 0;1=4
P 3.91 5.51 5 P 0 0;1=4
P 5.125 5.4 5 P 0 0;1=4
P 1.37925 5.78 5 P 0 0;1=4
P 1.45798996 5.78 5 P 0 0;1=4
P 1.42 5.78 5 P 0 0;1=4
P 1.335 5.78 5 P 0 0;1=4
P 12.63778996 2.55511998 11 P 0 0;1=1
P 11.53316004 1.612 6 P 0 0;1=3
P 8.4 3.76615 6 P 0 0;1=3
P 9.28185 4.642 6 P 0 0;1=3
P 12.73621004 4.36613996 11 P 0 0;1=1
P 10.63661004 2.41615 6 P 0 0;1=3
P 9.975 2.66445 6 P 0 0;1=3
P 8.4 3.81615 6 P 0 0;1=3
P 9.24185 4.642 6 P 0 0;1=3
P 11.53316004 2.532 6 P 0 0;1=3
P 12.63778996 4.60236998 11 P 0 0;1=1
P 8.45 3.66615 6 P 0 0;1=3
P 9.42358002 4.78291998 6 P 0 0;1=3
P 0.95951004 5.4595 5 P 0 0;1=0
P 8.45 3.71615 6 P 0 0;1=3
P 9.38358002 4.78291998 6 P 0 0;1=3
P 8.4 3.61615 6 P 0 0;1=3
P 9.49445 4.587 6 P 0 0;1=3
P 8.4 3.66615 6 P 0 0;1=3
P 9.45445 4.587 6 P 0 0;1=3
P 9.07353996 4.42 5 P 0 0;1=4
P 7.1926 5.15351004 5 P 0 0;1=0
P 8.1 3.66615 6 P 0 0;1=3
P 8.74578996 4.667 6 P 0 0;1=3
P 8.1 3.71615 6 P 0 0;1=3
P 8.78578996 4.667 6 P 0 0;1=3
P 8.2 3.66615 6 P 0 0;1=3
P 8.81665 4.78291998 6 P 0 0;1=3
P 8.2 3.71615 6 P 0 0;1=3
P 8.85665 4.78291998 6 P 0 0;1=3
P 8.05 3.76615 6 P 0 0;1=3
P 8.89061998 4.667 6 P 0 0;1=3
P 8.05 3.81615 6 P 0 0;1=3
P 8.93061998 4.667 6 P 0 0;1=3
P 9.02925 4.667 6 P 0 0;1=3
P 8.2 3.81615 6 P 0 0;1=3
P 9.06925 4.667 6 P 0 0;1=3
P 8.2 3.86615 6 P 0 0;1=3
P 4.68268002 2.71615 6 P 0 0;1=3
P 4.98268002 2.71615 6 P 0 0;1=3
P 2.14606004 2.51615 6 P 0 0;1=3
P 8.45 3.41615 6 P 0 0;1=3
P 8.18811004 5.0535 6 P 0 0;1=3
P 5.03268002 3.81615 6 P 0 0;1=3
P 4.07408002 4.01978996 5 P 0 0;1=0
P 8.45 3.46615 6 P 0 0;1=3
P 8.14811004 5.0535 6 P 0 0;1=3
P 5.03268002 2.16615 6 P 0 0;1=3
P 3.9099 5.395 5 P 0 0;1=0
P 8.45 3.26615 6 P 0 0;1=3
P 8.40071004 5.115 6 P 0 0;1=3
P 8.45 3.31615 6 P 0 0;1=3
P 8.36071004 5.115 6 P 0 0;1=3
P 8.35 3.26615 6 P 0 0;1=3
P 8.40071004 4.742 6 P 0 0;1=3
P 8.35 3.31615 6 P 0 0;1=3
P 8.36071004 4.742 6 P 0 0;1=3
P 8.3 3.56615 6 P 0 0;1=3
P 8.05 3.31615 6 P 0 0;1=3
P 7.58118996 5.169 6 P 0 0;1=3
P 8.25 3.56615 6 P 0 0;1=3
P 8.05 3.36615 6 P 0 0;1=3
P 7.62118996 5.169 6 P 0 0;1=3
P 2.24606004 2.86615 6 P 0 0;1=3
P 8.05 2.61615 25 P 0 0;1=3
P 8.05 2.66615 25 P 0 0;1=3
P 8.1 2.46615 25 P 0 0;1=3
P 8.1 2.41615 25 P 0 0;1=3
P 8.2 2.46615 25 P 0 0;1=3
P 8.2 2.41615 25 P 0 0;1=3
P 8.15 2.41615 25 P 0 0;1=3
P 8.15 2.36615 25 P 0 0;1=3
P 8.05 2.41615 25 P 0 0;1=3
P 8.05 2.36615 25 P 0 0;1=3
P 8.2 2.31615 25 P 0 0;1=3
P 8.2 2.26615 25 P 0 0;1=3
P 8.15 2.26615 25 P 0 0;1=3
P 8.15 2.21615 25 P 0 0;1=3
P 8.1 2.31615 25 P 0 0;1=3
P 8.1 2.26615 25 P 0 0;1=3
P 8.05 2.26615 25 P 0 0;1=3
P 8.05 2.21615 25 P 0 0;1=3
P 8.1 2.11615 25 P 0 0;1=3
P 8.1 2.06615 25 P 0 0;1=3
P 8.2 2.11615 25 P 0 0;1=3
P 8.2 2.06615 25 P 0 0;1=3
P 8.15 2.06615 25 P 0 0;1=3
P 8.15 2.01615 25 P 0 0;1=3
P 8.05 2.06615 25 P 0 0;1=3
P 8.05 2.01615 25 P 0 0;1=3
P 8.2 1.96615 25 P 0 0;1=3
P 8.2 1.91615 25 P 0 0;1=3
P 8.15 1.91615 25 P 0 0;1=3
P 8.15 1.86615 25 P 0 0;1=3
P 8.1 1.96615 25 P 0 0;1=3
P 8.1 1.91615 25 P 0 0;1=3
P 8.05 1.91615 25 P 0 0;1=3
P 8.05 1.86615 25 P 0 0;1=3
P 8.1 3.16615 25 P 0 0;1=3
P 8.1 3.11615 25 P 0 0;1=3
P 8.2 3.16615 25 P 0 0;1=3
P 8.2 3.11615 25 P 0 0;1=3
P 8.15 3.11615 25 P 0 0;1=3
P 8.15 3.06615 25 P 0 0;1=3
P 8.05 3.11615 25 P 0 0;1=3
P 8.05 3.06615 25 P 0 0;1=3
P 8.2 3.01615 25 P 0 0;1=3
P 8.2 2.96615 25 P 0 0;1=3
P 8.15 2.96615 25 P 0 0;1=3
P 8.15 2.91615 25 P 0 0;1=3
P 8.1 3.01615 25 P 0 0;1=3
P 8.1 2.96615 25 P 0 0;1=3
P 8.05 2.96615 25 P 0 0;1=3
P 8.05 2.91615 25 P 0 0;1=3
P 8 2.81615 25 P 0 0;1=3
P 8 2.76615 25 P 0 0;1=3
P 8.15 2.81615 25 P 0 0;1=3
P 8.15 2.76615 25 P 0 0;1=3
P 8.2 2.76615 25 P 0 0;1=3
P 8.2 2.71615 25 P 0 0;1=3
P 8.1 2.76615 25 P 0 0;1=3
P 8.1 2.71615 25 P 0 0;1=3
P 8.15 2.66615 25 P 0 0;1=3
P 8.15 2.61615 25 P 0 0;1=3
P 8.2 2.61615 25 P 0 0;1=3
P 8.2 2.56615 25 P 0 0;1=3
P 8.1 2.61615 25 P 0 0;1=3
P 8.1 2.56615 25 P 0 0;1=3
P 8.35 2.56615 25 P 0 0;1=3
P 8.35 2.61615 25 P 0 0;1=3
P 8.35 2.46615 25 P 0 0;1=3
P 8.35 2.41615 25 P 0 0;1=3
P 8.45 2.46615 25 P 0 0;1=3
P 8.45 2.41615 25 P 0 0;1=3
P 8.5 2.41615 25 P 0 0;1=3
P 8.5 2.36615 25 P 0 0;1=3
P 8.4 2.41615 25 P 0 0;1=3
P 8.4 2.36615 25 P 0 0;1=3
P 8.45 2.31615 25 P 0 0;1=3
P 8.45 2.26615 25 P 0 0;1=3
P 8.5 2.26615 25 P 0 0;1=3
P 8.5 2.21615 25 P 0 0;1=3
P 8.4 2.26615 25 P 0 0;1=3
P 8.4 2.21615 25 P 0 0;1=3
P 8.35 2.31615 25 P 0 0;1=3
P 8.35 2.26615 25 P 0 0;1=3
P 8.35 2.11615 25 P 0 0;1=3
P 8.35 2.06615 25 P 0 0;1=3
P 8.45 2.11615 25 P 0 0;1=3
P 8.45 2.06615 25 P 0 0;1=3
P 8.5 2.06615 25 P 0 0;1=3
P 8.5 2.01615 25 P 0 0;1=3
P 8.4 2.06615 25 P 0 0;1=3
P 8.4 2.01615 25 P 0 0;1=3
P 8.45 1.96615 25 P 0 0;1=3
P 8.45 1.91615 25 P 0 0;1=3
P 8.5 1.91615 25 P 0 0;1=3
P 8.5 1.86615 25 P 0 0;1=3
P 8.4 1.91615 25 P 0 0;1=3
P 8.4 1.86615 25 P 0 0;1=3
P 8.35 1.96615 25 P 0 0;1=3
P 8.35 1.91615 25 P 0 0;1=3
P 8.35 3.16615 25 P 0 0;1=3
P 8.35 3.11615 25 P 0 0;1=3
P 8.45 3.16615 25 P 0 0;1=3
P 8.45 3.11615 25 P 0 0;1=3
P 8.5 3.11615 25 P 0 0;1=3
P 8.5 3.06615 25 P 0 0;1=3
P 8.4 3.11615 25 P 0 0;1=3
P 8.4 3.06615 25 P 0 0;1=3
P 8.45 3.01615 25 P 0 0;1=3
P 8.45 2.96615 25 P 0 0;1=3
P 8.5 2.96615 25 P 0 0;1=3
P 8.5 2.91615 25 P 0 0;1=3
P 8.4 2.96615 25 P 0 0;1=3
P 8.4 2.91615 25 P 0 0;1=3
P 8.35 3.01615 25 P 0 0;1=3
P 8.35 2.96615 25 P 0 0;1=3
P 8.4 2.81615 25 P 0 0;1=3
P 8.4 2.76615 25 P 0 0;1=3
P 8.5 2.81615 25 P 0 0;1=3
P 8.5 2.76615 25 P 0 0;1=3
P 8.45 2.76615 25 P 0 0;1=3
P 8.45 2.71615 25 P 0 0;1=3
P 8.35 2.76615 25 P 0 0;1=3
P 8.35 2.71615 25 P 0 0;1=3
P 8.5 2.66615 25 P 0 0;1=3
P 8.5 2.61615 25 P 0 0;1=3
P 8.45 2.61615 25 P 0 0;1=3
P 8.45 2.56615 25 P 0 0;1=3
P 8.4 2.66615 25 P 0 0;1=3
P 8.4 2.61615 25 P 0 0;1=3
P 2.04606024 2.61615 25 P 0 0;1=3
P 2.04606024 2.66615 25 P 0 0;1=3
P 2.09606024 2.46615 25 P 0 0;1=3
P 2.09606024 2.41615 25 P 0 0;1=3
P 2.19606024 2.46615 25 P 0 0;1=3
P 2.19606024 2.41615 25 P 0 0;1=3
P 2.14606024 2.41615 25 P 0 0;1=3
P 2.14606024 2.36615 25 P 0 0;1=3
P 2.04606024 2.41615 25 P 0 0;1=3
P 2.04606024 2.36615 25 P 0 0;1=3
P 2.19606024 2.31615 25 P 0 0;1=3
P 2.19606024 2.26615 25 P 0 0;1=3
P 2.14606024 2.26615 25 P 0 0;1=3
P 2.14606024 2.21615 25 P 0 0;1=3
P 2.09606024 2.31615 25 P 0 0;1=3
P 2.09606024 2.26615 25 P 0 0;1=3
P 2.04606024 2.26615 25 P 0 0;1=3
P 2.04606024 2.21615 25 P 0 0;1=3
P 2.09606024 2.11615 25 P 0 0;1=3
P 2.09606024 2.06615 25 P 0 0;1=3
P 2.19606024 2.11615 25 P 0 0;1=3
P 2.19606024 2.06615 25 P 0 0;1=3
P 2.14606024 2.06615 25 P 0 0;1=3
P 2.14606024 2.01615 25 P 0 0;1=3
P 2.04606024 2.06615 25 P 0 0;1=3
P 2.04606024 2.01615 25 P 0 0;1=3
P 2.19606024 1.96615 25 P 0 0;1=3
P 2.19606024 1.91615 25 P 0 0;1=3
P 2.14606024 1.91615 25 P 0 0;1=3
P 2.14606024 1.86615 25 P 0 0;1=3
P 2.09606024 1.96615 25 P 0 0;1=3
P 2.09606024 1.91615 25 P 0 0;1=3
P 2.04606024 1.91615 25 P 0 0;1=3
P 2.04606024 1.86615 25 P 0 0;1=3
P 2.09606024 3.16615 25 P 0 0;1=3
P 2.09606024 3.11615 25 P 0 0;1=3
P 2.19606024 3.16615 25 P 0 0;1=3
P 2.19606024 3.11615 25 P 0 0;1=3
P 2.14606024 3.11615 25 P 0 0;1=3
P 2.14606024 3.06615 25 P 0 0;1=3
P 2.04606024 3.11615 25 P 0 0;1=3
P 2.04606024 3.06615 25 P 0 0;1=3
P 2.19606024 3.01615 25 P 0 0;1=3
P 2.19606024 2.96615 25 P 0 0;1=3
P 2.14606024 2.96615 25 P 0 0;1=3
P 2.14606024 2.91615 25 P 0 0;1=3
P 2.09606024 3.01615 25 P 0 0;1=3
P 2.09606024 2.96615 25 P 0 0;1=3
P 2.04606024 2.96615 25 P 0 0;1=3
P 2.04606024 2.91615 25 P 0 0;1=3
P 1.99605974 2.81615 25 P 0 0;1=3
P 1.99605974 2.76615 25 P 0 0;1=3
P 2.14606024 2.81615 25 P 0 0;1=3
P 2.14606024 2.76615 25 P 0 0;1=3
P 2.19606024 2.76615 25 P 0 0;1=3
P 2.19606024 2.71615 25 P 0 0;1=3
P 2.09606024 2.76615 25 P 0 0;1=3
P 2.09606024 2.71615 25 P 0 0;1=3
P 2.14606024 2.66615 25 P 0 0;1=3
P 2.14606024 2.61615 25 P 0 0;1=3
P 2.19606024 2.61615 25 P 0 0;1=3
P 2.19606024 2.56615 25 P 0 0;1=3
P 2.09606024 2.61615 25 P 0 0;1=3
P 2.09606024 2.56615 25 P 0 0;1=3
P 2.34606024 2.56615 25 P 0 0;1=3
P 2.34606024 2.61615 25 P 0 0;1=3
P 2.34606024 2.46615 25 P 0 0;1=3
P 2.34606024 2.41615 25 P 0 0;1=3
P 2.44606024 2.46615 25 P 0 0;1=3
P 2.44606024 2.41615 25 P 0 0;1=3
P 2.49606024 2.41615 25 P 0 0;1=3
P 2.49606024 2.36615 25 P 0 0;1=3
P 2.39606024 2.41615 25 P 0 0;1=3
P 2.39606024 2.36615 25 P 0 0;1=3
P 2.44606024 2.31615 25 P 0 0;1=3
P 2.44606024 2.26615 25 P 0 0;1=3
P 2.49606024 2.26615 25 P 0 0;1=3
P 2.49606024 2.21615 25 P 0 0;1=3
P 2.39606024 2.26615 25 P 0 0;1=3
P 2.39606024 2.21615 25 P 0 0;1=3
P 2.34606024 2.31615 25 P 0 0;1=3
P 2.34606024 2.26615 25 P 0 0;1=3
P 2.34606024 2.11615 25 P 0 0;1=3
P 2.34606024 2.06615 25 P 0 0;1=3
P 2.44606024 2.11615 25 P 0 0;1=3
P 2.44606024 2.06615 25 P 0 0;1=3
P 2.49606024 2.06615 25 P 0 0;1=3
P 2.49606024 2.01615 25 P 0 0;1=3
P 2.39606024 2.06615 25 P 0 0;1=3
P 2.39606024 2.01615 25 P 0 0;1=3
P 2.44606024 1.96615 25 P 0 0;1=3
P 2.44606024 1.91615 25 P 0 0;1=3
P 2.49606024 1.91615 25 P 0 0;1=3
P 2.49606024 1.86615 25 P 0 0;1=3
P 2.39606024 1.91615 25 P 0 0;1=3
P 2.39606024 1.86615 25 P 0 0;1=3
P 2.34606024 1.96615 25 P 0 0;1=3
P 2.34606024 1.91615 25 P 0 0;1=3
P 2.34606024 3.16615 25 P 0 0;1=3
P 2.34606024 3.11615 25 P 0 0;1=3
P 2.44606024 3.16615 25 P 0 0;1=3
P 2.44606024 3.11615 25 P 0 0;1=3
P 2.49606024 3.11615 25 P 0 0;1=3
P 2.49606024 3.06615 25 P 0 0;1=3
P 2.39606024 3.11615 25 P 0 0;1=3
P 2.39606024 3.06615 25 P 0 0;1=3
P 2.44606024 3.01615 25 P 0 0;1=3
P 2.44606024 2.96615 25 P 0 0;1=3
P 2.49606024 2.96615 25 P 0 0;1=3
P 2.49606024 2.91615 25 P 0 0;1=3
P 2.39606024 2.96615 25 P 0 0;1=3
P 2.39606024 2.91615 25 P 0 0;1=3
P 2.34606024 3.01615 25 P 0 0;1=3
P 2.34606024 2.96615 25 P 0 0;1=3
P 2.39606024 2.81615 25 P 0 0;1=3
P 2.39606024 2.76615 25 P 0 0;1=3
P 2.49606024 2.81615 25 P 0 0;1=3
P 2.49606024 2.76615 25 P 0 0;1=3
P 2.44606024 2.76615 25 P 0 0;1=3
P 2.44606024 2.71615 25 P 0 0;1=3
P 2.34606024 2.76615 25 P 0 0;1=3
P 2.34606024 2.71615 25 P 0 0;1=3
P 2.49606024 2.66615 25 P 0 0;1=3
P 2.49606024 2.61615 25 P 0 0;1=3
P 2.44606024 2.61615 25 P 0 0;1=3
P 2.44606024 2.56615 25 P 0 0;1=3
P 2.39606024 2.66615 25 P 0 0;1=3
P 2.39606024 2.61615 25 P 0 0;1=3
P 8.94061998 4.70574026 25 P 0 0;1=4
P 9.01925 4.70574026 25 P 0 0;1=4
P 9.07925 4.70574026 25 P 0 0;1=4
P 8.73579006 4.70573996 25 P 0 0;1=4
P 8.79579006 4.70573996 25 P 0 0;1=4
P 8.86665 4.74417972 25 P 0 0;1=4
P 8.80665 4.74417972 25 P 0 0;1=4
P 9.43358002 4.74417972 25 P 0 0;1=4
P 9.51531004 4.68098996 25 P 0 0;1=4
P 9.57531004 4.68098996 25 P 0 0;1=4
P 9.44445 4.62574026 25 P 0 0;1=4
P 9.50445 4.62574026 25 P 0 0;1=4
P 9.23185 4.68074026 25 P 0 0;1=4
P 9.29185 4.68074026 25 P 0 0;1=4
P 9.16098002 4.74417972 25 P 0 0;1=4
P 9.37358002 4.74417972 25 P 0 0;1=4
P 9.22098002 4.74417972 25 P 0 0;1=4
P 9.51531004 5.17873996 25 P 0 0;1=4
P 9.57531004 5.17873996 25 P 0 0;1=4
P 9.43358002 5.18127972 25 P 0 0;1=4
P 9.23185 5.18127972 25 P 0 0;1=4
P 9.29185 5.18127972 25 P 0 0;1=4
P 9.37358002 5.18127972 25 P 0 0;1=4
P 9.36271004 5.14223996 25 P 0 0;1=4
P 9.30271004 5.14223996 25 P 0 0;1=4
P 9.15011004 5.09223996 25 P 0 0;1=4
P 9.09011004 5.09223996 25 P 0 0;1=4
P 9.07925 5.20374026 25 P 0 0;1=4
P 9.01925 5.20374026 25 P 0 0;1=4
P 8.93440994 5.20876004 25 P 0 0;1=4
P 8.73579006 5.17873996 25 P 0 0;1=4
P 8.79579006 5.17873996 25 P 0 0;1=4
P 8.87440994 5.20876004 25 P 0 0;1=4
P 7.64205 4.74417972 25 P 0 0;1=4
P 7.70205 4.74417972 25 P 0 0;1=4
P 7.63118996 4.66826004 25 P 0 0;1=4
P 7.57118996 4.66826004 25 P 0 0;1=4
P 7.91465 4.61825974 25 P 0 0;1=4
P 7.78378996 4.74418002 25 P 0 0;1=4
P 7.84378996 4.74418002 25 P 0 0;1=4
P 7.85465 4.61825974 25 P 0 0;1=4
P 8.06725 4.74417972 25 P 0 0;1=4
P 8.12725 4.74417972 25 P 0 0;1=4
P 8.02207028 4.62815 25 P 0 0;1=4
P 8.08207028 4.62815 25 P 0 0;1=4
P 8.41070994 4.70326004 25 P 0 0;1=4
P 8.35070994 4.70326004 25 P 0 0;1=4
P 8.20898002 4.74417972 25 P 0 0;1=4
P 8.26898002 4.74417972 25 P 0 0;1=4
P 8.21208996 4.62826004 25 P 0 0;1=4
P 8.27208996 4.62826004 25 P 0 0;1=4
P 8.19811004 5.09223996 25 P 0 0;1=4
P 8.12725 5.13025974 25 P 0 0;1=4
P 8.06725 5.13025974 25 P 0 0;1=4
P 7.91465 5.13025974 25 P 0 0;1=4
P 7.92551004 5.09223996 25 P 0 0;1=4
P 7.98551004 5.09223996 25 P 0 0;1=4
P 7.85465 5.13025974 25 P 0 0;1=4
P 7.64204006 5.09223996 25 P 0 0;1=4
P 7.70204006 5.09223996 25 P 0 0;1=4
P 7.57118996 5.13026004 25 P 0 0;1=4
P 7.63118996 5.13026004 25 P 0 0;1=4
P 2.73225 4.70574026 25 P 0 0;1=4
P 2.79225 4.70574026 25 P 0 0;1=4
P 3.22830994 5.18128002 25 P 0 0;1=4
P 3.28830994 5.18128002 25 P 0 0;1=4
P 3.01571004 5.20373996 25 P 0 0;1=4
P 3.07571004 5.20373996 25 P 0 0;1=4
P 2.73225 5.17874026 25 P 0 0;1=4
P 2.79225 5.17874026 25 P 0 0;1=4
P 1.56765 4.66825974 25 P 0 0;1=4
P 1.62765 4.66825974 25 P 0 0;1=4
P 1.56765 5.13025974 25 P 0 0;1=4
P 1.62765 5.13025974 25 P 0 0;1=4
P 1.91110994 5.13026004 25 P 0 0;1=4
P 1.85110994 5.13026004 25 P 0 0;1=4
P 5.08267972 2.76615 25 P 0 0;1=3
P 5.03267972 2.76615 25 P 0 0;1=3
P 5.03267972 2.71615 25 P 0 0;1=3
P 4.93267972 2.76615 25 P 0 0;1=3
P 4.98267972 2.76615 25 P 0 0;1=3
P 4.93267972 2.71615 25 P 0 0;1=3
P 5.08267972 2.66615 25 P 0 0;1=3
P 4.98267972 2.66615 25 P 0 0;1=3
P 5.03267972 2.56615 25 P 0 0;1=3
P 4.93267972 2.56615 25 P 0 0;1=3
P 4.98267972 2.46615 25 P 0 0;1=3
P 4.98267972 2.51615 25 P 0 0;1=3
P 4.93267972 2.51615 25 P 0 0;1=3
P 5.08267972 2.51615 25 P 0 0;1=3
P 5.08267972 2.46615 25 P 0 0;1=3
P 5.03267972 2.21615 25 P 0 0;1=3
P 4.93267972 2.21615 25 P 0 0;1=3
P 4.98267972 2.31615 25 P 0 0;1=3
P 4.93267972 2.36615 25 P 0 0;1=3
P 5.08267972 2.31615 25 P 0 0;1=3
P 5.08267972 2.16615 25 P 0 0;1=3
P 4.93267972 2.16615 25 P 0 0;1=3
P 4.98267972 2.16615 25 P 0 0;1=3
P 4.93267972 1.96615 25 P 0 0;1=3
P 5.03267972 1.96615 25 P 0 0;1=3
P 5.03267972 2.11615 25 P 0 0;1=3
P 4.93267972 2.11615 25 P 0 0;1=3
P 4.98267972 2.01615 25 P 0 0;1=3
P 5.08267972 2.01615 25 P 0 0;1=3
P 4.98267972 1.86615 25 P 0 0;1=3
P 5.08267972 1.86615 25 P 0 0;1=3
P 4.78267972 3.81615 25 P 0 0;1=3
P 4.78267972 3.66615 25 P 0 0;1=3
P 4.73267972 3.81615 25 P 0 0;1=3
P 4.73267972 3.66615 25 P 0 0;1=3
P 4.68267972 3.81615 25 P 0 0;1=3
P 4.68267972 3.66615 25 P 0 0;1=3
P 4.78267972 3.51615 25 P 0 0;1=3
P 4.73267972 3.51615 25 P 0 0;1=3
P 4.68267972 3.51615 25 P 0 0;1=3
P 4.78267972 3.36615 25 P 0 0;1=3
P 4.73267972 3.36615 25 P 0 0;1=3
P 4.78267972 3.21615 25 P 0 0;1=3
P 4.73267972 3.21615 25 P 0 0;1=3
P 4.68267972 3.36615 25 P 0 0;1=3
P 4.68267972 3.21615 25 P 0 0;1=3
P 4.78267972 3.06615 25 P 0 0;1=3
P 4.73267972 3.06615 25 P 0 0;1=3
P 4.68267972 3.06615 25 P 0 0;1=3
P 4.78267972 2.91615 25 P 0 0;1=3
P 4.73267972 2.91615 25 P 0 0;1=3
P 4.68267972 2.91615 25 P 0 0;1=3
P 4.88267972 2.76615 25 P 0 0;1=3
P 4.88267972 2.66615 25 P 0 0;1=3
P 4.78267972 2.46615 25 P 0 0;1=3
P 4.88267972 2.56615 25 P 0 0;1=3
P 4.88267972 2.61615 25 P 0 0;1=3
P 4.68267972 2.46615 25 P 0 0;1=3
P 4.88267972 2.46615 25 P 0 0;1=3
P 4.88267972 2.51615 25 P 0 0;1=3
P 4.78267972 2.41615 25 P 0 0;1=3
P 4.88267972 2.41615 25 P 0 0;1=3
P 4.78267972 2.36615 25 P 0 0;1=3
P 4.78267972 2.31615 25 P 0 0;1=3
P 4.78267972 2.26615 25 P 0 0;1=3
P 4.78267972 2.21615 25 P 0 0;1=3
P 4.73267972 2.36615 25 P 0 0;1=3
P 4.68267972 2.31615 25 P 0 0;1=3
P 4.73267972 2.21615 25 P 0 0;1=3
P 4.88267972 2.21615 25 P 0 0;1=3
P 4.88267972 2.26615 25 P 0 0;1=3
P 4.88267972 2.31615 25 P 0 0;1=3
P 4.88267972 2.36615 25 P 0 0;1=3
P 4.73267972 2.16615 25 P 0 0;1=3
P 4.68267972 2.16615 25 P 0 0;1=3
P 4.78267972 1.96615 25 P 0 0;1=3
P 4.78267972 2.06615 25 P 0 0;1=3
P 4.78267972 2.01615 25 P 0 0;1=3
P 4.88267972 1.96615 25 P 0 0;1=3
P 4.88267972 2.06615 25 P 0 0;1=3
P 4.88267972 2.01615 25 P 0 0;1=3
P 4.78267972 2.11615 25 P 0 0;1=3
P 4.88267972 2.11615 25 P 0 0;1=3
P 4.73267972 2.11615 25 P 0 0;1=3
P 4.68267972 2.01615 25 P 0 0;1=3
P 4.73267972 1.96615 25 P 0 0;1=3
P 4.78267972 1.86615 25 P 0 0;1=3
P 4.88267972 1.86615 25 P 0 0;1=3
P 4.68267972 1.86615 25 P 0 0;1=3
P 4.63267972 3.81615 25 P 0 0;1=3
P 4.63267972 3.66615 25 P 0 0;1=3
P 4.58267972 3.81615 25 P 0 0;1=3
P 4.58267972 3.66615 25 P 0 0;1=3
P 4.63267972 3.51615 25 P 0 0;1=3
P 4.58267972 3.51615 25 P 0 0;1=3
P 4.63267972 3.36615 25 P 0 0;1=3
P 4.58267972 3.36615 25 P 0 0;1=3
P 4.63267972 3.21615 25 P 0 0;1=3
P 4.58267972 3.21615 25 P 0 0;1=3
P 4.63267972 3.06615 25 P 0 0;1=3
P 4.58267972 3.06615 25 P 0 0;1=3
P 4.63267972 2.91615 25 P 0 0;1=3
P 4.58267972 2.91615 25 P 0 0;1=3
P 4.58267972 2.46615 25 P 0 0;1=3
P 4.63267972 2.21615 25 P 0 0;1=3
P 4.58267972 2.31615 25 P 0 0;1=3
P 4.63267972 2.36615 25 P 0 0;1=3
P 4.58267972 2.01615 25 P 0 0;1=3
P 4.63267972 2.11615 25 P 0 0;1=3
P 4.63267972 1.96615 25 P 0 0;1=3
P 4.58267972 1.86615 25 P 0 0;1=3
P 2.04606024 3.41615 25 P 0 0;1=3
P 2.09606024 3.51615 25 P 0 0;1=3
P 3.37003996 5.18128002 25 P 0 0;1=4
P 3.43003996 5.18128002 25 P 0 0;1=4
P 3.29916998 5.14224026 25 P 0 0;1=4
P 3.35916998 5.14224026 25 P 0 0;1=4
P 2.93708002 4.70573996 25 P 0 0;1=4
P 3.07571004 4.70573996 25 P 0 0;1=4
P 3.01571004 4.70573996 25 P 0 0;1=4
P 2.87708002 4.70573996 25 P 0 0;1=4
P 2.93086998 5.20876024 25 P 0 0;1=4
P 2.87086998 5.20876024 25 P 0 0;1=4
P 2.80310994 4.74418002 25 P 0 0;1=4
P 2.86310994 4.74418002 25 P 0 0;1=4
P 3.08656998 5.09224026 25 P 0 0;1=4
P 3.14656998 5.09224026 25 P 0 0;1=4
P 2.26855 4.62825974 25 P 0 0;1=4
P 2.20855 4.62825974 25 P 0 0;1=4
P 2.26543996 4.74418002 25 P 0 0;1=4
P 2.20543996 4.74418002 25 P 0 0;1=4
P 2.34716998 4.70326004 25 P 0 0;1=4
P 2.07853002 4.62815 25 P 0 0;1=4
P 2.01853002 4.62815 25 P 0 0;1=4
P 2.12370994 4.74418002 25 P 0 0;1=4
P 2.06370994 4.74418002 25 P 0 0;1=4
P 2.19456998 5.09224026 25 P 0 0;1=4
P 2.13456998 5.09224026 25 P 0 0;1=4
P 2.12370994 5.13026004 25 P 0 0;1=4
P 2.06370994 5.13026004 25 P 0 0;1=4
P 1.6985 5.09224026 25 P 0 0;1=4
P 1.6385 5.09224026 25 P 0 0;1=4
P 1.85110994 4.61826004 25 P 0 0;1=4
P 1.63850994 4.74418002 25 P 0 0;1=4
P 1.69850994 4.74418002 25 P 0 0;1=4
P 1.98196998 5.09224026 25 P 0 0;1=4
P 1.92196998 5.09224026 25 P 0 0;1=4
P 1.84025 4.74417972 25 P 0 0;1=4
P 1.78025 4.74417972 25 P 0 0;1=4
P 11.03660974 2.71615 25 P 0 0;1=3
P 10.93660974 2.71615 25 P 0 0;1=3
P 11.03660974 2.76615 25 P 0 0;1=3
P 10.98660974 2.76615 25 P 0 0;1=3
P 10.93660974 2.76615 25 P 0 0;1=3
P 11.08660974 2.76615 25 P 0 0;1=3
P 11.03660974 2.56615 25 P 0 0;1=3
P 10.93660974 2.56615 25 P 0 0;1=3
P 10.98660974 2.66615 25 P 0 0;1=3
P 10.98660974 2.51615 25 P 0 0;1=3
P 10.93660974 2.51615 25 P 0 0;1=3
P 11.08660974 2.66615 25 P 0 0;1=3
P 11.08660974 2.51615 25 P 0 0;1=3
P 11.08660974 2.46615 25 P 0 0;1=3
P 10.98660974 2.46615 25 P 0 0;1=3
P 11.08660974 2.31615 25 P 0 0;1=3
P 10.93660974 2.36615 25 P 0 0;1=3
P 10.98660974 2.31615 25 P 0 0;1=3
P 10.93660974 2.21615 25 P 0 0;1=3
P 11.03660974 2.21615 25 P 0 0;1=3
P 11.03660974 2.11615 25 P 0 0;1=3
P 10.93660974 2.11615 25 P 0 0;1=3
P 10.98660974 2.01615 25 P 0 0;1=3
P 10.93660974 1.96615 25 P 0 0;1=3
P 11.03660974 1.96615 25 P 0 0;1=3
P 11.08660974 2.01615 25 P 0 0;1=3
P 10.98660974 2.16615 25 P 0 0;1=3
P 10.93660974 2.16615 25 P 0 0;1=3
P 11.08660974 2.16615 25 P 0 0;1=3
P 10.98660974 1.86615 25 P 0 0;1=3
P 11.08660974 1.86615 25 P 0 0;1=3
P 10.73660974 2.71615 25 P 0 0;1=3
P 10.73660974 2.76615 25 P 0 0;1=3
P 10.88660974 2.76615 25 P 0 0;1=3
P 10.78660974 2.76615 25 P 0 0;1=3
P 10.73660974 2.56615 25 P 0 0;1=3
P 10.68660974 2.66615 25 P 0 0;1=3
P 10.73660974 2.51615 25 P 0 0;1=3
P 10.68660974 2.51615 25 P 0 0;1=3
P 10.88660974 2.61615 25 P 0 0;1=3
P 10.88660974 2.56615 25 P 0 0;1=3
P 10.88660974 2.51615 25 P 0 0;1=3
P 10.78660974 2.56615 25 P 0 0;1=3
P 10.78660974 2.61615 25 P 0 0;1=3
P 10.78660974 2.66615 25 P 0 0;1=3
P 10.78660974 2.51615 25 P 0 0;1=3
P 10.78660974 2.46615 25 P 0 0;1=3
P 10.68660974 2.46615 25 P 0 0;1=3
P 10.88660974 2.46615 25 P 0 0;1=3
P 10.78660974 2.21615 25 P 0 0;1=3
P 10.78660974 2.26615 25 P 0 0;1=3
P 10.78660974 2.31615 25 P 0 0;1=3
P 10.78660974 2.36615 25 P 0 0;1=3
P 10.68660974 2.31615 25 P 0 0;1=3
P 10.73660974 2.36615 25 P 0 0;1=3
P 10.73660974 2.21615 25 P 0 0;1=3
P 10.78660974 2.41615 25 P 0 0;1=3
P 10.88660974 2.36615 25 P 0 0;1=3
P 10.88660974 2.31615 25 P 0 0;1=3
P 10.88660974 2.26615 25 P 0 0;1=3
P 10.88660974 2.21615 25 P 0 0;1=3
P 10.73660974 1.96615 25 P 0 0;1=3
P 10.68660974 2.01615 25 P 0 0;1=3
P 10.73660974 2.11615 25 P 0 0;1=3
P 10.78660974 2.11615 25 P 0 0;1=3
P 10.78660974 2.01615 25 P 0 0;1=3
P 10.78660974 1.96615 25 P 0 0;1=3
P 10.78660974 2.06615 25 P 0 0;1=3
P 10.68660974 2.16615 25 P 0 0;1=3
P 10.73660974 2.16615 25 P 0 0;1=3
P 10.88660974 2.01615 25 P 0 0;1=3
P 10.88660974 2.06615 25 P 0 0;1=3
P 10.88660974 2.11615 25 P 0 0;1=3
P 10.88660974 1.96615 25 P 0 0;1=3
P 10.78660974 1.91615 25 P 0 0;1=3
P 10.68660974 1.86615 25 P 0 0;1=3
P 10.78660974 1.86615 25 P 0 0;1=3
P 10.88660974 1.86615 25 P 0 0;1=3
P 10.63660974 2.71615 25 P 0 0;1=3
P 10.63660974 2.76615 25 P 0 0;1=3
P 10.63660974 2.56615 25 P 0 0;1=3
P 10.58660974 2.66615 25 P 0 0;1=3
P 10.63660974 2.51615 25 P 0 0;1=3
P 10.58660974 2.51615 25 P 0 0;1=3
P 10.58660974 2.46615 25 P 0 0;1=3
P 10.63660974 2.36615 25 P 0 0;1=3
P 10.58660974 2.31615 25 P 0 0;1=3
P 10.58660974 2.01615 25 P 0 0;1=3
P 10.63660974 1.96615 25 P 0 0;1=3
P 10.63660974 2.11615 25 P 0 0;1=3
P 10.58660974 1.86615 25 P 0 0;1=3
P 1.92345974 5.377 25 P 0 0;1=4
P 2.14345974 5.377 25 P 0 0;1=4
P 7.927 5.377 25 P 0 0;1=4
P 8.147 5.377 25 P 0 0;1=4
P 3.43003996 4.74418002 25 P 0 0;1=4
P 3.51177008 4.68098996 25 P 0 0;1=4
P 3.57177008 4.68098996 25 P 0 0;1=4
P 3.21743996 4.74418002 25 P 0 0;1=4
P 3.37003996 4.74418002 25 P 0 0;1=4
P 3.41 5.332 25 P 0 0;1=4
P 5.38047972 1.5957 25 P 0 0;1=4
P 5.38047972 1.7891 25 P 0 0;1=4
P 5.38047972 1.732 25 P 0 0;1=4
P 5.38047972 1.6528 25 P 0 0;1=4
P 5.53530974 1.8603 25 P 0 0;1=4
P 5.53530974 1.8032 25 P 0 0;1=4
P 5.53530974 2.2727 25 P 0 0;1=4
P 5.53530974 2.1373 25 P 0 0;1=4
P 5.53530974 1.9964 25 P 0 0;1=4
P 5.38047972 2.3403 25 P 0 0;1=4
P 5.38047972 2.2832 25 P 0 0;1=4
P 5.38047972 2.2049 25 P 0 0;1=4
P 5.38047972 2.1478 25 P 0 0;1=4
P 5.38047972 2.0642 25 P 0 0;1=4
P 5.38047972 2.0071 25 P 0 0;1=4
P 5.38047972 1.9288 25 P 0 0;1=4
P 5.38047972 1.8717 25 P 0 0;1=4
P 5.53530974 2.351 25 P 0 0;1=4
P 5.38047972 2.4757 25 P 0 0;1=4
P 5.38047972 2.4186 25 P 0 0;1=4
P 5.53530974 2.4902 25 P 0 0;1=4
P 5.53530974 2.6825 25 P 0 0;1=4
P 5.53530974 2.6254 25 P 0 0;1=4
P 5.38047972 2.5578 25 P 0 0;1=4
P 5.38047972 2.6149 25 P 0 0;1=4
P 10.43 1.3341 25 P 0 0;1=4
P 10.43 1.277 25 P 0 0;1=4
P 10.4159 1.43 25 P 0 0;1=4
P 10.473 1.43 25 P 0 0;1=4
P 10.37313996 1.55333474 25 P 0 0;1=4
P 10.41451004 1.51195472 25 P 0 0;1=4
P 10.295 1.713 25 P 0 0;1=4
P 10.295 1.6559 25 P 0 0;1=4
P 10.26 1.9179 25 P 0 0;1=4
P 10.29525 1.877 25 P 0 0;1=4
P 10.29525 1.8199 25 P 0 0;1=4
P 10.26 1.975 25 P 0 0;1=4
P 10.125 2.0651 25 P 0 0;1=4
P 10.125 2.1224 25 P 0 0;1=4
P 10.125 2.1795 25 P 0 0;1=4
P 10.01 2.2481 25 P 0 0;1=4
P 10.01 2.191 25 P 0 0;1=4
P 10.01 2.38435 25 P 0 0;1=4
P 10.01 2.32725 25 P 0 0;1=4
P 10.125 2.3168 25 P 0 0;1=4
P 10.125 2.2597 25 P 0 0;1=4
P 10.125 2.4519 25 P 0 0;1=4
P 10.125 2.3948 25 P 0 0;1=4
P 10.01 2.51945 25 P 0 0;1=4
P 10.01 2.46235 25 P 0 0;1=4
P 10.125 2.587 25 P 0 0;1=4
P 10.125 2.5299 25 P 0 0;1=4
P 10.01 2.673 25 P 0 0;1=4
P 10.01 2.6159 25 P 0 0;1=4
P 11.74315974 1.7035 25 P 0 0;1=4
P 11.74315974 1.6405 25 P 0 0;1=4
P 11.69315974 1.4805 25 P 0 0;1=4
P 11.69315974 1.5435 25 P 0 0;1=4
P 11.49315974 1.5605 25 P 0 0;1=4
P 11.49315974 1.6235 25 P 0 0;1=4
P 11.49315974 1.4635 25 P 0 0;1=4
P 11.49365974 1.401 25 P 0 0;1=4
P 11.69315974 2.6005 25 P 0 0;1=4
P 11.69315974 2.5035 25 P 0 0;1=4
P 11.69315974 2.4405 25 P 0 0;1=4
P 11.69315974 2.3435 25 P 0 0;1=4
P 11.69315974 2.2805 25 P 0 0;1=4
P 11.69315974 2.1835 25 P 0 0;1=4
P 11.69315974 1.9605 25 P 0 0;1=4
P 11.69315974 2.0235 25 P 0 0;1=4
P 11.69315974 2.1205 25 P 0 0;1=4
P 11.69315974 1.8005 25 P 0 0;1=4
P 11.69315974 1.8635 25 P 0 0;1=4
P 11.49315974 2.5205 25 P 0 0;1=4
P 11.49315974 2.5835 25 P 0 0;1=4
P 11.49315974 2.4235 25 P 0 0;1=4
P 11.49315974 2.3605 25 P 0 0;1=4
P 11.79315974 2.2635 25 P 0 0;1=4
P 11.79315974 2.2005 25 P 0 0;1=4
P 11.49315974 1.9435 25 P 0 0;1=4
P 11.49315974 2.1035 25 P 0 0;1=4
P 11.49315974 2.0405 25 P 0 0;1=4
P 11.49315974 1.8805 25 P 0 0;1=4
P 11.49365974 1.721 25 P 0 0;1=4
P 11.49315974 1.7835 25 P 0 0;1=4
P 10.125 2.7451 25 P 0 0;1=4
P 10.125 2.688 25 P 0 0;1=4
P 12.34 2.19 25 P 0 0;1=4
P 9.415 5.332 25 P 0 0;1=4
P 9.265 5.332 25 P 0 0;1=4
P 9.07 5.332 25 P 0 0;1=4
P 4.7 5.54929026 25 P 0 0;1=4
P 4.81 5.375 25 P 0 0;1=4
P 4.96 5.375 25 P 0 0;1=4
P 5.16 5.645 25 P 0 0;1=4
P 5.04440974 5.605 25 P 0 0;1=4
P 4.92 5.7 25 P 0 0;1=4
P 9.91 4.7 25 P 0 0;1=4
P 3.57 4.45 25 P 0 0;1=4
P 10.465 5.195 25 P 0 0;1=4
P 10.515 5.32 25 P 0 0;1=4
P 10.465 5.275 25 P 0 0;1=4
P 12.025 4.915 25 P 0 0;1=4
P 12.12 4.965 25 P 0 0;1=4
P 12.185 4.915 25 P 0 0;1=4
P 3.72 4.45 25 P 0 0;1=4
P 3.66 4.63 25 P 0 0;1=4
P 3.77 4.86 25 P 0 0;1=4
P 9.96 4.69 25 P 0 0;1=4
P 10.03 4.51 25 P 0 0;1=4
P 3.835 4.6 25 P 0 0;1=4
P 3.9865 4.635 25 P 0 0;1=4
P 4.14 4.655 25 P 0 0;1=4
P 4.1049 4.7649 25 P 0 0;1=4
P 1.28050974 5.78 25 P 0 0;1=4
P 3.87 5.125 25 P 0 0;1=4
P 0.4826 5.8976 25 P 0 0;1=4
P 0.84952972 5.17 25 P 0 0;1=4
P 0.955 5.325 25 P 0 0;1=4
P 1.31 5.355 25 P 0 0;1=4
P 1.20176998 5.78 25 P 0 0;1=4
P 6.31295 4.99705 25 P 0 0;1=4
P 6.87 5 25 P 0 0;1=4
P 9.64795974 0.79643002 25 P 0 0;1=4
P 9.40795 0.26133002 25 P 0 0;1=4
P 3.60998976 0.24 25 P 0 0;1=4
P 3.65998976 0.345 25 P 0 0;1=4
P 3.86 0.7751 25 P 0 0;1=0
P 6.905 4.94705 25 P 0 0;1=4
P 6.905 4.88705 25 P 0 0;1=4
P 6.955 4.8 25 P 0 0;1=4
P 6.955 4.84 25 P 0 0;1=4
P 6.955 4.72 25 P 0 0;1=4
P 6.955 4.76 25 P 0 0;1=4
P 6.59708976 5.0502 25 P 0 0;1=4
P 6.65218976 4.77 25 P 0 0;1=4
P 6.62119006 4.95641998 25 P 0 0;1=8
P 6.6015 4.93674026 25 P 0 0;1=8
P 6.64088002 4.93673996 25 P 0 0;1=8
P 6.62118976 4.91705 25 P 0 0;1=8
P 6.62118976 4.87768002 25 P 0 0;1=8
P 6.6015 4.89736024 25 P 0 0;1=8
P 6.64087992 4.89736004 25 P 0 0;1=8
P 6.62 4.69 25 P 0 0;1=4
P 6.62 4.725 25 P 0 0;1=4
P 6.385 5.07 25 P 0 0;1=4
P 5.53594026 4.55505 25 P 0 0;1=4
P 6.05708976 4.5102 25 P 0 0;1=4
P 6.01708976 4.5102 25 P 0 0;1=4
P 5.97708976 4.5102 25 P 0 0;1=4
P 5.93708976 4.5102 25 P 0 0;1=4
P 5.89708976 4.5102 25 P 0 0;1=4
P 6.09708976 4.5102 25 P 0 0;1=4
P 5.61708976 4.5102 25 P 0 0;1=4
P 5.65708976 4.5102 25 P 0 0;1=4
P 5.85708976 4.5102 25 P 0 0;1=4
P 5.81708976 4.5102 25 P 0 0;1=4
P 5.77708976 4.5102 25 P 0 0;1=4
P 5.73708976 4.5102 25 P 0 0;1=4
P 5.69708976 4.5102 25 P 0 0;1=4
P 5.57708976 4.5102 25 P 0 0;1=4
P 0.036 0.10868002 25 P 0 0;1=4
P 0.036 0.15868002 25 P 0 0;1=4
P 0.036 0.20868002 25 P 0 0;1=4
P 0.22873976 0.036 25 P 0 0;1=4
P 0.17873976 0.036 25 P 0 0;1=4
P 0.12873976 0.036 25 P 0 0;1=4
P 0.07873976 0.036 25 P 0 0;1=4
P 0.47873976 0.036 25 P 0 0;1=4
P 0.42873976 0.036 25 P 0 0;1=4
P 0.37873976 0.036 25 P 0 0;1=4
P 0.32873976 0.036 25 P 0 0;1=4
P 0.27873976 0.036 25 P 0 0;1=4
P 0.77873976 0.036 25 P 0 0;1=4
P 0.72873976 0.036 25 P 0 0;1=4
P 0.67873976 0.036 25 P 0 0;1=4
P 0.62873976 0.036 25 P 0 0;1=4
P 0.57873976 0.036 25 P 0 0;1=4
P 0.52873976 0.036 25 P 0 0;1=4
P 1.02873976 0.036 25 P 0 0;1=4
P 0.97873976 0.036 25 P 0 0;1=4
P 0.92873976 0.036 25 P 0 0;1=4
P 0.87873976 0.036 25 P 0 0;1=4
P 0.82873976 0.036 25 P 0 0;1=4
P 1.27873976 0.036 25 P 0 0;1=4
P 1.22873976 0.036 25 P 0 0;1=4
P 1.17873976 0.036 25 P 0 0;1=4
P 1.12873976 0.036 25 P 0 0;1=4
P 1.07873976 0.036 25 P 0 0;1=4
P 1.52873976 0.036 25 P 0 0;1=4
P 1.47873976 0.036 25 P 0 0;1=4
P 1.42873976 0.036 25 P 0 0;1=4
P 1.37873976 0.036 25 P 0 0;1=4
P 1.32873976 0.036 25 P 0 0;1=4
P 1.82873976 0.036 25 P 0 0;1=4
P 1.77873976 0.036 25 P 0 0;1=4
P 1.72873976 0.036 25 P 0 0;1=4
P 1.67873976 0.036 25 P 0 0;1=4
P 1.62873976 0.036 25 P 0 0;1=4
P 1.57873976 0.036 25 P 0 0;1=4
P 2.07873976 0.036 25 P 0 0;1=4
P 2.02873976 0.036 25 P 0 0;1=4
P 1.97873976 0.036 25 P 0 0;1=4
P 1.92873976 0.036 25 P 0 0;1=4
P 1.87873976 0.036 25 P 0 0;1=4
P 2.32873976 0.036 25 P 0 0;1=4
P 2.27873976 0.036 25 P 0 0;1=4
P 2.22873976 0.036 25 P 0 0;1=4
P 2.17873976 0.036 25 P 0 0;1=4
P 2.12873976 0.036 25 P 0 0;1=4
P 2.62873976 0.036 25 P 0 0;1=4
P 2.57873976 0.036 25 P 0 0;1=4
P 2.52873976 0.036 25 P 0 0;1=4
P 2.47873976 0.036 25 P 0 0;1=4
P 2.42873976 0.036 25 P 0 0;1=4
P 2.37873976 0.036 25 P 0 0;1=4
P 2.87873976 0.036 25 P 0 0;1=4
P 2.82873976 0.036 25 P 0 0;1=4
P 2.77873976 0.036 25 P 0 0;1=4
P 2.72873976 0.036 25 P 0 0;1=4
P 2.67873976 0.036 25 P 0 0;1=4
P 3.12873976 0.036 25 P 0 0;1=4
P 3.07873976 0.036 25 P 0 0;1=4
P 3.02873976 0.036 25 P 0 0;1=4
P 2.97873976 0.036 25 P 0 0;1=4
P 2.92873976 0.036 25 P 0 0;1=4
P 3.37873976 0.036 25 P 0 0;1=4
P 3.32873976 0.036 25 P 0 0;1=4
P 3.27873976 0.036 25 P 0 0;1=4
P 3.22873976 0.036 25 P 0 0;1=4
P 3.17873976 0.036 25 P 0 0;1=4
P 3.67873976 0.036 25 P 0 0;1=4
P 3.62873976 0.036 25 P 0 0;1=4
P 3.57873976 0.036 25 P 0 0;1=4
P 3.52873976 0.036 25 P 0 0;1=4
P 3.47873976 0.036 25 P 0 0;1=4
P 3.42873976 0.036 25 P 0 0;1=4
P 3.92873976 0.036 25 P 0 0;1=4
P 3.87873976 0.036 25 P 0 0;1=4
P 3.82873976 0.036 25 P 0 0;1=4
P 3.77873976 0.036 25 P 0 0;1=4
P 3.72873976 0.036 25 P 0 0;1=4
P 4.17873976 0.036 25 P 0 0;1=4
P 4.12873976 0.036 25 P 0 0;1=4
P 4.07873976 0.036 25 P 0 0;1=4
P 4.02873976 0.036 25 P 0 0;1=4
P 3.97873976 0.036 25 P 0 0;1=4
P 4.42873976 0.036 25 P 0 0;1=4
P 4.37873976 0.036 25 P 0 0;1=4
P 4.32873976 0.036 25 P 0 0;1=4
P 4.27873976 0.036 25 P 0 0;1=4
P 4.22873976 0.036 25 P 0 0;1=4
P 4.72873976 0.036 25 P 0 0;1=4
P 4.67873976 0.036 25 P 0 0;1=4
P 4.62873976 0.036 25 P 0 0;1=4
P 4.57873976 0.036 25 P 0 0;1=4
P 4.52873976 0.036 25 P 0 0;1=4
P 4.47873976 0.036 25 P 0 0;1=4
P 4.81833976 0.21825 25 P 0 0;1=4
P 4.81833976 0.16825 25 P 0 0;1=4
P 4.81833976 0.11825 25 P 0 0;1=4
P 4.81703888 0.06825906 25 P 0 0;1=4
P 4.77873809 0.03612175 25 P 0 0;1=4
P 6.80730974 0.036 25 P 0 0;1=4
P 6.75730974 0.036 25 P 0 0;1=4
P 6.70730974 0.036 25 P 0 0;1=4
P 6.65730955 0.03676043 25 P 0 0;1=4
P 6.62298947 0.07311939 25 P 0 0;1=4
P 6.62261998 0.12311998 25 P 0 0;1=4
P 6.62261998 0.17311998 25 P 0 0;1=4
P 6.62261998 0.22311998 25 P 0 0;1=4
P 7.00730974 0.036 25 P 0 0;1=4
P 6.95730974 0.036 25 P 0 0;1=4
P 6.90730974 0.036 25 P 0 0;1=4
P 6.85730974 0.036 25 P 0 0;1=4
P 0.036 0.25868002 25 P 0 0;1=4
P 0.036 0.30868002 25 P 0 0;1=4
P 0.036 0.35868002 25 P 0 0;1=4
P 0.036 0.40868002 25 P 0 0;1=4
P 0.036 0.45868002 25 P 0 0;1=4
P 4.96804006 0.46906998 25 P 0 0;1=4
P 4.91804941 0.46808051 25 P 0 0;1=4
P 4.87108927 0.45089055 25 P 0 0;1=4
P 4.83591132 0.41536132 25 P 0 0;1=4
P 4.81919035 0.36823996 25 P 0 0;1=4
P 4.81833976 0.31825 25 P 0 0;1=4
P 4.81833976 0.26825 25 P 0 0;1=4
P 5.21804006 0.46906998 25 P 0 0;1=4
P 5.16804006 0.46906998 25 P 0 0;1=4
P 5.11804006 0.46906998 25 P 0 0;1=4
P 5.06804006 0.46906998 25 P 0 0;1=4
P 5.01804006 0.46906998 25 P 0 0;1=4
P 5.51804006 0.46906998 25 P 0 0;1=4
P 5.46804006 0.46906998 25 P 0 0;1=4
P 5.41804006 0.46906998 25 P 0 0;1=4
P 5.36804006 0.46906998 25 P 0 0;1=4
P 5.31804006 0.46906998 25 P 0 0;1=4
P 5.26804006 0.46906998 25 P 0 0;1=4
P 5.76804006 0.46906998 25 P 0 0;1=4
P 5.71804006 0.46906998 25 P 0 0;1=4
P 5.66804006 0.46906998 25 P 0 0;1=4
P 5.61804006 0.46906998 25 P 0 0;1=4
P 5.56804006 0.46906998 25 P 0 0;1=4
P 6.01804006 0.46906998 25 P 0 0;1=4
P 5.96804006 0.46906998 25 P 0 0;1=4
P 5.91804006 0.46906998 25 P 0 0;1=4
P 5.86804006 0.46906998 25 P 0 0;1=4
P 5.81804006 0.46906998 25 P 0 0;1=4
P 6.31804006 0.46906998 25 P 0 0;1=4
P 6.26804006 0.46906998 25 P 0 0;1=4
P 6.21804006 0.46906998 25 P 0 0;1=4
P 6.16804006 0.46906998 25 P 0 0;1=4
P 6.11804006 0.46906998 25 P 0 0;1=4
P 6.06804006 0.46906998 25 P 0 0;1=4
P 6.56567894 0.45345098 25 P 0 0;1=4
P 6.5180314 0.46861841 25 P 0 0;1=4
P 6.46804006 0.46906998 25 P 0 0;1=4
P 6.41804006 0.46906998 25 P 0 0;1=4
P 6.36804006 0.46906998 25 P 0 0;1=4
P 6.62261998 0.27311998 25 P 0 0;1=4
P 6.62261998 0.32311998 25 P 0 0;1=4
P 6.62106949 0.37309951 25 P 0 0;1=4
P 6.60234085 0.41946063 25 P 0 0;1=4
P 0.036 0.50868002 25 P 0 0;1=4
P 0.036 0.55868002 25 P 0 0;1=4
P 11.845 2.85 25 P 0 0;1=4
P 8.98115 2.7861 25 P 0 0;1=4
P 8.98115 2.8989 25 P 0 0;1=4
P 11.58612972 2.855 25 P 0 0;1=4
P 11.50361998 2.8 25 P 0 0;1=4
P 11.50361998 2.73 25 P 0 0;1=4
P 5.5722 3 25 P 0 0;1=4
P 5.75779006 3.02558996 25 P 0 0;1=4
P 5.9192 2.943 25 P 0 0;1=4
P 4.07385974 2.55 25 P 0 0;1=4
P 3.86826998 2.64559026 25 P 0 0;1=4
P 9.995 2.87559026 25 P 0 0;1=4
P 10.11778976 2.78 25 P 0 0;1=4
P 7.2426 4.60351024 25 P 0 0;1=4
P 7.3401 4.85601024 25 P 0 0;1=4
P 7.1926 5.04351024 25 P 0 0;1=4
P 0.66 2.045 25 P 0 0;1=0
P 1.792 2.4781 25 P 0 0;1=4
P 2.97720974 2.8989 25 P 0 0;1=4
P 2.97720974 2.7861 25 P 0 0;1=4
P 2.9422 2.925 25 P 0 0;1=4
P 8.94278976 2.925 25 P 0 0;1=4
P 5.5822 2.855 25 P 0 0;1=4
P 5.84969026 2.85 25 P 0 0;1=4
P 0.65348996 1.85608996 25 P 0 0;1=4
P 0.65348996 1.91628996 25 P 0 0;1=4
P 0.09448996 4.60236998 27 P 0 3;1=1
P 0.35038996 4.20865994 27 P 0 3;1=1
P 0.09448996 4.2874 27 P 0 3;1=1
P 0.09448996 4.12991998 27 P 0 3;1=1
P 0.17322992 4.16928996 27 P 0 3;1=1
P 0.27165 4.09055 27 P 0 3;1=1
P 0.27165 3.93306998 27 P 0 3;1=1
P 0.35038996 4.05117992 27 P 0 3;1=1
P 0.35038996 3.8937 27 P 0 3;1=1
P 0.09448996 3.97243996 27 P 0 3;1=1
P 0.09448996 3.81495994 27 P 0 3;1=1
P 0.17322992 4.01180994 27 P 0 3;1=1
P 0.17322992 3.85432992 27 P 0 3;1=1
P 0.27165 3.77558996 27 P 0 3;1=1
P 0.27165 3.61810994 27 P 0 3;1=1
P 0.35038996 3.73621998 27 P 0 3;1=1
P 0.35038996 3.57873996 27 P 0 3;1=1
P 0.09448996 3.65747992 27 P 0 3;1=1
P 0.09448996 3.5 27 P 0 3;1=1
P 0.17322992 3.69685 27 P 0 3;1=1
P 0.17322992 3.53936998 27 P 0 3;1=1
P 0.27165 3.46062992 27 P 0 3;1=1
P 0.35038996 3.42125994 27 P 0 3;1=1
P 0.27165 3.30315 27 P 0 3;1=1
P 0.27165 3.22440994 27 P 0 3;1=1
P 0.17322992 3.38188996 27 P 0 3;1=1
P 0.17322992 3.30315 27 P 0 3;1=1
P 0.35038996 3.1063 27 P 0 3;1=1
P 0.35038996 2.94881998 27 P 0 3;1=1
P 0.27165 3.06692992 27 P 0 3;1=1
P 0.27165 2.90945 27 P 0 3;1=1
P 0.17322992 3.14566998 27 P 0 3;1=1
P 0.17322992 2.98818996 27 P 0 3;1=1
P 0.09448996 3.18503996 27 P 0 3;1=1
P 0.09448996 3.02755994 27 P 0 3;1=1
P 0.35038996 2.79133996 27 P 0 3;1=1
P 0.27165 2.75196998 27 P 0 3;1=1
P 0.35038996 2.63385994 27 P 0 3;1=1
P 0.17322992 2.83070994 27 P 0 3;1=1
P 0.09448996 2.87007992 27 P 0 3;1=1
P 0.09448996 2.7126 27 P 0 3;1=1
P 0.35038996 2.39763996 27 P 0 3;1=1
P 0.27165 2.51575 27 P 0 3;1=1
P 0.27165 2.35826998 27 P 0 3;1=1
P 0.17322992 2.59448996 27 P 0 3;1=1
P 0.17322992 2.43700994 27 P 0 3;1=1
P 0.09448996 2.47637992 27 P 0 3;1=1
P 0.09448996 2.3189 27 P 0 3;1=1
P 0.35038996 2.24015994 27 P 0 3;1=1
P 0.35038996 2.08267992 27 P 0 3;1=1
P 0.35038996 2.00393996 27 P 0 3;1=1
P 0.27165 2.20078996 27 P 0 3;1=1
P 0.17322992 2.27952992 27 P 0 3;1=1
P 0.09448996 2.16141998 27 P 0 3;1=1
P 0.09448996 2.08267992 27 P 0 3;1=1
P 0.17322992 1.96456998 27 P 0 3;1=1
P 0.09448996 1.84645994 27 P 0 3;1=1
P 0.09448996 4.44487992 27 P 0 3;1=1
P 12.63778996 2.00393996 27 P 0 3;1=1
P 12.55905 2.12205 27 P 0 3;1=1
P 12.55905 1.88582992 27 P 0 3;1=1
P 12.81495 2.12205 27 P 0 3;1=1
P 12.81495 2.04330994 27 P 0 3;1=1
P 12.73620994 2.39763996 27 P 0 3;1=1
P 12.73620994 2.24015994 27 P 0 3;1=1
P 12.63778996 2.3189 27 P 0 3;1=1
P 12.55905 2.35826998 27 P 0 3;1=1
P 12.55905 2.20078996 27 P 0 3;1=1
P 12.81495 2.43700994 27 P 0 3;1=1
P 12.81495 2.27952992 27 P 0 3;1=1
P 12.73620994 2.55511998 27 P 0 3;1=1
P 12.63778996 2.63385994 27 P 0 3;1=1
P 12.63778996 2.47637992 27 P 0 3;1=1
P 12.55905 2.51575 27 P 0 3;1=1
P 12.81495 2.67322992 27 P 0 3;1=1
P 12.73620994 2.94881998 27 P 0 3;1=1
P 12.73620994 2.79133996 27 P 0 3;1=1
P 12.63778996 3.02755994 27 P 0 3;1=1
P 12.63778996 2.87007992 27 P 0 3;1=1
P 12.55905 2.90945 27 P 0 3;1=1
P 12.55905 2.75196998 27 P 0 3;1=1
P 12.81495 2.98818996 27 P 0 3;1=1
P 12.81495 2.83070994 27 P 0 3;1=1
P 12.73620994 3.26377992 27 P 0 3;1=1
P 12.73620994 3.1063 27 P 0 3;1=1
P 12.63778996 3.18503996 27 P 0 3;1=1
P 12.55905 3.22440994 27 P 0 3;1=1
P 12.55905 3.06692992 27 P 0 3;1=1
P 12.81495 3.14566998 27 P 0 3;1=1
P 12.55905 3.53936998 27 P 0 3;1=1
P 12.63778996 3.57873996 27 P 0 3;1=1
P 12.63778996 3.42125994 27 P 0 3;1=1
P 12.73620994 3.5 27 P 0 3;1=1
P 12.73620994 3.34251998 27 P 0 3;1=1
P 12.63778996 3.34251998 27 P 0 3;1=1
P 12.81495 3.61810994 27 P 0 3;1=1
P 12.81495 3.46062992 27 P 0 3;1=1
P 12.55905 3.85432992 27 P 0 3;1=1
P 12.55905 3.69685 27 P 0 3;1=1
P 12.63778996 3.8937 27 P 0 3;1=1
P 12.63778996 3.73621998 27 P 0 3;1=1
P 12.73620994 3.81495994 27 P 0 3;1=1
P 12.73620994 3.65747992 27 P 0 3;1=1
P 12.81495 3.93306998 27 P 0 3;1=1
P 12.81495 3.77558996 27 P 0 3;1=1
P 12.55905 4.16928996 27 P 0 3;1=1
P 12.55905 4.01180994 27 P 0 3;1=1
P 12.63778996 4.20865994 27 P 0 3;1=1
P 12.63778996 4.05117992 27 P 0 3;1=1
P 12.73620994 4.12991998 27 P 0 3;1=1
P 12.73620994 3.97243996 27 P 0 3;1=1
P 12.81495 4.09055 27 P 0 3;1=1
P 12.55905 4.48425 27 P 0 3;1=1
P 12.55905 4.32676998 27 P 0 3;1=1
P 12.63778996 4.52361998 27 P 0 3;1=1
P 12.63778996 4.36613996 27 P 0 3;1=1
P 12.73620994 4.44487992 27 P 0 3;1=1
P 12.73620994 4.2874 27 P 0 3;1=1
P 12.81495 4.40550994 27 P 0 3;1=1
P 12.81495 4.24802992 27 P 0 3;1=1
P 12.55905 4.64173996 27 P 0 3;1=1
P 12.81495 4.56298996 27 P 0 3;1=1
P 0.27165 4.40550994 27 P 0 3;1=1
P 0.35038996 4.52361998 27 P 0 3;1=1
P 0.17322992 4.48425 27 P 0 3;1=1
P 0.27165 4.24802992 27 P 0 3;1=1
P 0.35038996 4.36613996 27 P 0 3;1=1
P 0.17322992 4.32676998 27 P 0 3;1=1
P 5.49220974 2.73 25 P 0 0;1=4
P 5.44885974 2.9414 25 P 0 0;1=4
P 5.44885974 3.0214 25 P 0 0;1=4
P 5.44885974 3.0564 25 P 0 0;1=4
P 5.44885974 3.1014 25 P 0 0;1=4
P 5.44885974 3.1364 25 P 0 0;1=4
P 5.44885974 3.2164 25 P 0 0;1=4
P 5.44885974 3.1814 25 P 0 0;1=4
P 5.44885974 2.9764 25 P 0 0;1=4
P 5.44885974 3.2614 25 P 0 0;1=4
P 5.44885974 3.2964 25 P 0 0;1=4
P 10.33998976 4.9231 25 P 0 0;1=4
P 10.38498976 4.9231 25 P 0 0;1=0
P 10.77498976 4.9231 25 P 0 0;1=4
P 10.72998976 4.9231 25 P 0 0;1=4
P 10.30498976 4.9431 25 P 0 0;1=4
P 10.26498976 4.9431 25 P 0 0;1=4
P 10.30498976 5.0281 25 P 0 0;1=4
P 10.30498976 5.0731 25 P 0 0;1=4
P 10.30498976 4.9831 25 P 0 0;1=4
P 10.26498976 5.0281 25 P 0 0;1=4
P 10.26498976 5.0731 25 P 0 0;1=4
P 10.26498976 4.9831 25 P 0 0;1=4
P 10.26498976 5.1181 25 P 0 0;1=4
P 10.30498976 5.1181 25 P 0 0;1=4
P 10.34498976 5.1181 25 P 0 0;1=4
P 10.42498976 4.9431 25 P 0 0;1=4
P 10.46498976 4.9431 25 P 0 0;1=4
P 10.38498976 5.1181 25 P 0 0;1=4
P 10.46498976 5.1181 25 P 0 0;1=4
P 10.42498976 5.1181 25 P 0 0;1=4
P 10.42498976 4.9831 25 P 0 0;1=4
P 10.42498976 5.0731 25 P 0 0;1=4
P 10.42498976 5.0281 25 P 0 0;1=4
P 10.46498976 4.9831 25 P 0 0;1=4
P 10.46498976 5.0731 25 P 0 0;1=4
P 10.46498976 5.0281 25 P 0 0;1=4
P 10.85498976 4.9431 25 P 0 0;1=4
P 10.81498976 4.9431 25 P 0 0;1=4
P 10.65498976 4.9431 25 P 0 0;1=4
P 10.69498976 4.9431 25 P 0 0;1=4
P 10.85498976 5.0281 25 P 0 0;1=4
P 10.85498976 5.0731 25 P 0 0;1=4
P 10.85498976 4.9831 25 P 0 0;1=4
P 10.81498976 5.0281 25 P 0 0;1=4
P 10.81498976 5.0731 25 P 0 0;1=4
P 10.81498976 4.9831 25 P 0 0;1=4
P 10.81498976 5.1181 25 P 0 0;1=4
P 10.85498976 5.1181 25 P 0 0;1=4
P 10.73498976 5.1181 25 P 0 0;1=4
P 10.69498976 5.1181 25 P 0 0;1=4
P 10.65498976 5.1181 25 P 0 0;1=4
P 10.77498976 5.1181 25 P 0 0;1=4
P 10.65498976 4.9831 25 P 0 0;1=4
P 10.65498976 5.0731 25 P 0 0;1=4
P 10.65498976 5.0281 25 P 0 0;1=4
P 10.69498976 4.9831 25 P 0 0;1=4
P 10.69498976 5.0731 25 P 0 0;1=4
P 10.69498976 5.0281 25 P 0 0;1=4
P 1.23905994 4.60351004 25 P 0 0;1=4
P 1.18905994 5.04351004 25 P 0 0;1=4
P 1.33655994 4.85601004 25 P 0 0;1=4
P 10.16606998 2.81 25 P 0 0;1=4
P 4.15220974 2.9281 25 P 0 0;1=4
P 11.45278976 2.9414 25 P 0 0;1=4
P 11.45278976 3.0214 25 P 0 0;1=4
P 11.45278976 3.0564 25 P 0 0;1=4
P 11.45278976 3.1014 25 P 0 0;1=4
P 11.45278976 3.1364 25 P 0 0;1=4
P 11.45278976 3.2164 25 P 0 0;1=4
P 11.45278976 3.1814 25 P 0 0;1=4
P 11.45278976 2.9764 25 P 0 0;1=4
P 11.45278976 3.2614 25 P 0 0;1=4
P 11.45278976 3.2964 25 P 0 0;1=4
P 0.09448996 1.45275994 27 P 0 3;1=1
P 0.27165 1.57086998 27 P 0 3;1=1
P 0.35038996 1.45275994 27 P 0 3;1=1
P 12.81495 1.49212992 27 P 0 3;1=1
P 12.73620994 1.61023996 27 P 0 3;1=1
P 12.55905 1.49212992 27 P 0 3;1=1
P 0.27165 1.88582992 27 P 0 3;1=1
P 12.73620994 1.9252 27 P 0 3;1=1
P 7.35730974 0.036 25 P 0 0;1=4
P 7.60730974 0.036 25 P 0 0;1=4
P 7.55730974 0.036 25 P 0 0;1=4
P 7.50730974 0.036 25 P 0 0;1=4
P 7.45730974 0.036 25 P 0 0;1=4
P 7.40730974 0.036 25 P 0 0;1=4
P 7.85730974 0.036 25 P 0 0;1=4
P 7.80730974 0.036 25 P 0 0;1=4
P 7.75730974 0.036 25 P 0 0;1=4
P 7.70730974 0.036 25 P 0 0;1=4
P 7.65730974 0.036 25 P 0 0;1=4
P 8.15730974 0.036 25 P 0 0;1=4
P 8.10730974 0.036 25 P 0 0;1=4
P 8.05730974 0.036 25 P 0 0;1=4
P 8.00730974 0.036 25 P 0 0;1=4
P 7.95730974 0.036 25 P 0 0;1=4
P 7.90730974 0.036 25 P 0 0;1=4
P 8.40730974 0.036 25 P 0 0;1=4
P 8.35730974 0.036 25 P 0 0;1=4
P 8.30730974 0.036 25 P 0 0;1=4
P 8.25730974 0.036 25 P 0 0;1=4
P 8.20730974 0.036 25 P 0 0;1=4
P 8.65730974 0.036 25 P 0 0;1=4
P 8.60730974 0.036 25 P 0 0;1=4
P 8.55730974 0.036 25 P 0 0;1=4
P 8.50730974 0.036 25 P 0 0;1=4
P 8.45730974 0.036 25 P 0 0;1=4
P 8.90730974 0.036 25 P 0 0;1=4
P 8.85730974 0.036 25 P 0 0;1=4
P 8.80730974 0.036 25 P 0 0;1=4
P 8.75730974 0.036 25 P 0 0;1=4
P 8.70730974 0.036 25 P 0 0;1=4
P 9.20730974 0.036 25 P 0 0;1=4
P 9.15730974 0.036 25 P 0 0;1=4
P 9.10730974 0.036 25 P 0 0;1=4
P 9.05730974 0.036 25 P 0 0;1=4
P 9.00730974 0.036 25 P 0 0;1=4
P 8.95730974 0.036 25 P 0 0;1=4
P 9.45730974 0.036 25 P 0 0;1=4
P 9.40730974 0.036 25 P 0 0;1=4
P 9.35730974 0.036 25 P 0 0;1=4
P 9.30730974 0.036 25 P 0 0;1=4
P 9.25730974 0.036 25 P 0 0;1=4
P 9.70730974 0.036 25 P 0 0;1=4
P 9.65730974 0.036 25 P 0 0;1=4
P 9.60730974 0.036 25 P 0 0;1=4
P 9.55730974 0.036 25 P 0 0;1=4
P 9.50730974 0.036 25 P 0 0;1=4
P 10.00730974 0.036 25 P 0 0;1=4
P 9.95730974 0.036 25 P 0 0;1=4
P 9.90730974 0.036 25 P 0 0;1=4
P 9.85730974 0.036 25 P 0 0;1=4
P 9.80730974 0.036 25 P 0 0;1=4
P 9.75730974 0.036 25 P 0 0;1=4
P 10.25730974 0.036 25 P 0 0;1=4
P 10.20730974 0.036 25 P 0 0;1=4
P 10.15730974 0.036 25 P 0 0;1=4
P 10.10730974 0.036 25 P 0 0;1=4
P 10.05730974 0.036 25 P 0 0;1=4
P 10.50730974 0.036 25 P 0 0;1=4
P 10.45730974 0.036 25 P 0 0;1=4
P 10.40730974 0.036 25 P 0 0;1=4
P 10.35730974 0.036 25 P 0 0;1=4
P 10.30730974 0.036 25 P 0 0;1=4
P 10.75730974 0.036 25 P 0 0;1=4
P 10.70730974 0.036 25 P 0 0;1=4
P 10.65730974 0.036 25 P 0 0;1=4
P 10.60730974 0.036 25 P 0 0;1=4
P 10.55730974 0.036 25 P 0 0;1=4
P 11.05730974 0.036 25 P 0 0;1=4
P 11.00730974 0.036 25 P 0 0;1=4
P 10.95730974 0.036 25 P 0 0;1=4
P 10.90730974 0.036 25 P 0 0;1=4
P 10.85730974 0.036 25 P 0 0;1=4
P 10.80730974 0.036 25 P 0 0;1=4
P 11.30730974 0.036 25 P 0 0;1=4
P 11.25730974 0.036 25 P 0 0;1=4
P 11.20730974 0.036 25 P 0 0;1=4
P 11.15730974 0.036 25 P 0 0;1=4
P 11.10730974 0.036 25 P 0 0;1=4
P 11.55730974 0.036 25 P 0 0;1=4
P 11.50730974 0.036 25 P 0 0;1=4
P 11.45730974 0.036 25 P 0 0;1=4
P 11.40730974 0.036 25 P 0 0;1=4
P 11.35730974 0.036 25 P 0 0;1=4
P 11.80730974 0.036 25 P 0 0;1=4
P 11.75730974 0.036 25 P 0 0;1=4
P 11.70730974 0.036 25 P 0 0;1=4
P 11.65730974 0.036 25 P 0 0;1=4
P 11.60730974 0.036 25 P 0 0;1=4
P 12.10730974 0.036 25 P 0 0;1=4
P 12.05730974 0.036 25 P 0 0;1=4
P 12.00730974 0.036 25 P 0 0;1=4
P 11.95730974 0.036 25 P 0 0;1=4
P 11.90730974 0.036 25 P 0 0;1=4
P 11.85730974 0.036 25 P 0 0;1=4
P 12.35730974 0.036 25 P 0 0;1=4
P 12.30730974 0.036 25 P 0 0;1=4
P 12.25730974 0.036 25 P 0 0;1=4
P 12.20730974 0.036 25 P 0 0;1=4
P 12.15730974 0.036 25 P 0 0;1=4
P 12.60730974 0.036 25 P 0 0;1=4
P 12.55730974 0.036 25 P 0 0;1=4
P 12.50730974 0.036 25 P 0 0;1=4
P 12.45730974 0.036 25 P 0 0;1=4
P 12.40730974 0.036 25 P 0 0;1=4
P 12.8892 0.22595974 25 P 0 0;1=4
P 12.8892 0.17595974 25 P 0 0;1=4
P 12.8892 0.12595974 25 P 0 0;1=4
P 12.88911073 0.07596083 25 P 0 0;1=4
P 12.85728868 0.03739114 25 P 0 0;1=4
P 12.80730974 0.036 25 P 0 0;1=4
P 12.75730974 0.036 25 P 0 0;1=4
P 12.70730974 0.036 25 P 0 0;1=4
P 12.65730974 0.036 25 P 0 0;1=4
P 12.8892 0.47595974 25 P 0 0;1=4
P 12.8892 0.42595974 25 P 0 0;1=4
P 12.8892 0.37595974 25 P 0 0;1=4
P 12.8892 0.32595974 25 P 0 0;1=4
P 12.8892 0.27595974 25 P 0 0;1=4
P 12.8892 0.62595974 25 P 0 0;1=4
P 12.8892 0.57595974 25 P 0 0;1=4
P 12.8892 0.52595974 25 P 0 0;1=4
P 0.036 1.00868002 25 P 0 0;1=4
P 0.036 1.05868002 25 P 0 0;1=4
P 0.036 1.10868002 25 P 0 0;1=4
P 0.036 1.15868002 25 P 0 0;1=4
P 0.036 1.20868002 25 P 0 0;1=4
P 0.036 1.25868002 25 P 0 0;1=4
P 0.036 1.30868002 25 P 0 0;1=4
P 0.036 1.35868002 25 P 0 0;1=4
P 0.036 1.40868002 25 P 0 0;1=4
P 0.036 1.45868002 25 P 0 0;1=4
P 0.036 1.50868002 25 P 0 0;1=4
P 0.036 1.55868002 25 P 0 0;1=4
P 0.036 1.60868002 25 P 0 0;1=4
P 0.036 1.65868002 25 P 0 0;1=4
P 0.036 1.70868002 25 P 0 0;1=4
P 0.036 1.75868002 25 P 0 0;1=4
P 0.036 1.80868002 25 P 0 0;1=4
P 0.036 1.85868002 25 P 0 0;1=4
P 0.036 1.90868002 25 P 0 0;1=4
P 0.036 1.95868002 25 P 0 0;1=4
P 0.036 2.00868002 25 P 0 0;1=4
P 0.036 2.05868002 25 P 0 0;1=4
P 0.036 2.10868002 25 P 0 0;1=4
P 0.036 2.15868002 25 P 0 0;1=4
P 0.036 2.20868002 25 P 0 0;1=4
P 0.036 2.25868002 25 P 0 0;1=4
P 0.036 2.30868002 25 P 0 0;1=4
P 0.036 2.35868002 25 P 0 0;1=4
P 0.036 2.40868002 25 P 0 0;1=4
P 0.036 2.45868002 25 P 0 0;1=4
P 0.036 2.50868002 25 P 0 0;1=4
P 0.036 2.55868002 25 P 0 0;1=4
P 0.036 2.60868002 25 P 0 0;1=4
P 0.036 2.65868002 25 P 0 0;1=4
P 0.036 2.70868002 25 P 0 0;1=4
P 0.036 2.75868002 25 P 0 0;1=4
P 0.036 2.80868002 25 P 0 0;1=4
P 0.036 2.85868002 25 P 0 0;1=4
P 0.036 2.90868002 25 P 0 0;1=4
P 0.036 2.95868002 25 P 0 0;1=4
P 0.036 3.00868002 25 P 0 0;1=4
P 0.036 3.05868002 25 P 0 0;1=4
P 0.036 3.10868002 25 P 0 0;1=4
P 0.036 3.15868002 25 P 0 0;1=4
P 0.036 3.20868002 25 P 0 0;1=4
P 0.036 3.25868002 25 P 0 0;1=4
P 0.036 3.30868002 25 P 0 0;1=4
P 0.036 3.35868002 25 P 0 0;1=4
P 0.036 3.40868002 25 P 0 0;1=4
P 0.036 3.45868002 25 P 0 0;1=4
P 0.036 3.50868002 25 P 0 0;1=4
P 0.036 3.55868002 25 P 0 0;1=4
P 0.036 3.60868002 25 P 0 0;1=4
P 0.036 3.65868002 25 P 0 0;1=4
P 0.036 3.70868002 25 P 0 0;1=4
P 0.036 3.75868002 25 P 0 0;1=4
P 0.036 3.80868002 25 P 0 0;1=4
P 0.036 3.85868002 25 P 0 0;1=4
P 0.036 3.90868002 25 P 0 0;1=4
P 0.036 3.95868002 25 P 0 0;1=4
P 0.036 4.00868002 25 P 0 0;1=4
P 0.036 4.05868002 25 P 0 0;1=4
P 0.036 4.10868002 25 P 0 0;1=4
P 0.036 4.15868002 25 P 0 0;1=4
P 0.036 4.20868002 25 P 0 0;1=4
P 0.036 4.25868002 25 P 0 0;1=4
P 0.036 4.30868002 25 P 0 0;1=4
P 0.036 4.35868002 25 P 0 0;1=4
P 0.036 4.40868002 25 P 0 0;1=4
P 0.036 4.45868002 25 P 0 0;1=4
P 0.036 4.50868002 25 P 0 0;1=4
P 0.036 4.55868002 25 P 0 0;1=4
P 0.036 4.60868002 25 P 0 0;1=4
P 0.036 4.65868002 25 P 0 0;1=4
P 0.036 4.70868002 25 P 0 0;1=4
P 0.036 4.75868002 25 P 0 0;1=4
P 12.8892 1.02595974 25 P 0 0;1=4
P 12.8892 1.27595974 25 P 0 0;1=4
P 12.8892 1.22595974 25 P 0 0;1=4
P 12.8892 1.17595974 25 P 0 0;1=4
P 12.8892 1.12595974 25 P 0 0;1=4
P 12.8892 1.07595974 25 P 0 0;1=4
P 12.8892 1.52595974 25 P 0 0;1=4
P 12.8892 1.47595974 25 P 0 0;1=4
P 12.8892 1.42595974 25 P 0 0;1=4
P 12.8892 1.37595974 25 P 0 0;1=4
P 12.8892 1.32595974 25 P 0 0;1=4
P 12.8892 1.77595974 25 P 0 0;1=4
P 12.8892 1.72595974 25 P 0 0;1=4
P 12.8892 1.67595974 25 P 0 0;1=4
P 12.8892 1.62595974 25 P 0 0;1=4
P 12.8892 1.57595974 25 P 0 0;1=4
P 12.8892 2.07595974 25 P 0 0;1=4
P 12.8892 2.02595974 25 P 0 0;1=4
P 12.8892 1.97595974 25 P 0 0;1=4
P 12.8892 1.92595974 25 P 0 0;1=4
P 12.8892 1.87595974 25 P 0 0;1=4
P 12.8892 1.82595974 25 P 0 0;1=4
P 12.8892 2.32595974 25 P 0 0;1=4
P 12.8892 2.27595974 25 P 0 0;1=4
P 12.8892 2.22595974 25 P 0 0;1=4
P 12.8892 2.17595974 25 P 0 0;1=4
P 12.8892 2.57595974 25 P 0 0;1=4
P 12.8892 2.52595974 25 P 0 0;1=4
P 12.8892 2.47595974 25 P 0 0;1=4
P 12.8892 2.42595974 25 P 0 0;1=4
P 12.8892 2.37595974 25 P 0 0;1=4
P 12.8892 2.82595974 25 P 0 0;1=4
P 12.8892 2.77595974 25 P 0 0;1=4
P 12.8892 2.72595974 25 P 0 0;1=4
P 12.8892 2.67595974 25 P 0 0;1=4
P 12.8892 2.62595974 25 P 0 0;1=4
P 12.8892 3.12595974 25 P 0 0;1=4
P 12.8892 3.07595974 25 P 0 0;1=4
P 12.8892 3.02595974 25 P 0 0;1=4
P 12.8892 2.97595974 25 P 0 0;1=4
P 12.8892 2.92595974 25 P 0 0;1=4
P 12.8892 2.87595974 25 P 0 0;1=4
P 12.8892 3.37595974 25 P 0 0;1=4
P 12.8892 3.32595974 25 P 0 0;1=4
P 12.8892 3.27595974 25 P 0 0;1=4
P 12.8892 3.22595974 25 P 0 0;1=4
P 12.8892 3.17595974 25 P 0 0;1=4
P 12.8892 3.62595974 25 P 0 0;1=4
P 12.8892 3.57595974 25 P 0 0;1=4
P 12.8892 3.52595974 25 P 0 0;1=4
P 12.8892 3.47595974 25 P 0 0;1=4
P 12.8892 3.42595974 25 P 0 0;1=4
P 12.8892 3.92595974 25 P 0 0;1=4
P 12.8892 3.87595974 25 P 0 0;1=4
P 12.8892 3.82595974 25 P 0 0;1=4
P 12.8892 3.77595974 25 P 0 0;1=4
P 12.8892 3.72595974 25 P 0 0;1=4
P 12.8892 3.67595974 25 P 0 0;1=4
P 12.8892 4.17595974 25 P 0 0;1=4
P 12.8892 4.12595974 25 P 0 0;1=4
P 12.8892 4.07595974 25 P 0 0;1=4
P 12.8892 4.02595974 25 P 0 0;1=4
P 12.8892 3.97595974 25 P 0 0;1=4
P 12.8892 4.42595974 25 P 0 0;1=4
P 12.8892 4.37595974 25 P 0 0;1=4
P 12.8892 4.32595974 25 P 0 0;1=4
P 12.8892 4.27595974 25 P 0 0;1=4
P 12.8892 4.22595974 25 P 0 0;1=4
P 12.8892 4.67595974 25 P 0 0;1=4
P 12.8892 4.62595974 25 P 0 0;1=4
P 12.8892 4.57595974 25 P 0 0;1=4
P 12.8892 4.52595974 25 P 0 0;1=4
P 12.8892 4.47595974 25 P 0 0;1=4
P 12.8892 4.82595974 25 P 0 0;1=4
P 12.8892 4.77595974 25 P 0 0;1=4
P 12.8892 4.72595974 25 P 0 0;1=4
P 0.036 5.25868002 25 P 0 0;1=4
P 0.036 5.30868002 25 P 0 0;1=4
P 0.036 5.35868002 25 P 0 0;1=4
P 0.036 5.40868002 25 P 0 0;1=4
P 0.036 5.45868002 25 P 0 0;1=4
P 0.036 5.50868002 25 P 0 0;1=4
P 0.036 5.55868002 25 P 0 0;1=4
P 0.036 5.60868002 25 P 0 0;1=4
P 0.036 5.65868002 25 P 0 0;1=4
P 0.036 5.70868002 25 P 0 0;1=4
P 0.036 5.75868002 25 P 0 0;1=4
P 0.036 5.80868002 25 P 0 0;1=4
P 0.036 5.85868002 25 P 0 0;1=4
P 0.036 5.90868002 25 P 0 0;1=4
P 0.03826998 5.95863002 25 P 0 0;1=4
P 0.07901024 5.98761998 25 P 0 0;1=4
P 0.12901024 5.98761998 25 P 0 0;1=4
P 0.17901024 5.98761998 25 P 0 0;1=4
P 0.22901024 5.98761998 25 P 0 0;1=4
P 0.27901024 5.98761998 25 P 0 0;1=4
P 0.32901024 5.98761998 25 P 0 0;1=4
P 0.37901024 5.98761998 25 P 0 0;1=4
P 0.42901024 5.98761998 25 P 0 0;1=4
P 0.47901024 5.98761998 25 P 0 0;1=4
P 0.52901024 5.98761998 25 P 0 0;1=4
P 0.57901024 5.98761998 25 P 0 0;1=4
P 0.62901024 5.98761998 25 P 0 0;1=4
P 0.67901024 5.98761998 25 P 0 0;1=4
P 0.72901024 5.98761998 25 P 0 0;1=4
P 0.77901024 5.98761998 25 P 0 0;1=4
P 0.82901024 5.98761998 25 P 0 0;1=4
P 0.87901024 5.98761998 25 P 0 0;1=4
P 0.92901024 5.98761998 25 P 0 0;1=4
P 0.97901024 5.98761998 25 P 0 0;1=4
P 1.02901024 5.98761998 25 P 0 0;1=4
P 1.07901024 5.98761998 25 P 0 0;1=4
P 1.12901024 5.98761998 25 P 0 0;1=4
P 1.17901024 5.98761998 25 P 0 0;1=4
P 1.22901024 5.98761998 25 P 0 0;1=4
P 1.27901024 5.98761998 25 P 0 0;1=4
P 1.32901024 5.98761998 25 P 0 0;1=4
P 1.37901024 5.98761998 25 P 0 0;1=4
P 1.42901024 5.98761998 25 P 0 0;1=4
P 1.47901024 5.98761998 25 P 0 0;1=4
P 1.52901024 5.98761998 25 P 0 0;1=4
P 1.57901024 5.98761998 25 P 0 0;1=4
P 1.62901024 5.98761998 25 P 0 0;1=4
P 1.67901024 5.98761998 25 P 0 0;1=4
P 1.72901024 5.98761998 25 P 0 0;1=4
P 1.77901024 5.98761998 25 P 0 0;1=4
P 1.82901024 5.98761998 25 P 0 0;1=4
P 1.87901024 5.98761998 25 P 0 0;1=4
P 1.92901024 5.98761998 25 P 0 0;1=4
P 1.97901024 5.98761998 25 P 0 0;1=4
P 2.02901024 5.98761998 25 P 0 0;1=4
P 2.07901024 5.98761998 25 P 0 0;1=4
P 2.12901024 5.98761998 25 P 0 0;1=4
P 2.17901024 5.98761998 25 P 0 0;1=4
P 2.22901024 5.98761998 25 P 0 0;1=4
P 2.27901024 5.98761998 25 P 0 0;1=4
P 2.32901024 5.98761998 25 P 0 0;1=4
P 2.37901024 5.98761998 25 P 0 0;1=4
P 2.42901024 5.98761998 25 P 0 0;1=4
P 2.47901024 5.98761998 25 P 0 0;1=4
P 2.52901024 5.98761998 25 P 0 0;1=4
P 2.57901024 5.98761998 25 P 0 0;1=4
P 2.62901024 5.98761998 25 P 0 0;1=4
P 2.67901024 5.98761998 25 P 0 0;1=4
P 2.72901024 5.98761998 25 P 0 0;1=4
P 2.77901024 5.98761998 25 P 0 0;1=4
P 2.82901024 5.98761998 25 P 0 0;1=4
P 2.87901024 5.98761998 25 P 0 0;1=4
P 2.92901024 5.98761998 25 P 0 0;1=4
P 2.97901024 5.98761998 25 P 0 0;1=4
P 3.02901024 5.98761998 25 P 0 0;1=4
P 3.07901024 5.98761998 25 P 0 0;1=4
P 3.12901024 5.98761998 25 P 0 0;1=4
P 3.17901024 5.98761998 25 P 0 0;1=4
P 3.22901024 5.98761998 25 P 0 0;1=4
P 3.27901024 5.98761998 25 P 0 0;1=4
P 3.32901024 5.98761998 25 P 0 0;1=4
P 3.37901024 5.98761998 25 P 0 0;1=4
P 3.42901024 5.98761998 25 P 0 0;1=4
P 3.47901024 5.98761998 25 P 0 0;1=4
P 3.52901024 5.98761998 25 P 0 0;1=4
P 3.57901024 5.98761998 25 P 0 0;1=4
P 3.62901024 5.98761998 25 P 0 0;1=4
P 3.67901024 5.98761998 25 P 0 0;1=4
P 3.72901024 5.98761998 25 P 0 0;1=4
P 3.77901024 5.98761998 25 P 0 0;1=4
P 3.82901024 5.98761998 25 P 0 0;1=4
P 3.87901024 5.98761998 25 P 0 0;1=4
P 3.92901024 5.98761998 25 P 0 0;1=4
P 3.97901024 5.98761998 25 P 0 0;1=4
P 4.02901024 5.98761998 25 P 0 0;1=4
P 4.07901024 5.98761998 25 P 0 0;1=4
P 4.12901024 5.98761998 25 P 0 0;1=4
P 4.17901024 5.98761998 25 P 0 0;1=4
P 4.22901024 5.98761998 25 P 0 0;1=4
P 4.27901024 5.98761998 25 P 0 0;1=4
P 4.32901024 5.98761998 25 P 0 0;1=4
P 4.37901024 5.98761998 25 P 0 0;1=4
P 4.42901024 5.98761998 25 P 0 0;1=4
P 4.47901024 5.98761998 25 P 0 0;1=4
P 4.52901024 5.98761998 25 P 0 0;1=4
P 4.57901024 5.98761998 25 P 0 0;1=4
P 4.62901024 5.98761998 25 P 0 0;1=4
P 4.67901024 5.98761998 25 P 0 0;1=4
P 4.72901024 5.98761998 25 P 0 0;1=4
P 4.77901024 5.98761998 25 P 0 0;1=4
P 4.82901024 5.98761998 25 P 0 0;1=4
P 4.87901024 5.98761998 25 P 0 0;1=4
P 4.92901024 5.98761998 25 P 0 0;1=4
P 4.97901024 5.98761998 25 P 0 0;1=4
P 5.02901024 5.98761998 25 P 0 0;1=4
P 5.07901024 5.98761998 25 P 0 0;1=4
P 5.12901024 5.98761998 25 P 0 0;1=4
P 5.17901024 5.98761998 25 P 0 0;1=4
P 5.22901024 5.98761998 25 P 0 0;1=4
P 5.27901024 5.98761998 25 P 0 0;1=4
P 5.32901024 5.98761998 25 P 0 0;1=4
P 5.37901024 5.98761998 25 P 0 0;1=4
P 5.42901024 5.98761998 25 P 0 0;1=4
P 5.47901024 5.98761998 25 P 0 0;1=4
P 5.52901024 5.98761998 25 P 0 0;1=4
P 5.57901024 5.98761998 25 P 0 0;1=4
P 5.62901024 5.98761998 25 P 0 0;1=4
P 5.67901024 5.98761998 25 P 0 0;1=4
P 5.72901024 5.98761998 25 P 0 0;1=4
P 5.77901024 5.98761998 25 P 0 0;1=4
P 5.82901024 5.98761998 25 P 0 0;1=4
P 5.87901024 5.98761998 25 P 0 0;1=4
P 5.92901024 5.98761998 25 P 0 0;1=4
P 5.97901024 5.98761998 25 P 0 0;1=4
P 6.02901024 5.98761998 25 P 0 0;1=4
P 6.07901024 5.98761998 25 P 0 0;1=4
P 6.12901024 5.98761998 25 P 0 0;1=4
P 6.17901024 5.98761998 25 P 0 0;1=4
P 6.22901024 5.98761998 25 P 0 0;1=4
P 6.27901024 5.98761998 25 P 0 0;1=4
P 6.32901024 5.98761998 25 P 0 0;1=4
P 6.37901024 5.98761998 25 P 0 0;1=4
P 6.42901024 5.98761998 25 P 0 0;1=4
P 6.47901024 5.98761998 25 P 0 0;1=4
P 6.52901024 5.98761998 25 P 0 0;1=4
P 6.57901024 5.98761998 25 P 0 0;1=4
P 6.62901024 5.98761998 25 P 0 0;1=4
P 6.67901024 5.98761998 25 P 0 0;1=4
P 6.72901024 5.98761998 25 P 0 0;1=4
P 6.77901024 5.98761998 25 P 0 0;1=4
P 6.82901024 5.98761998 25 P 0 0;1=4
P 6.87901024 5.98761998 25 P 0 0;1=4
P 6.92901024 5.98761998 25 P 0 0;1=4
P 6.97901024 5.98761998 25 P 0 0;1=4
P 12.8892 5.47595974 25 P 0 0;1=4
P 12.8892 5.42595974 25 P 0 0;1=4
P 12.8892 5.37595974 25 P 0 0;1=4
P 12.8892 5.32595974 25 P 0 0;1=4
P 12.8892 5.27595974 25 P 0 0;1=4
P 12.8892 5.72595974 25 P 0 0;1=4
P 12.8892 5.67595974 25 P 0 0;1=4
P 12.8892 5.62595974 25 P 0 0;1=4
P 12.8892 5.57595974 25 P 0 0;1=4
P 12.8892 5.52595974 25 P 0 0;1=4
P 7.37901024 5.98761998 25 P 0 0;1=4
P 7.42901024 5.98761998 25 P 0 0;1=4
P 7.47901024 5.98761998 25 P 0 0;1=4
P 7.52901024 5.98761998 25 P 0 0;1=4
P 7.57901024 5.98761998 25 P 0 0;1=4
P 7.62901024 5.98761998 25 P 0 0;1=4
P 7.67901024 5.98761998 25 P 0 0;1=4
P 7.72901024 5.98761998 25 P 0 0;1=4
P 7.77901024 5.98761998 25 P 0 0;1=4
P 7.82901024 5.98761998 25 P 0 0;1=4
P 7.87901024 5.98761998 25 P 0 0;1=4
P 7.92901024 5.98761998 25 P 0 0;1=4
P 7.97901024 5.98761998 25 P 0 0;1=4
P 8.02901024 5.98761998 25 P 0 0;1=4
P 8.07901024 5.98761998 25 P 0 0;1=4
P 8.12901024 5.98761998 25 P 0 0;1=4
P 8.17901024 5.98761998 25 P 0 0;1=4
P 8.22901024 5.98761998 25 P 0 0;1=4
P 8.27901024 5.98761998 25 P 0 0;1=4
P 8.32901024 5.98761998 25 P 0 0;1=4
P 8.37901024 5.98761998 25 P 0 0;1=4
P 8.42901024 5.98761998 25 P 0 0;1=4
P 8.47901024 5.98761998 25 P 0 0;1=4
P 8.52901024 5.98761998 25 P 0 0;1=4
P 8.57901024 5.98761998 25 P 0 0;1=4
P 8.62901024 5.98761998 25 P 0 0;1=4
P 8.67901024 5.98761998 25 P 0 0;1=4
P 8.72901024 5.98761998 25 P 0 0;1=4
P 8.77901024 5.98761998 25 P 0 0;1=4
P 8.82901024 5.98761998 25 P 0 0;1=4
P 8.87901024 5.98761998 25 P 0 0;1=4
P 8.92901024 5.98761998 25 P 0 0;1=4
P 8.97901024 5.98761998 25 P 0 0;1=4
P 9.02901024 5.98761998 25 P 0 0;1=4
P 9.07901024 5.98761998 25 P 0 0;1=4
P 9.12901024 5.98761998 25 P 0 0;1=4
P 9.17901024 5.98761998 25 P 0 0;1=4
P 9.22901024 5.98761998 25 P 0 0;1=4
P 9.27901024 5.98761998 25 P 0 0;1=4
P 9.32901024 5.98761998 25 P 0 0;1=4
P 9.37901024 5.98761998 25 P 0 0;1=4
P 9.42901024 5.98761998 25 P 0 0;1=4
P 9.47901024 5.98761998 25 P 0 0;1=4
P 9.52901024 5.98761998 25 P 0 0;1=4
P 9.57901024 5.98761998 25 P 0 0;1=4
P 9.62901024 5.98761998 25 P 0 0;1=4
P 9.67901024 5.98761998 25 P 0 0;1=4
P 9.72901024 5.98761998 25 P 0 0;1=4
P 9.77901024 5.98761998 25 P 0 0;1=4
P 9.82901024 5.98761998 25 P 0 0;1=4
P 9.87901024 5.98761998 25 P 0 0;1=4
P 9.92901024 5.98761998 25 P 0 0;1=4
P 9.97901024 5.98761998 25 P 0 0;1=4
P 10.02901024 5.98761998 25 P 0 0;1=4
P 10.07901024 5.98761998 25 P 0 0;1=4
P 10.12901024 5.98761998 25 P 0 0;1=4
P 10.17901024 5.98761998 25 P 0 0;1=4
P 10.22901024 5.98761998 25 P 0 0;1=4
P 10.27901024 5.98761998 25 P 0 0;1=4
P 10.32901024 5.98761998 25 P 0 0;1=4
P 10.37901024 5.98761998 25 P 0 0;1=4
P 10.42901024 5.98761998 25 P 0 0;1=4
P 10.47901024 5.98761998 25 P 0 0;1=4
P 10.52901024 5.98761998 25 P 0 0;1=4
P 10.57901024 5.98761998 25 P 0 0;1=4
P 10.62901024 5.98761998 25 P 0 0;1=4
P 10.67901024 5.98761998 25 P 0 0;1=4
P 10.72901024 5.98761998 25 P 0 0;1=4
P 10.77901024 5.98761998 25 P 0 0;1=4
P 10.82901024 5.98761998 25 P 0 0;1=4
P 10.87901024 5.98761998 25 P 0 0;1=4
P 10.92901024 5.98761998 25 P 0 0;1=4
P 10.97901024 5.98761998 25 P 0 0;1=4
P 11.02901024 5.98761998 25 P 0 0;1=4
P 11.07901024 5.98761998 25 P 0 0;1=4
P 11.12901024 5.98761998 25 P 0 0;1=4
P 11.17901024 5.98761998 25 P 0 0;1=4
P 11.22901024 5.98761998 25 P 0 0;1=4
P 11.27901024 5.98761998 25 P 0 0;1=4
P 11.32901024 5.98761998 25 P 0 0;1=4
P 11.37901024 5.98761998 25 P 0 0;1=4
P 11.42901024 5.98761998 25 P 0 0;1=4
P 11.47901024 5.98761998 25 P 0 0;1=4
P 11.52901024 5.98761998 25 P 0 0;1=4
P 11.57901024 5.98761998 25 P 0 0;1=4
P 11.62901024 5.98761998 25 P 0 0;1=4
P 11.67901024 5.98761998 25 P 0 0;1=4
P 11.72901024 5.98761998 25 P 0 0;1=4
P 11.77901024 5.98761998 25 P 0 0;1=4
P 11.82901024 5.98761998 25 P 0 0;1=4
P 11.87901024 5.98761998 25 P 0 0;1=4
P 11.92901024 5.98761998 25 P 0 0;1=4
P 11.97901024 5.98761998 25 P 0 0;1=4
P 12.02901024 5.98761998 25 P 0 0;1=4
P 12.07901024 5.98761998 25 P 0 0;1=4
P 12.12901024 5.98761998 25 P 0 0;1=4
P 12.17901024 5.98761998 25 P 0 0;1=4
P 12.22901024 5.98761998 25 P 0 0;1=4
P 12.27901024 5.98761998 25 P 0 0;1=4
P 12.32901024 5.98761998 25 P 0 0;1=4
P 12.37901024 5.98761998 25 P 0 0;1=4
P 12.42901024 5.98761998 25 P 0 0;1=4
P 12.47901024 5.98761998 25 P 0 0;1=4
P 12.52901024 5.98761998 25 P 0 0;1=4
P 12.57901024 5.98761998 25 P 0 0;1=4
P 12.62901024 5.98761998 25 P 0 0;1=4
P 12.67901024 5.98761998 25 P 0 0;1=4
P 12.72901024 5.98761998 25 P 0 0;1=4
P 12.77901024 5.98761998 25 P 0 0;1=4
P 12.82901024 5.98761998 25 P 0 0;1=4
P 12.87725994 5.97451004 25 P 0 0;1=4
P 12.8892 5.92595974 25 P 0 0;1=4
P 12.8892 5.87595974 25 P 0 0;1=4
P 12.8892 5.82595974 25 P 0 0;1=4
P 12.8892 5.77595974 25 P 0 0;1=4
P 4.33605 4.9231 25 P 0 0;1=4
P 4.38105 4.9231 25 P 0 0;1=4
P 4.30105 4.9431 25 P 0 0;1=4
P 4.42105 4.9431 25 P 0 0;1=4
P 4.46105 4.9431 25 P 0 0;1=4
P 4.26105 4.9431 25 P 0 0;1=4
P 4.72605 4.9231 25 P 0 0;1=4
P 4.65105 4.9431 25 P 0 0;1=4
P 4.69105 4.9431 25 P 0 0;1=4
P 4.85105 4.9431 25 P 0 0;1=4
P 4.81105 4.9431 25 P 0 0;1=4
P 4.77105 4.9231 25 P 0 0;1=4
P 4.30105 5.0281 25 P 0 0;1=4
P 4.30105 5.0731 25 P 0 0;1=4
P 4.30105 4.9831 25 P 0 0;1=4
P 4.34105 5.1181 25 P 0 0;1=4
P 4.38105 5.1181 25 P 0 0;1=4
P 4.46105 5.1181 25 P 0 0;1=4
P 4.42105 5.1181 25 P 0 0;1=4
P 4.42105 4.9831 25 P 0 0;1=4
P 4.42105 5.0731 25 P 0 0;1=4
P 4.42105 5.0281 25 P 0 0;1=4
P 4.46105 4.9831 25 P 0 0;1=4
P 4.46105 5.0731 25 P 0 0;1=4
P 4.46105 5.0281 25 P 0 0;1=4
P 4.26105 5.0281 25 P 0 0;1=4
P 4.26105 5.0731 25 P 0 0;1=4
P 4.26105 4.9831 25 P 0 0;1=4
P 4.73105 5.1181 25 P 0 0;1=4
P 4.69105 5.1181 25 P 0 0;1=4
P 4.65105 5.1181 25 P 0 0;1=4
P 4.65105 4.9831 25 P 0 0;1=4
P 4.65105 5.0731 25 P 0 0;1=4
P 4.65105 5.0281 25 P 0 0;1=4
P 4.69105 4.9831 25 P 0 0;1=4
P 4.69105 5.0731 25 P 0 0;1=4
P 4.69105 5.0281 25 P 0 0;1=4
P 4.85105 5.0281 25 P 0 0;1=4
P 4.85105 5.0731 25 P 0 0;1=4
P 4.85105 4.9831 25 P 0 0;1=4
P 4.81105 5.0281 25 P 0 0;1=4
P 4.81105 5.0731 25 P 0 0;1=4
P 4.81105 4.9831 25 P 0 0;1=4
P 4.81105 5.1181 25 P 0 0;1=4
P 4.85105 5.1181 25 P 0 0;1=4
P 4.77105 5.1181 25 P 0 0;1=4
P 4.30105 5.1181 25 P 0 0;1=4
P 4.26105 5.1181 25 P 0 0;1=4
P 9.45795 0.36633002 25 P 0 0;1=4
P 6.62 4.645 25 P 0 0;1=4
P 6.62 4.61 25 P 0 0;1=4
P 6.605 4.77 25 P 0 0;1=4
P 6.315 4.9 25 P 0 0;1=4
P 6.315 4.865 25 P 0 0;1=4
P 6.315 4.82 25 P 0 0;1=4
P 6.315 4.785 25 P 0 0;1=4
P 6.315 4.705 25 P 0 0;1=4
P 6.315 4.74 25 P 0 0;1=4
P 6.315 4.66 25 P 0 0;1=4
P 6.315 4.625 25 P 0 0;1=4
P 1.51672972 5.78 25 P 0 0;1=4
P 1.12303002 5.46015974 25 P 0 0;1=4
P 1.20176998 5.46016004 25 P 0 0;1=4
P 1.51673002 5.46015974 25 P 0 0;1=4
P 1.36 5.355 25 P 0 0;1=4
P 1.41 5.355 25 P 0 0;1=4
P 1.46 5.355 25 P 0 0;1=4
P 1.305 5.885 25 P 0 0;1=4
P 1.355 5.885 25 P 0 0;1=4
P 1.405 5.885 25 P 0 0;1=4
P 1.455 5.885 25 P 0 0;1=4
P 0.705 5.355 25 P 0 0;1=4
P 0.7 5.267 25 P 0 0;1=0
P 0.73 5.175 25 P 0 0;1=4
P 1.03 5.065 25 P 0 0;1=4
P 1.28050994 5.46016004 25 P 0 0;1=4
P 12.215 4.915 25 P 0 0;1=4
P 12.055 4.915 25 P 0 0;1=4
P 10.465 5.245 25 P 0 0;1=4
P 10.465 5.165 25 P 0 0;1=4
P 11.7719 4.80998976 25 P 0 0;1=4
P 11.7719 4.85498976 25 P 0 0;1=4
P 11.7719 4.90498976 25 P 0 0;1=4
P 11.7719 4.94998976 25 P 0 0;1=4
P 11.9719 4.94998976 25 P 0 0;1=4
P 11.9719 4.80998976 25 P 0 0;1=4
P 11.9719 4.85498976 25 P 0 0;1=4
P 11.9719 4.90498976 25 P 0 0;1=4
P 11.9219 4.94998976 25 P 0 0;1=4
P 11.9219 4.80998976 25 P 0 0;1=4
P 11.8719 4.94998976 25 P 0 0;1=4
P 11.8719 4.80998976 25 P 0 0;1=4
P 11.8219 4.80998976 25 P 0 0;1=4
P 11.8219 4.94998976 25 P 0 0;1=4
P 11.69315974 2.6635 25 P 0 0;1=4
P 10.125 2.008 25 P 0 0;1=4
P 5.53530974 1.6642 25 P 0 0;1=4
P 5.53530974 1.7213 25 P 0 0;1=4
P 5.53530974 2.0802 25 P 0 0;1=4
P 5.53530974 1.9393 25 P 0 0;1=4
P 5.53530974 2.2156 25 P 0 0;1=4
P 5.53530974 2.4081 25 P 0 0;1=4
P 5.53530974 2.5473 25 P 0 0;1=4
P 2.86855 4.92 25 P 0 0;1=4
P 2.79767972 4.92 25 P 0 0;1=4
P 3.08113976 4.92 25 P 0 0;1=4
P 3.36460974 4.926 25 P 0 0;1=4
P 3.22287972 4.92 25 P 0 0;1=4
P 3.50633976 4.92 25 P 0 0;1=4
P 3.43546998 4.928 25 P 0 0;1=4
P 3.15398002 4.81401998 25 P 0 0;1=4
P 3.22288002 4.81401998 25 P 0 0;1=4
P 3.36461024 4.81401998 25 P 0 0;1=4
P 3.43547028 4.81401998 25 P 0 0;1=4
P 3.50634026 4.81401998 25 P 0 0;1=4
P 3.22287972 5.023 25 P 0 0;1=4
P 3.50633976 5.023 25 P 0 0;1=4
P 3.43546998 5.023 25 P 0 0;1=4
P 3.14 4.92 25 P 0 0;1=4
P 3.275 4.92 25 P 0 0;1=4
P 3.26 5.332 25 P 0 0;1=4
P 3.06792028 5.332 25 P 0 0;1=4
P 3.51176998 5.17874026 25 P 0 0;1=4
P 3.57176998 5.17874026 25 P 0 0;1=4
P 3.15743996 4.74418002 25 P 0 0;1=4
P 1.63307972 4.92 25 P 0 0;1=4
P 1.84567972 4.92 25 P 0 0;1=4
P 1.77480974 4.92 25 P 0 0;1=4
P 1.70395 4.92 25 P 0 0;1=4
P 2.12913976 4.92 25 P 0 0;1=4
P 2.05827972 4.92 25 P 0 0;1=4
P 1.98740974 4.92 25 P 0 0;1=4
P 1.91653976 4.92 25 P 0 0;1=4
P 2.34173976 4.92 25 P 0 0;1=4
P 2.27086998 4.92 25 P 0 0;1=4
P 2.20000974 4.926 25 P 0 0;1=4
P 2.34173976 4.81 25 P 0 0;1=4
P 2.27086998 4.81 25 P 0 0;1=4
P 2.20000974 4.81 25 P 0 0;1=4
P 1.63173002 4.81526998 25 P 0 0;1=4
P 1.7 4.812 25 P 0 0;1=4
P 1.84567972 4.81 25 P 0 0;1=4
P 1.776 4.812 25 P 0 0;1=4
P 2.12913976 4.81 25 P 0 0;1=4
P 1.99 4.81 25 P 0 0;1=4
P 1.92 4.81 25 P 0 0;1=4
P 2.40716998 5.15374026 25 P 0 0;1=4
P 2.34716998 5.15374026 25 P 0 0;1=4
P 10.58660974 2.16615 25 P 0 0;1=3
P 10.63660974 2.16615 25 P 0 0;1=3
P 10.63660974 2.21615 25 P 0 0;1=3
P 10.88660974 1.91615 25 P 0 0;1=3
P 10.88660974 2.41615 25 P 0 0;1=3
P 10.88660974 2.66615 25 P 0 0;1=3
P 11.03660974 2.41615 25 P 0 0;1=3
P 11.03660974 2.36615 25 P 0 0;1=3
P 1.91110994 4.61826004 25 P 0 0;1=4
P 2.40716998 4.70326004 25 P 0 0;1=4
P 2.945 4.92 25 P 0 0;1=4
P 3.01027972 4.92 25 P 0 0;1=4
P 7.78 2.4781 25 P 0 0;1=0
P 2.24606024 3.86615 25 P 0 0;1=3
P 2.49606024 3.86615 25 P 0 0;1=3
P 2.24606024 3.81615 25 P 0 0;1=3
P 2.19606024 3.76615 25 P 0 0;1=3
P 2.24606024 3.76615 25 P 0 0;1=3
P 2.29606024 3.76615 25 P 0 0;1=3
P 2.49606024 3.71615 25 P 0 0;1=3
P 2.49606024 3.56615 25 P 0 0;1=3
P 2.44606024 3.56615 25 P 0 0;1=3
P 2.39606024 3.56615 25 P 0 0;1=3
P 2.29606024 3.61615 25 P 0 0;1=3
P 2.24606024 3.71615 25 P 0 0;1=3
P 2.24606024 3.66615 25 P 0 0;1=3
P 2.24606024 3.61615 25 P 0 0;1=3
P 2.19606024 3.61615 25 P 0 0;1=3
P 2.19606024 3.56615 25 P 0 0;1=3
P 2.14606024 3.56615 25 P 0 0;1=3
P 2.04606024 3.56615 25 P 0 0;1=3
P 1.99605974 3.56615 25 P 0 0;1=3
P 2.04606024 3.51615 25 P 0 0;1=3
P 2.04605974 3.46615 25 P 0 0;1=3
P 2.19606024 3.51615 25 P 0 0;1=3
P 2.24606024 3.51615 25 P 0 0;1=3
P 2.29606024 3.51615 25 P 0 0;1=3
P 2.49606024 3.41615 25 P 0 0;1=3
P 2.44606024 3.36615 25 P 0 0;1=3
P 2.24606024 3.46615 25 P 0 0;1=3
P 2.24606024 3.41615 25 P 0 0;1=3
P 2.29606024 3.36615 25 P 0 0;1=3
P 2.24606024 3.36615 25 P 0 0;1=3
P 2.19606024 3.36615 25 P 0 0;1=3
P 1.99605974 3.41615 25 P 0 0;1=3
P 2.09606024 3.36615 25 P 0 0;1=3
P 2.24606024 3.31615 25 P 0 0;1=3
P 2.24606024 3.26615 25 P 0 0;1=3
P 2.29606024 3.21615 25 P 0 0;1=3
P 2.24606024 3.21615 25 P 0 0;1=3
P 2.19606024 3.21615 25 P 0 0;1=3
P 2.09606024 3.21615 25 P 0 0;1=3
P 2.14606024 3.16615 25 P 0 0;1=3
P 2.04606024 3.16615 25 P 0 0;1=3
P 2.24606024 3.16615 25 P 0 0;1=3
P 2.29606024 3.16615 25 P 0 0;1=3
P 2.34606024 3.21615 25 P 0 0;1=3
P 2.44606024 3.21615 25 P 0 0;1=3
P 2.49606024 3.21615 25 P 0 0;1=3
P 2.49606024 3.26615 25 P 0 0;1=3
P 2.49606024 3.16615 25 P 0 0;1=3
P 2.39606024 3.16615 25 P 0 0;1=3
P 2.29606024 3.06615 25 P 0 0;1=3
P 2.29606024 3.11615 25 P 0 0;1=3
P 2.29606024 2.96615 25 P 0 0;1=3
P 2.29606024 3.01615 25 P 0 0;1=3
P 2.24606024 3.06615 25 P 0 0;1=3
P 2.24606024 3.11615 25 P 0 0;1=3
P 2.24606024 2.96615 25 P 0 0;1=3
P 2.24606024 3.01615 25 P 0 0;1=3
P 2.34606024 2.86615 25 P 0 0;1=3
P 2.34606024 2.91615 25 P 0 0;1=3
P 2.29606024 2.76615 25 P 0 0;1=3
P 2.29606024 2.81615 25 P 0 0;1=3
P 2.24606024 2.76615 25 P 0 0;1=3
P 2.24606024 2.81615 25 P 0 0;1=3
P 2.19606024 2.81615 25 P 0 0;1=3
P 2.09606024 2.81615 25 P 0 0;1=3
P 2.09606024 2.86615 25 P 0 0;1=3
P 2.19606024 3.06615 25 P 0 0;1=3
P 2.14606024 3.01615 25 P 0 0;1=3
P 2.09606024 3.06615 25 P 0 0;1=3
P 2.04606024 3.01615 25 P 0 0;1=3
P 2.09606024 2.91615 25 P 0 0;1=3
P 2.14606024 2.86615 25 P 0 0;1=3
P 2.04606024 2.86615 25 P 0 0;1=3
P 2.19606024 2.91615 25 P 0 0;1=3
P 2.24606024 2.91615 25 P 0 0;1=3
P 2.29606024 2.91615 25 P 0 0;1=3
P 2.39606024 3.01615 25 P 0 0;1=3
P 2.34606024 3.06615 25 P 0 0;1=3
P 2.44606024 3.06615 25 P 0 0;1=3
P 2.49606024 3.01615 25 P 0 0;1=3
P 2.44606024 2.91615 25 P 0 0;1=3
P 2.44606024 2.86615 25 P 0 0;1=3
P 2.39606024 2.86615 25 P 0 0;1=3
P 2.34606024 2.81615 25 P 0 0;1=3
P 2.44606024 2.81615 25 P 0 0;1=3
P 2.49606024 2.86615 25 P 0 0;1=3
P 2.49606024 2.71615 25 P 0 0;1=3
P 2.44606024 2.66615 25 P 0 0;1=3
P 2.39606024 2.71615 25 P 0 0;1=3
P 2.34606024 2.66615 25 P 0 0;1=3
P 2.29606024 2.71615 25 P 0 0;1=3
P 2.29606024 2.66615 25 P 0 0;1=3
P 2.24606024 2.71615 25 P 0 0;1=3
P 2.24606024 2.66615 25 P 0 0;1=3
P 2.19606024 2.66615 25 P 0 0;1=3
P 2.14606024 2.71615 25 P 0 0;1=3
P 2.09606024 2.66615 25 P 0 0;1=3
P 2.04606024 2.71615 25 P 0 0;1=3
P 2.04606024 2.56615 25 P 0 0;1=3
P 2.04606024 2.51615 25 P 0 0;1=3
P 2.04606024 2.46615 25 P 0 0;1=3
P 2.09606024 2.51615 25 P 0 0;1=3
P 2.14606024 2.56615 25 P 0 0;1=3
P 2.24606024 2.61615 25 P 0 0;1=3
P 2.24606024 2.56615 25 P 0 0;1=3
P 2.29606024 2.61615 25 P 0 0;1=3
P 2.29606024 2.56615 25 P 0 0;1=3
P 2.34606024 2.51615 25 P 0 0;1=3
P 2.29606024 2.51615 25 P 0 0;1=3
P 2.24606024 2.51615 25 P 0 0;1=3
P 2.19606024 2.51615 25 P 0 0;1=3
P 2.14606024 2.46615 25 P 0 0;1=3
P 2.24606024 2.46615 25 P 0 0;1=3
P 2.29606024 2.46615 25 P 0 0;1=3
P 2.29606024 2.41615 25 P 0 0;1=3
P 2.24606024 2.41615 25 P 0 0;1=3
P 2.24606024 2.36615 25 P 0 0;1=3
P 2.19606024 2.36615 25 P 0 0;1=3
P 2.29606024 2.36615 25 P 0 0;1=3
P 2.39606024 2.46615 25 P 0 0;1=3
P 2.39606024 2.51615 25 P 0 0;1=3
P 2.39606024 2.56615 25 P 0 0;1=3
P 2.44606024 2.51615 25 P 0 0;1=3
P 2.49606024 2.56615 25 P 0 0;1=3
P 2.49606024 2.51615 25 P 0 0;1=3
P 2.49606024 2.46615 25 P 0 0;1=3
P 2.44606024 2.36615 25 P 0 0;1=3
P 2.49606024 2.31615 25 P 0 0;1=3
P 2.39606024 2.31615 25 P 0 0;1=3
P 2.34606024 2.36615 25 P 0 0;1=3
P 2.29606024 2.31615 25 P 0 0;1=3
P 2.24606024 2.31615 25 P 0 0;1=3
P 2.04606024 2.31615 25 P 0 0;1=3
P 2.04606024 2.16615 25 P 0 0;1=3
P 2.04606024 2.11615 25 P 0 0;1=3
P 2.04606024 1.96615 25 P 0 0;1=3
P 2.09606024 2.01615 25 P 0 0;1=3
P 2.14606024 1.96615 25 P 0 0;1=3
P 2.09606024 1.86615 25 P 0 0;1=3
P 2.19606024 1.86615 25 P 0 0;1=3
P 2.24606024 1.86615 25 P 0 0;1=3
P 2.29606024 1.86615 25 P 0 0;1=3
P 2.34606024 1.86615 25 P 0 0;1=3
P 2.24606024 1.91615 25 P 0 0;1=3
P 2.29606024 1.91615 25 P 0 0;1=3
P 2.24606024 1.96615 25 P 0 0;1=3
P 2.29606024 1.96615 25 P 0 0;1=3
P 2.19606024 2.01615 25 P 0 0;1=3
P 2.24606024 2.01615 25 P 0 0;1=3
P 2.29606024 2.01615 25 P 0 0;1=3
P 2.34606024 2.01615 25 P 0 0;1=3
P 2.39606024 1.96615 25 P 0 0;1=3
P 2.44606024 2.01615 25 P 0 0;1=3
P 2.49606024 1.96615 25 P 0 0;1=3
P 2.44606024 1.86615 25 P 0 0;1=3
P 2.49606024 2.11615 25 P 0 0;1=3
P 2.44606024 2.16615 25 P 0 0;1=3
P 2.49606024 2.16615 25 P 0 0;1=3
P 2.44606024 2.21615 25 P 0 0;1=3
P 2.39606024 2.16615 25 P 0 0;1=3
P 2.39606024 2.11615 25 P 0 0;1=3
P 2.34606024 2.16615 25 P 0 0;1=3
P 2.34606024 2.21615 25 P 0 0;1=3
P 2.29606024 2.21615 25 P 0 0;1=3
P 2.29606024 2.16615 25 P 0 0;1=3
P 2.29606024 2.06615 25 P 0 0;1=3
P 2.29606024 2.11615 25 P 0 0;1=3
P 2.24606024 2.11615 25 P 0 0;1=3
P 2.24606024 2.16615 25 P 0 0;1=3
P 2.24606024 2.06615 25 P 0 0;1=3
P 2.24606024 2.21615 25 P 0 0;1=3
P 2.29606024 2.26615 25 P 0 0;1=3
P 2.24606024 2.26615 25 P 0 0;1=3
P 2.19606024 2.21615 25 P 0 0;1=3
P 2.19606024 2.16615 25 P 0 0;1=3
P 2.14606024 2.11615 25 P 0 0;1=3
P 2.14606024 2.16615 25 P 0 0;1=3
P 2.09606024 2.21615 25 P 0 0;1=3
P 2.09606024 2.16615 25 P 0 0;1=3
P 2.09606024 2.36615 25 P 0 0;1=3
P 2.14606024 2.31615 25 P 0 0;1=3
P 1.99605974 2.71615 25 P 0 0;1=3
P 1.99605974 2.86615 25 P 0 0;1=3
P 2.04605974 2.81615 25 P 0 0;1=3
P 2.04605974 2.76615 25 P 0 0;1=3
P 3.29373976 5.023 25 P 0 0;1=4
P 2.14606024 3.26615 25 P 0 0;1=3
P 2.04606024 3.26615 25 P 0 0;1=3
P 2.04606024 3.21615 25 P 0 0;1=3
P 2.14606024 3.21615 25 P 0 0;1=3
P 2.39606024 3.21615 25 P 0 0;1=3
P 2.39606024 3.26615 25 P 0 0;1=3
P 2.29606024 3.26615 25 P 0 0;1=3
P 2.29606024 3.31615 25 P 0 0;1=3
P 2.34606024 3.36615 25 P 0 0;1=3
P 2.14606024 3.41615 25 P 0 0;1=3
P 2.09606024 3.61615 25 P 0 0;1=3
P 2.29606024 3.46615 25 P 0 0;1=3
P 2.29606024 3.41615 25 P 0 0;1=3
P 2.39606024 3.41615 25 P 0 0;1=3
P 2.34606024 3.51615 25 P 0 0;1=3
P 2.34606024 3.61615 25 P 0 0;1=3
P 2.34606024 3.56615 25 P 0 0;1=3
P 2.44606024 3.51615 25 P 0 0;1=3
P 2.44606024 3.61615 25 P 0 0;1=3
P 2.14606024 3.71615 25 P 0 0;1=3
P 2.04606024 3.71615 25 P 0 0;1=3
P 2.09606024 3.76615 25 P 0 0;1=3
P 2.14606024 3.86615 25 P 0 0;1=3
P 2.04606024 3.86615 25 P 0 0;1=3
P 2.29606024 3.71615 25 P 0 0;1=3
P 2.29606024 3.66615 25 P 0 0;1=3
P 2.39606024 3.71615 25 P 0 0;1=3
P 2.34606024 3.76615 25 P 0 0;1=3
P 2.29606024 3.81615 25 P 0 0;1=3
P 2.39606024 3.86615 25 P 0 0;1=3
P 2.29606024 3.86615 25 P 0 0;1=3
P 2.44606024 3.76615 25 P 0 0;1=3
P 2.19606024 2.86615 25 P 0 0;1=3
P 3.36460974 5.023 25 P 0 0;1=4
P 3.29374026 4.81401998 25 P 0 0;1=4
P 3.01028002 4.81401998 25 P 0 0;1=4
P 2.94141024 4.81401998 25 P 0 0;1=4
P 2.86555 4.81401998 25 P 0 0;1=4
P 2.79768002 4.81401998 25 P 0 0;1=4
P 3.15200974 5.023 25 P 0 0;1=4
P 3.08113976 5.023 25 P 0 0;1=4
P 3.01027972 5.023 25 P 0 0;1=4
P 2.93940974 5.023 25 P 0 0;1=4
P 2.86855 5.023 25 P 0 0;1=4
P 2.79767972 5.023 25 P 0 0;1=4
P 1.70395 5.023 25 P 0 0;1=4
P 1.63307972 5.023 25 P 0 0;1=4
P 1.77480974 5.023 25 P 0 0;1=4
P 1.91653976 5.023 25 P 0 0;1=4
P 1.84567972 5.023 25 P 0 0;1=4
P 1.98740974 5.023 25 P 0 0;1=4
P 2.05827972 5.023 25 P 0 0;1=4
P 2.12913976 5.023 25 P 0 0;1=4
P 2.20000974 5.023 25 P 0 0;1=4
P 2.27086998 5.023 25 P 0 0;1=4
P 2.34173976 5.023 25 P 0 0;1=4
P 1.56220974 5.023 25 P 0 0;1=4
P 1.56221024 4.81401998 25 P 0 0;1=4
P 2.06086998 4.81 25 P 0 0;1=4
P 2.41260974 5.023 25 P 0 0;1=4
P 2.41261024 4.81401998 25 P 0 0;1=4
P 2.72680974 5.023 25 P 0 0;1=4
P 2.72681024 4.81401998 25 P 0 0;1=4
P 3.57721024 4.81401998 25 P 0 0;1=4
P 3.57720974 5.023 25 P 0 0;1=4
P 4.88267972 1.91615 25 P 0 0;1=3
P 4.78267972 1.91615 25 P 0 0;1=3
P 5.03267972 2.36615 25 P 0 0;1=3
P 5.03267972 2.41615 25 P 0 0;1=3
P 4.88267972 3.66615 25 P 0 0;1=3
P 4.83267972 3.66615 25 P 0 0;1=3
P 5.03267972 3.66615 25 P 0 0;1=3
P 4.93267972 3.66615 25 P 0 0;1=3
P 4.98267972 3.66615 25 P 0 0;1=3
P 4.88267972 3.51615 25 P 0 0;1=3
P 4.83267972 3.51615 25 P 0 0;1=3
P 5.03267972 3.51615 25 P 0 0;1=3
P 4.93267972 3.51615 25 P 0 0;1=3
P 4.98267972 3.51615 25 P 0 0;1=3
P 4.88267972 3.81615 25 P 0 0;1=3
P 4.83267972 3.81615 25 P 0 0;1=3
P 4.93267972 3.81615 25 P 0 0;1=3
P 4.98267972 3.81615 25 P 0 0;1=3
P 4.88267972 3.36615 25 P 0 0;1=3
P 4.83267972 3.36615 25 P 0 0;1=3
P 5.03267972 3.36615 25 P 0 0;1=3
P 4.93267972 3.36615 25 P 0 0;1=3
P 4.98267972 3.36615 25 P 0 0;1=3
P 4.83267972 3.21615 25 P 0 0;1=3
P 4.88267972 3.21615 25 P 0 0;1=3
P 4.98267972 3.21615 25 P 0 0;1=3
P 4.93267972 3.21615 25 P 0 0;1=3
P 5.03267972 3.21615 25 P 0 0;1=3
P 4.83267972 3.06615 25 P 0 0;1=3
P 4.88267972 3.06615 25 P 0 0;1=3
P 4.98267972 3.06615 25 P 0 0;1=3
P 4.93267972 3.06615 25 P 0 0;1=3
P 5.03267972 3.06615 25 P 0 0;1=3
P 4.83267972 2.91615 25 P 0 0;1=3
P 4.88267972 2.91615 25 P 0 0;1=3
P 4.98267972 2.91615 25 P 0 0;1=3
P 4.93267972 2.91615 25 P 0 0;1=3
P 5.03267972 2.91615 25 P 0 0;1=3
P 4.78268002 2.51615 25 P 0 0;1=3
P 4.73268002 2.51615 25 P 0 0;1=3
P 4.68268002 2.51615 25 P 0 0;1=3
P 4.63268002 2.51615 25 P 0 0;1=3
P 4.58268002 2.51615 25 P 0 0;1=3
P 4.63268002 2.56615 25 P 0 0;1=3
P 4.73268002 2.56615 25 P 0 0;1=3
P 4.78268002 2.56615 25 P 0 0;1=3
P 4.78268002 2.61615 25 P 0 0;1=3
P 4.78268002 2.66615 25 P 0 0;1=3
P 4.68268002 2.66615 25 P 0 0;1=3
P 4.58268002 2.66615 25 P 0 0;1=3
P 4.73268002 2.71615 25 P 0 0;1=3
P 4.63268002 2.71615 25 P 0 0;1=3
P 4.63268002 2.76615 25 P 0 0;1=3
P 4.73268002 2.76615 25 P 0 0;1=3
P 4.78268002 2.76615 25 P 0 0;1=3
P 4.63267972 2.16615 25 P 0 0;1=3
P 4.78267972 2.16615 25 P 0 0;1=3
P 10.63660974 2.91615 25 P 0 0;1=3
P 10.58660974 2.91615 25 P 0 0;1=3
P 10.63660974 3.06615 25 P 0 0;1=3
P 10.58660974 3.06615 25 P 0 0;1=3
P 10.63660974 3.36615 25 P 0 0;1=3
P 10.58660974 3.36615 25 P 0 0;1=3
P 10.63660974 3.21615 25 P 0 0;1=3
P 10.58660974 3.21615 25 P 0 0;1=3
P 10.58660974 3.66615 25 P 0 0;1=3
P 10.63660974 3.51615 25 P 0 0;1=3
P 10.58660974 3.51615 25 P 0 0;1=3
P 10.63660974 3.81615 25 P 0 0;1=3
P 10.63660974 3.66615 25 P 0 0;1=3
P 10.58660974 3.81615 25 P 0 0;1=3
P 10.83660974 2.91615 25 P 0 0;1=3
P 10.78660974 2.91615 25 P 0 0;1=3
P 10.73660974 2.91615 25 P 0 0;1=3
P 10.68660974 2.91615 25 P 0 0;1=3
P 10.88660974 2.91615 25 P 0 0;1=3
P 10.88660974 3.06615 25 P 0 0;1=3
P 10.83660974 3.06615 25 P 0 0;1=3
P 10.78660974 3.06615 25 P 0 0;1=3
P 10.73660974 3.06615 25 P 0 0;1=3
P 10.68660974 3.06615 25 P 0 0;1=3
P 10.88660974 3.21615 25 P 0 0;1=3
P 10.83660974 3.21615 25 P 0 0;1=3
P 10.83660974 3.36615 25 P 0 0;1=3
P 10.88660974 3.36615 25 P 0 0;1=3
P 10.78660974 3.36615 25 P 0 0;1=3
P 10.73660974 3.36615 25 P 0 0;1=3
P 10.78660974 3.21615 25 P 0 0;1=3
P 10.73660974 3.21615 25 P 0 0;1=3
P 10.68660974 3.36615 25 P 0 0;1=3
P 10.68660974 3.21615 25 P 0 0;1=3
P 10.83660974 3.51615 25 P 0 0;1=3
P 10.88660974 3.51615 25 P 0 0;1=3
P 10.83660974 3.66615 25 P 0 0;1=3
P 10.78660974 3.66615 25 P 0 0;1=3
P 10.73660974 3.66615 25 P 0 0;1=3
P 10.68660974 3.66615 25 P 0 0;1=3
P 10.78660974 3.51615 25 P 0 0;1=3
P 10.73660974 3.51615 25 P 0 0;1=3
P 10.68660974 3.51615 25 P 0 0;1=3
P 10.83660974 3.81615 25 P 0 0;1=3
P 10.88660974 3.81615 25 P 0 0;1=3
P 10.88660974 3.66615 25 P 0 0;1=3
P 10.78660974 3.81615 25 P 0 0;1=3
P 10.73660974 3.81615 25 P 0 0;1=3
P 10.68660974 3.81615 25 P 0 0;1=3
P 11.03660974 2.91615 25 P 0 0;1=3
P 10.93660974 2.91615 25 P 0 0;1=3
P 10.98660974 2.91615 25 P 0 0;1=3
P 11.03660974 3.06615 25 P 0 0;1=3
P 10.93660974 3.06615 25 P 0 0;1=3
P 10.98660974 3.06615 25 P 0 0;1=3
P 11.03660974 3.21615 25 P 0 0;1=3
P 10.93660974 3.21615 25 P 0 0;1=3
P 10.98660974 3.21615 25 P 0 0;1=3
P 10.98660974 3.36615 25 P 0 0;1=3
P 10.93660974 3.36615 25 P 0 0;1=3
P 11.03660974 3.36615 25 P 0 0;1=3
P 10.98660974 3.51615 25 P 0 0;1=3
P 10.93660974 3.51615 25 P 0 0;1=3
P 11.03660974 3.51615 25 P 0 0;1=3
P 10.98660974 3.66615 25 P 0 0;1=3
P 10.93660974 3.66615 25 P 0 0;1=3
P 11.03660974 3.66615 25 P 0 0;1=3
P 10.98660974 3.81615 25 P 0 0;1=3
P 10.93660974 3.81615 25 P 0 0;1=3
P 3.07691024 4.81401998 25 P 0 0;1=4
P 8.1 1.86615 25 P 0 0;1=3
P 8.15 2.16615 25 P 0 0;1=3
P 8.15 2.11615 25 P 0 0;1=3
P 8.15 1.96615 25 P 0 0;1=3
P 8.1 2.01615 25 P 0 0;1=3
P 8.05 1.96615 25 P 0 0;1=3
P 8.05 2.11615 25 P 0 0;1=3
P 8.05 2.16615 25 P 0 0;1=3
P 8.15 2.31615 25 P 0 0;1=3
P 8.1 2.36615 25 P 0 0;1=3
P 8.1 2.16615 25 P 0 0;1=3
P 8.1 2.21615 25 P 0 0;1=3
P 8.05 2.31615 25 P 0 0;1=3
P 8.15 2.46615 25 P 0 0;1=3
P 8.15 2.56615 25 P 0 0;1=3
P 8.1 2.51615 25 P 0 0;1=3
P 8.05 2.46615 25 P 0 0;1=3
P 8.05 2.51615 25 P 0 0;1=3
P 8.05 2.56615 25 P 0 0;1=3
P 8.1 2.66615 25 P 0 0;1=3
P 8.05 2.76615 25 P 0 0;1=3
P 8.05 2.81615 25 P 0 0;1=3
P 8 2.86615 25 P 0 0;1=3
P 8 2.71615 25 P 0 0;1=3
P 8.05 2.71615 25 P 0 0;1=3
P 8.15 2.71615 25 P 0 0;1=3
P 8.05 2.86615 25 P 0 0;1=3
P 8.15 2.86615 25 P 0 0;1=3
P 8.1 2.91615 25 P 0 0;1=3
P 8.1 2.86615 25 P 0 0;1=3
P 8.1 2.81615 25 P 0 0;1=3
P 8.05 3.01615 25 P 0 0;1=3
P 8.1 3.06615 25 P 0 0;1=3
P 8.15 3.01615 25 P 0 0;1=3
P 8.15 3.16615 25 P 0 0;1=3
P 8.05 3.16615 25 P 0 0;1=3
P 8 3.41615 25 P 0 0;1=3
P 8.05 3.41615 25 P 0 0;1=3
P 8.1 3.36615 25 P 0 0;1=3
P 8.1 3.21615 25 P 0 0;1=3
P 8.15 3.56615 25 P 0 0;1=3
P 8.05 3.56615 25 P 0 0;1=3
P 8 3.56615 25 P 0 0;1=3
P 8.05 3.51615 25 P 0 0;1=3
P 8.05 3.46615 25 P 0 0;1=3
P 8.1 3.51615 25 P 0 0;1=3
P 8.35 1.86615 25 P 0 0;1=3
P 8.3 1.86615 25 P 0 0;1=3
P 8.25 1.86615 25 P 0 0;1=3
P 8.2 1.86615 25 P 0 0;1=3
P 8.25 2.06615 25 P 0 0;1=3
P 8.25 2.16615 25 P 0 0;1=3
P 8.25 2.11615 25 P 0 0;1=3
P 8.3 2.11615 25 P 0 0;1=3
P 8.3 2.06615 25 P 0 0;1=3
P 8.4 2.11615 25 P 0 0;1=3
P 8.4 2.16615 25 P 0 0;1=3
P 8.4 1.96615 25 P 0 0;1=3
P 8.35 2.01615 25 P 0 0;1=3
P 8.3 2.01615 25 P 0 0;1=3
P 8.25 2.01615 25 P 0 0;1=3
P 8.2 2.01615 25 P 0 0;1=3
P 8.3 1.96615 25 P 0 0;1=3
P 8.25 1.96615 25 P 0 0;1=3
P 8.3 1.91615 25 P 0 0;1=3
P 8.25 1.91615 25 P 0 0;1=3
P 8.2 2.16615 25 P 0 0;1=3
P 8.2 2.21615 25 P 0 0;1=3
P 8.25 2.26615 25 P 0 0;1=3
P 8.3 2.26615 25 P 0 0;1=3
P 8.25 2.21615 25 P 0 0;1=3
P 8.3 2.16615 25 P 0 0;1=3
P 8.3 2.21615 25 P 0 0;1=3
P 8.35 2.21615 25 P 0 0;1=3
P 8.35 2.16615 25 P 0 0;1=3
P 8.25 2.31615 25 P 0 0;1=3
P 8.3 2.31615 25 P 0 0;1=3
P 8.35 2.36615 25 P 0 0;1=3
P 8.4 2.31615 25 P 0 0;1=3
P 8.3 2.36615 25 P 0 0;1=3
P 8.2 2.36615 25 P 0 0;1=3
P 8.25 2.36615 25 P 0 0;1=3
P 8.25 2.41615 25 P 0 0;1=3
P 8.3 2.41615 25 P 0 0;1=3
P 8.4 2.56615 25 P 0 0;1=3
P 8.4 2.51615 25 P 0 0;1=3
P 8.4 2.46615 25 P 0 0;1=3
P 8.3 2.46615 25 P 0 0;1=3
P 8.25 2.46615 25 P 0 0;1=3
P 8.2 2.51615 25 P 0 0;1=3
P 8.25 2.51615 25 P 0 0;1=3
P 8.3 2.51615 25 P 0 0;1=3
P 8.35 2.51615 25 P 0 0;1=3
P 8.3 2.56615 25 P 0 0;1=3
P 8.3 2.61615 25 P 0 0;1=3
P 8.25 2.56615 25 P 0 0;1=3
P 8.25 2.61615 25 P 0 0;1=3
P 8.2 2.66615 25 P 0 0;1=3
P 8.25 2.66615 25 P 0 0;1=3
P 8.3 2.66615 25 P 0 0;1=3
P 8.35 2.66615 25 P 0 0;1=3
P 8.25 2.71615 25 P 0 0;1=3
P 8.3 2.71615 25 P 0 0;1=3
P 8.4 2.71615 25 P 0 0;1=3
P 8.35 2.81615 25 P 0 0;1=3
P 8.4 2.86615 25 P 0 0;1=3
P 8.3 2.91615 25 P 0 0;1=3
P 8.25 2.91615 25 P 0 0;1=3
P 8.2 2.91615 25 P 0 0;1=3
P 8.2 2.81615 25 P 0 0;1=3
P 8.25 2.81615 25 P 0 0;1=3
P 8.25 2.76615 25 P 0 0;1=3
P 8.3 2.81615 25 P 0 0;1=3
P 8.3 2.76615 25 P 0 0;1=3
P 8.35 2.91615 25 P 0 0;1=3
P 8.35 2.86615 25 P 0 0;1=3
P 8.35 3.06615 25 P 0 0;1=3
P 8.4 3.01615 25 P 0 0;1=3
P 8.2 3.06615 25 P 0 0;1=3
P 8.25 3.01615 25 P 0 0;1=3
P 8.25 2.96615 25 P 0 0;1=3
P 8.25 3.11615 25 P 0 0;1=3
P 8.25 3.06615 25 P 0 0;1=3
P 8.3 3.01615 25 P 0 0;1=3
P 8.3 2.96615 25 P 0 0;1=3
P 8.3 3.11615 25 P 0 0;1=3
P 8.3 3.06615 25 P 0 0;1=3
P 8.25 3.16615 25 P 0 0;1=3
P 8.3 3.16615 25 P 0 0;1=3
P 8.4 3.16615 25 P 0 0;1=3
P 8.25 3.41615 25 P 0 0;1=3
P 8.3 3.36615 25 P 0 0;1=3
P 8.25 3.36615 25 P 0 0;1=3
P 8.2 3.36615 25 P 0 0;1=3
P 8.25 3.31615 25 P 0 0;1=3
P 8.25 3.26615 25 P 0 0;1=3
P 8.3 3.21615 25 P 0 0;1=3
P 8.25 3.21615 25 P 0 0;1=3
P 8.2 3.21615 25 P 0 0;1=3
P 8.35 3.21615 25 P 0 0;1=3
P 8.4 3.56615 25 P 0 0;1=3
P 8.3 3.61615 25 P 0 0;1=3
P 8.25 3.66615 25 P 0 0;1=3
P 8.25 3.61615 25 P 0 0;1=3
P 8.2 3.61615 25 P 0 0;1=3
P 8.2 3.56615 25 P 0 0;1=3
P 8.2 3.51615 25 P 0 0;1=3
P 8.25 3.51615 25 P 0 0;1=3
P 8.3 3.51615 25 P 0 0;1=3
P 8.25 3.46615 25 P 0 0;1=3
P 8.25 3.86615 25 P 0 0;1=3
P 8.25 3.81615 25 P 0 0;1=3
P 8.2 3.76615 25 P 0 0;1=3
P 8.25 3.76615 25 P 0 0;1=3
P 8.3 3.76615 25 P 0 0;1=3
P 8.25 3.71615 25 P 0 0;1=3
P 8.45 1.86615 25 P 0 0;1=3
P 8.5 2.16615 25 P 0 0;1=3
P 8.5 2.11615 25 P 0 0;1=3
P 8.5 1.96615 25 P 0 0;1=3
P 8.45 2.01615 25 P 0 0;1=3
P 8.45 2.21615 25 P 0 0;1=3
P 8.45 2.16615 25 P 0 0;1=3
P 8.5 2.31615 25 P 0 0;1=3
P 8.45 2.36615 25 P 0 0;1=3
P 8.5 2.46615 25 P 0 0;1=3
P 8.5 2.51615 25 P 0 0;1=3
P 8.5 2.56615 25 P 0 0;1=3
P 8.45 2.51615 25 P 0 0;1=3
P 8.45 2.66615 25 P 0 0;1=3
P 8.5 2.71615 25 P 0 0;1=3
P 8.5 2.86615 25 P 0 0;1=3
P 8.45 2.81615 25 P 0 0;1=3
P 8.45 2.86615 25 P 0 0;1=3
P 8.45 2.91615 25 P 0 0;1=3
P 8.5 3.01615 25 P 0 0;1=3
P 8.45 3.06615 25 P 0 0;1=3
P 8.5 3.16615 25 P 0 0;1=3
P 8.5 3.41615 25 P 0 0;1=3
P 8.45 3.36615 25 P 0 0;1=3
P 8.45 3.21615 25 P 0 0;1=3
P 8.5 3.21615 25 P 0 0;1=3
P 8.5 3.26615 25 P 0 0;1=3
P 8.5 3.56615 25 P 0 0;1=3
P 8.45 3.56615 25 P 0 0;1=3
P 8.5 3.86615 25 P 0 0;1=3
P 8.5 3.71615 25 P 0 0;1=3
P 8.2 2.86615 25 P 0 0;1=3
P 8.05 3.26615 25 P 0 0;1=3
P 8.05 3.21615 25 P 0 0;1=3
P 8.3 3.26615 25 P 0 0;1=3
P 8.3 3.31615 25 P 0 0;1=3
P 8.35 3.36615 25 P 0 0;1=3
P 8.15 3.26615 25 P 0 0;1=3
P 8.15 3.21615 25 P 0 0;1=3
P 8.4 3.21615 25 P 0 0;1=3
P 8.4 3.26615 25 P 0 0;1=3
P 8.1 3.61615 25 P 0 0;1=3
P 8.3 3.46615 25 P 0 0;1=3
P 8.3 3.41615 25 P 0 0;1=3
P 8.35 3.51615 25 P 0 0;1=3
P 8.35 3.61615 25 P 0 0;1=3
P 8.35 3.56615 25 P 0 0;1=3
P 8.15 3.41615 25 P 0 0;1=3
P 8.45 3.51615 25 P 0 0;1=3
P 8.45 3.61615 25 P 0 0;1=3
P 8.4 3.41615 25 P 0 0;1=3
P 8.05 3.71615 25 P 0 0;1=3
P 8.1 3.76615 25 P 0 0;1=3
P 8.05 3.86615 25 P 0 0;1=3
P 8.3 3.71615 25 P 0 0;1=3
P 8.3 3.66615 25 P 0 0;1=3
P 8.35 3.76615 25 P 0 0;1=3
P 8.3 3.81615 25 P 0 0;1=3
P 8.3 3.86615 25 P 0 0;1=3
P 8.15 3.71615 25 P 0 0;1=3
P 8.15 3.86615 25 P 0 0;1=3
P 8.45 3.76615 25 P 0 0;1=3
P 8.4 3.71615 25 P 0 0;1=3
P 8.4 3.86615 25 P 0 0;1=3
P 3.28831004 4.68073996 25 P 0 0;1=4
P 3.22831004 4.68073996 25 P 0 0;1=4
P 3.50091004 4.62573996 25 P 0 0;1=4
P 3.44091004 4.62573996 25 P 0 0;1=4
P 7.56575 5.023 25 P 0 0;1=4
P 7.63661998 5.023 25 P 0 0;1=4
P 7.84921998 5.023 25 P 0 0;1=4
P 7.77835 5.023 25 P 0 0;1=4
P 7.70748976 5.023 25 P 0 0;1=4
P 7.92007972 5.023 25 P 0 0;1=4
P 8.06181998 5.023 25 P 0 0;1=4
P 8.13267972 5.023 25 P 0 0;1=4
P 7.99095 5.023 25 P 0 0;1=4
P 8.34527972 5.023 25 P 0 0;1=4
P 8.27440974 5.023 25 P 0 0;1=4
P 8.20355 5.023 25 P 0 0;1=4
P 8.41615 5.023 25 P 0 0;1=4
P 7.63661998 4.92 25 P 0 0;1=4
P 7.84921998 4.9207 25 P 0 0;1=4
P 7.70748976 4.9207 25 P 0 0;1=4
P 7.77835 4.9207 25 P 0 0;1=4
P 7.99095 4.9207 25 P 0 0;1=4
P 7.92007972 4.9207 25 P 0 0;1=4
P 8.06181998 4.9207 25 P 0 0;1=4
P 8.13267972 4.9207 25 P 0 0;1=4
P 8.27440974 4.9207 25 P 0 0;1=4
P 8.20355 4.9267 25 P 0 0;1=4
P 8.34527972 4.9207 25 P 0 0;1=4
P 7.63526998 4.81527028 25 P 0 0;1=4
P 7.84921998 4.81 25 P 0 0;1=4
P 7.77953976 4.812 25 P 0 0;1=4
P 7.70353976 4.812 25 P 0 0;1=4
P 8.13267972 4.81 25 P 0 0;1=4
P 8.06440974 4.81 25 P 0 0;1=4
P 7.99353976 4.81 25 P 0 0;1=4
P 7.92353976 4.81 25 P 0 0;1=4
P 8.27440974 4.81 25 P 0 0;1=4
P 8.34527972 4.81 25 P 0 0;1=4
P 8.20355 4.81 25 P 0 0;1=4
P 8.41615 4.81401998 25 P 0 0;1=4
P 8.86909026 4.81401998 25 P 0 0;1=4
P 8.73035 4.81401998 25 P 0 0;1=4
P 8.80122028 4.81401998 25 P 0 0;1=4
P 8.94495 4.81401998 25 P 0 0;1=4
P 9.08045 4.81401998 25 P 0 0;1=4
P 9.01382028 4.81401998 25 P 0 0;1=4
P 9.36815 4.81401998 25 P 0 0;1=4
P 9.29728002 4.81401998 25 P 0 0;1=4
P 9.22642028 4.81401998 25 P 0 0;1=4
P 9.15752028 4.81401998 25 P 0 0;1=4
P 9.43901024 4.81401998 25 P 0 0;1=4
P 9.50988002 4.81401998 25 P 0 0;1=4
P 9.58075 4.81401998 25 P 0 0;1=4
P 8.80121998 5.023 25 P 0 0;1=4
P 8.73035 5.023 25 P 0 0;1=4
P 8.87208976 5.023 25 P 0 0;1=4
P 9.08467972 5.023 25 P 0 0;1=4
P 9.01381998 5.023 25 P 0 0;1=4
P 8.94295 5.023 25 P 0 0;1=4
P 8.87208976 4.92 25 P 0 0;1=4
P 8.80121998 4.92 25 P 0 0;1=4
P 9.01381998 4.92 25 P 0 0;1=4
P 9.08467972 4.92 25 P 0 0;1=4
P 9.22641998 4.92 25 P 0 0;1=4
P 9.36815 4.926 25 P 0 0;1=4
P 9.50987972 4.92 25 P 0 0;1=4
P 9.43900974 4.928 25 P 0 0;1=4
P 9.36815 5.023 25 P 0 0;1=4
P 9.29727972 5.023 25 P 0 0;1=4
P 9.22641998 5.023 25 P 0 0;1=4
P 9.15555 5.023 25 P 0 0;1=4
P 9.50987972 5.023 25 P 0 0;1=4
P 9.43900974 5.023 25 P 0 0;1=4
P 9.58075 5.023 25 P 0 0;1=4
P 8.94853976 4.92 25 P 0 0;1=4
P 9.27853976 4.92 25 P 0 0;1=4
P 9.14353976 4.92 25 P 0 0;1=4
P 8.13811004 5.09223996 25 P 0 0;1=4
P 8.35071004 5.15373996 25 P 0 0;1=4
P 8.41071004 5.15373996 25 P 0 0;1=4
P 7.56575 4.81401998 25 P 0 0;1=4
P 8.88061998 4.70574026 25 P 0 0;1=4
P 2.45985 4.77875 27 P 0 0;1=9
P 1.51496998 4.77875 27 P 0 0;1=9
P 2.44016998 5.05826998 27 P 0 0;1=9
P 1.53465 5.05826998 27 P 0 0;1=9
P 3.60476998 4.77875 27 P 0 0;1=9
P 2.67956998 4.77875 27 P 0 0;1=9
P 3.60476998 5.05826998 27 P 0 0;1=9
P 2.69925 5.05826998 27 P 0 0;1=9
P 8.46338996 4.77875 27 P 0 0;1=9
P 7.51850994 4.77875 27 P 0 0;1=9
P 8.44370994 5.05826998 27 P 0 0;1=9
P 7.53818996 5.05826998 27 P 0 0;1=9
P 9.60830994 4.77875 27 P 0 0;1=9
P 8.68310994 4.77875 27 P 0 0;1=9
P 9.60830994 5.05826998 27 P 0 0;1=9
P 8.70278996 5.05826998 27 P 0 0;1=9
P 10.82676998 5.49685 28 P 0 2;1=10
P 10.99213002 5.49685 28 P 0 2;1=10
P 11.15748002 5.49685 28 P 0 2;1=10
P 11.32283996 5.49685 28 P 0 2;1=10
P 11.48818996 5.49685 28 P 0 2;1=10
P 11.65353996 5.49685 28 P 0 2;1=10
P 11.8189 5.49685 28 P 0 2;1=10
P 11.98425 5.49685 28 P 0 2;1=10
P 12.14961004 5.49685 28 P 0 2;1=11
P 10.83662028 1.37795 25 P 0 2;1=12
P 10.83661998 1.6378 25 P 0 2;1=12
P 8.25 1.6378 25 P 0 2;1=12
P 8.25 1.37795 25 P 0 2;1=12
P 6.96457008 1.39763996 25 P 0 2;1=12
P 6.96456998 1.65748002 25 P 0 2;1=12
P 6.96457028 4.0748 25 P 0 2;1=12
P 6.96456998 4.33465 25 P 0 2;1=12
P 8.25 4.09448976 25 P 0 2;1=12
P 8.25 4.35433002 25 P 0 2;1=12
P 10.83662008 4.09448996 25 P 0 2;1=12
P 10.83661998 4.35433002 25 P 0 2;1=12
P 12.12205 4.0748 25 P 0 2;1=12
P 12.12205 4.33465 25 P 0 2;1=12
P 12.12205 1.65748002 25 P 0 2;1=12
P 12.12205 1.39763976 25 P 0 2;1=12
P 11.99212972 4.20473002 25 P 0 2;1=4
P 12.03020522 4.11286004 25 P 0 2;1=4
P 12.03018002 4.2965747 25 P 0 2;1=4
P 12.21391998 4.11288524 25 P 0 2;1=4
P 12.25196998 4.20473002 25 P 0 2;1=4
P 12.21389469 4.2966 25 P 0 2;1=4
P 10.7067 4.22441024 25 P 0 2;1=4
P 10.7447752 4.13253996 25 P 0 2;1=4
P 10.74475 4.31625472 25 P 0 2;1=4
P 10.92848996 4.13256516 25 P 0 2;1=4
P 10.96653996 4.22441004 25 P 0 2;1=4
P 10.92846467 4.31628002 25 P 0 2;1=4
P 8.12007992 4.22441004 25 P 0 2;1=4
P 8.15815522 4.13253996 25 P 0 2;1=4
P 8.15813002 4.31625472 25 P 0 2;1=4
P 8.34186998 4.13256516 25 P 0 2;1=4
P 8.37991998 4.22441004 25 P 0 2;1=4
P 8.34184469 4.31628002 25 P 0 2;1=4
P 6.83465 4.20473002 25 P 0 2;1=4
P 6.8727252 4.11286004 25 P 0 2;1=4
P 6.8727 4.2965747 25 P 0 2;1=4
P 7.05643996 4.11288524 25 P 0 2;1=4
P 7.09448996 4.20473002 25 P 0 2;1=4
P 7.05641467 4.2966 25 P 0 2;1=4
P 6.83465 1.52756024 25 P 0 2;1=4
P 6.8727252 1.43568996 25 P 0 2;1=4
P 6.8727 1.61940472 25 P 0 2;1=4
P 7.05643996 1.43571516 25 P 0 2;1=4
P 7.09448996 1.52756004 25 P 0 2;1=4
P 7.05641467 1.61943002 25 P 0 2;1=4
P 8.15815522 1.416 25 P 0 2;1=4
P 8.12008002 1.50786998 25 P 0 2;1=4
P 8.15813002 1.5997247 25 P 0 2;1=4
P 8.34186998 1.4160252 25 P 0 2;1=4
P 8.34184469 1.59975 25 P 0 2;1=4
P 8.37992028 1.50786998 25 P 0 2;1=4
P 10.74475 1.5997247 25 P 0 2;1=4
P 10.92846467 1.59975 25 P 0 2;1=4
P 10.96654026 1.50786998 25 P 0 2;1=4
P 10.92848996 1.4160252 25 P 0 2;1=4
P 10.7447752 1.416 25 P 0 2;1=4
P 10.7067 1.50787028 25 P 0 2;1=4
P 12.2126 1.43700974 25 P 0 2;1=4
P 12.25196998 1.52756004 25 P 0 2;1=4
P 12.2126 1.61810974 25 P 0 2;1=4
P 12.0315 1.61810974 25 P 0 2;1=4
P 11.99213002 1.52755974 25 P 0 2;1=4
P 12.0315 1.43700974 25 P 0 2;1=4
P 4.83268002 1.37795 25 P 0 2;1=12
P 4.83267972 1.6378 25 P 0 2;1=12
P 2.24605974 1.6378 25 P 0 2;1=12
P 2.24606024 1.37795 25 P 0 2;1=12
P 0.96063002 1.39763976 25 P 0 2;1=12
P 0.96062972 1.65748002 25 P 0 2;1=12
P 0.96063002 4.0748 25 P 0 2;1=12
P 0.96062972 4.33465 25 P 0 2;1=12
P 2.24606004 4.09448996 25 P 0 2;1=12
P 2.24605974 4.35433002 25 P 0 2;1=12
P 4.83268002 4.09448976 25 P 0 2;1=12
P 4.83267972 4.35433002 25 P 0 2;1=12
P 6.11811024 4.0748 25 P 0 2;1=12
P 6.11810974 4.33465 25 P 0 2;1=12
P 6.11810974 1.65748002 25 P 0 2;1=12
P 6.11811004 1.39763996 25 P 0 2;1=12
P 5.98818976 4.20473002 25 P 0 2;1=4
P 6.02626516 4.11286004 25 P 0 2;1=4
P 6.02623996 4.2965747 25 P 0 2;1=4
P 6.20998002 4.11288524 25 P 0 2;1=4
P 6.24803002 4.20472972 25 P 0 2;1=4
P 6.20995472 4.2966 25 P 0 2;1=4
P 4.70275994 4.22441004 25 P 0 2;1=4
P 4.74083524 4.13253996 25 P 0 2;1=4
P 4.74081004 4.31625472 25 P 0 2;1=4
P 4.92455 4.13256516 25 P 0 2;1=4
P 4.9626 4.22440974 25 P 0 2;1=4
P 4.9245247 4.31628002 25 P 0 2;1=4
P 2.11613996 4.22441004 25 P 0 2;1=4
P 2.15421516 4.13253996 25 P 0 2;1=4
P 2.15418996 4.31625472 25 P 0 2;1=4
P 2.33793002 4.13256516 25 P 0 2;1=4
P 2.37598002 4.22440974 25 P 0 2;1=4
P 2.33790472 4.31628002 25 P 0 2;1=4
P 0.83070974 4.20473002 25 P 0 2;1=4
P 0.86878524 4.11286004 25 P 0 2;1=4
P 0.86876004 4.2965747 25 P 0 2;1=4
P 1.0525 4.11288524 25 P 0 2;1=4
P 1.09055 4.20472972 25 P 0 2;1=4
P 1.0524747 4.2966 25 P 0 2;1=4
P 0.83070994 1.52756004 25 P 0 2;1=4
P 0.86878524 1.43568996 25 P 0 2;1=4
P 0.86876004 1.61940472 25 P 0 2;1=4
P 1.0525 1.43571516 25 P 0 2;1=4
P 1.09055 1.52755974 25 P 0 2;1=4
P 1.0524747 1.61943002 25 P 0 2;1=4
P 2.15421516 1.416 25 P 0 2;1=4
P 2.11614006 1.50786998 25 P 0 2;1=4
P 2.15418996 1.5997247 25 P 0 2;1=4
P 2.33793002 1.4160252 25 P 0 2;1=4
P 2.33790472 1.59975 25 P 0 2;1=4
P 2.37598002 1.50786998 25 P 0 2;1=4
P 4.74081004 1.5997247 25 P 0 2;1=4
P 4.9245247 1.59975 25 P 0 2;1=4
P 4.9626 1.50786998 25 P 0 2;1=4
P 4.92455 1.4160252 25 P 0 2;1=4
P 4.74083524 1.416 25 P 0 2;1=4
P 4.70276004 1.50786998 25 P 0 2;1=4
P 6.20865994 1.43701004 25 P 0 2;1=4
P 6.24803002 1.52755974 25 P 0 2;1=4
P 6.20865994 1.61811004 25 P 0 2;1=4
P 6.02755994 1.61811004 25 P 0 2;1=4
P 5.98818996 1.52756004 25 P 0 2;1=4
P 6.02755994 1.43701004 25 P 0 2;1=4
P 12.59646998 0.8189 25 P 0 0;1=4
P 12.5571 0.72835 25 P 0 0;1=4
P 12.59646998 0.6378 25 P 0 0;1=4
P 12.68701998 0.59843002 25 P 0 0;1=12
P 12.77756998 0.6378 25 P 0 0;1=4
P 12.81693976 0.72835 25 P 0 0;1=4
P 12.77756998 0.8189 25 P 0 0;1=4
P 12.68701998 0.85827028 25 P 0 0;1=12
P 12.59646998 5.24803002 25 P 0 0;1=4
P 12.5571 5.15748002 25 P 0 0;1=4
P 12.59646998 5.06693002 25 P 0 0;1=4
P 12.68701998 5.02756004 25 P 0 0;1=12
P 12.77756998 5.06693002 25 P 0 0;1=4
P 12.81693976 5.15748002 25 P 0 0;1=4
P 12.77756998 5.24803002 25 P 0 0;1=4
P 12.68701998 5.2874 25 P 0 0;1=12
P 0.1319 5.20866024 25 P 0 0;1=4
P 0.09252992 5.11811004 25 P 0 0;1=4
P 0.1319 5.02756024 25 P 0 0;1=4
P 0.22245 4.98818976 25 P 0 0;1=12
P 0.313 5.02756024 25 P 0 0;1=4
P 0.35236998 5.11811024 25 P 0 0;1=4
P 0.313 5.20866024 25 P 0 0;1=4
P 0.22245 5.24803002 25 P 0 0;1=12
P 0.1319 0.77953002 25 P 0 0;1=4
P 0.09252972 0.68898002 25 P 0 0;1=4
P 0.1319 0.59843002 25 P 0 0;1=4
P 0.22245 0.55905974 25 P 0 0;1=12
P 0.313 0.59843002 25 P 0 0;1=4
P 0.35236998 0.68898002 25 P 0 0;1=4
P 0.313 0.77953002 25 P 0 0;1=4
P 0.22245 0.8189 25 P 0 0;1=12
P 10.80498996 5.56656004 25 P 0 0;1=4
P 10.84498996 5.56656004 25 P 0 0;1=4
P 10.80498996 5.42656004 25 P 0 0;1=4
P 10.84498996 5.42656004 25 P 0 0;1=4
P 11.01035 5.42656024 25 P 0 0;1=4
P 10.97035 5.42656024 25 P 0 0;1=4
P 11.01035 5.56656024 25 P 0 0;1=4
P 10.97035 5.56656024 25 P 0 0;1=4
P 11.17570994 5.42656004 25 P 0 0;1=4
P 11.13570994 5.42656004 25 P 0 0;1=4
P 11.17570994 5.56656004 25 P 0 0;1=4
P 11.13570994 5.56656004 25 P 0 0;1=4
P 11.34106998 5.42656024 25 P 0 0;1=4
P 11.30106998 5.42656024 25 P 0 0;1=4
P 11.34106998 5.56656024 25 P 0 0;1=4
P 11.30106998 5.56656024 25 P 0 0;1=4
P 11.50642992 5.42656004 25 P 0 0;1=4
P 11.46642992 5.42656004 25 P 0 0;1=4
P 11.50642992 5.56656004 25 P 0 0;1=4
P 11.46642992 5.56656004 25 P 0 0;1=4
P 11.67178996 5.42656004 25 P 0 0;1=4
P 11.63178996 5.42656004 25 P 0 0;1=4
P 11.67178996 5.56656004 25 P 0 0;1=4
P 11.63178996 5.56656004 25 P 0 0;1=4
P 11.83715 5.42656024 25 P 0 0;1=4
P 11.79715 5.42656024 25 P 0 0;1=4
P 11.83715 5.56656024 25 P 0 0;1=4
P 11.79715 5.56656024 25 P 0 0;1=4
P 12.00250994 5.42656004 25 P 0 0;1=4
P 11.96250994 5.42656004 25 P 0 0;1=4
P 12.00250994 5.56656004 25 P 0 0;1=4
P 11.96250994 5.56656004 25 P 0 0;1=4
P 12.16786998 5.42656024 25 P 0 0;1=4
P 12.12786998 5.42656024 25 P 0 0;1=4
P 12.16786998 5.56656024 25 P 0 0;1=4
P 12.12786998 5.56656024 25 P 0 0;1=4
P 7.32284006 0.23621998 25 P 0 0;1=4
P 7.28019518 0.33921998 25 P 0 0;1=4
P 7.17716998 0.38189026 25 P 0 0;1=13
P 7.28016998 0.13319469 25 P 0 0;1=4
P 7.17717028 0.09055 25 P 0 0;1=13
P 7.07414469 0.13321998 25 P 0 0;1=4
P 7.0315 0.23621998 25 P 0 0;1=4
P 7.07416998 0.33924518 25 P 0 0;1=4
P 7.32283976 5.7874 25 P 0 0;1=4
P 7.28019518 5.8904 25 P 0 0;1=4
P 7.17716998 5.93307028 25 P 0 0;1=13
P 7.28016998 5.6843747 25 P 0 0;1=4
P 7.17716998 5.64173002 25 P 0 0;1=13
P 7.07414469 5.6844 25 P 0 0;1=4
P 7.0315 5.7874 25 P 0 0;1=4
P 7.07416998 5.8904252 25 P 0 0;1=4
P 2.24606004 3.56615 6 P 0 0;1=3
P 8.2 3.26615 6 P 0 0;1=3
P 7.65203996 5.0535 6 P 0 0;1=3
P 2.29606004 2.86615 6 P 0 0;1=3
P 2.29606004 3.56615 6 P 0 0;1=3
P 7.69203996 5.0535 6 P 0 0;1=3
P 8.2 3.31615 6 P 0 0;1=3
P 1.33906004 4.69351004 5 P 0 0;1=0
P 0.80806998 5.46193996 5 P 0 0;1=0
P 3.733 5.075 5 P 0 0;1=4
P 1.28906004 4.69351004 5 P 0 0;1=0
P 8.2 3.41615 6 P 0 0;1=3
P 7.86465 5.169 6 P 0 0;1=3
P 3.94 4.765 5 P 0 0;1=0
P 2.34606004 3.26615 6 P 0 0;1=3
P 2.39716998 4.742 6 P 0 0;1=3
P 8.2 3.46615 6 P 0 0;1=3
P 7.90465 5.169 6 P 0 0;1=3
P 2.06646004 5.29 5 P 0 0;1=0
P 2.34606004 3.31615 6 P 0 0;1=3
P 2.35716998 4.742 6 P 0 0;1=3
P 1.33906004 5.15351004 5 P 0 0;1=0
P 3.105 4.47 5 P 0 0;1=4
P 8 3.46615 6 P 0 0;1=3
P 7.93551004 5.0535 6 P 0 0;1=3
P 2.00146004 5.29 5 P 0 0;1=0
P 2.25855 4.667 6 P 0 0;1=3
P 2.39606004 3.31615 6 P 0 0;1=3
P 1.18906004 5.15351004 5 P 0 0;1=0
P 3.07 4.42 5 P 0 0;1=4
P 8 3.51615 6 P 0 0;1=3
P 7.97551004 5.0535 6 P 0 0;1=3
P 2.21855 4.667 6 P 0 0;1=3
P 2.39606004 3.36615 6 P 0 0;1=3
P 8.11725 5.169 6 P 0 0;1=3
P 8.4 3.46615 6 P 0 0;1=3
P 3.635 0.715 5 P 0 0;1=0
P 4.63268002 2.81615 6 P 0 0;1=3
P 2.44606004 3.26615 6 P 0 0;1=3
P 2.39716998 5.115 6 P 0 0;1=3
P 8.07725 5.169 6 P 0 0;1=3
P 8.4 3.51615 6 P 0 0;1=3
P 2.44606004 3.31615 6 P 0 0;1=3
P 2.35716998 5.115 6 P 0 0;1=3
P 8.5 3.46615 6 P 0 0;1=3
P 8.07206998 4.66688996 6 P 0 0;1=3
P 2.25543996 4.78291998 6 P 0 0;1=3
P 2.49606004 3.31615 6 P 0 0;1=3
P 8.5 3.51615 6 P 0 0;1=3
P 8.03206998 4.66688996 6 P 0 0;1=3
P 4.02 4.42 5 P 0 0;1=0
P 4.58268002 2.76615 6 P 0 0;1=3
P 2.21543996 4.78291998 6 P 0 0;1=3
P 2.49606004 3.36615 6 P 0 0;1=3
P 8.35 3.41615 6 P 0 0;1=3
P 8.11725 4.78291998 6 P 0 0;1=3
P 4.78268002 2.71615 6 P 0 0;1=3
P 2.11371004 4.78291998 6 P 0 0;1=3
P 2.34606004 3.41615 6 P 0 0;1=3
P 8.35 3.46615 6 P 0 0;1=3
P 8.07725 4.78291998 6 P 0 0;1=3
P 5.08268002 2.71615 6 P 0 0;1=3
P 4.06 4.86 5 P 0 0;1=0
P 2.07371004 4.78291998 6 P 0 0;1=3
P 2.34606004 3.46615 6 P 0 0;1=3
P 2.18456998 5.0535 6 P 0 0;1=3
P 2.44606004 3.41615 6 P 0 0;1=3
P 10.93661004 2.41615 6 P 0 0;1=3
P 2.14456998 5.0535 6 P 0 0;1=3
P 2.44606004 3.46615 6 P 0 0;1=3
P 10.93661004 2.46615 6 P 0 0;1=3
P 8.5 3.31615 6 P 0 0;1=3
P 8.25898002 4.78291998 6 P 0 0;1=3
P 4.88268002 2.71615 6 P 0 0;1=3
P 2.06853002 4.66688996 6 P 0 0;1=3
P 2.49606004 3.46615 6 P 0 0;1=3
P 8.5 3.36615 6 P 0 0;1=3
P 8.21898002 4.78291998 6 P 0 0;1=3
P 2.02853002 4.66688996 6 P 0 0;1=3
P 2.49606004 3.51615 6 P 0 0;1=3
P 8.4 3.31615 6 P 0 0;1=3
P 8.26208996 4.667 6 P 0 0;1=3
P 2.11371004 5.169 6 P 0 0;1=3
P 2.39606004 3.46615 6 P 0 0;1=3
P 8.4 3.36615 6 P 0 0;1=3
P 8.22208996 4.667 6 P 0 0;1=3
P 3.84 0.69 5 P 0 0;1=0
P 4.68268002 2.76615 6 P 0 0;1=3
P 2.07371004 5.169 6 P 0 0;1=3
P 2.39606004 3.51615 6 P 0 0;1=3
P 3.56 0.49 5 P 0 0;1=0
P 4.73268002 2.81615 6 P 0 0;1=3
P 1.57765 5.169 6 P 0 0;1=3
P 2.04606004 3.31615 6 P 0 0;1=3
P 9.10853996 4.47 5 P 0 0;1=4
P 7.3426 5.15351004 5 P 0 0;1=0
P 3.785 0.69 5 P 0 0;1=0
P 4.78268002 2.81615 6 P 0 0;1=3
P 1.61765 5.169 6 P 0 0;1=3
P 2.04606004 3.36615 6 P 0 0;1=3
P 8.1 3.26615 6 P 0 0;1=3
P 7.58118996 4.707 6 P 0 0;1=3
P 2.09606004 3.26615 6 P 0 0;1=3
P 1.57765 4.707 6 P 0 0;1=3
P 5.08268002 1.96615 6 P 0 0;1=3
P 8.1 3.31615 6 P 0 0;1=3
P 7.62118996 4.707 6 P 0 0;1=3
P 3.75998996 0.345 5 P 0 0;1=0
P 4.68268002 2.81615 6 P 0 0;1=3
P 2.09606004 3.31615 6 P 0 0;1=3
P 1.61765 4.707 6 P 0 0;1=3
P 0.58 5.591 5 P 0 0;1=0
P 11.67761998 2.85 5 P 0 0;1=4
P 11.865 4.455 5 P 0 0;1=0
P 5.67368996 2.85 5 P 0 0;1=4
P 5.855 3.07 5 P 0 0;1=4
P 5.8522 2.97 5 P 0 0;1=4
P 7.2926 5.15351004 5 P 0 0;1=4
P 7.2426 5.15351004 5 P 0 0;1=4
P 7.1926 4.95351004 5 P 0 0;1=4
P 7.42603996 5.15895 5 P 0 0;1=0
P 3.94 4.655 5 P 0 0;1=4
P 3.77 4.765 5 P 0 0;1=4
P 4.14 4.745 5 P 0 0;1=4
P 4.76 5.375 5 P 0 0;1=4
P 4.96 5.5 5 P 0 0;1=4
P 5.16 5.555 5 P 0 0;1=4
P 4.892 5.767 5 P 0 0;1=4
P 5.088 5.767 5 P 0 0;1=4
P 0.91 5.075 5 P 0 0;1=4
P 1.03 4.96 5 P 0 0;1=4
P 1.03 5.155 5 P 0 0;1=4
P 1.38906004 5.15351004 5 P 0 0;1=0
P 1.23906004 5.15351004 5 P 0 0;1=4
P 1.28906004 5.15351004 5 P 0 0;1=4
P 1.18906004 4.95351004 5 P 0 0;1=4
P 0.83 5.355 5 P 0 0;1=4
P 0.9 5.355 5 P 0 0;1=4
P 0.755 5.355 5 P 0 0;1=4
P 0.73 5.205 5 P 0 0;1=4
P 0.81016004 5.17 5 P 0 0;1=4
P 1.094 5.356 5 P 0 0;1=0
P 1.044 5.448 5 P 0 0;1=4
P 1.4 5.46 5 P 0 0;1=4
P 1.32 5.46 5 P 0 0;1=4
P 1.43798996 5.46016004 5 P 0 0;1=4
P 1.35925 5.46016004 5 P 0 0;1=4
P 0.89 5.885 5 P 0 0;1=4
P 0.81 5.885 5 P 0 0;1=4
P 0.73 5.885 5 P 0 0;1=4
P 0.97 5.885 5 P 0 0;1=4
P 1.04 5.885 5 P 0 0;1=4
P 1.12 5.885 5 P 0 0;1=4
P 8.15 3.31615 6 P 0 0;1=3
P 7.65205 4.78291998 6 P 0 0;1=3
P 11.235 3.3 5 P 0 0;1=4
P 5.815 0.925 5 P 0 0;1=0
P 3.635 0.49 5 P 0 0;1=0
P 4.58268002 2.81615 6 P 0 0;1=3
P 2.19606004 3.26615 6 P 0 0;1=3
P 1.6485 5.0535 6 P 0 0;1=3
P 8.15 3.36615 6 P 0 0;1=3
P 7.69205 4.78291998 6 P 0 0;1=3
P 2.19606004 3.31615 6 P 0 0;1=3
P 1.6885 5.0535 6 P 0 0;1=3
P 8.1 3.41615 6 P 0 0;1=3
P 7.79378996 4.78291998 6 P 0 0;1=3
P 2.14606004 3.31615 6 P 0 0;1=3
P 1.64851004 4.78291998 6 P 0 0;1=3
P 8.1 3.46615 6 P 0 0;1=3
P 7.83378996 4.78291998 6 P 0 0;1=3
P 2.14606004 3.36615 6 P 0 0;1=3
P 1.68851004 4.78291998 6 P 0 0;1=3
P 0.73 4.96 5 P 0 0;1=0
P 3.795 4.6 5 P 0 0;1=4
P 4.86 5.375 5 P 0 0;1=4
P 8.15 3.46615 6 P 0 0;1=3
P 7.86465 4.657 6 P 0 0;1=3
P 2.09606004 3.41615 6 P 0 0;1=3
P 1.79025 4.78291998 6 P 0 0;1=3
P 8.15 3.51615 6 P 0 0;1=3
P 7.90465 4.657 6 P 0 0;1=3
P 2.09606004 3.46615 6 P 0 0;1=3
P 1.83025 4.78291998 6 P 0 0;1=3
P 2.19606004 3.41615 6 P 0 0;1=3
P 1.86111004 5.169 6 P 0 0;1=3
P 2.19606004 3.46615 6 P 0 0;1=3
P 1.90111004 5.169 6 P 0 0;1=3
P 6.72708996 4.5652 5 P 0 0;1=4
P 6.76208996 4.5652 5 P 0 0;1=4
P 6.79708996 4.5652 5 P 0 0;1=4
P 6.83708996 4.5652 5 P 0 0;1=0
P 6.90208996 4.5652 5 P 0 0;1=4
P 6.87208996 4.5652 5 P 0 0;1=4
P 10.99998996 4.9531 5 P 0 0;1=4
P 11.03998996 4.9531 5 P 0 0;1=4
P 10.99998996 4.9131 5 P 0 0;1=4
P 11.03998996 4.9131 5 P 0 0;1=4
P 11.21998996 4.9531 5 P 0 0;1=4
P 11.17998996 4.9531 5 P 0 0;1=4
P 11.13498996 4.9531 5 P 0 0;1=4
P 11.08498996 4.9531 5 P 0 0;1=4
P 11.21998996 4.9131 5 P 0 0;1=4
P 11.17998996 4.9131 5 P 0 0;1=4
P 11.08498996 4.9131 5 P 0 0;1=4
P 11.13498996 4.9131 5 P 0 0;1=4
P 10.99998996 5.1631 5 P 0 0;1=4
P 11.03998996 5.1631 5 P 0 0;1=4
P 10.99998996 5.1231 5 P 0 0;1=4
P 10.99998996 5.0381 5 P 0 0;1=4
P 10.99998996 5.0831 5 P 0 0;1=4
P 10.99998996 4.9931 5 P 0 0;1=4
P 11.03998996 4.9931 5 P 0 0;1=4
P 11.03998996 5.0831 5 P 0 0;1=4
P 11.03998996 5.0381 5 P 0 0;1=4
P 11.03998996 5.1231 5 P 0 0;1=4
P 11.21998996 5.1631 5 P 0 0;1=4
P 11.17998996 5.1631 5 P 0 0;1=4
P 11.08498996 5.1631 5 P 0 0;1=4
P 11.13498996 5.1631 5 P 0 0;1=4
P 11.21998996 5.1231 5 P 0 0;1=4
P 11.21998996 5.0381 5 P 0 0;1=4
P 11.21998996 5.0831 5 P 0 0;1=4
P 11.21998996 4.9931 5 P 0 0;1=4
P 11.17998996 4.9931 5 P 0 0;1=4
P 11.17998996 5.1231 5 P 0 0;1=4
P 11.17998996 5.0831 5 P 0 0;1=4
P 11.17998996 5.0381 5 P 0 0;1=4
P 11.13498996 5.1231 5 P 0 0;1=4
P 11.08498996 5.1231 5 P 0 0;1=4
P 11.6269 4.90498996 5 P 0 0;1=4
P 11.6269 4.85498996 5 P 0 0;1=4
P 11.4269 4.80998996 5 P 0 0;1=4
P 11.4269 4.85498996 5 P 0 0;1=4
P 11.4269 4.90498996 5 P 0 0;1=4
P 11.4269 4.94998996 5 P 0 0;1=4
P 11.4769 4.94998996 5 P 0 0;1=4
P 11.4769 4.80998996 5 P 0 0;1=4
P 11.5269 4.94998996 5 P 0 0;1=4
P 11.5269 4.80998996 5 P 0 0;1=4
P 11.5769 4.94998996 5 P 0 0;1=4
P 11.6269 4.94998996 5 P 0 0;1=4
P 11.6269 4.80998996 5 P 0 0;1=4
P 11.5769 4.80998996 5 P 0 0;1=4
P 10.82676998 5.71338996 13 P 0 0;1=10
P 10.99213002 5.71338996 13 P 0 0;1=10
P 11.15748002 5.71338996 13 P 0 0;1=10
P 11.32283996 5.71338996 13 P 0 0;1=10
P 11.48818996 5.71338996 13 P 0 0;1=10
P 11.65353996 5.71338996 13 P 0 0;1=10
P 11.8189 5.71338996 13 P 0 0;1=10
P 11.98425 5.71338996 13 P 0 0;1=10
P 12.14961004 5.71338996 13 P 0 0;1=10
P 10.80498996 5.7831 5 P 0 0;1=4
P 10.84498996 5.7831 5 P 0 0;1=4
P 10.80498996 5.6431 5 P 0 0;1=4
P 10.84498996 5.6431 5 P 0 0;1=4
P 11.01035 5.6431 5 P 0 0;1=4
P 10.97035 5.6431 5 P 0 0;1=4
P 11.01035 5.7831 5 P 0 0;1=4
P 10.97035 5.7831 5 P 0 0;1=4
P 11.17571004 5.6431 5 P 0 0;1=4
P 11.13571004 5.6431 5 P 0 0;1=4
P 11.17571004 5.7831 5 P 0 0;1=4
P 11.13571004 5.7831 5 P 0 0;1=4
P 11.34106998 5.6431 5 P 0 0;1=4
P 11.30106998 5.6431 5 P 0 0;1=4
P 11.34106998 5.7831 5 P 0 0;1=4
P 11.30106998 5.7831 5 P 0 0;1=4
P 11.50643002 5.6431 5 P 0 0;1=4
P 11.46643002 5.6431 5 P 0 0;1=4
P 11.50643002 5.7831 5 P 0 0;1=4
P 11.46643002 5.7831 5 P 0 0;1=4
P 11.67178996 5.6431 5 P 0 0;1=4
P 11.63178996 5.6431 5 P 0 0;1=4
P 11.67178996 5.7831 5 P 0 0;1=4
P 11.63178996 5.7831 5 P 0 0;1=4
P 11.83715 5.6431 5 P 0 0;1=4
P 11.79715 5.6431 5 P 0 0;1=4
P 11.83715 5.7831 5 P 0 0;1=4
P 11.79715 5.7831 5 P 0 0;1=4
P 12.00251004 5.6431 5 P 0 0;1=4
P 11.96251004 5.6431 5 P 0 0;1=4
P 12.00251004 5.7831 5 P 0 0;1=4
P 11.96251004 5.7831 5 P 0 0;1=4
P 12.16786998 5.6431 5 P 0 0;1=4
P 12.12786998 5.6431 5 P 0 0;1=4
P 12.16786998 5.7831 5 P 0 0;1=4
P 12.12786998 5.7831 5 P 0 0;1=4
P 5.03605 5.1631 5 P 0 0;1=4
P 5.03605 4.9931 5 P 0 0;1=4
P 5.03605 5.0831 5 P 0 0;1=4
P 5.03605 5.0381 5 P 0 0;1=4
P 5.03605 5.1231 5 P 0 0;1=4
P 5.21605 5.1631 5 P 0 0;1=4
P 5.17605 5.1631 5 P 0 0;1=4
P 5.08105 5.1631 5 P 0 0;1=4
P 5.13105 5.1631 5 P 0 0;1=4
P 5.21605 5.1231 5 P 0 0;1=4
P 5.21605 5.0381 5 P 0 0;1=4
P 5.21605 5.0831 5 P 0 0;1=4
P 5.21605 4.9931 5 P 0 0;1=4
P 5.17605 4.9931 5 P 0 0;1=4
P 5.17605 5.1231 5 P 0 0;1=4
P 5.17605 5.0831 5 P 0 0;1=4
P 5.17605 5.0381 5 P 0 0;1=4
P 5.13105 5.1231 5 P 0 0;1=4
P 5.08105 5.1231 5 P 0 0;1=4
P 4.99605 5.1631 5 P 0 0;1=4
P 4.99605 5.1231 5 P 0 0;1=4
P 4.99605 5.0381 5 P 0 0;1=4
P 4.99605 5.0831 5 P 0 0;1=4
P 4.99605 4.9931 5 P 0 0;1=4
P 5.03605 4.9531 5 P 0 0;1=4
P 5.03605 4.9131 5 P 0 0;1=4
P 5.21605 4.9531 5 P 0 0;1=4
P 5.17605 4.9531 5 P 0 0;1=4
P 5.13105 4.9531 5 P 0 0;1=4
P 5.08105 4.9531 5 P 0 0;1=4
P 5.21605 4.9131 5 P 0 0;1=4
P 5.17605 4.9131 5 P 0 0;1=4
P 5.08105 4.9131 5 P 0 0;1=4
P 5.13105 4.9131 5 P 0 0;1=4
P 4.99605 4.9531 5 P 0 0;1=4
P 4.99605 4.9131 5 P 0 0;1=4
P 6.34948996 5.03 5 P 0 0;1=4
P 2.74225 5.14 6 P 0 0;1=3
P 2.04606004 3.61615 6 P 0 0;1=3
P 2.14606004 3.46615 6 P 0 0;1=3
P 1.86111004 4.657 6 P 0 0;1=3
P 2.78225 5.14 6 P 0 0;1=3
P 2.04606004 3.66615 6 P 0 0;1=3
P 2.14606004 3.51615 6 P 0 0;1=3
P 1.90111004 4.657 6 P 0 0;1=3
P 1.93196998 5.0535 6 P 0 0;1=3
P 1.99606004 3.46615 6 P 0 0;1=3
P 4.58268002 2.56615 6 P 0 0;1=3
P 1.97196998 5.0535 6 P 0 0;1=3
P 1.99606004 3.51615 6 P 0 0;1=3
P 2.88086998 5.17001998 6 P 0 0;1=3
P 2.14606004 3.61615 6 P 0 0;1=3
P 2.34606004 3.66615 6 P 0 0;1=3
P 3.56176998 4.71973002 6 P 0 0;1=3
P 2.92086998 5.17001998 6 P 0 0;1=3
P 2.14606004 3.66615 6 P 0 0;1=3
P 2.34606004 3.71615 6 P 0 0;1=3
P 3.52176998 4.71973002 6 P 0 0;1=3
P 2.39606004 3.61615 6 P 0 0;1=3
P 3.49091004 4.587 6 P 0 0;1=3
P 2.39606004 3.66615 6 P 0 0;1=3
P 3.45091004 4.587 6 P 0 0;1=3
P 2.49606004 3.61615 6 P 0 0;1=3
P 3.56176998 5.14 6 P 0 0;1=3
P 2.49606004 3.66615 6 P 0 0;1=3
P 3.52176998 5.14 6 P 0 0;1=3
P 2.44606004 3.66615 6 P 0 0;1=3
P 3.42003996 4.78291998 6 P 0 0;1=3
P 4.30605 4.6631 5 P 0 0;1=4
P 4.34105 4.6431 5 P 0 0;1=4
P 4.38605 4.6431 5 P 0 0;1=4
P 4.42605 4.6631 5 P 0 0;1=4
P 4.46605 4.6631 5 P 0 0;1=4
P 4.30605 4.7031 5 P 0 0;1=4
P 4.42605 4.7031 5 P 0 0;1=4
P 4.46605 4.7031 5 P 0 0;1=4
P 4.26605 4.6631 5 P 0 0;1=4
P 4.26605 4.7031 5 P 0 0;1=4
P 4.65605 4.6631 5 P 0 0;1=4
P 4.69605 4.6631 5 P 0 0;1=4
P 4.65605 4.7031 5 P 0 0;1=4
P 4.69605 4.7031 5 P 0 0;1=4
P 4.73105 4.6431 5 P 0 0;1=4
P 4.81605 4.6631 5 P 0 0;1=4
P 4.85605 4.6631 5 P 0 0;1=4
P 4.81605 4.7031 5 P 0 0;1=4
P 4.85605 4.7031 5 P 0 0;1=4
P 4.77605 4.6431 5 P 0 0;1=4
P 5.17605 4.7131 5 P 0 0;1=4
P 5.17605 4.6731 5 P 0 0;1=4
P 5.08105 4.6731 5 P 0 0;1=4
P 5.13105 4.6731 5 P 0 0;1=4
P 5.03605 4.6731 5 P 0 0;1=4
P 5.03605 4.7131 5 P 0 0;1=4
P 4.30605 4.7481 5 P 0 0;1=4
P 4.30605 4.7931 5 P 0 0;1=4
P 4.30605 4.8381 5 P 0 0;1=4
P 4.38605 4.8381 5 P 0 0;1=4
P 4.34605 4.8381 5 P 0 0;1=4
P 4.46605 4.8381 5 P 0 0;1=4
P 4.42605 4.8381 5 P 0 0;1=4
P 4.42605 4.7931 5 P 0 0;1=4
P 4.42605 4.7481 5 P 0 0;1=4
P 4.46605 4.7931 5 P 0 0;1=4
P 4.46605 4.7481 5 P 0 0;1=4
P 4.26605 4.7481 5 P 0 0;1=4
P 4.26605 4.7931 5 P 0 0;1=4
P 4.26605 4.8381 5 P 0 0;1=4
P 4.65605 4.8381 5 P 0 0;1=4
P 4.65605 4.7931 5 P 0 0;1=4
P 4.65605 4.7481 5 P 0 0;1=4
P 4.69605 4.8381 5 P 0 0;1=4
P 4.69605 4.7931 5 P 0 0;1=4
P 4.69605 4.7481 5 P 0 0;1=4
P 4.73605 4.8381 5 P 0 0;1=4
P 4.81605 4.8381 5 P 0 0;1=4
P 4.81605 4.7931 5 P 0 0;1=4
P 4.81605 4.7481 5 P 0 0;1=4
P 4.85605 4.8381 5 P 0 0;1=4
P 4.85605 4.7931 5 P 0 0;1=4
P 4.85605 4.7481 5 P 0 0;1=4
P 4.77605 4.8381 5 P 0 0;1=4
P 5.08105 4.8431 5 P 0 0;1=4
P 5.13105 4.8431 5 P 0 0;1=4
P 5.17605 4.8431 5 P 0 0;1=4
P 5.17605 4.8031 5 P 0 0;1=4
P 5.17605 4.7581 5 P 0 0;1=4
P 5.03605 4.8431 5 P 0 0;1=4
P 5.03605 4.8031 5 P 0 0;1=4
P 5.03605 4.7581 5 P 0 0;1=4
P 4.58268002 2.96615 6 P 0 0;1=3
P 4.63268002 2.96615 6 P 0 0;1=3
P 4.63268002 3.11615 6 P 0 0;1=3
P 4.58268002 3.01615 6 P 0 0;1=3
P 4.58268002 3.11615 6 P 0 0;1=3
P 4.63268002 3.01615 6 P 0 0;1=3
P 4.63268002 3.31615 6 P 0 0;1=3
P 4.58268002 3.26615 6 P 0 0;1=3
P 4.58268002 3.31615 6 P 0 0;1=3
P 4.63268002 3.26615 6 P 0 0;1=3
P 4.63268002 3.16615 6 P 0 0;1=3
P 4.58268002 3.16615 6 P 0 0;1=3
P 4.58268002 3.46615 6 P 0 0;1=3
P 4.63268002 3.41615 6 P 0 0;1=3
P 4.63268002 3.46615 6 P 0 0;1=3
P 4.58268002 3.41615 6 P 0 0;1=3
P 4.58268002 3.61615 6 P 0 0;1=3
P 4.58268002 3.56615 6 P 0 0;1=3
P 4.63268002 3.61615 6 P 0 0;1=3
P 4.63268002 3.56615 6 P 0 0;1=3
P 4.58268002 3.71615 6 P 0 0;1=3
P 4.63268002 3.71615 6 P 0 0;1=3
P 4.58268002 3.76615 6 P 0 0;1=3
P 4.58268002 3.86615 6 P 0 0;1=3
P 4.63268002 3.76615 6 P 0 0;1=3
P 4.63268002 3.86615 6 P 0 0;1=3
P 4.68268002 2.96615 6 P 0 0;1=3
P 4.73268002 2.96615 6 P 0 0;1=3
P 4.78268002 2.96615 6 P 0 0;1=3
P 4.68268002 3.11615 6 P 0 0;1=3
P 4.68268002 3.01615 6 P 0 0;1=3
P 4.73268002 3.11615 6 P 0 0;1=3
P 4.73268002 3.01615 6 P 0 0;1=3
P 4.78268002 3.11615 6 P 0 0;1=3
P 4.78268002 3.01615 6 P 0 0;1=3
P 4.73268002 3.31615 6 P 0 0;1=3
P 4.73268002 3.26615 6 P 0 0;1=3
P 4.68268002 3.26615 6 P 0 0;1=3
P 4.68268002 3.31615 6 P 0 0;1=3
P 4.78268002 3.26615 6 P 0 0;1=3
P 4.78268002 3.31615 6 P 0 0;1=3
P 4.73268002 3.16615 6 P 0 0;1=3
P 4.68268002 3.16615 6 P 0 0;1=3
P 4.78268002 3.16615 6 P 0 0;1=3
P 4.73268002 3.41615 6 P 0 0;1=3
P 4.68268002 3.41615 6 P 0 0;1=3
P 4.68268002 3.46615 6 P 0 0;1=3
P 4.73268002 3.46615 6 P 0 0;1=3
P 4.78268002 3.46615 6 P 0 0;1=3
P 4.78268002 3.41615 6 P 0 0;1=3
P 4.73268002 3.56615 6 P 0 0;1=3
P 4.73268002 3.61615 6 P 0 0;1=3
P 4.68268002 3.56615 6 P 0 0;1=3
P 4.68268002 3.61615 6 P 0 0;1=3
P 4.78268002 3.61615 6 P 0 0;1=3
P 4.78268002 3.56615 6 P 0 0;1=3
P 4.73268002 3.71615 6 P 0 0;1=3
P 4.68268002 3.71615 6 P 0 0;1=3
P 4.78268002 3.71615 6 P 0 0;1=3
P 4.73268002 3.76615 6 P 0 0;1=3
P 4.73268002 3.86615 6 P 0 0;1=3
P 4.68268002 3.76615 6 P 0 0;1=3
P 4.68268002 3.86615 6 P 0 0;1=3
P 4.78268002 3.76615 6 P 0 0;1=3
P 4.78268002 3.86615 6 P 0 0;1=3
P 4.88268002 3.86615 6 P 0 0;1=3
P 4.83268002 3.86615 6 P 0 0;1=3
P 5.03268002 3.86615 6 P 0 0;1=3
P 4.93268002 3.86615 6 P 0 0;1=3
P 4.98268002 3.86615 6 P 0 0;1=3
P 4.88268002 3.76615 6 P 0 0;1=3
P 4.83268002 3.76615 6 P 0 0;1=3
P 5.03268002 3.76615 6 P 0 0;1=3
P 4.93268002 3.76615 6 P 0 0;1=3
P 4.98268002 3.76615 6 P 0 0;1=3
P 4.88268002 3.71615 6 P 0 0;1=3
P 4.83268002 3.71615 6 P 0 0;1=3
P 5.03268002 3.71615 6 P 0 0;1=3
P 4.93268002 3.71615 6 P 0 0;1=3
P 4.98268002 3.71615 6 P 0 0;1=3
P 4.88268002 3.61615 6 P 0 0;1=3
P 4.83268002 3.61615 6 P 0 0;1=3
P 5.03268002 3.61615 6 P 0 0;1=3
P 4.93268002 3.61615 6 P 0 0;1=3
P 4.98268002 3.61615 6 P 0 0;1=3
P 4.88268002 3.56615 6 P 0 0;1=3
P 4.83268002 3.56615 6 P 0 0;1=3
P 5.03268002 3.56615 6 P 0 0;1=3
P 4.93268002 3.56615 6 P 0 0;1=3
P 4.98268002 3.56615 6 P 0 0;1=3
P 4.88268002 3.46615 6 P 0 0;1=3
P 4.83268002 3.46615 6 P 0 0;1=3
P 5.03268002 3.46615 6 P 0 0;1=3
P 4.93268002 3.46615 6 P 0 0;1=3
P 4.98268002 3.46615 6 P 0 0;1=3
P 4.88268002 3.41615 6 P 0 0;1=3
P 4.83268002 3.41615 6 P 0 0;1=3
P 5.03268002 3.41615 6 P 0 0;1=3
P 4.93268002 3.41615 6 P 0 0;1=3
P 4.98268002 3.41615 6 P 0 0;1=3
P 4.88268002 3.31615 6 P 0 0;1=3
P 4.83268002 3.31615 6 P 0 0;1=3
P 5.03268002 3.31615 6 P 0 0;1=3
P 4.93268002 3.31615 6 P 0 0;1=3
P 4.98268002 3.31615 6 P 0 0;1=3
P 4.83268002 3.26615 6 P 0 0;1=3
P 4.88268002 3.26615 6 P 0 0;1=3
P 4.98268002 3.26615 6 P 0 0;1=3
P 4.93268002 3.26615 6 P 0 0;1=3
P 5.03268002 3.26615 6 P 0 0;1=3
P 4.83268002 3.16615 6 P 0 0;1=3
P 4.88268002 3.16615 6 P 0 0;1=3
P 4.98268002 3.16615 6 P 0 0;1=3
P 4.93268002 3.16615 6 P 0 0;1=3
P 5.03268002 3.16615 6 P 0 0;1=3
P 4.83268002 3.11615 6 P 0 0;1=3
P 4.88268002 3.11615 6 P 0 0;1=3
P 4.98268002 3.11615 6 P 0 0;1=3
P 4.93268002 3.11615 6 P 0 0;1=3
P 5.03268002 3.11615 6 P 0 0;1=3
P 4.83268002 3.01615 6 P 0 0;1=3
P 4.88268002 3.01615 6 P 0 0;1=3
P 4.98268002 3.01615 6 P 0 0;1=3
P 4.93268002 3.01615 6 P 0 0;1=3
P 5.03268002 3.01615 6 P 0 0;1=3
P 4.83268002 2.96615 6 P 0 0;1=3
P 4.88268002 2.96615 6 P 0 0;1=3
P 4.98268002 2.96615 6 P 0 0;1=3
P 4.93268002 2.96615 6 P 0 0;1=3
P 5.03268002 2.96615 6 P 0 0;1=3
P 2.44606004 3.71615 6 P 0 0;1=3
P 3.38003996 4.78291998 6 P 0 0;1=3
P 2.19606004 3.81615 6 P 0 0;1=3
P 3.02571004 4.667 6 P 0 0;1=3
P 2.19606004 3.86615 6 P 0 0;1=3
P 3.06571004 4.667 6 P 0 0;1=3
P 3.27831004 4.642 6 P 0 0;1=3
P 2.39606004 3.76615 6 P 0 0;1=3
P 4.73268002 2.66615 6 P 0 0;1=3
P 10.73661004 2.66615 6 P 0 0;1=3
P 3.23831004 4.642 6 P 0 0;1=3
P 2.39606004 3.81615 6 P 0 0;1=3
P 5.03268002 2.61615 6 P 0 0;1=3
P 3.34916998 5.1035 6 P 0 0;1=3
P 2.49606004 3.76615 6 P 0 0;1=3
P 3.30916998 5.1035 6 P 0 0;1=3
P 2.49606004 3.81615 6 P 0 0;1=3
P 11.03661004 2.61615 6 P 0 0;1=3
P 2.74225 4.667 6 P 0 0;1=3
P 2.09606004 3.66615 6 P 0 0;1=3
P 2.44606004 3.81615 6 P 0 0;1=3
P 3.20743996 4.78291998 6 P 0 0;1=3
P 2.78225 4.667 6 P 0 0;1=3
P 2.09606004 3.71615 6 P 0 0;1=3
P 2.44606004 3.86615 6 P 0 0;1=3
P 3.16743996 4.78291998 6 P 0 0;1=3
P 2.34606004 3.81615 6 P 0 0;1=3
P 3.27831004 5.22001998 6 P 0 0;1=3
P 2.34606004 3.86615 6 P 0 0;1=3
P 3.23831004 5.22001998 6 P 0 0;1=3
P 4.63268002 2.61615 6 P 0 0;1=3
P 10.98661004 2.61615 6 P 0 0;1=3
P 2.19606004 3.66615 6 P 0 0;1=3
P 2.81311004 4.78291998 6 P 0 0;1=3
P 10.98661004 2.56615 6 P 0 0;1=3
P 2.19606004 3.71615 6 P 0 0;1=3
P 2.85311004 4.78291998 6 P 0 0;1=3
P 0.64808996 1.655 5 P 0 0;1=4
P 5.76 2.66 5 P 0 0;1=0
P 10.63661004 2.61615 6 P 0 0;1=3
P 2.09606004 3.81615 6 P 0 0;1=3
P 3.09656998 5.0535 6 P 0 0;1=3
P 2.09606004 3.86615 6 P 0 0;1=3
P 3.13656998 5.0535 6 P 0 0;1=3
P 2.88708002 4.667 6 P 0 0;1=3
P 2.04606004 3.76615 6 P 0 0;1=3
P 10.73661004 2.61615 6 P 0 0;1=3
P 2.92708002 4.667 6 P 0 0;1=3
P 2.04606004 3.81615 6 P 0 0;1=3
P 10.68661004 2.61615 6 P 0 0;1=3
P 5.03268002 2.46615 6 P 0 0;1=3
P 5.03268002 2.51615 6 P 0 0;1=3
P 11.08661004 2.56615 6 P 0 0;1=3
P 10.68661004 2.56615 6 P 0 0;1=3
P 9.175 5.255 5 P 0 0;1=0
P 4.73268002 2.61615 6 P 0 0;1=3
P 9.11853996 5.255 5 P 0 0;1=0
P 5.08268002 2.41615 6 P 0 0;1=3
P 10.93661004 2.66615 6 P 0 0;1=3
P 10.58661004 2.61615 6 P 0 0;1=3
P 8.15 3.76615 6 P 0 0;1=3
P 9.02925 5.165 6 P 0 0;1=3
P 4.98268002 2.21615 6 P 0 0;1=3
P 10.58661004 2.56615 6 P 0 0;1=3
P 8.15 3.81615 6 P 0 0;1=3
P 9.06925 5.165 6 P 0 0;1=3
P 11.03661004 2.66615 6 P 0 0;1=3
P 4.98268002 2.26615 6 P 0 0;1=3
P 10.93661004 2.61615 6 P 0 0;1=3
P 5.03268002 2.26615 6 P 0 0;1=3
P 11.08661004 2.61615 6 P 0 0;1=3
P 5.03268002 2.31615 6 P 0 0;1=3
P 10.63661004 2.66615 6 P 0 0;1=3
P 3.775 5.295 5 P 0 0;1=0
P 0.73 5.78 5 P 0 0;1=4
P 8.07 5.29 5 P 0 0;1=0
P 3.8399 4.765 5 P 0 0;1=0
P 0.81 5.78 5 P 0 0;1=4
P 8.005 5.29 5 P 0 0;1=0
P 11.08661004 1.91615 6 P 0 0;1=3
P 4.98268002 1.91615 6 P 0 0;1=3
P 4.98268002 1.96615 6 P 0 0;1=3
P 4.93268002 1.86615 6 P 0 0;1=3
P 4.93268002 1.91615 6 P 0 0;1=3
P 5.03268002 1.86615 6 P 0 0;1=3
P 5.08268002 1.91615 6 P 0 0;1=3
P 5.08268002 2.56615 6 P 0 0;1=3
P 8.15 2.51615 6 P 0 0;1=3
P 4.98268002 2.61615 6 P 0 0;1=3
P 10.68661004 2.71615 6 P 0 0;1=3
P 10.98661004 2.71615 6 P 0 0;1=3
P 10.78661004 2.71615 6 P 0 0;1=3
P 4.93268002 2.66615 6 P 0 0;1=3
P 10.88661004 2.71615 6 P 0 0;1=3
P 10.68661004 2.76615 6 P 0 0;1=3
P 9.64 0.71 5 P 0 0;1=0
P 10.58661004 2.81615 6 P 0 0;1=3
P 9.43296004 0.49133002 5 P 0 0;1=0
P 9.43296004 0.73633002 5 P 0 0;1=0
P 10.63661004 2.81615 6 P 0 0;1=3
P 4.68268002 2.56615 6 P 0 0;1=3
P 10.68661004 2.81615 6 P 0 0;1=3
P 9.55795 0.36633002 5 P 0 0;1=0
P 10.73661004 2.81615 6 P 0 0;1=3
P 9.35796004 0.49133002 5 P 0 0;1=0
P 5.03268002 2.66615 6 P 0 0;1=3
P 10.78661004 2.81615 6 P 0 0;1=3
P 9.58296004 0.71133002 5 P 0 0;1=0
P 5.08268002 2.61615 6 P 0 0;1=3
P 11.08661004 1.96615 6 P 0 0;1=3
P 11.03661004 1.86615 6 P 0 0;1=3
P 11.03661004 1.91615 6 P 0 0;1=3
P 10.93661004 1.86615 6 P 0 0;1=3
P 10.93661004 1.91615 6 P 0 0;1=3
P 10.98661004 1.91615 6 P 0 0;1=3
P 10.98661004 1.96615 6 P 0 0;1=3
P 4.93268002 2.61615 6 P 0 0;1=3
P 11.03661004 2.01615 6 P 0 0;1=3
P 11.03661004 2.06615 6 P 0 0;1=3
P 10.93661004 2.01615 6 P 0 0;1=3
P 10.93661004 2.06615 6 P 0 0;1=3
P 10.98661004 2.06615 6 P 0 0;1=3
P 10.98661004 2.11615 6 P 0 0;1=3
P 11.08661004 2.06615 6 P 0 0;1=3
P 11.08661004 2.11615 6 P 0 0;1=3
P 3.115 5.255 5 P 0 0;1=0
P 4.63268002 2.66615 6 P 0 0;1=3
P 11.08661004 2.21615 6 P 0 0;1=3
P 4.98268002 2.56615 6 P 0 0;1=3
P 11.08661004 2.26615 6 P 0 0;1=3
P 11.03661004 2.26615 6 P 0 0;1=3
P 2.14606004 3.76615 6 P 0 0;1=3
P 3.02571004 5.165 6 P 0 0;1=3
P 11.03661004 2.31615 6 P 0 0;1=3
P 10.98661004 2.21615 6 P 0 0;1=3
P 10.98661004 2.26615 6 P 0 0;1=3
P 3.17146004 5.255 5 P 0 0;1=0
P 4.68268002 2.61615 6 P 0 0;1=3
P 10.93661004 2.26615 6 P 0 0;1=3
P 10.58661004 2.76615 6 P 0 0;1=3
P 4 5.29 5 P 0 0;1=0
P 10.93661004 2.31615 6 P 0 0;1=3
P 10.88661004 2.16615 6 P 0 0;1=3
P 10.73661004 1.91615 6 P 0 0;1=3
P 10.395 1.28555 6 P 0 0;1=3
P 12.81495 1.96456998 11 P 0 0;1=1
P 9.42358002 5.22001998 6 P 0 0;1=3
P 8.98115 2.825 6 P 0 0;1=3
P 4.58268002 2.61615 6 P 0 0;1=3
P 9.38358002 5.22001998 6 P 0 0;1=3
P 8.98115 2.865 6 P 0 0;1=3
P 2.14606004 3.81615 6 P 0 0;1=3
P 3.06571004 5.165 6 P 0 0;1=3
P 11.08661004 2.71615 6 P 0 0;1=3
P 3.985 4.88998996 5 P 0 0;1=0
P 11.73316004 2.652 6 P 0 0;1=3
P 12.55905 4.40551004 11 P 0 0;1=1
P 11.73316004 2.612 6 P 0 0;1=3
P 12.63778996 4.44488002 11 P 0 0;1=1
P 8.3 2.86615 6 P 0 0;1=3
P 4.83268002 2.16615 6 P 0 0;1=3
P 0.69348996 1.90611998 6 P 0 0;1=3
P 11.73316004 2.492 6 P 0 0;1=3
P 12.55905 4.24803002 11 P 0 0;1=1
P 4.88268002 2.16615 6 P 0 0;1=3
P 0.69348996 1.86611998 6 P 0 0;1=3
P 11.73316004 2.452 6 P 0 0;1=3
P 12.63778996 4.2874 11 P 0 0;1=1
P 8.25 2.86615 6 P 0 0;1=3
P 12.55905 3.93306998 11 P 0 0;1=1
P 11.73316004 2.332 6 P 0 0;1=3
P 12.63778996 3.97243996 11 P 0 0;1=1
P 11.73316004 2.292 6 P 0 0;1=3
P 10.83661004 2.16615 6 P 0 0;1=3
P 11.53316004 2.092 6 P 0 0;1=3
P 12.55905 3.77558996 11 P 0 0;1=1
P 11.53316004 2.052 6 P 0 0;1=3
P 12.63778996 3.81496004 11 P 0 0;1=1
P 12.81495 3.53936998 11 P 0 0;1=1
P 10.68661004 2.26615 6 P 0 0;1=3
P 9.975 2.3758 6 P 0 0;1=3
P 12.81495 3.38188996 11 P 0 0;1=1
P 10.73661004 2.31615 6 P 0 0;1=3
P 9.975 2.23955 6 P 0 0;1=3
P 12.81495 2.20078996 11 P 0 0;1=1
P 10.68661004 1.91615 6 P 0 0;1=3
P 10.42445 1.395 6 P 0 0;1=3
P 12.81495 2.75196998 11 P 0 0;1=1
P 10.73661004 2.01615 6 P 0 0;1=3
P 10.26025 1.82845 6 P 0 0;1=3
P 12.73621004 3.73621998 11 P 0 0;1=1
P 10.58661004 2.21615 6 P 0 0;1=3
P 10.09 2.26825 6 P 0 0;1=3
P 10.73661004 2.41615 6 P 0 0;1=3
P 10.09 2.69655 6 P 0 0;1=3
P 12.73621004 4.52361998 11 P 0 0;1=1
P 7.3426 4.69351004 5 P 0 0;1=0
P 11.73316004 1.532 6 P 0 0;1=3
P 12.55905 2.27953002 11 P 0 0;1=1
P 7.2926 4.69351004 5 P 0 0;1=0
P 12.73621004 3.57873996 11 P 0 0;1=1
P 10.68661004 2.21615 6 P 0 0;1=3
P 9.975 2.3358 6 P 0 0;1=3
P 12.73621004 3.42126004 11 P 0 0;1=1
P 10.73661004 2.26615 6 P 0 0;1=3
P 9.975 2.19955 6 P 0 0;1=3
P 11.73316004 2.172 6 P 0 0;1=3
P 12.55905 3.46063002 11 P 0 0;1=1
P 4.98268002 2.36615 6 P 0 0;1=3
P 10.73661004 1.86615 6 P 0 0;1=3
P 10.395 1.32555 6 P 0 0;1=3
P 12.73621004 2.00393996 11 P 0 0;1=1
P 11.73316004 2.132 6 P 0 0;1=3
P 12.63778996 3.5 11 P 0 0;1=1
P 3.38003996 5.22001998 6 P 0 0;1=3
P 2.97721004 2.865 6 P 0 0;1=3
P 4.98268002 2.41615 6 P 0 0;1=3
P 12.63778996 1.76771998 11 P 0 0;1=1
P 3.42003996 5.22001998 6 P 0 0;1=3
P 2.97721004 2.825 6 P 0 0;1=3
P 4.88268002 2.81615 6 P 0 0;1=3
P 4.93268002 2.81615 6 P 0 0;1=3
P 4.98268002 2.81615 6 P 0 0;1=3
P 5.03268002 2.81615 6 P 0 0;1=3
P 5.08268002 2.81615 6 P 0 0;1=3
P 11.03661004 2.81615 6 P 0 0;1=3
P 11.08661004 2.81615 6 P 0 0;1=3
P 10.98661004 2.81615 6 P 0 0;1=3
P 10.93661004 2.81615 6 P 0 0;1=3
P 10.88661004 2.81615 6 P 0 0;1=3
P 5.27886004 3.0214 5 P 0 0;1=4
P 5.27886004 3.0564 5 P 0 0;1=4
P 5.27886004 3.1014 5 P 0 0;1=4
P 5.27886004 3.1364 5 P 0 0;1=4
P 5.27886004 2.9764 5 P 0 0;1=4
P 5.27886004 2.9414 5 P 0 0;1=4
P 5.27886004 3.2614 5 P 0 0;1=4
P 5.27886004 3.2964 5 P 0 0;1=4
P 5.27886004 3.2164 5 P 0 0;1=4
P 5.27886004 3.1814 5 P 0 0;1=4
P 11.28278996 3.1814 5 P 0 0;1=4
P 11.28278996 3.2164 5 P 0 0;1=4
P 11.28278996 3.2964 5 P 0 0;1=4
P 11.28278996 3.2614 5 P 0 0;1=4
P 11.28278996 2.9414 5 P 0 0;1=4
P 11.28278996 2.9764 5 P 0 0;1=4
P 11.28278996 3.1364 5 P 0 0;1=4
P 11.28278996 3.1014 5 P 0 0;1=4
P 11.28278996 3.0564 5 P 0 0;1=4
P 11.28278996 3.0214 5 P 0 0;1=4
P 5.59708996 4.7302 5 P 0 0;1=4
P 5.57708996 4.6802 5 P 0 0;1=4
P 5.75708996 4.7302 5 P 0 0;1=4
P 5.83708996 4.7302 5 P 0 0;1=4
P 5.69708996 4.6802 5 P 0 0;1=4
P 5.73708996 4.6802 5 P 0 0;1=4
P 5.77708996 4.6802 5 P 0 0;1=4
P 5.81708996 4.6802 5 P 0 0;1=4
P 5.85708996 4.6802 5 P 0 0;1=4
P 5.67708996 4.7302 5 P 0 0;1=4
P 5.65708996 4.6802 5 P 0 0;1=4
P 5.61708996 4.6802 5 P 0 0;1=4
P 6.13708996 4.7602 5 P 0 0;1=4
P 6.09708996 4.6802 5 P 0 0;1=4
P 6.13708996 4.6402 5 P 0 0;1=4
P 6.13708996 4.6802 5 P 0 0;1=4
P 6.13708996 4.7202 5 P 0 0;1=4
P 5.91708996 4.7302 5 P 0 0;1=4
P 5.99708996 4.7302 5 P 0 0;1=4
P 6.07708996 4.7302 5 P 0 0;1=4
P 5.89708996 4.6802 5 P 0 0;1=4
P 5.93708996 4.6802 5 P 0 0;1=4
P 5.97708996 4.6802 5 P 0 0;1=4
P 6.01708996 4.6802 5 P 0 0;1=4
P 6.05708996 4.6802 5 P 0 0;1=4
P 5.59708996 4.7702 5 P 0 0;1=4
P 5.59708996 4.8102 5 P 0 0;1=4
P 5.75708996 4.8102 5 P 0 0;1=4
P 5.83708996 4.8102 5 P 0 0;1=4
P 5.75708996 4.7702 5 P 0 0;1=4
P 5.83708996 4.7702 5 P 0 0;1=4
P 5.67708996 4.8102 5 P 0 0;1=4
P 5.67708996 4.7702 5 P 0 0;1=4
P 6.13708996 4.9252 5 P 0 0;1=4
P 6.13708996 4.8402 5 P 0 0;1=4
P 6.13708996 4.8002 5 P 0 0;1=4
P 6.13708996 4.8852 5 P 0 0;1=4
P 5.91708996 4.8102 5 P 0 0;1=4
P 5.99708996 4.8102 5 P 0 0;1=4
P 5.91708996 4.7702 5 P 0 0;1=4
P 5.99708996 4.7702 5 P 0 0;1=4
P 6.07708996 4.8102 5 P 0 0;1=4
P 6.07708996 4.7702 5 P 0 0;1=4
P 4.93268002 2.26615 6 P 0 0;1=3
P 4.93268002 2.31615 6 P 0 0;1=3
P 5.08268002 2.36615 6 P 0 0;1=3
P 12.81495 3.22441004 11 P 0 0;1=1
P 10.68661004 2.06615 6 P 0 0;1=3
P 10.09 2.13095 6 P 0 0;1=3
P 10.63661004 2.31615 6 P 0 0;1=3
P 10.09 2.40335 6 P 0 0;1=3
P 12.81495 3.85433002 11 P 0 0;1=1
P 11.73316004 2.012 6 P 0 0;1=3
P 12.63778996 3.1063 11 P 0 0;1=1
P 11.73316004 1.972 6 P 0 0;1=3
P 12.55905 3.14566998 11 P 0 0;1=1
P 11.53316004 1.732 6 P 0 0;1=3
P 12.55905 2.98818996 11 P 0 0;1=1
P 12.81495 3.69685 11 P 0 0;1=1
P 10.58661004 2.26615 6 P 0 0;1=3
P 10.09 2.30825 6 P 0 0;1=3
P 11.53316004 1.772 6 P 0 0;1=3
P 12.63778996 2.94881998 11 P 0 0;1=1
P 12.81495 4.32676998 11 P 0 0;1=1
P 10.63661004 2.46615 6 P 0 0;1=3
P 9.975 2.62445 6 P 0 0;1=3
P 12.63778996 2.79133996 11 P 0 0;1=1
P 11.73316004 1.852 6 P 0 0;1=3
P 12.55905 2.83071004 11 P 0 0;1=1
P 11.73316004 1.812 6 P 0 0;1=3
P 10.73661004 2.46615 6 P 0 0;1=3
P 10.09 2.73655 6 P 0 0;1=3
P 12.81495 4.48425 11 P 0 0;1=1
P 10.63661004 2.26615 6 P 0 0;1=3
P 10.09 2.44335 6 P 0 0;1=3
P 12.73621004 3.8937 11 P 0 0;1=1
P 10.58661004 2.41615 6 P 0 0;1=3
P 9.975 2.5109 6 P 0 0;1=3
P 12.81495 4.16928996 11 P 0 0;1=1
P 1.025 -0.35 27 P 0 3;1=6
P 1.325 -0.35 27 P 0 3;1=6
P 1.175 -0.35 27 P 0 3;1=6
P 0.725 -0.35 27 P 0 3;1=6
P 0.875 -0.35 27 P 0 3;1=6
P 12.73621004 4.05118002 11 P 0 0;1=1
P 10.68661004 2.36615 6 P 0 0;1=3
P 10.09 2.53845 6 P 0 0;1=3
P 12.81495 2.35826998 11 P 0 0;1=1
P 10.63661004 1.86615 6 P 0 0;1=3
P 10.35543002 1.52156998 6 P 0 0;1=3
P 5.03268002 2.01615 6 P 0 0;1=3
P 5.08268002 2.21615 6 P 0 0;1=3
P 12.73621004 2.16141998 11 P 0 0;1=1
P 10.68661004 1.96615 6 P 0 0;1=3
P 10.46445 1.395 6 P 0 0;1=3
P 0.2 -0.293 19 P 0 0;1=14
P 12.27 0.29 19 P 0 0;1=14
P 0.66 0.29 19 P 0 0;1=14
P 0.2 5.82361998 19 P 0 0;1=14
P 12.81495 1.57086998 11 P 0 0;1=1
P 12.73621004 1.5315 11 P 0 0;1=1
P 12.63778996 2.7126 11 P 0 0;1=1
P 12.55905 2.67323002 11 P 0 0;1=1
P 12.55905 1.64961004 11 P 0 0;1=1
P 12.63778996 1.61023996 11 P 0 0;1=1
P 12.55905 1.57086998 11 P 0 0;1=1
P 12.63778996 1.5315 11 P 0 0;1=1
P 12.73621004 1.68898002 11 P 0 0;1=1
P 12.81495 1.64961004 11 P 0 0;1=1
P 12.63778996 1.68898002 11 P 0 0;1=1
P 12.55905 1.72835 11 P 0 0;1=1
P 12.81495 1.72835 11 P 0 0;1=1
P 12.73621004 1.45276004 11 P 0 0;1=1
P 12.81495 1.41338996 11 P 0 0;1=1
P 12.73621004 1.37401998 11 P 0 0;1=7
P 12.63778996 1.45276004 11 P 0 0;1=1
P 12.55905 1.41338996 11 P 0 0;1=1
P 0.35038996 1.5315 11 P 0 0;1=1
P 0.27165 1.49213002 11 P 0 0;1=1
P 0.17323002 2.67323002 11 P 0 0;1=1
P 0.09448996 2.63386004 11 P 0 0;1=1
P 0.09448996 1.61023996 11 P 0 0;1=1
P 0.17323002 1.57086998 11 P 0 0;1=1
P 0.09448996 1.5315 11 P 0 0;1=1
P 0.17323002 1.49213002 11 P 0 0;1=1
P 0.27165 1.64961004 11 P 0 0;1=1
P 0.35038996 1.61023996 11 P 0 0;1=1
P 0.17323002 1.64961004 11 P 0 0;1=1
P 0.09448996 1.68898002 11 P 0 0;1=1
P 0.35038996 1.68898002 11 P 0 0;1=1
P 0.27165 1.41338996 11 P 0 0;1=1
P 0.35038996 1.37401998 11 P 0 0;1=1
P 0.27165 1.33465 11 P 0 0;1=7
P 0.17323002 1.41338996 11 P 0 0;1=1
P 0.09448996 1.37401998 11 P 0 0;1=1
P 10.20866004 5.4441 24 P 0 0;1=15
P 5.78346004 5.4441 24 P 0 0;1=15
P 12.7252 6.31661998 19 P 0 0;1=14
P 0.2 6.31661998 19 P 0 0;1=14
P 12.7252 -0.293 19 P 0 0;1=14
P 0.22245 4.87401004 17 P 0 0;1=5
P 12.68701004 0.46063002 20 P 0 0;1=16
P 12.68701998 5.4252 20 P 0 0;1=16
P 0.22245 0.42126004 20 P 0 0;1=16
P 0.22255 5.38583002 20 P 0 0;1=16
P 7.17716998 5.7874 23 P 0 0;1=17
P 7.17716998 0.23621998 23 P 0 0;1=17
P 0.22245 0.68898002 22 P 0 0;1=18
P 0.22245 5.11811004 22 P 0 0;1=18
P 12.68701998 5.15748002 22 P 0 0;1=18
P 12.68701998 0.72835 22 P 0 0;1=18
P 6.11811004 1.52756004 22 P 0 0;1=18
P 6.11811004 4.20473002 22 P 0 0;1=18
P 4.83268002 4.22441004 22 P 0 0;1=18
P 2.24606004 4.22441004 22 P 0 0;1=18
P 0.96063002 4.20473002 22 P 0 0;1=18
P 0.96063002 1.52756004 22 P 0 0;1=18
P 2.24606004 1.50786998 22 P 0 0;1=18
P 4.83268002 1.50786998 22 P 0 0;1=18
P 6.04921004 2.58268002 21 P 0 0;1=19
P 1.05905 2.58268002 26 P 0 0;1=20
P 12.12205 1.52756004 22 P 0 0;1=18
P 12.12205 4.20473002 22 P 0 0;1=18
P 10.83661998 4.22441004 22 P 0 0;1=18
P 8.25 4.22441004 22 P 0 0;1=18
P 6.96456998 4.20473002 22 P 0 0;1=18
P 6.96456998 1.52756004 22 P 0 0;1=18
P 8.25 1.50786998 22 P 0 0;1=18
P 10.83661998 1.50786998 22 P 0 0;1=18
P 12.05315 2.58268002 21 P 0 0;1=19
P 7.06298996 2.58268002 26 P 0 0;1=20
P 12.33465 5.69528002 18 P 0 0;1=21
P 3.58311004 4.91851004 14 P 0 0;1=22
P 2.72091004 4.91851004 14 P 0 0;1=22
P 9.58665 4.91851004 14 P 0 0;1=22
P 8.72445 4.91851004 14 P 0 0;1=22
P 2.41851004 4.91851004 14 P 0 0;1=22
P 1.55631004 4.91851004 14 P 0 0;1=22
P 8.42205 4.91851004 14 P 0 0;1=22
P 7.55985 4.91851004 14 P 0 0;1=22
P 0.22243996 1.79331004 16 P 0 0;1=23
P 0.22243996 4.67323002 16 P 0 0;1=23
P 12.687 1.83268002 16 P 0 0;1=23
P 12.687 4.7126 16 P 0 0;1=23
P 0.7687 5.62008002 12 P 0 0;1=24
P 1.47736004 5.62008002 12 P 0 0;1=24
L 12.30808002 1.99858996 12.34808002 1.99858996 1 P 0 
L 12.34808002 1.99858996 12.34808002 1.98058996 1 P 0 
L 12.34808002 1.98058996 12.29608002 1.98058996 1 P 0 
L 12.29608002 1.98058996 12.29608002 1.99858996 1 P 0 
L 12.29608002 1.99858996 12.30808002 1.99858996 1 P 0 
L 12.30208002 1.99258996 12.34108002 1.99258996 3 P 0 
L 12.30301004 1.98658996 12.34201004 1.98658996 3 P 0 
L 12.30301004 1.93658996 12.34201004 1.93658996 3 P 0 
L 12.30208002 1.94258996 12.34108002 1.94258996 3 P 0 
L 12.30808002 1.94858996 12.34808002 1.94858996 1 P 0 
L 12.34808002 1.94858996 12.34808002 1.93058996 1 P 0 
L 12.34808002 1.93058996 12.29608002 1.93058996 1 P 0 
L 12.29608002 1.93058996 12.29608002 1.94858996 1 P 0 
L 12.29608002 1.94858996 12.30808002 1.94858996 1 P 0 
L 0.58606004 1.92081998 0.62606004 1.92081998 1 P 0 
L 0.62606004 1.92081998 0.62606004 1.90281998 1 P 0 
L 0.62606004 1.90281998 0.57406004 1.90281998 1 P 0 
L 0.57406004 1.90281998 0.57406004 1.92081998 1 P 0 
L 0.57406004 1.92081998 0.58606004 1.92081998 1 P 0 
L 0.58006004 1.91481998 0.61906004 1.91481998 3 P 0 
L 0.58098996 1.90881998 0.61998996 1.90881998 3 P 0 
L 0.58098996 1.85881998 0.61998996 1.85881998 3 P 0 
L 0.58006004 1.86481998 0.61906004 1.86481998 3 P 0 
L 0.58606004 1.87081998 0.62606004 1.87081998 1 P 0 
L 0.62606004 1.87081998 0.62606004 1.85281998 1 P 0 
L 0.62606004 1.85281998 0.57406004 1.85281998 1 P 0 
L 0.57406004 1.85281998 0.57406004 1.87081998 1 P 0 
L 0.57406004 1.87081998 0.58606004 1.87081998 1 P 0 
L 2.63991998 2.879 2.67991998 2.879 1 P 0 
L 2.67991998 2.879 2.67991998 2.861 1 P 0 
L 2.67991998 2.861 2.62791998 2.861 1 P 0 
L 2.62791998 2.861 2.62791998 2.879 1 P 0 
L 2.62791998 2.879 2.63991998 2.879 1 P 0 
L 2.63391998 2.873 2.67291998 2.873 3 P 0 
L 2.63485 2.867 2.67385 2.867 3 P 0 
L 2.63485 2.817 2.67385 2.817 3 P 0 
L 2.63391998 2.823 2.67291998 2.823 3 P 0 
L 2.63991998 2.829 2.67991998 2.829 1 P 0 
L 2.67991998 2.829 2.67991998 2.811 1 P 0 
L 2.67991998 2.811 2.62791998 2.811 1 P 0 
L 2.62791998 2.811 2.62791998 2.829 1 P 0 
L 2.62791998 2.829 2.63991998 2.829 1 P 0 
L 8.64386004 2.829 8.68386004 2.829 1 P 0 
L 8.68386004 2.829 8.68386004 2.811 1 P 0 
L 8.68386004 2.811 8.63186004 2.811 1 P 0 
L 8.63186004 2.811 8.63186004 2.829 1 P 0 
L 8.63186004 2.829 8.64386004 2.829 1 P 0 
L 8.63786004 2.823 8.67686004 2.823 3 P 0 
L 8.63878996 2.817 8.67778996 2.817 3 P 0 
L 8.63878996 2.867 8.67778996 2.867 3 P 0 
L 8.63786004 2.873 8.67686004 2.873 3 P 0 
L 8.64386004 2.879 8.68386004 2.879 1 P 0 
L 8.68386004 2.879 8.68386004 2.861 1 P 0 
L 8.68386004 2.861 8.63186004 2.861 1 P 0 
L 8.63186004 2.861 8.63186004 2.879 1 P 0 
L 8.63186004 2.879 8.64386004 2.879 1 P 0 
L 11.625 2.664 11.665 2.664 1 P 0 
L 11.665 2.664 11.665 2.646 1 P 0 
L 11.665 2.646 11.613 2.646 1 P 0 
L 11.613 2.646 11.613 2.664 1 P 0 
L 11.613 2.664 11.625 2.664 1 P 0 
L 11.619 2.658 11.658 2.658 3 P 0 
L 11.61993002 2.652 11.65893002 2.652 3 P 0 
L 11.61993002 2.607 11.65893002 2.607 3 P 0 
L 11.619 2.613 11.658 2.613 3 P 0 
L 11.625 2.619 11.665 2.619 1 P 0 
L 11.665 2.619 11.665 2.601 1 P 0 
L 11.665 2.601 11.613 2.601 1 P 0 
L 11.613 2.601 11.613 2.619 1 P 0 
L 11.613 2.619 11.625 2.619 1 P 0 
L 11.425 2.584 11.465 2.584 1 P 0 
L 11.465 2.584 11.465 2.566 1 P 0 
L 11.465 2.566 11.413 2.566 1 P 0 
L 11.413 2.566 11.413 2.584 1 P 0 
L 11.413 2.584 11.425 2.584 1 P 0 
L 11.419 2.578 11.458 2.578 3 P 0 
L 11.41993002 2.572 11.45893002 2.572 3 P 0 
L 11.41993002 2.527 11.45893002 2.527 3 P 0 
L 11.419 2.533 11.458 2.533 3 P 0 
L 11.425 2.539 11.465 2.539 1 P 0 
L 11.465 2.539 11.465 2.521 1 P 0 
L 11.465 2.521 11.413 2.521 1 P 0 
L 11.413 2.521 11.413 2.539 1 P 0 
L 11.413 2.539 11.425 2.539 1 P 0 
L 11.625 2.504 11.665 2.504 1 P 0 
L 11.665 2.504 11.665 2.486 1 P 0 
L 11.665 2.486 11.613 2.486 1 P 0 
L 11.613 2.486 11.613 2.504 1 P 0 
L 11.613 2.504 11.625 2.504 1 P 0 
L 11.619 2.498 11.658 2.498 3 P 0 
L 11.61993002 2.492 11.65893002 2.492 3 P 0 
L 11.61993002 2.447 11.65893002 2.447 3 P 0 
L 11.619 2.453 11.658 2.453 3 P 0 
L 11.625 2.459 11.665 2.459 1 P 0 
L 11.665 2.459 11.665 2.441 1 P 0 
L 11.665 2.441 11.613 2.441 1 P 0 
L 11.613 2.441 11.613 2.459 1 P 0 
L 11.613 2.459 11.625 2.459 1 P 0 
L 11.425 2.424 11.465 2.424 1 P 0 
L 11.465 2.424 11.465 2.406 1 P 0 
L 11.465 2.406 11.413 2.406 1 P 0 
L 11.413 2.406 11.413 2.424 1 P 0 
L 11.413 2.424 11.425 2.424 1 P 0 
L 11.419 2.418 11.458 2.418 3 P 0 
L 11.41993002 2.412 11.45893002 2.412 3 P 0 
L 11.41993002 2.367 11.45893002 2.367 3 P 0 
L 11.419 2.373 11.458 2.373 3 P 0 
L 11.425 2.379 11.465 2.379 1 P 0 
L 11.465 2.379 11.465 2.361 1 P 0 
L 11.465 2.361 11.413 2.361 1 P 0 
L 11.413 2.361 11.413 2.379 1 P 0 
L 11.413 2.379 11.425 2.379 1 P 0 
L 11.625 2.344 11.665 2.344 1 P 0 
L 11.665 2.344 11.665 2.326 1 P 0 
L 11.665 2.326 11.613 2.326 1 P 0 
L 11.613 2.326 11.613 2.344 1 P 0 
L 11.613 2.344 11.625 2.344 1 P 0 
L 11.619 2.338 11.658 2.338 3 P 0 
L 11.61993002 2.332 11.65893002 2.332 3 P 0 
L 11.61993002 2.287 11.65893002 2.287 3 P 0 
L 11.619 2.293 11.658 2.293 3 P 0 
L 11.625 2.299 11.665 2.299 1 P 0 
L 11.665 2.299 11.665 2.281 1 P 0 
L 11.665 2.281 11.613 2.281 1 P 0 
L 11.613 2.281 11.613 2.299 1 P 0 
L 11.613 2.299 11.625 2.299 1 P 0 
L 11.425 2.264 11.465 2.264 1 P 0 
L 11.465 2.264 11.465 2.246 1 P 0 
L 11.465 2.246 11.413 2.246 1 P 0 
L 11.413 2.246 11.413 2.264 1 P 0 
L 11.413 2.264 11.425 2.264 1 P 0 
L 11.419 2.258 11.458 2.258 3 P 0 
L 11.41993002 2.252 11.45893002 2.252 3 P 0 
L 11.41993002 2.207 11.45893002 2.207 3 P 0 
L 11.419 2.213 11.458 2.213 3 P 0 
L 11.425 2.219 11.465 2.219 1 P 0 
L 11.465 2.219 11.465 2.201 1 P 0 
L 11.465 2.201 11.413 2.201 1 P 0 
L 11.413 2.201 11.413 2.219 1 P 0 
L 11.413 2.219 11.425 2.219 1 P 0 
L 11.625 2.184 11.665 2.184 1 P 0 
L 11.665 2.184 11.665 2.166 1 P 0 
L 11.665 2.166 11.613 2.166 1 P 0 
L 11.613 2.166 11.613 2.184 1 P 0 
L 11.613 2.184 11.625 2.184 1 P 0 
L 11.619 2.178 11.658 2.178 3 P 0 
L 11.61993002 2.172 11.65893002 2.172 3 P 0 
L 11.61993002 2.127 11.65893002 2.127 3 P 0 
L 11.619 2.133 11.658 2.133 3 P 0 
L 11.625 2.139 11.665 2.139 1 P 0 
L 11.665 2.139 11.665 2.121 1 P 0 
L 11.665 2.121 11.613 2.121 1 P 0 
L 11.613 2.121 11.613 2.139 1 P 0 
L 11.613 2.139 11.625 2.139 1 P 0 
L 11.425 2.104 11.465 2.104 1 P 0 
L 11.465 2.104 11.465 2.086 1 P 0 
L 11.465 2.086 11.413 2.086 1 P 0 
L 11.413 2.086 11.413 2.104 1 P 0 
L 11.413 2.104 11.425 2.104 1 P 0 
L 11.419 2.098 11.458 2.098 3 P 0 
L 11.41993002 2.092 11.45893002 2.092 3 P 0 
L 11.41993002 2.047 11.45893002 2.047 3 P 0 
L 11.419 2.053 11.458 2.053 3 P 0 
L 11.425 2.059 11.465 2.059 1 P 0 
L 11.465 2.059 11.465 2.041 1 P 0 
L 11.465 2.041 11.413 2.041 1 P 0 
L 11.413 2.041 11.413 2.059 1 P 0 
L 11.413 2.059 11.425 2.059 1 P 0 
L 11.625 2.024 11.665 2.024 1 P 0 
L 11.665 2.024 11.665 2.006 1 P 0 
L 11.665 2.006 11.613 2.006 1 P 0 
L 11.613 2.006 11.613 2.024 1 P 0 
L 11.613 2.024 11.625 2.024 1 P 0 
L 11.619 2.018 11.658 2.018 3 P 0 
L 11.61993002 2.012 11.65893002 2.012 3 P 0 
L 11.61993002 1.967 11.65893002 1.967 3 P 0 
L 11.619 1.973 11.658 1.973 3 P 0 
L 11.625 1.979 11.665 1.979 1 P 0 
L 11.665 1.979 11.665 1.961 1 P 0 
L 11.665 1.961 11.613 1.961 1 P 0 
L 11.613 1.961 11.613 1.979 1 P 0 
L 11.613 1.979 11.625 1.979 1 P 0 
L 11.425 1.944 11.465 1.944 1 P 0 
L 11.465 1.944 11.465 1.926 1 P 0 
L 11.465 1.926 11.413 1.926 1 P 0 
L 11.413 1.926 11.413 1.944 1 P 0 
L 11.413 1.944 11.425 1.944 1 P 0 
L 11.419 1.938 11.458 1.938 3 P 0 
L 11.41993002 1.932 11.45893002 1.932 3 P 0 
L 11.41993002 1.887 11.45893002 1.887 3 P 0 
L 11.419 1.893 11.458 1.893 3 P 0 
L 11.425 1.899 11.465 1.899 1 P 0 
L 11.465 1.899 11.465 1.881 1 P 0 
L 11.465 1.881 11.413 1.881 1 P 0 
L 11.413 1.881 11.413 1.899 1 P 0 
L 11.413 1.899 11.425 1.899 1 P 0 
L 11.625 1.864 11.665 1.864 1 P 0 
L 11.665 1.864 11.665 1.846 1 P 0 
L 11.665 1.846 11.613 1.846 1 P 0 
L 11.613 1.846 11.613 1.864 1 P 0 
L 11.613 1.864 11.625 1.864 1 P 0 
L 11.619 1.858 11.658 1.858 3 P 0 
L 11.61993002 1.852 11.65893002 1.852 3 P 0 
L 11.61993002 1.807 11.65893002 1.807 3 P 0 
L 11.619 1.813 11.658 1.813 3 P 0 
L 11.625 1.819 11.665 1.819 1 P 0 
L 11.665 1.819 11.665 1.801 1 P 0 
L 11.665 1.801 11.613 1.801 1 P 0 
L 11.613 1.801 11.613 1.819 1 P 0 
L 11.613 1.819 11.625 1.819 1 P 0 
L 11.425 1.784 11.465 1.784 1 P 0 
L 11.465 1.784 11.465 1.766 1 P 0 
L 11.465 1.766 11.413 1.766 1 P 0 
L 11.413 1.766 11.413 1.784 1 P 0 
L 11.413 1.784 11.425 1.784 1 P 0 
L 11.419 1.778 11.458 1.778 3 P 0 
L 11.41993002 1.772 11.45893002 1.772 3 P 0 
L 11.41993002 1.727 11.45893002 1.727 3 P 0 
L 11.419 1.733 11.458 1.733 3 P 0 
L 11.425 1.739 11.465 1.739 1 P 0 
L 11.465 1.739 11.465 1.721 1 P 0 
L 11.465 1.721 11.413 1.721 1 P 0 
L 11.413 1.721 11.413 1.739 1 P 0 
L 11.413 1.739 11.425 1.739 1 P 0 
L 11.625 1.704 11.665 1.704 1 P 0 
L 11.665 1.704 11.665 1.686 1 P 0 
L 11.665 1.686 11.613 1.686 1 P 0 
L 11.613 1.686 11.613 1.704 1 P 0 
L 11.613 1.704 11.625 1.704 1 P 0 
L 11.619 1.698 11.658 1.698 3 P 0 
L 11.61993002 1.692 11.65893002 1.692 3 P 0 
L 11.61993002 1.647 11.65893002 1.647 3 P 0 
L 11.619 1.653 11.658 1.653 3 P 0 
L 11.625 1.659 11.665 1.659 1 P 0 
L 11.665 1.659 11.665 1.641 1 P 0 
L 11.665 1.641 11.613 1.641 1 P 0 
L 11.613 1.641 11.613 1.659 1 P 0 
L 11.613 1.659 11.625 1.659 1 P 0 
L 11.425 1.624 11.465 1.624 1 P 0 
L 11.465 1.624 11.465 1.606 1 P 0 
L 11.465 1.606 11.413 1.606 1 P 0 
L 11.413 1.606 11.413 1.624 1 P 0 
L 11.413 1.624 11.425 1.624 1 P 0 
L 11.419 1.618 11.458 1.618 3 P 0 
L 11.41993002 1.612 11.45893002 1.612 3 P 0 
L 11.41993002 1.567 11.45893002 1.567 3 P 0 
L 11.419 1.573 11.458 1.573 3 P 0 
L 11.425 1.579 11.465 1.579 1 P 0 
L 11.465 1.579 11.465 1.561 1 P 0 
L 11.465 1.561 11.413 1.561 1 P 0 
L 11.413 1.561 11.413 1.579 1 P 0 
L 11.413 1.579 11.425 1.579 1 P 0 
L 11.425 1.464 11.465 1.464 1 P 0 
L 11.465 1.464 11.465 1.446 1 P 0 
L 11.465 1.446 11.413 1.446 1 P 0 
L 11.413 1.446 11.413 1.464 1 P 0 
L 11.413 1.464 11.425 1.464 1 P 0 
L 11.419 1.458 11.458 1.458 3 P 0 
L 11.41993002 1.452 11.45893002 1.452 3 P 0 
L 11.41993002 1.407 11.45893002 1.407 3 P 0 
L 11.419 1.413 11.458 1.413 3 P 0 
L 11.425 1.419 11.465 1.419 1 P 0 
L 11.465 1.419 11.465 1.401 1 P 0 
L 11.465 1.401 11.413 1.401 1 P 0 
L 11.413 1.401 11.413 1.419 1 P 0 
L 11.413 1.419 11.425 1.419 1 P 0 
L 11.625 1.499 11.665 1.499 1 P 0 
L 11.665 1.499 11.665 1.481 1 P 0 
L 11.665 1.481 11.613 1.481 1 P 0 
L 11.613 1.481 11.613 1.499 1 P 0 
L 11.613 1.499 11.625 1.499 1 P 0 
L 11.619 1.493 11.658 1.493 3 P 0 
L 11.61993002 1.487 11.65893002 1.487 3 P 0 
L 11.61993002 1.532 11.65893002 1.532 3 P 0 
L 11.619 1.538 11.658 1.538 3 P 0 
L 11.625 1.544 11.665 1.544 1 P 0 
L 11.665 1.544 11.665 1.526 1 P 0 
L 11.665 1.526 11.613 1.526 1 P 0 
L 11.613 1.526 11.613 1.544 1 P 0 
L 11.613 1.544 11.625 1.544 1 P 0 
L 1.88908002 -1.91246004 1.89293002 -1.91246004 0 P 0 ;0
L 1.89126998 -1.91146004 1.89656998 -1.91146004 0 P 0 ;0
L 1.89393996 -1.91046004 1.9155 -1.91046004 0 P 0 ;0
L 1.91593996 -1.91246004 1.92048996 -1.91246004 0 P 0 ;0
L 1.9126 -1.91146004 1.9184 -1.91146004 0 P 0 ;0
L 1.89763002 -1.90946004 1.91016998 -1.90946004 0 P 0 ;0
L 1.89053002 -1.96001004 1.8974 -1.96001004 0 P 0 ;0
L 1.89053002 -1.95901004 1.8974 -1.95901004 0 P 0 ;0
L 1.89053002 -1.95801004 1.8974 -1.95801004 0 P 0 ;0
L 1.89053002 -1.95701004 1.8974 -1.95701004 0 P 0 ;0
L 1.89053002 -1.95601004 1.8974 -1.95601004 0 P 0 ;0
L 1.89053002 -1.95501004 1.8974 -1.95501004 0 P 0 ;0
L 1.89053002 -1.95401004 1.8974 -1.95401004 0 P 0 ;0
L 1.89053002 -1.95301004 1.89741004 -1.95301004 0 P 0 ;0
L 1.89053002 -1.95201004 1.89741998 -1.95201004 0 P 0 ;0
L 1.89053002 -1.95101004 1.89743996 -1.95101004 0 P 0 ;0
L 1.89053002 -1.95001004 1.89745 -1.95001004 0 P 0 ;0
L 1.89053002 -1.94901004 1.89746004 -1.94901004 0 P 0 ;0
L 1.89053002 -1.94801004 1.89753002 -1.94801004 0 P 0 ;0
L 1.89053002 -1.94701004 1.8977 -1.94701004 0 P 0 ;0
L 1.89053002 -1.94601004 1.89798002 -1.94601004 0 P 0 ;0
L 1.89053002 -1.94501004 1.89861004 -1.94501004 0 P 0 ;0
L 1.89053002 -1.94401004 1.90005 -1.94401004 0 P 0 ;0
L 1.89053002 -1.94301004 1.9113 -1.94301004 0 P 0 ;0
L 1.89053002 -1.94201004 1.91168002 -1.94201004 0 P 0 ;0
L 1.89053002 -1.94101004 1.91246998 -1.94101004 0 P 0 ;0
L 1.89053002 -1.94001004 1.90093996 -1.94001004 0 P 0 ;0
L 1.89053002 -1.93901004 1.89856004 -1.93901004 0 P 0 ;0
L 1.89053002 -1.93801004 1.89786998 -1.93801004 0 P 0 ;0
L 1.89053002 -1.93701004 1.89753996 -1.93701004 0 P 0 ;0
L 1.89053002 -1.93601004 1.89746998 -1.93601004 0 P 0 ;0
L 1.89053002 -1.93501004 1.89743996 -1.93501004 0 P 0 ;0
L 1.89053002 -1.93401004 1.89741998 -1.93401004 0 P 0 ;0
L 1.89053002 -1.93301004 1.8974 -1.93301004 0 P 0 ;0
L 1.89053002 -1.93201004 1.8974 -1.93201004 0 P 0 ;0
L 1.89053002 -1.93101004 1.8974 -1.93101004 0 P 0 ;0
L 1.89053002 -1.93001004 1.8974 -1.93001004 0 P 0 ;0
L 1.89053002 -1.92901004 1.8974 -1.92901004 0 P 0 ;0
L 1.89053002 -1.92801004 1.89753002 -1.92801004 0 P 0 ;0
L 1.89053002 -1.92701004 1.89793996 -1.92701004 0 P 0 ;0
L 1.89053002 -1.92601004 1.91713002 -1.92601004 0 P 0 ;0
L 1.89053002 -1.92501004 1.91628996 -1.92501004 0 P 0 ;0
L 1.89053002 -1.92401004 1.91513996 -1.92401004 0 P 0 ;0
L 1.89053002 -1.92301004 1.91321998 -1.92301004 0 P 0 ;0
L 1.89053002 -1.92201004 1.90551004 -1.92201004 0 P 0 ;0
L 1.89438996 -1.97246004 1.91331004 -1.97246004 0 P 0 ;0
L 1.89106998 -1.97146004 1.89973002 -1.97146004 0 P 0 ;0
L 1.88878002 -1.97046004 1.8949 -1.97046004 0 P 0 ;0
L 1.88698002 -1.96946004 1.89206998 -1.96946004 0 P 0 ;0
L 1.88546004 -1.96846004 1.88986998 -1.96846004 0 P 0 ;0
L 1.88416998 -1.96746004 1.88808996 -1.96746004 0 P 0 ;0
L 1.88288002 -1.96646004 1.88655 -1.96646004 0 P 0 ;0
L 1.88176998 -1.96546004 1.88518002 -1.96546004 0 P 0 ;0
L 1.88068996 -1.96446004 1.88393996 -1.96446004 0 P 0 ;0
L 1.87968996 -1.96346004 1.88286004 -1.96346004 0 P 0 ;0
L 1.87878002 -1.96246004 1.88186004 -1.96246004 0 P 0 ;0
L 1.8786 -1.92046004 1.88126998 -1.92046004 0 P 0 ;0
L 1.87946998 -1.91946004 1.88223002 -1.91946004 0 P 0 ;0
L 1.88048002 -1.91846004 1.88321004 -1.91846004 0 P 0 ;0
L 1.88153996 -1.91746004 1.88436998 -1.91746004 0 P 0 ;0
L 1.88273002 -1.91646004 1.88558996 -1.91646004 0 P 0 ;0
L 1.88406004 -1.91546004 1.88696998 -1.91546004 0 P 0 ;0
L 1.88548996 -1.91446004 1.88853002 -1.91446004 0 P 0 ;0
L 1.88718002 -1.91346004 1.89041998 -1.91346004 0 P 0 ;0
L 1.90896004 -1.92963996 1.90921998 -1.92991998 0 P 0 ;0
L 1.90921998 -1.92991998 1.90945 -1.93021998 0 P 0 ;0
L 1.90945 -1.93021998 1.90966004 -1.93053002 0 P 0 ;0
L 1.90966004 -1.93053002 1.90983002 -1.93086004 0 P 0 ;0
L 1.90983002 -1.93086004 1.90998002 -1.93121004 0 P 0 ;0
L 1.90998002 -1.93121004 1.9101 -1.93156998 0 P 0 ;0
L 1.9101 -1.93156998 1.91018996 -1.93193996 0 P 0 ;0
L 1.91018996 -1.93193996 1.91023996 -1.93231004 0 P 0 ;0
L 1.91023996 -1.93231004 1.91026998 -1.93265 0 P 0 ;0
L 1.91026998 -1.93265 1.91026004 -1.93298002 0 P 0 ;0
L 1.91026004 -1.93298002 1.91023002 -1.93331004 0 P 0 ;0
L 1.91023002 -1.93331004 1.91016998 -1.93363996 0 P 0 ;0
L 1.91016998 -1.93363996 1.91008996 -1.93396004 0 P 0 ;0
L 1.91008996 -1.93396004 1.90998002 -1.93428002 0 P 0 ;0
L 1.90998002 -1.93428002 1.90983996 -1.93458002 0 P 0 ;0
L 1.90983996 -1.93458002 1.90968996 -1.93486998 0 P 0 ;0
L 1.90968996 -1.93486998 1.90951004 -1.93516004 0 P 0 ;0
L 1.90951004 -1.93516004 1.90921004 -1.93556004 0 P 0 ;0
L 1.90921004 -1.93556004 1.90888002 -1.93593002 0 P 0 ;0
L 1.90888002 -1.93593002 1.90853002 -1.93626998 0 P 0 ;0
L 1.90853002 -1.93626998 1.90815 -1.93658996 0 P 0 ;0
L 1.90815 -1.93658996 1.90773996 -1.93686998 0 P 0 ;0
L 1.90773996 -1.93686998 1.90731998 -1.93711998 0 P 0 ;0
L 1.90731998 -1.93711998 1.90686998 -1.93733996 0 P 0 ;0
L 1.90686998 -1.93733996 1.90615 -1.93761004 0 P 0 ;0
L 1.90615 -1.93761004 1.90541998 -1.93783002 0 P 0 ;0
L 1.90541998 -1.93783002 1.90466004 -1.93798002 0 P 0 ;0
L 1.90466004 -1.93798002 1.9039 -1.93808002 0 P 0 ;0
L 1.9039 -1.93808002 1.90311998 -1.9381 0 P 0 ;0
L 1.90311998 -1.9381 1.90196004 -1.93808002 0 P 0 ;0
L 1.90196004 -1.93808002 1.90078996 -1.93798996 0 P 0 ;0
L 1.90078996 -1.93798996 1.90068002 -1.93798002 0 P 0 ;0
L 1.90068002 -1.93798002 1.90058002 -1.93795 0 P 0 ;0
L 1.90058002 -1.93795 1.90046998 -1.93791998 0 P 0 ;0
L 1.90046998 -1.93791998 1.90038002 -1.93788002 0 P 0 ;0
L 1.90038002 -1.93788002 1.90028002 -1.93783002 0 P 0 ;0
L 1.90028002 -1.93783002 1.90018996 -1.93778002 0 P 0 ;0
L 1.90018996 -1.93778002 1.9001 -1.93771004 0 P 0 ;0
L 1.9001 -1.93771004 1.90001998 -1.93763996 0 P 0 ;0
L 1.90001998 -1.93763996 1.89988002 -1.93748002 0 P 0 ;0
L 1.89988002 -1.93748002 1.89978002 -1.93733996 0 P 0 ;0
L 1.89978002 -1.93733996 1.89961998 -1.93703996 0 P 0 ;0
L 1.89961998 -1.93703996 1.89956998 -1.93688002 0 P 0 ;0
L 1.89956998 -1.93688002 1.89951998 -1.93671004 0 P 0 ;0
L 1.89951998 -1.93671004 1.89948996 -1.93655 0 P 0 ;0
L 1.89948996 -1.93655 1.89946998 -1.93636998 0 P 0 ;0
L 1.89946998 -1.93636998 1.8994 -1.93323002 0 P 0 ;0
L 1.8994 -1.93323002 1.8994 -1.92833002 0 P 0 ;0
L 1.8994 -1.92833002 1.90353996 -1.92833002 0 P 0 ;0
L 1.90353996 -1.92833002 1.90436998 -1.92835 0 P 0 ;0
L 1.90436998 -1.92835 1.9052 -1.92843002 0 P 0 ;0
L 1.9052 -1.92843002 1.90603002 -1.92853996 0 P 0 ;0
L 1.90603002 -1.92853996 1.90683996 -1.92871004 0 P 0 ;0
L 1.90683996 -1.92871004 1.90751004 -1.9289 0 P 0 ;0
L 1.90751004 -1.9289 1.90818002 -1.92913002 0 P 0 ;0
L 1.90818002 -1.92913002 1.90851998 -1.92928996 0 P 0 ;0
L 1.90851998 -1.92928996 1.90868002 -1.92938996 0 P 0 ;0
L 1.90868002 -1.92938996 1.90883002 -1.92951004 0 P 0 ;0
L 1.90883002 -1.92951004 1.90896004 -1.92963996 0 P 0 ;0
L 1.91188996 -1.96001004 1.91638996 -1.96001004 0 P 0 ;0
L 1.91156998 -1.95901004 1.91926998 -1.95901004 0 P 0 ;0
L 1.91125 -1.95801004 1.91891998 -1.95801004 0 P 0 ;0
L 1.91091998 -1.95701004 1.91853002 -1.95701004 0 P 0 ;0
L 1.9106 -1.95601004 1.91811004 -1.95601004 0 P 0 ;0
L 1.91025 -1.95501004 1.91765 -1.95501004 0 P 0 ;0
L 1.90988996 -1.95401004 1.91718996 -1.95401004 0 P 0 ;0
L 1.90953002 -1.95301004 1.91673002 -1.95301004 0 P 0 ;0
L 1.90918002 -1.95201004 1.91626998 -1.95201004 0 P 0 ;0
L 1.90881998 -1.95101004 1.91576004 -1.95101004 0 P 0 ;0
L 1.90841004 -1.95001004 1.91523996 -1.95001004 0 P 0 ;0
L 1.90793996 -1.94901004 1.91471004 -1.94901004 0 P 0 ;0
L 1.90738996 -1.94801004 1.91418002 -1.94801004 0 P 0 ;0
L 1.90676998 -1.94701004 1.9136 -1.94701004 0 P 0 ;0
L 1.90598996 -1.94601004 1.91261004 -1.94601004 0 P 0 ;0
L 1.90495 -1.94501004 1.91175 -1.94501004 0 P 0 ;0
L 1.90325 -1.94401004 1.91133002 -1.94401004 0 P 0 ;0
L 1.90456004 -1.94001004 1.91383002 -1.94001004 0 P 0 ;0
L 1.90801004 -1.93901004 1.91523002 -1.93901004 0 P 0 ;0
L 1.90956998 -1.93801004 1.91635 -1.93801004 0 P 0 ;0
L 1.9106 -1.93701004 1.91718002 -1.93701004 0 P 0 ;0
L 1.91133996 -1.93601004 1.91781004 -1.93601004 0 P 0 ;0
L 1.91183996 -1.93501004 1.91826004 -1.93501004 0 P 0 ;0
L 1.91213002 -1.93401004 1.9186 -1.93401004 0 P 0 ;0
L 1.91226004 -1.93301004 1.9188 -1.93301004 0 P 0 ;0
L 1.91221998 -1.93201004 1.9189 -1.93201004 0 P 0 ;0
L 1.91201998 -1.93101004 1.9189 -1.93101004 0 P 0 ;0
L 1.91163996 -1.93001004 1.91878996 -1.93001004 0 P 0 ;0
L 1.91105 -1.92901004 1.91856998 -1.92901004 0 P 0 ;0
L 1.91013996 -1.92801004 1.91823002 -1.92801004 0 P 0 ;0
L 1.90816998 -1.92701004 1.91776004 -1.92701004 0 P 0 ;0
L 1.90313996 -1.94011004 1.90316998 -1.9401 0 P 0 ;0
L 1.90316998 -1.9401 1.9032 -1.9401 0 P 0 ;0
L 1.9032 -1.9401 1.90398002 -1.94006998 0 P 0 ;0
L 1.90398002 -1.94006998 1.90406004 -1.94006998 0 P 0 ;0
L 1.90406004 -1.94006998 1.90413996 -1.94006004 0 P 0 ;0
L 1.90413996 -1.94006004 1.9049 -1.93996998 0 P 0 ;0
L 1.9049 -1.93996998 1.90493996 -1.93996004 0 P 0 ;0
L 1.90493996 -1.93996004 1.90498996 -1.93996004 0 P 0 ;0
L 1.90498996 -1.93996004 1.90506998 -1.93993996 0 P 0 ;0
L 1.90506998 -1.93993996 1.90581998 -1.93978002 0 P 0 ;0
L 1.90581998 -1.93978002 1.90586004 -1.93978002 0 P 0 ;0
L 1.90586004 -1.93978002 1.90593996 -1.93976004 0 P 0 ;0
L 1.90593996 -1.93976004 1.90596998 -1.93973996 0 P 0 ;0
L 1.90596998 -1.93973996 1.90671004 -1.93953002 0 P 0 ;0
L 1.90671004 -1.93953002 1.90678996 -1.93951004 0 P 0 ;0
L 1.90678996 -1.93951004 1.90758996 -1.93921004 0 P 0 ;0
L 1.90758996 -1.93921004 1.90766004 -1.93916998 0 P 0 ;0
L 1.90766004 -1.93916998 1.9077 -1.93915 0 P 0 ;0
L 1.9077 -1.93915 1.90773996 -1.93913996 0 P 0 ;0
L 1.90773996 -1.93913996 1.90818996 -1.93891998 0 P 0 ;0
L 1.90818996 -1.93891998 1.90821998 -1.9389 0 P 0 ;0
L 1.90821998 -1.9389 1.90826004 -1.93888996 0 P 0 ;0
L 1.90826004 -1.93888996 1.90828996 -1.93886998 0 P 0 ;0
L 1.90828996 -1.93886998 1.90833002 -1.93885 0 P 0 ;0
L 1.90833002 -1.93885 1.90875 -1.9386 0 P 0 ;0
L 1.90875 -1.9386 1.90883002 -1.93856004 0 P 0 ;0
L 1.90883002 -1.93856004 1.90888996 -1.93851004 0 P 0 ;0
L 1.90888996 -1.93851004 1.90928996 -1.93823002 0 P 0 ;0
L 1.90928996 -1.93823002 1.90933002 -1.9382 0 P 0 ;0
L 1.90933002 -1.9382 1.90936004 -1.93818002 0 P 0 ;0
L 1.90936004 -1.93818002 1.90938996 -1.93815 0 P 0 ;0
L 1.90938996 -1.93815 1.90941998 -1.93813002 0 P 0 ;0
L 1.90941998 -1.93813002 1.9098 -1.93781998 0 P 0 ;0
L 1.9098 -1.93781998 1.90986004 -1.93776004 0 P 0 ;0
L 1.90986004 -1.93776004 1.90988996 -1.93773996 0 P 0 ;0
L 1.90988996 -1.93773996 1.90991998 -1.93771004 0 P 0 ;0
L 1.90991998 -1.93771004 1.91028002 -1.93736004 0 P 0 ;0
L 1.91028002 -1.93736004 1.91038996 -1.93725 0 P 0 ;0
L 1.91038996 -1.93725 1.91071004 -1.93688002 0 P 0 ;0
L 1.91071004 -1.93688002 1.91073996 -1.93685 0 P 0 ;0
L 1.91073996 -1.93685 1.91116004 -1.9363 0 P 0 ;0
L 1.91116004 -1.9363 1.9112 -1.93623002 0 P 0 ;0
L 1.9112 -1.93623002 1.91138002 -1.93595 0 P 0 ;0
L 1.91138002 -1.93595 1.9114 -1.93591004 0 P 0 ;0
L 1.9114 -1.93591004 1.91143996 -1.93585 0 P 0 ;0
L 1.91143996 -1.93585 1.91146004 -1.93581004 0 P 0 ;0
L 1.91146004 -1.93581004 1.91161004 -1.93551998 0 P 0 ;0
L 1.91161004 -1.93551998 1.91163002 -1.93548996 0 P 0 ;0
L 1.91163002 -1.93548996 1.91165 -1.93545 0 P 0 ;0
L 1.91165 -1.93545 1.91166004 -1.93541004 0 P 0 ;0
L 1.91166004 -1.93541004 1.91168002 -1.93538002 0 P 0 ;0
L 1.91168002 -1.93538002 1.91181004 -1.93506998 0 P 0 ;0
L 1.91181004 -1.93506998 1.91183996 -1.935 0 P 0 ;0
L 1.91183996 -1.935 1.91186004 -1.93496004 0 P 0 ;0
L 1.91186004 -1.93496004 1.91186998 -1.93493002 0 P 0 ;0
L 1.91186998 -1.93493002 1.91198002 -1.93461004 0 P 0 ;0
L 1.91198002 -1.93461004 1.91198996 -1.93456998 0 P 0 ;0
L 1.91198996 -1.93456998 1.912 -1.93453996 0 P 0 ;0
L 1.912 -1.93453996 1.9121 -1.93413996 0 P 0 ;0
L 1.9121 -1.93413996 1.91211998 -1.9341 0 P 0 ;0
L 1.91211998 -1.9341 1.91211998 -1.93406004 0 P 0 ;0
L 1.91211998 -1.93406004 1.91213002 -1.93401998 0 P 0 ;0
L 1.91213002 -1.93401998 1.91213996 -1.93398996 0 P 0 ;0
L 1.91213996 -1.93398996 1.9122 -1.93366004 0 P 0 ;0
L 1.9122 -1.93366004 1.91221004 -1.93358002 0 P 0 ;0
L 1.91221004 -1.93358002 1.91221004 -1.93353996 0 P 0 ;0
L 1.91221004 -1.93353996 1.91221998 -1.9335 0 P 0 ;0
L 1.91221998 -1.9335 1.91225 -1.93316998 0 P 0 ;0
L 1.91225 -1.93316998 1.91226004 -1.93308996 0 P 0 ;0
L 1.91226004 -1.93308996 1.91226004 -1.93268002 0 P 0 ;0
L 1.91226004 -1.93268002 1.91226998 -1.93263996 0 P 0 ;0
L 1.91226998 -1.93263996 1.91226998 -1.9326 0 P 0 ;0
L 1.91226998 -1.9326 1.91226004 -1.93251998 0 P 0 ;0
L 1.91226004 -1.93251998 1.91223996 -1.93218996 0 P 0 ;0
L 1.91223996 -1.93218996 1.91223996 -1.93215 0 P 0 ;0
L 1.91223996 -1.93215 1.91223002 -1.9321 0 P 0 ;0
L 1.91223002 -1.9321 1.91223002 -1.93206004 0 P 0 ;0
L 1.91223002 -1.93206004 1.91221998 -1.93201998 0 P 0 ;0
L 1.91221998 -1.93201998 1.91216998 -1.93163996 0 P 0 ;0
L 1.91216998 -1.93163996 1.91216004 -1.9316 0 P 0 ;0
L 1.91216004 -1.9316 1.91213996 -1.93151004 0 P 0 ;0
L 1.91213996 -1.93151004 1.91213002 -1.93146998 0 P 0 ;0
L 1.91213002 -1.93146998 1.91205 -1.93111004 0 P 0 ;0
L 1.91205 -1.93111004 1.91203996 -1.93106004 0 P 0 ;0
L 1.91203996 -1.93106004 1.91203002 -1.93101998 0 P 0 ;0
L 1.91203002 -1.93101998 1.91201004 -1.93098002 0 P 0 ;0
L 1.91201004 -1.93098002 1.912 -1.93093996 0 P 0 ;0
L 1.912 -1.93093996 1.91188002 -1.93058002 0 P 0 ;0
L 1.91188002 -1.93058002 1.91186998 -1.93053996 0 P 0 ;0
L 1.91186998 -1.93053996 1.91185 -1.9305 0 P 0 ;0
L 1.91185 -1.9305 1.91183996 -1.93046004 0 P 0 ;0
L 1.91183996 -1.93046004 1.91181998 -1.93043002 0 P 0 ;0
L 1.91181998 -1.93043002 1.91166998 -1.93008002 0 P 0 ;0
L 1.91166998 -1.93008002 1.91166004 -1.93003996 0 P 0 ;0
L 1.91166004 -1.93003996 1.9116 -1.92991998 0 P 0 ;0
L 1.9116 -1.92991998 1.91141998 -1.92958996 0 P 0 ;0
L 1.91141998 -1.92958996 1.9114 -1.92955 0 P 0 ;0
L 1.9114 -1.92955 1.91138002 -1.92951998 0 P 0 ;0
L 1.91138002 -1.92951998 1.91133002 -1.92945 0 P 0 ;0
L 1.91133002 -1.92945 1.91113002 -1.92913002 0 P 0 ;0
L 1.91113002 -1.92913002 1.91111004 -1.92908996 0 P 0 ;0
L 1.91111004 -1.92908996 1.91108996 -1.92906004 0 P 0 ;0
L 1.91108996 -1.92906004 1.91106004 -1.92901998 0 P 0 ;0
L 1.91106004 -1.92901998 1.91103002 -1.92898996 0 P 0 ;0
L 1.91103002 -1.92898996 1.9108 -1.92868996 0 P 0 ;0
L 1.9108 -1.92868996 1.91076998 -1.92866004 0 P 0 ;0
L 1.91076998 -1.92866004 1.91075 -1.92861998 0 P 0 ;0
L 1.91075 -1.92861998 1.91068996 -1.92856004 0 P 0 ;0
L 1.91068996 -1.92856004 1.91043002 -1.92828002 0 P 0 ;0
L 1.91043002 -1.92828002 1.91035 -1.9282 0 P 0 ;0
L 1.91035 -1.9282 1.91033002 -1.92816998 0 P 0 ;0
L 1.91033002 -1.92816998 1.91018996 -1.92803996 0 P 0 ;0
L 1.91018996 -1.92803996 1.91018002 -1.92803996 0 P 0 ;0
L 1.91018002 -1.92803996 1.91016004 -1.92801998 0 P 0 ;0
L 1.91016004 -1.92801998 1.91011998 -1.92798996 0 P 0 ;0
L 1.91011998 -1.92798996 1.91006004 -1.92793002 0 P 0 ;0
L 1.91006004 -1.92793002 1.90991004 -1.92781998 0 P 0 ;0
L 1.90991004 -1.92781998 1.90988002 -1.9278 0 P 0 ;0
L 1.90988002 -1.9278 1.90983996 -1.92776998 0 P 0 ;0
L 1.90983996 -1.92776998 1.90976998 -1.92771998 0 P 0 ;0
L 1.90976998 -1.92771998 1.90961004 -1.92761998 0 P 0 ;0
L 1.90961004 -1.92761998 1.90953996 -1.92756998 0 P 0 ;0
L 1.90953996 -1.92756998 1.9095 -1.92755 0 P 0 ;0
L 1.9095 -1.92755 1.90946998 -1.92753002 0 P 0 ;0
L 1.90946998 -1.92753002 1.9093 -1.92743996 0 P 0 ;0
L 1.9093 -1.92743996 1.90926004 -1.92741998 0 P 0 ;0
L 1.90926004 -1.92741998 1.90923002 -1.9274 0 P 0 ;0
L 1.90923002 -1.9274 1.90915 -1.92736998 0 P 0 ;0
L 1.90915 -1.92736998 1.90896998 -1.92728996 0 P 0 ;0
L 1.90896998 -1.92728996 1.90893996 -1.92728002 0 P 0 ;0
L 1.90893996 -1.92728002 1.9089 -1.92726004 0 P 0 ;0
L 1.9089 -1.92726004 1.90886998 -1.92725 0 P 0 ;0
L 1.90886998 -1.92725 1.90883002 -1.92723996 0 P 0 ;0
L 1.90883002 -1.92723996 1.90816004 -1.92701004 0 P 0 ;0
L 1.90816004 -1.92701004 1.90813996 -1.927 0 P 0 ;0
L 1.90813996 -1.927 1.9081 -1.92698996 0 P 0 ;0
L 1.9081 -1.92698996 1.90803996 -1.92696998 0 P 0 ;0
L 1.90803996 -1.92696998 1.90736998 -1.92678002 0 P 0 ;0
L 1.90736998 -1.92678002 1.90723996 -1.92675 0 P 0 ;0
L 1.90723996 -1.92675 1.90643002 -1.92658996 0 P 0 ;0
L 1.90643002 -1.92658996 1.90636998 -1.92656998 0 P 0 ;0
L 1.90636998 -1.92656998 1.90633996 -1.92656998 0 P 0 ;0
L 1.90633996 -1.92656998 1.90631004 -1.92656004 0 P 0 ;0
L 1.90631004 -1.92656004 1.90548996 -1.92645 0 P 0 ;0
L 1.90548996 -1.92645 1.90543996 -1.92643996 0 P 0 ;0
L 1.90543996 -1.92643996 1.9054 -1.92643002 0 P 0 ;0
L 1.9054 -1.92643002 1.90538002 -1.92643002 0 P 0 ;0
L 1.90538002 -1.92643002 1.90455 -1.92636004 0 P 0 ;0
L 1.90455 -1.92636004 1.90443002 -1.92636004 0 P 0 ;0
L 1.90443002 -1.92636004 1.9036 -1.92633002 0 P 0 ;0
L 1.9036 -1.92633002 1.8994 -1.92633002 0 P 0 ;0
L 1.8994 -1.92633002 1.89798002 -1.92691004 0 P 0 ;0
L 1.89798002 -1.92691004 1.8974 -1.92833002 0 P 0 ;0
L 1.8974 -1.92833002 1.8974 -1.93328002 0 P 0 ;0
L 1.8974 -1.93328002 1.89748002 -1.93643002 0 P 0 ;0
L 1.89748002 -1.93643002 1.89748002 -1.93656004 0 P 0 ;0
L 1.89748002 -1.93656004 1.8975 -1.93673002 0 P 0 ;0
L 1.8975 -1.93673002 1.89751004 -1.93681004 0 P 0 ;0
L 1.89751004 -1.93681004 1.89751998 -1.9369 0 P 0 ;0
L 1.89751998 -1.9369 1.89755 -1.93706004 0 P 0 ;0
L 1.89755 -1.93706004 1.89758002 -1.93718996 0 P 0 ;0
L 1.89758002 -1.93718996 1.89758996 -1.93723002 0 P 0 ;0
L 1.89758996 -1.93723002 1.89763002 -1.9374 0 P 0 ;0
L 1.89763002 -1.9374 1.89763996 -1.93743996 0 P 0 ;0
L 1.89763996 -1.93743996 1.89766004 -1.93748002 0 P 0 ;0
L 1.89766004 -1.93748002 1.89768002 -1.93756004 0 P 0 ;0
L 1.89768002 -1.93756004 1.89773996 -1.93771998 0 P 0 ;0
L 1.89773996 -1.93771998 1.89776004 -1.93776004 0 P 0 ;0
L 1.89776004 -1.93776004 1.89776998 -1.9378 0 P 0 ;0
L 1.89776998 -1.9378 1.89781004 -1.93788002 0 P 0 ;0
L 1.89781004 -1.93788002 1.89788002 -1.93803996 0 P 0 ;0
L 1.89788002 -1.93803996 1.8979 -1.93808002 0 P 0 ;0
L 1.8979 -1.93808002 1.89791998 -1.93811004 0 P 0 ;0
L 1.89791998 -1.93811004 1.89796004 -1.93818996 0 P 0 ;0
L 1.89796004 -1.93818996 1.89803996 -1.93833996 0 P 0 ;0
L 1.89803996 -1.93833996 1.89813996 -1.93848002 0 P 0 ;0
L 1.89813996 -1.93848002 1.89823002 -1.93861998 0 P 0 ;0
L 1.89823002 -1.93861998 1.89828002 -1.93868996 0 P 0 ;0
L 1.89828002 -1.93868996 1.89831004 -1.93873002 0 P 0 ;0
L 1.89831004 -1.93873002 1.89833996 -1.93876004 0 P 0 ;0
L 1.89833996 -1.93876004 1.8984 -1.93883996 0 P 0 ;0
L 1.8984 -1.93883996 1.89848996 -1.93893002 0 P 0 ;0
L 1.89848996 -1.93893002 1.89851004 -1.93896004 0 P 0 ;0
L 1.89851004 -1.93896004 1.89868002 -1.93913002 0 P 0 ;0
L 1.89868002 -1.93913002 1.89871004 -1.93915 0 P 0 ;0
L 1.89871004 -1.93915 1.89878996 -1.93921998 0 P 0 ;0
L 1.89878996 -1.93921998 1.89885 -1.93928002 0 P 0 ;0
L 1.89885 -1.93928002 1.89888002 -1.9393 0 P 0 ;0
L 1.89888002 -1.9393 1.89891998 -1.93931998 0 P 0 ;0
L 1.89891998 -1.93931998 1.89901004 -1.93938996 0 P 0 ;0
L 1.89901004 -1.93938996 1.89903996 -1.93941004 0 P 0 ;0
L 1.89903996 -1.93941004 1.89906998 -1.93943996 0 P 0 ;0
L 1.89906998 -1.93943996 1.8991 -1.93946004 0 P 0 ;0
L 1.8991 -1.93946004 1.89913996 -1.93948002 0 P 0 ;0
L 1.89913996 -1.93948002 1.89923002 -1.93953996 0 P 0 ;0
L 1.89923002 -1.93953996 1.89926998 -1.93956004 0 P 0 ;0
L 1.89926998 -1.93956004 1.8993 -1.93958002 0 P 0 ;0
L 1.8993 -1.93958002 1.89933996 -1.9396 0 P 0 ;0
L 1.89933996 -1.9396 1.89936998 -1.93961004 0 P 0 ;0
L 1.89936998 -1.93961004 1.89938002 -1.93961004 0 P 0 ;0
L 1.89938002 -1.93961004 1.89946998 -1.93966004 0 P 0 ;0
L 1.89946998 -1.93966004 1.89953996 -1.9397 0 P 0 ;0
L 1.89953996 -1.9397 1.89971998 -1.93976998 0 P 0 ;0
L 1.89971998 -1.93976998 1.89975 -1.93978996 0 P 0 ;0
L 1.89975 -1.93978996 1.89978996 -1.9398 0 P 0 ;0
L 1.89978996 -1.9398 1.89986998 -1.93983002 0 P 0 ;0
L 1.89986998 -1.93983002 1.89996998 -1.93986004 0 P 0 ;0
L 1.89996998 -1.93986004 1.90001004 -1.93986998 0 P 0 ;0
L 1.90001004 -1.93986998 1.90005 -1.93988996 0 P 0 ;0
L 1.90005 -1.93988996 1.90013002 -1.9399 0 P 0 ;0
L 1.90013002 -1.9399 1.90023002 -1.93993002 0 P 0 ;0
L 1.90023002 -1.93993002 1.90023996 -1.93993002 0 P 0 ;0
L 1.90023996 -1.93993002 1.90028002 -1.93993996 0 P 0 ;0
L 1.90028002 -1.93993996 1.90031004 -1.93995 0 P 0 ;0
L 1.90031004 -1.93995 1.90036004 -1.93995 0 P 0 ;0
L 1.90036004 -1.93995 1.9004 -1.93996004 0 P 0 ;0
L 1.9004 -1.93996004 1.9005 -1.93996998 0 P 0 ;0
L 1.9005 -1.93996998 1.90061004 -1.93998996 0 P 0 ;0
L 1.90061004 -1.93998996 1.90063996 -1.93998996 0 P 0 ;0
L 1.90063996 -1.93998996 1.90181004 -1.94006998 0 P 0 ;0
L 1.90181004 -1.94006998 1.90183996 -1.94008002 0 P 0 ;0
L 1.90183996 -1.94008002 1.90191004 -1.94008002 0 P 0 ;0
L 1.90191004 -1.94008002 1.90308002 -1.9401 0 P 0 ;0
L 1.90308002 -1.9401 1.90311004 -1.9401 0 P 0 ;0
L 1.90311004 -1.9401 1.90313996 -1.94011004 0 P 0 ;0
L 1.90841004 -1.97146004 1.91683996 -1.97146004 0 P 0 ;0
L 1.9135 -1.97046004 1.91931004 -1.97046004 0 P 0 ;0
L 1.91655 -1.96946004 1.92131004 -1.96946004 0 P 0 ;0
L 1.91891998 -1.96846004 1.92301004 -1.96846004 0 P 0 ;0
L 1.92088996 -1.96746004 1.9245 -1.96746004 0 P 0 ;0
L 1.92251004 -1.96646004 1.9258 -1.96646004 0 P 0 ;0
L 1.92391004 -1.96546004 1.92696004 -1.96546004 0 P 0 ;0
L 1.92513002 -1.96446004 1.92803002 -1.96446004 0 P 0 ;0
L 1.9262 -1.96346004 1.92898996 -1.96346004 0 P 0 ;0
L 1.92713996 -1.96246004 1.92986004 -1.96246004 0 P 0 ;0
L 1.928 -1.96146004 1.93068996 -1.96146004 0 P 0 ;0
L 1.92878002 -1.96046004 1.93143002 -1.96046004 0 P 0 ;0
L 1.92951004 -1.95946004 1.93216004 -1.95946004 0 P 0 ;0
L 1.93016998 -1.95846004 1.93278996 -1.95846004 0 P 0 ;0
L 1.93078002 -1.95746004 1.93341004 -1.95746004 0 P 0 ;0
L 1.93133002 -1.95646004 1.93396004 -1.95646004 0 P 0 ;0
L 1.93185 -1.95546004 1.93448996 -1.95546004 0 P 0 ;0
L 1.93231004 -1.95446004 1.93495 -1.95446004 0 P 0 ;0
L 1.93275 -1.95346004 1.93541004 -1.95346004 0 P 0 ;0
L 1.93311998 -1.95246004 1.93586004 -1.95246004 0 P 0 ;0
L 1.93348002 -1.95146004 1.93628996 -1.95146004 0 P 0 ;0
L 1.93376998 -1.95046004 1.93666004 -1.95046004 0 P 0 ;0
L 1.93405 -1.94946004 1.93693002 -1.94946004 0 P 0 ;0
L 1.93428002 -1.94846004 1.93715 -1.94846004 0 P 0 ;0
L 1.93446998 -1.94746004 1.93733002 -1.94746004 0 P 0 ;0
L 1.93466004 -1.94646004 1.93743002 -1.94646004 0 P 0 ;0
L 1.93478996 -1.94546004 1.93748996 -1.94546004 0 P 0 ;0
L 1.9349 -1.94446998 1.93751998 -1.94446998 0 P 0 ;0
L 1.93496998 -1.94346004 1.93755 -1.94346004 0 P 0 ;0
L 1.93501998 -1.94246004 1.93758002 -1.94246004 0 P 0 ;0
L 1.93505 -1.94146998 1.93758996 -1.94146998 0 P 0 ;0
L 1.93503002 -1.94046004 1.93755 -1.94046004 0 P 0 ;0
L 1.935 -1.93946004 1.93751998 -1.93946004 0 P 0 ;0
L 1.93491998 -1.93846004 1.93748002 -1.93846004 0 P 0 ;0
L 1.93481004 -1.93746004 1.93738996 -1.93746004 0 P 0 ;0
L 1.93468996 -1.93646004 1.93726998 -1.93646004 0 P 0 ;0
L 1.93451004 -1.93546004 1.93716004 -1.93546004 0 P 0 ;0
L 1.93433002 -1.93446004 1.93703996 -1.93446004 0 P 0 ;0
L 1.93408996 -1.93346004 1.93685 -1.93346004 0 P 0 ;0
L 1.93383002 -1.93246004 1.93666004 -1.93246004 0 P 0 ;0
L 1.93353002 -1.93146004 1.93638996 -1.93146004 0 P 0 ;0
L 1.9332 -1.93046004 1.93611998 -1.93046004 0 P 0 ;0
L 1.93283996 -1.92946004 1.93576998 -1.92946004 0 P 0 ;0
L 1.93241004 -1.92846004 1.93541004 -1.92846004 0 P 0 ;0
L 1.93198996 -1.92746004 1.93498002 -1.92746004 0 P 0 ;0
L 1.93146998 -1.92646004 1.93451004 -1.92646004 0 P 0 ;0
L 1.93096004 -1.92546004 1.93398002 -1.92546004 0 P 0 ;0
L 1.93035 -1.92446998 1.93338002 -1.92446998 0 P 0 ;0
L 1.92973002 -1.92346004 1.93275 -1.92346004 0 P 0 ;0
L 1.92903002 -1.92246004 1.93201004 -1.92246004 0 P 0 ;0
L 1.92831004 -1.92146004 1.93125 -1.92146004 0 P 0 ;0
L 1.92746998 -1.92046004 1.93041004 -1.92046004 0 P 0 ;0
L 1.92661004 -1.91946004 1.92948996 -1.91946004 0 P 0 ;0
L 1.92558996 -1.91846004 1.92851004 -1.91846004 0 P 0 ;0
L 1.9245 -1.91746004 1.92741998 -1.91746004 0 P 0 ;0
L 1.92328996 -1.91646004 1.92621998 -1.91646004 0 P 0 ;0
L 1.92188002 -1.91546004 1.92491998 -1.91546004 0 P 0 ;0
L 1.92026004 -1.91446004 1.92358996 -1.91446004 0 P 0 ;0
L 1.91835 -1.91346004 1.92208002 -1.91346004 0 P 0 ;0
L 1.82446998 -2.08323996 1.87608002 -2.08323996 0 P 0 ;0
L 1.82403002 -2.08223996 1.87601004 -2.08223996 0 P 0 ;0
L 1.8234 -2.08123996 1.87591004 -2.08123996 0 P 0 ;0
L 1.82256004 -2.08023996 1.87578002 -2.08023996 0 P 0 ;0
L 1.82166004 -2.07923996 1.87558996 -2.07923996 0 P 0 ;0
L 1.82061998 -2.07823996 1.87533002 -2.07823996 0 P 0 ;0
L 1.81946004 -2.07723996 1.87498996 -2.07723996 0 P 0 ;0
L 1.81818002 -2.07623996 1.8746 -2.07623996 0 P 0 ;0
L 1.8168 -2.07523996 1.87416998 -2.07523996 0 P 0 ;0
L 1.81541998 -2.07423996 1.87371004 -2.07423996 0 P 0 ;0
L 1.81403002 -2.07323996 1.87316998 -2.07323996 0 P 0 ;0
L 1.81265 -2.07223996 1.87261004 -2.07223996 0 P 0 ;0
L 1.81126998 -2.07123996 1.87196004 -2.07123996 0 P 0 ;0
L 1.80986004 -2.07023996 1.87128002 -2.07023996 0 P 0 ;0
L 1.80843996 -2.06923996 1.87051998 -2.06923996 0 P 0 ;0
L 1.80703002 -2.06823996 1.8697 -2.06823996 0 P 0 ;0
L 1.80561004 -2.06723996 1.86883002 -2.06723996 0 P 0 ;0
L 1.8042 -2.06623996 1.86796004 -2.06623996 0 P 0 ;0
L 1.80278002 -2.06523996 1.86705 -2.06523996 0 P 0 ;0
L 1.80136004 -2.06423996 1.86608002 -2.06423996 0 P 0 ;0
L 1.79995 -2.06323996 1.8651 -2.06323996 0 P 0 ;0
L 1.79865 -2.06223996 1.86411004 -2.06223996 0 P 0 ;0
L 1.79735 -2.06123996 1.86301998 -2.06123996 0 P 0 ;0
L 1.79605 -2.06023996 1.86193002 -2.06023996 0 P 0 ;0
L 1.79475 -2.05923996 1.86083996 -2.05923996 0 P 0 ;0
L 1.79345 -2.05823996 1.85966998 -2.05823996 0 P 0 ;0
L 1.79215 -2.05723996 1.85846004 -2.05723996 0 P 0 ;0
L 1.79088002 -2.05623996 1.85726004 -2.05623996 0 P 0 ;0
L 1.78971998 -2.05523996 1.85598996 -2.05523996 0 P 0 ;0
L 1.78856004 -2.05423996 1.85461998 -2.05423996 0 P 0 ;0
L 1.7874 -2.05323996 1.85326004 -2.05323996 0 P 0 ;0
L 1.78623002 -2.05223996 1.8519 -2.05223996 0 P 0 ;0
L 1.78506998 -2.05123996 1.85053996 -2.05123996 0 P 0 ;0
L 1.78398002 -2.05023996 1.84918002 -2.05023996 0 P 0 ;0
L 1.783 -2.04923996 1.84781004 -2.04923996 0 P 0 ;0
L 1.87086004 -2.03023996 1.87535 -2.03023996 0 P 0 ;0
L 1.91633002 -1.91473002 1.9183 -1.91565 0 P 0 ;0
L 1.9183 -1.91565 1.92018996 -1.91673002 0 P 0 ;0
L 1.92018996 -1.91673002 1.92196998 -1.91796998 0 P 0 ;0
L 1.92196998 -1.91796998 1.92365 -1.91936004 0 P 0 ;0
L 1.92365 -1.91936004 1.9252 -1.92088002 0 P 0 ;0
L 1.9252 -1.92088002 1.92661004 -1.92253996 0 P 0 ;0
L 1.92661004 -1.92253996 1.92795 -1.92436998 0 P 0 ;0
L 1.92795 -1.92436998 1.92913996 -1.9263 0 P 0 ;0
L 1.92913996 -1.9263 1.93018002 -1.92831998 0 P 0 ;0
L 1.93018002 -1.92831998 1.93106998 -1.93041004 0 P 0 ;0
L 1.93106998 -1.93041004 1.93178996 -1.93256004 0 P 0 ;0
L 1.93178996 -1.93256004 1.93236004 -1.93476004 0 P 0 ;0
L 1.93236004 -1.93476004 1.93276004 -1.93703996 0 P 0 ;0
L 1.93276004 -1.93703996 1.93298996 -1.93933996 0 P 0 ;0
L 1.93298996 -1.93933996 1.93306004 -1.94165 0 P 0 ;0
L 1.93306004 -1.94165 1.93295 -1.94396998 0 P 0 ;0
L 1.93295 -1.94396998 1.93268002 -1.94626004 0 P 0 ;0
L 1.93268002 -1.94626004 1.93223002 -1.94853996 0 P 0 ;0
L 1.93223002 -1.94853996 1.93161998 -1.95071998 0 P 0 ;0
L 1.93161998 -1.95071998 1.93085 -1.95285 0 P 0 ;0
L 1.93085 -1.95285 1.92991004 -1.95491004 0 P 0 ;0
L 1.92991004 -1.95491004 1.92881004 -1.95688996 0 P 0 ;0
L 1.92881004 -1.95688996 1.92756004 -1.95878002 0 P 0 ;0
L 1.92756004 -1.95878002 1.92616004 -1.96056998 0 P 0 ;0
L 1.92616004 -1.96056998 1.92493996 -1.9619 0 P 0 ;0
L 1.92493996 -1.9619 1.92361998 -1.96313996 0 P 0 ;0
L 1.92361998 -1.96313996 1.9222 -1.96426004 0 P 0 ;0
L 1.9222 -1.96426004 1.9207 -1.96526998 0 P 0 ;0
L 1.9207 -1.96526998 1.91911004 -1.96616998 0 P 0 ;0
L 1.91911004 -1.96616998 1.91686998 -1.96721004 0 P 0 ;0
L 1.91686998 -1.96721004 1.91456004 -1.96806998 0 P 0 ;0
L 1.91456004 -1.96806998 1.91218996 -1.96876004 0 P 0 ;0
L 1.91218996 -1.96876004 1.90975 -1.96926998 0 P 0 ;0
L 1.90975 -1.96926998 1.90725 -1.9696 0 P 0 ;0
L 1.90725 -1.9696 1.90473002 -1.96973996 0 P 0 ;0
L 1.90473002 -1.96973996 1.9022 -1.96968996 0 P 0 ;0
L 1.9022 -1.96968996 1.89966998 -1.96945 0 P 0 ;0
L 1.89966998 -1.96945 1.89778002 -1.96913002 0 P 0 ;0
L 1.89778002 -1.96913002 1.89591998 -1.96868996 0 P 0 ;0
L 1.89591998 -1.96868996 1.8941 -1.96811004 0 P 0 ;0
L 1.8941 -1.96811004 1.89231004 -1.96741004 0 P 0 ;0
L 1.89231004 -1.96741004 1.89058002 -1.96658002 0 P 0 ;0
L 1.89058002 -1.96658002 1.88875 -1.96553996 0 P 0 ;0
L 1.88875 -1.96553996 1.88698996 -1.96435 0 P 0 ;0
L 1.88698996 -1.96435 1.88533996 -1.96303002 0 P 0 ;0
L 1.88533996 -1.96303002 1.88378996 -1.9616 0 P 0 ;0
L 1.88378996 -1.9616 1.88235 -1.96003996 0 P 0 ;0
L 1.88235 -1.96003996 1.88103002 -1.95838996 0 P 0 ;0
L 1.88103002 -1.95838996 1.87983996 -1.95663002 0 P 0 ;0
L 1.87983996 -1.95663002 1.87861998 -1.95446998 0 P 0 ;0
L 1.87861998 -1.95446998 1.87758002 -1.9522 0 P 0 ;0
L 1.87758002 -1.9522 1.87673996 -1.94986004 0 P 0 ;0
L 1.87673996 -1.94986004 1.8761 -1.94745 0 P 0 ;0
L 1.8761 -1.94745 1.87568002 -1.945 0 P 0 ;0
L 1.87568002 -1.945 1.87546004 -1.94248996 0 P 0 ;0
L 1.87546004 -1.94248996 1.87546004 -1.93998996 0 P 0 ;0
L 1.87546004 -1.93998996 1.87566998 -1.93748996 0 P 0 ;0
L 1.87566998 -1.93748996 1.87608996 -1.93501998 0 P 0 ;0
L 1.87608996 -1.93501998 1.87671998 -1.9326 0 P 0 ;0
L 1.87671998 -1.9326 1.87755 -1.93023002 0 P 0 ;0
L 1.87755 -1.93023002 1.8786 -1.92793002 0 P 0 ;0
L 1.8786 -1.92793002 1.87981998 -1.92575 0 P 0 ;0
L 1.87981998 -1.92575 1.88123002 -1.92368002 0 P 0 ;0
L 1.88123002 -1.92368002 1.88281004 -1.92175 0 P 0 ;0
L 1.88281004 -1.92175 1.88455 -1.91996004 0 P 0 ;0
L 1.88455 -1.91996004 1.88643002 -1.91831998 0 P 0 ;0
L 1.88643002 -1.91831998 1.88845 -1.91686004 0 P 0 ;0
L 1.88845 -1.91686004 1.88986998 -1.91598996 0 P 0 ;0
L 1.88986998 -1.91598996 1.89135 -1.91523002 0 P 0 ;0
L 1.89135 -1.91523002 1.89288002 -1.91458996 0 P 0 ;0
L 1.89288002 -1.91458996 1.89446998 -1.91406004 0 P 0 ;0
L 1.89446998 -1.91406004 1.89688996 -1.91343996 0 P 0 ;0
L 1.89688996 -1.91343996 1.89935 -1.91298996 0 P 0 ;0
L 1.89935 -1.91298996 1.90183996 -1.91271004 0 P 0 ;0
L 1.90183996 -1.91271004 1.9044 -1.91261004 0 P 0 ;0
L 1.9044 -1.91261004 1.90695 -1.91268002 0 P 0 ;0
L 1.90695 -1.91268002 1.90948996 -1.91291998 0 P 0 ;0
L 1.90948996 -1.91291998 1.91181998 -1.91331998 0 P 0 ;0
L 1.91181998 -1.91331998 1.91408996 -1.91393002 0 P 0 ;0
L 1.91408996 -1.91393002 1.91633002 -1.91473002 0 P 0 ;0
L 1.89498002 -1.90801998 1.8922 -1.90893002 0 P 0 ;0
L 1.8922 -1.90893002 1.88948002 -1.91003002 0 P 0 ;0
L 1.88948002 -1.91003002 1.88686004 -1.91133002 0 P 0 ;0
L 1.88686004 -1.91133002 1.88431004 -1.91283996 0 P 0 ;0
L 1.88431004 -1.91283996 1.88201004 -1.91446004 0 P 0 ;0
L 1.88201004 -1.91446004 1.87985 -1.91626998 0 P 0 ;0
L 1.87985 -1.91626998 1.87785 -1.91826004 0 P 0 ;0
L 1.87785 -1.91826004 1.87601998 -1.92041004 0 P 0 ;0
L 1.87601998 -1.92041004 1.87441004 -1.92266998 0 P 0 ;0
L 1.87441004 -1.92266998 1.87298996 -1.92505 0 P 0 ;0
L 1.87298996 -1.92505 1.87178002 -1.92756004 0 P 0 ;0
L 1.87178002 -1.92756004 1.87078996 -1.93015 0 P 0 ;0
L 1.87078996 -1.93015 1.87 -1.93286998 0 P 0 ;0
L 1.87 -1.93286998 1.86943996 -1.93563996 0 P 0 ;0
L 1.86943996 -1.93563996 1.86908996 -1.93845 0 P 0 ;0
L 1.86908996 -1.93845 1.86898002 -1.94128996 0 P 0 ;0
L 1.86898002 -1.94128996 1.86911998 -1.94485 0 P 0 ;0
L 1.86911998 -1.94485 1.86953996 -1.94841004 0 P 0 ;0
L 1.86953996 -1.94841004 1.86996004 -1.95048996 0 P 0 ;0
L 1.86996004 -1.95048996 1.87053002 -1.95251998 0 P 0 ;0
L 1.87053002 -1.95251998 1.87125 -1.95451998 0 P 0 ;0
L 1.87125 -1.95451998 1.87211004 -1.95643002 0 P 0 ;0
L 1.87211004 -1.95643002 1.8731 -1.95826004 0 P 0 ;0
L 1.8731 -1.95826004 1.87423996 -1.96001998 0 P 0 ;0
L 1.87423996 -1.96001998 1.87636998 -1.96278996 0 P 0 ;0
L 1.87636998 -1.96278996 1.87871998 -1.96536998 0 P 0 ;0
L 1.87871998 -1.96536998 1.88145 -1.96788002 0 P 0 ;0
L 1.88145 -1.96788002 1.88436998 -1.97015 0 P 0 ;0
L 1.88436998 -1.97015 1.88621004 -1.97135 0 P 0 ;0
L 1.88621004 -1.97135 1.88813002 -1.97238002 0 P 0 ;0
L 1.88813002 -1.97238002 1.89013002 -1.97326004 0 P 0 ;0
L 1.89013002 -1.97326004 1.89228002 -1.97398996 0 P 0 ;0
L 1.89228002 -1.97398996 1.89446998 -1.97455 0 P 0 ;0
L 1.89446998 -1.97455 1.89671004 -1.97493996 0 P 0 ;0
L 1.89671004 -1.97493996 1.90076998 -1.97533996 0 P 0 ;0
L 1.90076998 -1.97533996 1.90485 -1.97546998 0 P 0 ;0
L 1.90485 -1.97546998 1.90821004 -1.97531998 0 P 0 ;0
L 1.90821004 -1.97531998 1.91153996 -1.97488996 0 P 0 ;0
L 1.91153996 -1.97488996 1.91481998 -1.97418996 0 P 0 ;0
L 1.91481998 -1.97418996 1.9171 -1.9735 0 P 0 ;0
L 1.9171 -1.9735 1.91933002 -1.97266004 0 P 0 ;0
L 1.91933002 -1.97266004 1.92148002 -1.97166004 0 P 0 ;0
L 1.92148002 -1.97166004 1.92356998 -1.97048996 0 P 0 ;0
L 1.92356998 -1.97048996 1.92553996 -1.96918996 0 P 0 ;0
L 1.92553996 -1.96918996 1.92741004 -1.96773996 0 P 0 ;0
L 1.92741004 -1.96773996 1.92916004 -1.96616998 0 P 0 ;0
L 1.92916004 -1.96616998 1.93081004 -1.96446004 0 P 0 ;0
L 1.93081004 -1.96446004 1.93236998 -1.96256998 0 P 0 ;0
L 1.93236998 -1.96256998 1.93381004 -1.96058996 0 P 0 ;0
L 1.93381004 -1.96058996 1.93511998 -1.95851004 0 P 0 ;0
L 1.93511998 -1.95851004 1.93628996 -1.95633996 0 P 0 ;0
L 1.93628996 -1.95633996 1.93803996 -1.95251998 0 P 0 ;0
L 1.93803996 -1.95251998 1.93858002 -1.95101998 0 P 0 ;0
L 1.93858002 -1.95101998 1.93898996 -1.94948002 0 P 0 ;0
L 1.93898996 -1.94948002 1.93928996 -1.94786998 0 P 0 ;0
L 1.93928996 -1.94786998 1.93946004 -1.94625 0 P 0 ;0
L 1.93946004 -1.94625 1.9396 -1.94178002 0 P 0 ;0
L 1.9396 -1.94178002 1.93946004 -1.93803996 0 P 0 ;0
L 1.93946004 -1.93803996 1.93905 -1.9343 0 P 0 ;0
L 1.93905 -1.9343 1.93863996 -1.93213996 0 P 0 ;0
L 1.93863996 -1.93213996 1.93808002 -1.93001998 0 P 0 ;0
L 1.93808002 -1.93001998 1.93736004 -1.92795 0 P 0 ;0
L 1.93736004 -1.92795 1.93653002 -1.92601004 0 P 0 ;0
L 1.93653002 -1.92601004 1.93555 -1.92415 0 P 0 ;0
L 1.93555 -1.92415 1.93441998 -1.92236004 0 P 0 ;0
L 1.93441998 -1.92236004 1.9331 -1.92056004 0 P 0 ;0
L 1.9331 -1.92056004 1.93166998 -1.91885 0 P 0 ;0
L 1.93166998 -1.91885 1.93011998 -1.91723002 0 P 0 ;0
L 1.93011998 -1.91723002 1.92896004 -1.91615 0 P 0 ;0
L 1.92896004 -1.91615 1.92775 -1.91511004 0 P 0 ;0
L 1.92775 -1.91511004 1.92493002 -1.91295 0 P 0 ;0
L 1.92493002 -1.91295 1.9221 -1.91108002 0 P 0 ;0
L 1.9221 -1.91108002 1.92095 -1.91043002 0 P 0 ;0
L 1.92095 -1.91043002 1.91975 -1.90985 0 P 0 ;0
L 1.91975 -1.90985 1.91796004 -1.90913996 0 P 0 ;0
L 1.91796004 -1.90913996 1.91613002 -1.90856004 0 P 0 ;0
L 1.91613002 -1.90856004 1.91423996 -1.9081 0 P 0 ;0
L 1.91423996 -1.9081 1.91086004 -1.90751998 0 P 0 ;0
L 1.91086004 -1.90751998 1.90743002 -1.90716004 0 P 0 ;0
L 1.90743002 -1.90716004 1.90401004 -1.90701004 0 P 0 ;0
L 1.90401004 -1.90701004 1.90058002 -1.90708002 0 P 0 ;0
L 1.90058002 -1.90708002 1.8987 -1.90726004 0 P 0 ;0
L 1.8987 -1.90726004 1.89683002 -1.90756998 0 P 0 ;0
L 1.89683002 -1.90756998 1.89498002 -1.90801998 0 P 0 ;0
L 1.86643002 -2.02923996 1.87525 -2.02923996 0 P 0 ;0
L 1.86176998 -2.02823996 1.87515 -2.02823996 0 P 0 ;0
L 1.85588996 -2.02723996 1.87505 -2.02723996 0 P 0 ;0
L 1.78365 -2.00523996 1.87281004 -2.00523996 0 P 0 ;0
L 1.78451004 -2.00423996 1.87271004 -2.00423996 0 P 0 ;0
L 1.78546998 -2.00323996 1.87261004 -2.00323996 0 P 0 ;0
L 1.78655 -2.00223996 1.8725 -2.00223996 0 P 0 ;0
L 1.78776004 -2.00123996 1.8724 -2.00123996 0 P 0 ;0
L 1.78915 -2.00023996 1.8723 -2.00023996 0 P 0 ;0
L 1.79078996 -1.99923996 1.8722 -1.99923996 0 P 0 ;0
L 1.79263996 -1.99823996 1.87208996 -1.99823996 0 P 0 ;0
L 1.79458996 -1.99723996 1.87198996 -1.99723996 0 P 0 ;0
L 1.79686998 -1.99623996 1.87188002 -1.99623996 0 P 0 ;0
L 1.79946004 -1.99523996 1.87178002 -1.99523996 0 P 0 ;0
L 1.80231004 -1.99423996 1.86961998 -1.99423996 0 P 0 ;0
L 1.80596004 -1.99323996 1.86218002 -1.99323996 0 P 0 ;0
L 1.81051004 -1.99223996 1.85398002 -1.99223996 0 P 0 ;0
L 1.81676004 -1.99123996 1.84395 -1.99123996 0 P 0 ;0
L 1.87786998 -1.96146004 1.88093996 -1.96146004 0 P 0 ;0
L 1.8771 -1.96046004 1.88013002 -1.96046004 0 P 0 ;0
L 1.87633996 -1.95946004 1.87933996 -1.95946004 0 P 0 ;0
L 1.87561998 -1.95846004 1.87866998 -1.95846004 0 P 0 ;0
L 1.87496998 -1.95746004 1.87801998 -1.95746004 0 P 0 ;0
L 1.8744 -1.95646004 1.87745 -1.95646004 0 P 0 ;0
L 1.87386998 -1.95546004 1.87688002 -1.95546004 0 P 0 ;0
L 1.87341998 -1.95446004 1.87641998 -1.95446004 0 P 0 ;0
L 1.87298996 -1.95346004 1.87596004 -1.95346004 0 P 0 ;0
L 1.87263002 -1.95246004 1.87555 -1.95246004 0 P 0 ;0
L 1.87231004 -1.95146004 1.87518996 -1.95146004 0 P 0 ;0
L 1.87203002 -1.95046004 1.87483002 -1.95046004 0 P 0 ;0
L 1.87178996 -1.94946004 1.87456998 -1.94946004 0 P 0 ;0
L 1.87158996 -1.94846004 1.87431004 -1.94846004 0 P 0 ;0
L 1.87143996 -1.94746004 1.87408002 -1.94746004 0 P 0 ;0
L 1.87133002 -1.94646004 1.8739 -1.94646004 0 P 0 ;0
L 1.87121004 -1.94546004 1.87373002 -1.94546004 0 P 0 ;0
L 1.8711 -1.94446998 1.87361998 -1.94446998 0 P 0 ;0
L 1.87106998 -1.94346004 1.87353996 -1.94346004 0 P 0 ;0
L 1.87103002 -1.94246004 1.87346004 -1.94246004 0 P 0 ;0
L 1.87098996 -1.94146998 1.87346004 -1.94146998 0 P 0 ;0
L 1.87101004 -1.94046004 1.87346004 -1.94046004 0 P 0 ;0
L 1.87106004 -1.93946004 1.87348996 -1.93946004 0 P 0 ;0
L 1.87111004 -1.93846004 1.87358002 -1.93846004 0 P 0 ;0
L 1.87123002 -1.93746004 1.87366004 -1.93746004 0 P 0 ;0
L 1.87135 -1.93646004 1.87381998 -1.93646004 0 P 0 ;0
L 1.87151004 -1.93546004 1.87398996 -1.93546004 0 P 0 ;0
L 1.87171998 -1.93446004 1.87416998 -1.93446004 0 P 0 ;0
L 1.87191998 -1.93346004 1.87443002 -1.93346004 0 P 0 ;0
L 1.8722 -1.93246004 1.87468996 -1.93246004 0 P 0 ;0
L 1.87248996 -1.93146004 1.875 -1.93146004 0 P 0 ;0
L 1.87281004 -1.93046004 1.87535 -1.93046004 0 P 0 ;0
L 1.87318996 -1.92946004 1.87571004 -1.92946004 0 P 0 ;0
L 1.87356998 -1.92846004 1.87616004 -1.92846004 0 P 0 ;0
L 1.87405 -1.92746004 1.87661004 -1.92746004 0 P 0 ;0
L 1.87453002 -1.92646004 1.87711998 -1.92646004 0 P 0 ;0
L 1.87506998 -1.92546004 1.87768996 -1.92546004 0 P 0 ;0
L 1.87566004 -1.92446998 1.87826998 -1.92446998 0 P 0 ;0
L 1.87628996 -1.92346004 1.87896004 -1.92346004 0 P 0 ;0
L 1.87701004 -1.92246004 1.87963996 -1.92246004 0 P 0 ;0
L 1.87775 -1.92146004 1.88046004 -1.92146004 0 P 0 ;0
L 1.90483996 -1.97346004 1.9009 -1.97333996 0 P 0 ;0
L 1.9009 -1.97333996 1.89698002 -1.97295 0 P 0 ;0
L 1.89698002 -1.97295 1.89488996 -1.97258996 0 P 0 ;0
L 1.89488996 -1.97258996 1.89285 -1.97206998 0 P 0 ;0
L 1.89285 -1.97206998 1.89086004 -1.97138996 0 P 0 ;0
L 1.89086004 -1.97138996 1.889 -1.97058002 0 P 0 ;0
L 1.889 -1.97058002 1.88723002 -1.96961998 0 P 0 ;0
L 1.88723002 -1.96961998 1.88553002 -1.96851998 0 P 0 ;0
L 1.88553002 -1.96851998 1.88273996 -1.96636004 0 P 0 ;0
L 1.88273996 -1.96636004 1.88013996 -1.96396004 0 P 0 ;0
L 1.88013996 -1.96396004 1.8779 -1.9615 0 P 0 ;0
L 1.8779 -1.9615 1.87588002 -1.95886998 0 P 0 ;0
L 1.87588002 -1.95886998 1.87483002 -1.95723996 0 P 0 ;0
L 1.87483002 -1.95723996 1.8739 -1.95553996 0 P 0 ;0
L 1.8739 -1.95553996 1.87311004 -1.95376998 0 P 0 ;0
L 1.87311004 -1.95376998 1.87243002 -1.95191004 0 P 0 ;0
L 1.87243002 -1.95191004 1.8719 -1.95001998 0 P 0 ;0
L 1.8719 -1.95001998 1.87151998 -1.9481 0 P 0 ;0
L 1.87151998 -1.9481 1.87111004 -1.94468996 0 P 0 ;0
L 1.87111004 -1.94468996 1.87098002 -1.94128996 0 P 0 ;0
L 1.87098002 -1.94128996 1.87108996 -1.93861004 0 P 0 ;0
L 1.87108996 -1.93861004 1.87141004 -1.93596998 0 P 0 ;0
L 1.87141004 -1.93596998 1.87195 -1.93335 0 P 0 ;0
L 1.87195 -1.93335 1.87268996 -1.93078996 0 P 0 ;0
L 1.87268996 -1.93078996 1.87361998 -1.92835 0 P 0 ;0
L 1.87361998 -1.92835 1.87475 -1.926 0 P 0 ;0
L 1.87475 -1.926 1.87608996 -1.92376004 0 P 0 ;0
L 1.87608996 -1.92376004 1.8776 -1.92163996 0 P 0 ;0
L 1.8776 -1.92163996 1.87931998 -1.91961998 0 P 0 ;0
L 1.87931998 -1.91961998 1.8812 -1.91775 0 P 0 ;0
L 1.8812 -1.91775 1.88323002 -1.91605 0 P 0 ;0
L 1.88323002 -1.91605 1.8854 -1.91451998 0 P 0 ;0
L 1.8854 -1.91451998 1.88781004 -1.91308996 0 P 0 ;0
L 1.88781004 -1.91308996 1.89031004 -1.91186004 0 P 0 ;0
L 1.89031004 -1.91186004 1.89288002 -1.9108 0 P 0 ;0
L 1.89288002 -1.9108 1.89553002 -1.90995 0 P 0 ;0
L 1.89553002 -1.90995 1.89723002 -1.90953002 0 P 0 ;0
L 1.89723002 -1.90953002 1.89896004 -1.90923996 0 P 0 ;0
L 1.89896004 -1.90923996 1.90068996 -1.90908002 0 P 0 ;0
L 1.90068996 -1.90908002 1.90398996 -1.90901004 0 P 0 ;0
L 1.90398996 -1.90901004 1.90728002 -1.90915 0 P 0 ;0
L 1.90728002 -1.90915 1.91058996 -1.90951004 0 P 0 ;0
L 1.91058996 -1.90951004 1.91383996 -1.91006004 0 P 0 ;0
L 1.91383996 -1.91006004 1.91558996 -1.91048996 0 P 0 ;0
L 1.91558996 -1.91048996 1.91728996 -1.91101998 0 P 0 ;0
L 1.91728996 -1.91101998 1.91895 -1.91168002 0 P 0 ;0
L 1.91895 -1.91168002 1.92001998 -1.9122 0 P 0 ;0
L 1.92001998 -1.9122 1.92105 -1.91278996 0 P 0 ;0
L 1.92105 -1.91278996 1.92376998 -1.91458002 0 P 0 ;0
L 1.92376998 -1.91458002 1.92648996 -1.91666998 0 P 0 ;0
L 1.92648996 -1.91666998 1.92763002 -1.91763996 0 P 0 ;0
L 1.92763002 -1.91763996 1.92871004 -1.91865 0 P 0 ;0
L 1.92871004 -1.91865 1.93018002 -1.92018996 0 P 0 ;0
L 1.93018002 -1.92018996 1.93153002 -1.9218 0 P 0 ;0
L 1.93153002 -1.9218 1.93276998 -1.92348996 0 P 0 ;0
L 1.93276998 -1.92348996 1.93381004 -1.92515 0 P 0 ;0
L 1.93381004 -1.92515 1.93471998 -1.92686998 0 P 0 ;0
L 1.93471998 -1.92686998 1.9355 -1.92866998 0 P 0 ;0
L 1.9355 -1.92866998 1.93616998 -1.93061004 0 P 0 ;0
L 1.93616998 -1.93061004 1.93668996 -1.93258002 0 P 0 ;0
L 1.93668996 -1.93258002 1.93706998 -1.93458996 0 P 0 ;0
L 1.93706998 -1.93458996 1.93746998 -1.93818996 0 P 0 ;0
L 1.93746998 -1.93818996 1.9376 -1.94178996 0 P 0 ;0
L 1.9376 -1.94178996 1.93746004 -1.94611004 0 P 0 ;0
L 1.93746004 -1.94611004 1.93731004 -1.94758996 0 P 0 ;0
L 1.93731004 -1.94758996 1.93705 -1.94903996 0 P 0 ;0
L 1.93705 -1.94903996 1.93666998 -1.95041998 0 P 0 ;0
L 1.93666998 -1.95041998 1.93618002 -1.95176004 0 P 0 ;0
L 1.93618002 -1.95176004 1.9345 -1.95545 0 P 0 ;0
L 1.9345 -1.95545 1.93338996 -1.9575 0 P 0 ;0
L 1.93338996 -1.9575 1.93216004 -1.95946998 0 P 0 ;0
L 1.93216004 -1.95946998 1.93078996 -1.96133996 0 P 0 ;0
L 1.93078996 -1.96133996 1.92931004 -1.96311998 0 P 0 ;0
L 1.92931004 -1.96311998 1.92776998 -1.96473002 0 P 0 ;0
L 1.92776998 -1.96473002 1.92613002 -1.96621004 0 P 0 ;0
L 1.92613002 -1.96621004 1.92438002 -1.96756004 0 P 0 ;0
L 1.92438002 -1.96756004 1.92253002 -1.96878002 0 P 0 ;0
L 1.92253002 -1.96878002 1.92056998 -1.96986998 0 P 0 ;0
L 1.92056998 -1.96986998 1.91855 -1.97081998 0 P 0 ;0
L 1.91855 -1.97081998 1.91646004 -1.97161004 0 P 0 ;0
L 1.91646004 -1.97161004 1.91433002 -1.97223996 0 P 0 ;0
L 1.91433002 -1.97223996 1.9112 -1.97291004 0 P 0 ;0
L 1.9112 -1.97291004 1.90803996 -1.97331998 0 P 0 ;0
L 1.90803996 -1.97331998 1.90483996 -1.97346004 0 P 0 ;0
L 1.90476004 -1.97173996 1.9048 -1.97173996 0 P 0 ;0
L 1.9048 -1.97173996 1.90483996 -1.97173002 0 P 0 ;0
L 1.90483996 -1.97173002 1.90736004 -1.9716 0 P 0 ;0
L 1.90736004 -1.9716 1.9074 -1.97158996 0 P 0 ;0
L 1.9074 -1.97158996 1.90746998 -1.97158996 0 P 0 ;0
L 1.90746998 -1.97158996 1.90751004 -1.97158002 0 P 0 ;0
L 1.90751004 -1.97158002 1.91001004 -1.97126004 0 P 0 ;0
L 1.91001004 -1.97126004 1.91005 -1.97125 0 P 0 ;0
L 1.91005 -1.97125 1.91008002 -1.97123996 0 P 0 ;0
L 1.91008002 -1.97123996 1.91011998 -1.97123996 0 P 0 ;0
L 1.91011998 -1.97123996 1.91016004 -1.97123002 0 P 0 ;0
L 1.91016004 -1.97123002 1.9126 -1.97071998 0 P 0 ;0
L 1.9126 -1.97071998 1.9126 -1.97071004 0 P 0 ;0
L 1.9126 -1.97071004 1.91266998 -1.97071004 0 P 0 ;0
L 1.91266998 -1.97071004 1.91271004 -1.97068996 0 P 0 ;0
L 1.91271004 -1.97068996 1.91275 -1.97068002 0 P 0 ;0
L 1.91275 -1.97068002 1.91511998 -1.96998996 0 P 0 ;0
L 1.91511998 -1.96998996 1.91515 -1.96998996 0 P 0 ;0
L 1.91515 -1.96998996 1.91518996 -1.96996998 0 P 0 ;0
L 1.91518996 -1.96996998 1.91523002 -1.96996004 0 P 0 ;0
L 1.91523002 -1.96996004 1.91526004 -1.96995 0 P 0 ;0
L 1.91526004 -1.96995 1.91756998 -1.96908002 0 P 0 ;0
L 1.91756998 -1.96908002 1.91761004 -1.96906998 0 P 0 ;0
L 1.91761004 -1.96906998 1.91768002 -1.96903996 0 P 0 ;0
L 1.91768002 -1.96903996 1.91771004 -1.96901998 0 P 0 ;0
L 1.91771004 -1.96901998 1.91995 -1.96798002 0 P 0 ;0
L 1.91995 -1.96798002 1.92001998 -1.96795 0 P 0 ;0
L 1.92001998 -1.96795 1.92005 -1.96793002 0 P 0 ;0
L 1.92005 -1.96793002 1.92008996 -1.96791004 0 P 0 ;0
L 1.92008996 -1.96791004 1.92168002 -1.96701998 0 P 0 ;0
L 1.92168002 -1.96701998 1.92171998 -1.967 0 P 0 ;0
L 1.92171998 -1.967 1.92175 -1.96698002 0 P 0 ;0
L 1.92175 -1.96698002 1.92178996 -1.96695 0 P 0 ;0
L 1.92178996 -1.96695 1.92181998 -1.96693002 0 P 0 ;0
L 1.92181998 -1.96693002 1.92331998 -1.96591998 0 P 0 ;0
L 1.92331998 -1.96591998 1.92336004 -1.9659 0 P 0 ;0
L 1.92336004 -1.9659 1.92341998 -1.96586004 0 P 0 ;0
L 1.92341998 -1.96586004 1.92345 -1.96583002 0 P 0 ;0
L 1.92345 -1.96583002 1.92486004 -1.9647 0 P 0 ;0
L 1.92486004 -1.9647 1.92493002 -1.96465 0 P 0 ;0
L 1.92493002 -1.96465 1.92496004 -1.96463002 0 P 0 ;0
L 1.92496004 -1.96463002 1.92498996 -1.9646 0 P 0 ;0
L 1.92498996 -1.9646 1.92631004 -1.96336998 0 P 0 ;0
L 1.92631004 -1.96336998 1.9264 -1.96328002 0 P 0 ;0
L 1.9264 -1.96328002 1.92641998 -1.96325 0 P 0 ;0
L 1.92641998 -1.96325 1.92763996 -1.96191998 0 P 0 ;0
L 1.92763996 -1.96191998 1.92766998 -1.96188996 0 P 0 ;0
L 1.92766998 -1.96188996 1.92768996 -1.96186004 0 P 0 ;0
L 1.92768996 -1.96186004 1.92771998 -1.96183002 0 P 0 ;0
L 1.92771998 -1.96183002 1.92773996 -1.9618 0 P 0 ;0
L 1.92773996 -1.9618 1.92913996 -1.96001004 0 P 0 ;0
L 1.92913996 -1.96001004 1.92918996 -1.95995 0 P 0 ;0
L 1.92918996 -1.95995 1.92921004 -1.95991004 0 P 0 ;0
L 1.92921004 -1.95991004 1.92923002 -1.95988002 0 P 0 ;0
L 1.92923002 -1.95988002 1.93048002 -1.95798996 0 P 0 ;0
L 1.93048002 -1.95798996 1.93051998 -1.95793002 0 P 0 ;0
L 1.93051998 -1.95793002 1.93053996 -1.95788996 0 P 0 ;0
L 1.93053996 -1.95788996 1.93056004 -1.95786004 0 P 0 ;0
L 1.93056004 -1.95786004 1.93166004 -1.95588002 0 P 0 ;0
L 1.93166004 -1.95588002 1.93171004 -1.95576998 0 P 0 ;0
L 1.93171004 -1.95576998 1.93173002 -1.95573996 0 P 0 ;0
L 1.93173002 -1.95573996 1.93266998 -1.95366998 0 P 0 ;0
L 1.93266998 -1.95366998 1.93271004 -1.95356998 0 P 0 ;0
L 1.93271004 -1.95356998 1.93273002 -1.95353002 0 P 0 ;0
L 1.93273002 -1.95353002 1.9335 -1.9514 0 P 0 ;0
L 1.9335 -1.9514 1.93351004 -1.95136998 0 P 0 ;0
L 1.93351004 -1.95136998 1.93353002 -1.95133002 0 P 0 ;0
L 1.93353002 -1.95133002 1.93355 -1.95125 0 P 0 ;0
L 1.93355 -1.95125 1.93416004 -1.94906998 0 P 0 ;0
L 1.93416004 -1.94906998 1.93416998 -1.94903002 0 P 0 ;0
L 1.93416998 -1.94903002 1.93418002 -1.949 0 P 0 ;0
L 1.93418002 -1.949 1.93418002 -1.94896004 0 P 0 ;0
L 1.93418002 -1.94896004 1.93418996 -1.94891998 0 P 0 ;0
L 1.93418996 -1.94891998 1.93463996 -1.94665 0 P 0 ;0
L 1.93463996 -1.94665 1.93463996 -1.94661004 0 P 0 ;0
L 1.93463996 -1.94661004 1.93465 -1.94656998 0 P 0 ;0
L 1.93465 -1.94656998 1.93466004 -1.9465 0 P 0 ;0
L 1.93466004 -1.9465 1.93493996 -1.9442 0 P 0 ;0
L 1.93493996 -1.9442 1.93493996 -1.94413002 0 P 0 ;0
L 1.93493996 -1.94413002 1.93495 -1.94408996 0 P 0 ;0
L 1.93495 -1.94408996 1.93495 -1.94406004 0 P 0 ;0
L 1.93495 -1.94406004 1.93505 -1.94173996 0 P 0 ;0
L 1.93505 -1.94173996 1.93506004 -1.94171004 0 P 0 ;0
L 1.93506004 -1.94171004 1.93506004 -1.9416 0 P 0 ;0
L 1.93506004 -1.9416 1.93498996 -1.93928996 0 P 0 ;0
L 1.93498996 -1.93928996 1.93498996 -1.93921004 0 P 0 ;0
L 1.93498996 -1.93921004 1.93498002 -1.93913996 0 P 0 ;0
L 1.93498002 -1.93913996 1.93475 -1.93683996 0 P 0 ;0
L 1.93475 -1.93683996 1.93473996 -1.93676998 0 P 0 ;0
L 1.93473996 -1.93676998 1.93473002 -1.93673002 0 P 0 ;0
L 1.93473002 -1.93673002 1.93473002 -1.93668996 0 P 0 ;0
L 1.93473002 -1.93668996 1.93433002 -1.93441004 0 P 0 ;0
L 1.93433002 -1.93441004 1.93431998 -1.93436998 0 P 0 ;0
L 1.93431998 -1.93436998 1.93431004 -1.93433996 0 P 0 ;0
L 1.93431004 -1.93433996 1.93428996 -1.93426004 0 P 0 ;0
L 1.93428996 -1.93426004 1.93373002 -1.93206004 0 P 0 ;0
L 1.93373002 -1.93206004 1.93368996 -1.93191998 0 P 0 ;0
L 1.93368996 -1.93191998 1.93296004 -1.92976998 0 P 0 ;0
L 1.93296004 -1.92976998 1.93293996 -1.9297 0 P 0 ;0
L 1.93293996 -1.9297 1.93291004 -1.92963002 0 P 0 ;0
L 1.93291004 -1.92963002 1.93201998 -1.92753996 0 P 0 ;0
L 1.93201998 -1.92753996 1.93196998 -1.92743002 0 P 0 ;0
L 1.93196998 -1.92743002 1.93196004 -1.9274 0 P 0 ;0
L 1.93196004 -1.9274 1.93091998 -1.92538996 0 P 0 ;0
L 1.93091998 -1.92538996 1.9309 -1.92536004 0 P 0 ;0
L 1.9309 -1.92536004 1.93088002 -1.92531998 0 P 0 ;0
L 1.93088002 -1.92531998 1.93086004 -1.92528996 0 P 0 ;0
L 1.93086004 -1.92528996 1.93083996 -1.92525 0 P 0 ;0
L 1.93083996 -1.92525 1.92965 -1.92331998 0 P 0 ;0
L 1.92965 -1.92331998 1.92956998 -1.9232 0 P 0 ;0
L 1.92956998 -1.9232 1.92823002 -1.92136004 0 P 0 ;0
L 1.92823002 -1.92136004 1.92818002 -1.9213 0 P 0 ;0
L 1.92818002 -1.9213 1.92816004 -1.92126998 0 P 0 ;0
L 1.92816004 -1.92126998 1.92813002 -1.92123996 0 P 0 ;0
L 1.92813002 -1.92123996 1.92671998 -1.91958002 0 P 0 ;0
L 1.92671998 -1.91958002 1.9266 -1.91946004 0 P 0 ;0
L 1.9266 -1.91946004 1.92505 -1.91793002 0 P 0 ;0
L 1.92505 -1.91793002 1.92498996 -1.91786998 0 P 0 ;0
L 1.92498996 -1.91786998 1.92493002 -1.91781998 0 P 0 ;0
L 1.92493002 -1.91781998 1.92325 -1.91643002 0 P 0 ;0
L 1.92325 -1.91643002 1.92318996 -1.91636998 0 P 0 ;0
L 1.92318996 -1.91636998 1.92311998 -1.91631998 0 P 0 ;0
L 1.92311998 -1.91631998 1.92133002 -1.91508002 0 P 0 ;0
L 1.92133002 -1.91508002 1.92126004 -1.91503996 0 P 0 ;0
L 1.92126004 -1.91503996 1.92121998 -1.91501004 0 P 0 ;0
L 1.92121998 -1.91501004 1.92118002 -1.91498996 0 P 0 ;0
L 1.92118002 -1.91498996 1.91928996 -1.91391004 0 P 0 ;0
L 1.91928996 -1.91391004 1.91926004 -1.91388996 0 P 0 ;0
L 1.91926004 -1.91388996 1.91913996 -1.91383002 0 P 0 ;0
L 1.91913996 -1.91383002 1.91716998 -1.91291004 0 P 0 ;0
L 1.91716998 -1.91291004 1.91711998 -1.91288996 0 P 0 ;0
L 1.91711998 -1.91288996 1.91705 -1.91286004 0 P 0 ;0
L 1.91705 -1.91286004 1.917 -1.91285 0 P 0 ;0
L 1.917 -1.91285 1.91476998 -1.91203996 0 P 0 ;0
L 1.91476998 -1.91203996 1.91468996 -1.91201998 0 P 0 ;0
L 1.91468996 -1.91201998 1.91465 -1.912 0 P 0 ;0
L 1.91465 -1.912 1.9146 -1.91198996 0 P 0 ;0
L 1.9146 -1.91198996 1.91233002 -1.91138996 0 P 0 ;0
L 1.91233002 -1.91138996 1.91228002 -1.91138002 0 P 0 ;0
L 1.91228002 -1.91138002 1.91223996 -1.91136998 0 P 0 ;0
L 1.91223996 -1.91136998 1.91216004 -1.91136004 0 P 0 ;0
L 1.91216004 -1.91136004 1.90983002 -1.91095 0 P 0 ;0
L 1.90983002 -1.91095 1.9098 -1.91093996 0 P 0 ;0
L 1.9098 -1.91093996 1.90976004 -1.91093996 0 P 0 ;0
L 1.90976004 -1.91093996 1.90971998 -1.91093002 0 P 0 ;0
L 1.90971998 -1.91093002 1.90968002 -1.91093002 0 P 0 ;0
L 1.90968002 -1.91093002 1.90713996 -1.91068996 0 P 0 ;0
L 1.90713996 -1.91068996 1.9071 -1.91068002 0 P 0 ;0
L 1.9071 -1.91068002 1.907 -1.91068002 0 P 0 ;0
L 1.907 -1.91068002 1.90445 -1.91061004 0 P 0 ;0
L 1.90445 -1.91061004 1.90431004 -1.91061004 0 P 0 ;0
L 1.90431004 -1.91061004 1.90176004 -1.91071004 0 P 0 ;0
L 1.90176004 -1.91071004 1.90173002 -1.91071998 0 P 0 ;0
L 1.90173002 -1.91071998 1.90166004 -1.91071998 0 P 0 ;0
L 1.90166004 -1.91071998 1.90161998 -1.91073002 0 P 0 ;0
L 1.90161998 -1.91073002 1.89913002 -1.911 0 P 0 ;0
L 1.89913002 -1.911 1.89906004 -1.91101004 0 P 0 ;0
L 1.89906004 -1.91101004 1.89901998 -1.91101998 0 P 0 ;0
L 1.89901998 -1.91101998 1.89898996 -1.91101998 0 P 0 ;0
L 1.89898996 -1.91101998 1.89653002 -1.91146998 0 P 0 ;0
L 1.89653002 -1.91146998 1.8965 -1.91148002 0 P 0 ;0
L 1.8965 -1.91148002 1.89646004 -1.91148002 0 P 0 ;0
L 1.89646004 -1.91148002 1.8964 -1.9115 0 P 0 ;0
L 1.8964 -1.9115 1.89396998 -1.91211998 0 P 0 ;0
L 1.89396998 -1.91211998 1.89393996 -1.91213002 0 P 0 ;0
L 1.89393996 -1.91213002 1.89383002 -1.91216004 0 P 0 ;0
L 1.89383002 -1.91216004 1.89225 -1.91268996 0 P 0 ;0
L 1.89225 -1.91268996 1.89218002 -1.91271998 0 P 0 ;0
L 1.89218002 -1.91271998 1.89211004 -1.91273996 0 P 0 ;0
L 1.89211004 -1.91273996 1.8921 -1.91273996 0 P 0 ;0
L 1.8921 -1.91273996 1.89058002 -1.91338996 0 P 0 ;0
L 1.89058002 -1.91338996 1.89043996 -1.91345 0 P 0 ;0
L 1.89043996 -1.91345 1.88896004 -1.91421004 0 P 0 ;0
L 1.88896004 -1.91421004 1.88893002 -1.91423002 0 P 0 ;0
L 1.88893002 -1.91423002 1.8889 -1.91423996 0 P 0 ;0
L 1.8889 -1.91423996 1.88886004 -1.91426004 0 P 0 ;0
L 1.88886004 -1.91426004 1.88883002 -1.91428002 0 P 0 ;0
L 1.88883002 -1.91428002 1.88741004 -1.91515 0 P 0 ;0
L 1.88741004 -1.91515 1.88733996 -1.91518996 0 P 0 ;0
L 1.88733996 -1.91518996 1.88728002 -1.91523996 0 P 0 ;0
L 1.88728002 -1.91523996 1.88526004 -1.9167 0 P 0 ;0
L 1.88526004 -1.9167 1.88521998 -1.91673002 0 P 0 ;0
L 1.88521998 -1.91673002 1.88518996 -1.91675 0 P 0 ;0
L 1.88518996 -1.91675 1.88516004 -1.91678002 0 P 0 ;0
L 1.88516004 -1.91678002 1.88511998 -1.91681004 0 P 0 ;0
L 1.88511998 -1.91681004 1.88323002 -1.91845 0 P 0 ;0
L 1.88323002 -1.91845 1.8832 -1.91846998 0 P 0 ;0
L 1.8832 -1.91846998 1.88311004 -1.91856004 0 P 0 ;0
L 1.88311004 -1.91856004 1.88136998 -1.92036004 0 P 0 ;0
L 1.88136998 -1.92036004 1.88128002 -1.92045 0 P 0 ;0
L 1.88128002 -1.92045 1.88125 -1.92048996 0 P 0 ;0
L 1.88125 -1.92048996 1.87968002 -1.92241998 0 P 0 ;0
L 1.87968002 -1.92241998 1.87965 -1.92245 0 P 0 ;0
L 1.87965 -1.92245 1.87961998 -1.92248996 0 P 0 ;0
L 1.87961998 -1.92248996 1.87956998 -1.92256004 0 P 0 ;0
L 1.87956998 -1.92256004 1.87816998 -1.92461998 0 P 0 ;0
L 1.87816998 -1.92461998 1.8781 -1.92473002 0 P 0 ;0
L 1.8781 -1.92473002 1.87808002 -1.92476998 0 P 0 ;0
L 1.87808002 -1.92476998 1.87685 -1.92695 0 P 0 ;0
L 1.87685 -1.92695 1.87683002 -1.92698996 0 P 0 ;0
L 1.87683002 -1.92698996 1.87681004 -1.92701998 0 P 0 ;0
L 1.87681004 -1.92701998 1.87678996 -1.92706998 0 P 0 ;0
L 1.87678996 -1.92706998 1.87676998 -1.92711004 0 P 0 ;0
L 1.87676998 -1.92711004 1.87573002 -1.92941004 0 P 0 ;0
L 1.87573002 -1.92941004 1.87571004 -1.92945 0 P 0 ;0
L 1.87571004 -1.92945 1.8757 -1.92948996 0 P 0 ;0
L 1.8757 -1.92948996 1.87568002 -1.92951998 0 P 0 ;0
L 1.87568002 -1.92951998 1.87566998 -1.92956998 0 P 0 ;0
L 1.87566998 -1.92956998 1.87483996 -1.93193002 0 P 0 ;0
L 1.87483996 -1.93193002 1.87481004 -1.93201004 0 P 0 ;0
L 1.87481004 -1.93201004 1.87478996 -1.93208996 0 P 0 ;0
L 1.87478996 -1.93208996 1.87416004 -1.93451998 0 P 0 ;0
L 1.87416004 -1.93451998 1.87413996 -1.93456004 0 P 0 ;0
L 1.87413996 -1.93456004 1.87413002 -1.9346 0 P 0 ;0
L 1.87413002 -1.9346 1.87413002 -1.93463996 0 P 0 ;0
L 1.87413002 -1.93463996 1.87411998 -1.93468002 0 P 0 ;0
L 1.87411998 -1.93468002 1.8737 -1.93715 0 P 0 ;0
L 1.8737 -1.93715 1.87368996 -1.93718996 0 P 0 ;0
L 1.87368996 -1.93718996 1.87368002 -1.93723996 0 P 0 ;0
L 1.87368002 -1.93723996 1.87368002 -1.93731998 0 P 0 ;0
L 1.87368002 -1.93731998 1.87346998 -1.93981998 0 P 0 ;0
L 1.87346998 -1.93981998 1.87346004 -1.93986004 0 P 0 ;0
L 1.87346004 -1.93986004 1.87346004 -1.94258002 0 P 0 ;0
L 1.87346004 -1.94258002 1.87346998 -1.94266004 0 P 0 ;0
L 1.87346998 -1.94266004 1.87368002 -1.94516998 0 P 0 ;0
L 1.87368002 -1.94516998 1.87368996 -1.94521004 0 P 0 ;0
L 1.87368996 -1.94521004 1.87368996 -1.94525 0 P 0 ;0
L 1.87368996 -1.94525 1.87371004 -1.94533996 0 P 0 ;0
L 1.87371004 -1.94533996 1.87413996 -1.94778996 0 P 0 ;0
L 1.87413996 -1.94778996 1.87413996 -1.94783996 0 P 0 ;0
L 1.87413996 -1.94783996 1.87416998 -1.94796004 0 P 0 ;0
L 1.87416998 -1.94796004 1.87481004 -1.95036998 0 P 0 ;0
L 1.87481004 -1.95036998 1.87483996 -1.95048996 0 P 0 ;0
L 1.87483996 -1.95048996 1.87486004 -1.95053002 0 P 0 ;0
L 1.87486004 -1.95053002 1.8757 -1.95288002 0 P 0 ;0
L 1.8757 -1.95288002 1.87571004 -1.95291998 0 P 0 ;0
L 1.87571004 -1.95291998 1.87575 -1.953 0 P 0 ;0
L 1.87575 -1.953 1.87576004 -1.95303996 0 P 0 ;0
L 1.87576004 -1.95303996 1.8768 -1.9553 0 P 0 ;0
L 1.8768 -1.9553 1.87686004 -1.95541998 0 P 0 ;0
L 1.87686004 -1.95541998 1.87688002 -1.95545 0 P 0 ;0
L 1.87688002 -1.95545 1.8781 -1.95761004 0 P 0 ;0
L 1.8781 -1.95761004 1.87811998 -1.95761004 0 P 0 ;0
L 1.87811998 -1.95761004 1.8781 -1.95761998 0 P 0 ;0
L 1.8781 -1.95761998 1.87813996 -1.95768996 0 P 0 ;0
L 1.87813996 -1.95768996 1.87816998 -1.95771998 0 P 0 ;0
L 1.87816998 -1.95771998 1.87818996 -1.95775 0 P 0 ;0
L 1.87818996 -1.95775 1.87938002 -1.95951004 0 P 0 ;0
L 1.87938002 -1.95951004 1.87943996 -1.9596 0 P 0 ;0
L 1.87943996 -1.9596 1.87946998 -1.95963002 0 P 0 ;0
L 1.87946998 -1.95963002 1.88078002 -1.96128996 0 P 0 ;0
L 1.88078002 -1.96128996 1.88081004 -1.96131998 0 P 0 ;0
L 1.88081004 -1.96131998 1.88083002 -1.96135 0 P 0 ;0
L 1.88083002 -1.96135 1.88086004 -1.96136998 0 P 0 ;0
L 1.88086004 -1.96136998 1.88088002 -1.9614 0 P 0 ;0
L 1.88088002 -1.9614 1.88231998 -1.96295 0 P 0 ;0
L 1.88231998 -1.96295 1.88233996 -1.96298002 0 P 0 ;0
L 1.88233996 -1.96298002 1.8824 -1.96303996 0 P 0 ;0
L 1.8824 -1.96303996 1.88243002 -1.96306004 0 P 0 ;0
L 1.88243002 -1.96306004 1.88398002 -1.9645 0 P 0 ;0
L 1.88398002 -1.9645 1.88401004 -1.96451998 0 P 0 ;0
L 1.88401004 -1.96451998 1.88403002 -1.96455 0 P 0 ;0
L 1.88403002 -1.96455 1.88406998 -1.96458002 0 P 0 ;0
L 1.88406998 -1.96458002 1.88408996 -1.9646 0 P 0 ;0
L 1.88408996 -1.9646 1.88575 -1.96591004 0 P 0 ;0
L 1.88575 -1.96591004 1.88578002 -1.96593996 0 P 0 ;0
L 1.88578002 -1.96593996 1.88586998 -1.966 0 P 0 ;0
L 1.88586998 -1.966 1.88761998 -1.96718996 0 P 0 ;0
L 1.88761998 -1.96718996 1.88766004 -1.96721004 0 P 0 ;0
L 1.88766004 -1.96721004 1.88775 -1.96726998 0 P 0 ;0
L 1.88775 -1.96726998 1.88958996 -1.96831998 0 P 0 ;0
L 1.88958996 -1.96831998 1.88965 -1.96836004 0 P 0 ;0
L 1.88965 -1.96836004 1.88968002 -1.96836998 0 P 0 ;0
L 1.88968002 -1.96836998 1.88971998 -1.96838996 0 P 0 ;0
L 1.88971998 -1.96838996 1.89145 -1.96921998 0 P 0 ;0
L 1.89145 -1.96921998 1.89151004 -1.96925 0 P 0 ;0
L 1.89151004 -1.96925 1.89155 -1.96926004 0 P 0 ;0
L 1.89155 -1.96926004 1.89158002 -1.96926998 0 P 0 ;0
L 1.89158002 -1.96926998 1.89336004 -1.96996998 0 P 0 ;0
L 1.89336004 -1.96996998 1.89336004 -1.96998002 0 P 0 ;0
L 1.89336004 -1.96998002 1.89346004 -1.97001004 0 P 0 ;0
L 1.89346004 -1.97001004 1.89348996 -1.97001998 0 P 0 ;0
L 1.89348996 -1.97001998 1.89531998 -1.9706 0 P 0 ;0
L 1.89531998 -1.9706 1.89536004 -1.97061004 0 P 0 ;0
L 1.89536004 -1.97061004 1.89541998 -1.97063002 0 P 0 ;0
L 1.89541998 -1.97063002 1.89546004 -1.97063002 0 P 0 ;0
L 1.89546004 -1.97063002 1.89731998 -1.97108002 0 P 0 ;0
L 1.89731998 -1.97108002 1.89741998 -1.9711 0 P 0 ;0
L 1.89741998 -1.9711 1.89746004 -1.9711 0 P 0 ;0
L 1.89746004 -1.9711 1.89746004 -1.97111004 0 P 0 ;0
L 1.89746004 -1.97111004 1.89933996 -1.97141998 0 P 0 ;0
L 1.89933996 -1.97141998 1.89936998 -1.97143002 0 P 0 ;0
L 1.89936998 -1.97143002 1.89941004 -1.97143002 0 P 0 ;0
L 1.89941004 -1.97143002 1.89945 -1.97143996 0 P 0 ;0
L 1.89945 -1.97143996 1.89948002 -1.97143996 0 P 0 ;0
L 1.89948002 -1.97143996 1.90201004 -1.97168002 0 P 0 ;0
L 1.90201004 -1.97168002 1.90205 -1.97168002 0 P 0 ;0
L 1.90205 -1.97168002 1.90208996 -1.97168996 0 P 0 ;0
L 1.90208996 -1.97168996 1.90216004 -1.97168996 0 P 0 ;0
L 1.90216004 -1.97168996 1.90468996 -1.97173996 0 P 0 ;0
L 1.90468996 -1.97173996 1.90476004 -1.97173996 0 P 0 ;0
L 1.80616004 -2.12823996 1.83348996 -2.12823996 0 P 0 ;0
L 1.79591998 -2.12723996 1.8396 -2.12723996 0 P 0 ;0
L 1.78818002 -2.12623996 1.84465 -2.12623996 0 P 0 ;0
L 1.82003996 -2.09123996 1.87618996 -2.09123996 0 P 0 ;0
L 1.82198996 -2.09023996 1.8762 -2.09023996 0 P 0 ;0
L 1.82325 -2.08923996 1.8762 -2.08923996 0 P 0 ;0
L 1.82411998 -2.08823996 1.87618996 -2.08823996 0 P 0 ;0
L 1.82463002 -2.08723996 1.87616998 -2.08723996 0 P 0 ;0
L 1.82488002 -2.08623996 1.87615 -2.08623996 0 P 0 ;0
L 1.82493002 -2.08523996 1.87613002 -2.08523996 0 P 0 ;0
L 1.82476998 -2.08423996 1.87611004 -2.08423996 0 P 0 ;0
L 1.64846004 -2.08295 1.73316998 -2.08295 0 P 0 ;0
L 1.64811998 -2.08195 1.73356998 -2.08195 0 P 0 ;0
L 1.64776998 -2.08095 1.73398002 -2.08095 0 P 0 ;0
L 1.64743002 -2.07995 1.73438002 -2.07995 0 P 0 ;0
L 1.64708996 -2.07895 1.73478996 -2.07895 0 P 0 ;0
L 1.64673996 -2.07795 1.7352 -2.07795 0 P 0 ;0
L 1.6464 -2.07695 1.7356 -2.07695 0 P 0 ;0
L 1.64605 -2.07595 1.73601004 -2.07595 0 P 0 ;0
L 1.64571004 -2.07495 1.73641004 -2.07495 0 P 0 ;0
L 1.64536004 -2.07395 1.73681004 -2.07395 0 P 0 ;0
L 1.64501998 -2.07295 1.73721998 -2.07295 0 P 0 ;0
L 1.64466998 -2.07195 1.73761998 -2.07195 0 P 0 ;0
L 1.64433002 -2.07095 1.73803002 -2.07095 0 P 0 ;0
L 1.64398002 -2.06995 1.69251004 -2.06995 0 P 0 ;0
L 1.69583002 -2.06995 1.73843996 -2.06995 0 P 0 ;0
L 1.64363002 -2.06895 1.69168002 -2.06895 0 P 0 ;0
L 1.69671998 -2.06895 1.73883996 -2.06895 0 P 0 ;0
L 1.64328996 -2.06795 1.69136004 -2.06795 0 P 0 ;0
L 1.69708996 -2.06795 1.73925 -2.06795 0 P 0 ;0
L 1.64293996 -2.06695 1.69108002 -2.06695 0 P 0 ;0
L 1.69738002 -2.06695 1.73965 -2.06695 0 P 0 ;0
L 1.64258996 -2.06595 1.6908 -2.06595 0 P 0 ;0
L 1.69768002 -2.06595 1.74006004 -2.06595 0 P 0 ;0
L 1.64223996 -2.06495 1.69051998 -2.06495 0 P 0 ;0
L 1.69796998 -2.06495 1.74046004 -2.06495 0 P 0 ;0
L 1.6419 -2.06395 1.69023002 -2.06395 0 P 0 ;0
L 1.69826998 -2.06395 1.74086004 -2.06395 0 P 0 ;0
L 1.64155 -2.06295 1.68996004 -2.06295 0 P 0 ;0
L 1.69856004 -2.06295 1.74126998 -2.06295 0 P 0 ;0
L 1.6412 -2.06195 1.68966998 -2.06195 0 P 0 ;0
L 1.69886004 -2.06195 1.74168002 -2.06195 0 P 0 ;0
L 1.64085 -2.06095 1.68938996 -2.06095 0 P 0 ;0
L 1.69915 -2.06095 1.74208002 -2.06095 0 P 0 ;0
L 1.6405 -2.05995 1.68911004 -2.05995 0 P 0 ;0
L 1.69945 -2.05995 1.74248002 -2.05995 0 P 0 ;0
L 1.64016004 -2.05895 1.68883002 -2.05895 0 P 0 ;0
L 1.69973996 -2.05895 1.74288996 -2.05895 0 P 0 ;0
L 1.63981004 -2.05795 1.68855 -2.05795 0 P 0 ;0
L 1.70003996 -2.05795 1.74328996 -2.05795 0 P 0 ;0
L 1.63946004 -2.05695 1.68826998 -2.05695 0 P 0 ;0
L 1.70033002 -2.05695 1.7437 -2.05695 0 P 0 ;0
L 1.63911004 -2.05595 1.68798996 -2.05595 0 P 0 ;0
L 1.70063002 -2.05595 1.7441 -2.05595 0 P 0 ;0
L 1.63876998 -2.05495 1.68771004 -2.05495 0 P 0 ;0
L 1.70091998 -2.05495 1.74451004 -2.05495 0 P 0 ;0
L 1.63841998 -2.05395 1.68741998 -2.05395 0 P 0 ;0
L 1.70121998 -2.05395 1.74491004 -2.05395 0 P 0 ;0
L 1.63806998 -2.05295 1.68713996 -2.05295 0 P 0 ;0
L 1.70151004 -2.05295 1.74531004 -2.05295 0 P 0 ;0
L 1.63771998 -2.05195 1.68686004 -2.05195 0 P 0 ;0
L 1.70181004 -2.05195 1.74571998 -2.05195 0 P 0 ;0
L 1.63738002 -2.05095 1.68658002 -2.05095 0 P 0 ;0
L 1.7021 -2.05095 1.74611998 -2.05095 0 P 0 ;0
L 1.63703002 -2.04995 1.6863 -2.04995 0 P 0 ;0
L 1.7024 -2.04995 1.74653002 -2.04995 0 P 0 ;0
L 1.63668002 -2.04895 1.68601998 -2.04895 0 P 0 ;0
L 1.70268996 -2.04895 1.74693002 -2.04895 0 P 0 ;0
L 1.63633002 -2.04795 1.68573996 -2.04795 0 P 0 ;0
L 1.70298996 -2.04795 1.74733002 -2.04795 0 P 0 ;0
L 1.63598002 -2.04695 1.68546004 -2.04695 0 P 0 ;0
L 1.70328002 -2.04695 1.74773996 -2.04695 0 P 0 ;0
L 1.63563996 -2.04595 1.68518002 -2.04595 0 P 0 ;0
L 1.70358002 -2.04595 1.74813996 -2.04595 0 P 0 ;0
L 1.63528996 -2.04495 1.6849 -2.04495 0 P 0 ;0
L 1.70386998 -2.04495 1.74855 -2.04495 0 P 0 ;0
L 1.63493996 -2.04395 1.68461004 -2.04395 0 P 0 ;0
L 1.70416998 -2.04395 1.74895 -2.04395 0 P 0 ;0
L 1.63458996 -2.04295 1.68433002 -2.04295 0 P 0 ;0
L 1.70446004 -2.04295 1.74936004 -2.04295 0 P 0 ;0
L 1.63425 -2.04195 1.68405 -2.04195 0 P 0 ;0
L 1.70475 -2.04195 1.74976004 -2.04195 0 P 0 ;0
L 1.6339 -2.04095 1.68376998 -2.04095 0 P 0 ;0
L 1.70503002 -2.04095 1.75016004 -2.04095 0 P 0 ;0
L 1.63355 -2.03995 1.68348996 -2.03995 0 P 0 ;0
L 1.70531998 -2.03995 1.75056998 -2.03995 0 P 0 ;0
L 1.6332 -2.03895 1.68321004 -2.03895 0 P 0 ;0
L 1.7056 -2.03895 1.75096998 -2.03895 0 P 0 ;0
L 1.63286004 -2.03795 1.68293002 -2.03795 0 P 0 ;0
L 1.70588996 -2.03795 1.75138002 -2.03795 0 P 0 ;0
L 1.63251004 -2.03695 1.68266004 -2.03695 0 P 0 ;0
L 1.70618002 -2.03695 1.75178002 -2.03695 0 P 0 ;0
L 1.63216004 -2.03595 1.68238002 -2.03595 0 P 0 ;0
L 1.70646998 -2.03595 1.75218996 -2.03595 0 P 0 ;0
L 1.63181004 -2.03495 1.6821 -2.03495 0 P 0 ;0
L 1.70675 -2.03495 1.75258996 -2.03495 0 P 0 ;0
L 1.63146998 -2.03395 1.68183002 -2.03395 0 P 0 ;0
L 1.70703996 -2.03395 1.75298996 -2.03395 0 P 0 ;0
L 1.63111998 -2.03295 1.68155 -2.03295 0 P 0 ;0
L 1.70733002 -2.03295 1.7534 -2.03295 0 P 0 ;0
L 1.63076998 -2.03195 1.68126998 -2.03195 0 P 0 ;0
L 1.70761004 -2.03195 1.75381004 -2.03195 0 P 0 ;0
L 1.63041998 -2.03095 1.68098996 -2.03095 0 P 0 ;0
L 1.7079 -2.03095 1.75421004 -2.03095 0 P 0 ;0
L 1.63006998 -2.02995 1.68071004 -2.02995 0 P 0 ;0
L 1.70818996 -2.02995 1.75461004 -2.02995 0 P 0 ;0
L 1.62973002 -2.02895 1.68043996 -2.02895 0 P 0 ;0
L 1.70846998 -2.02895 1.75501998 -2.02895 0 P 0 ;0
L 1.62938002 -2.02795 1.68016004 -2.02795 0 P 0 ;0
L 1.70876004 -2.02795 1.75541998 -2.02795 0 P 0 ;0
L 1.62903002 -2.02695 1.67988002 -2.02695 0 P 0 ;0
L 1.70905 -2.02695 1.75583002 -2.02695 0 P 0 ;0
L 1.62868002 -2.02595 1.6796 -2.02595 0 P 0 ;0
L 1.70933996 -2.02595 1.75623002 -2.02595 0 P 0 ;0
L 1.62831004 -2.02495 1.67933002 -2.02495 0 P 0 ;0
L 1.70961998 -2.02495 1.75663996 -2.02495 0 P 0 ;0
L 1.62793996 -2.02395 1.67905 -2.02395 0 P 0 ;0
L 1.70991004 -2.02395 1.75703996 -2.02395 0 P 0 ;0
L 1.62756998 -2.02295 1.67876998 -2.02295 0 P 0 ;0
L 1.7102 -2.02295 1.75743996 -2.02295 0 P 0 ;0
L 1.6272 -2.02195 1.6785 -2.02195 0 P 0 ;0
L 1.71048002 -2.02195 1.75785 -2.02195 0 P 0 ;0
L 1.62683002 -2.02095 1.67821998 -2.02095 0 P 0 ;0
L 1.71076004 -2.02095 1.75825 -2.02095 0 P 0 ;0
L 1.62646998 -2.01995 1.67793996 -2.01995 0 P 0 ;0
L 1.71101004 -2.01995 1.75866004 -2.01995 0 P 0 ;0
L 1.6261 -2.01895 1.67766004 -2.01895 0 P 0 ;0
L 1.71126998 -2.01895 1.75906004 -2.01895 0 P 0 ;0
L 1.62573002 -2.01795 1.67738996 -2.01795 0 P 0 ;0
L 1.71151998 -2.01795 1.75946998 -2.01795 0 P 0 ;0
L 1.62536004 -2.01695 1.67711004 -2.01695 0 P 0 ;0
L 1.71176998 -2.01695 1.75986998 -2.01695 0 P 0 ;0
L 1.62498996 -2.01595 1.67683002 -2.01595 0 P 0 ;0
L 1.71203002 -2.01595 1.76026998 -2.01595 0 P 0 ;0
L 1.62461998 -2.01495 1.67656004 -2.01495 0 P 0 ;0
L 1.71228002 -2.01495 1.76068002 -2.01495 0 P 0 ;0
L 1.62425 -2.01395 1.67628002 -2.01395 0 P 0 ;0
L 1.71253996 -2.01395 1.76108002 -2.01395 0 P 0 ;0
L 1.62388002 -2.01295 1.67601998 -2.01295 0 P 0 ;0
L 1.71278996 -2.01295 1.76148996 -2.01295 0 P 0 ;0
L 1.62351004 -2.01195 1.67576998 -2.01195 0 P 0 ;0
L 1.71305 -2.01195 1.76188996 -2.01195 0 P 0 ;0
L 1.62313996 -2.01095 1.67551998 -2.01095 0 P 0 ;0
L 1.7133 -2.01095 1.76228996 -2.01095 0 P 0 ;0
L 1.62276998 -2.00995 1.67528002 -2.00995 0 P 0 ;0
L 1.71355 -2.00995 1.7627 -2.00995 0 P 0 ;0
L 1.6224 -2.00895 1.67503002 -2.00895 0 P 0 ;0
L 1.71381004 -2.00895 1.7631 -2.00895 0 P 0 ;0
L 1.62203002 -2.00795 1.67478996 -2.00795 0 P 0 ;0
L 1.71406004 -2.00795 1.76351004 -2.00795 0 P 0 ;0
L 1.62166004 -2.00695 1.67453996 -2.00695 0 P 0 ;0
L 1.71431004 -2.00695 1.76391004 -2.00695 0 P 0 ;0
L 1.62128996 -2.00595 1.67428996 -2.00595 0 P 0 ;0
L 1.71453996 -2.00595 1.76431998 -2.00595 0 P 0 ;0
L 1.62091004 -2.00495 1.67405 -2.00495 0 P 0 ;0
L 1.71476998 -2.00495 1.76471998 -2.00495 0 P 0 ;0
L 1.62051998 -2.00395 1.6738 -2.00395 0 P 0 ;0
L 1.715 -2.00395 1.76511998 -2.00395 0 P 0 ;0
L 1.62013002 -2.00295 1.67355 -2.00295 0 P 0 ;0
L 1.71523002 -2.00295 1.76553002 -2.00295 0 P 0 ;0
L 1.61973996 -2.00195 1.67331004 -2.00195 0 P 0 ;0
L 1.71546004 -2.00195 1.76593996 -2.00195 0 P 0 ;0
L 1.61935 -2.00095 1.67306004 -2.00095 0 P 0 ;0
L 1.71568996 -2.00095 1.76633996 -2.00095 0 P 0 ;0
L 1.61896004 -1.99995 1.67283996 -1.99995 0 P 0 ;0
L 1.71591998 -1.99995 1.76673996 -1.99995 0 P 0 ;0
L 1.61856998 -1.99895 1.67261998 -1.99895 0 P 0 ;0
L 1.71613996 -1.99895 1.76715 -1.99895 0 P 0 ;0
L 1.71638002 -1.99795 1.76755 -1.99795 0 P 0 ;0
L 1.7166 -1.99695 1.76796004 -1.99695 0 P 0 ;0
L 1.71683002 -1.99595 1.76836004 -1.99595 0 P 0 ;0
L 1.71866998 -1.99495 1.76876998 -1.99495 0 P 0 ;0
L 1.78213996 -2.04823996 1.84641998 -2.04823996 0 P 0 ;0
L 1.78138002 -2.04723996 1.84498996 -2.04723996 0 P 0 ;0
L 1.78071004 -2.04623996 1.84356004 -2.04623996 0 P 0 ;0
L 1.7801 -2.04523996 1.84213996 -2.04523996 0 P 0 ;0
L 1.77956004 -2.04423996 1.84071004 -2.04423996 0 P 0 ;0
L 1.77908996 -2.04323996 1.83928002 -2.04323996 0 P 0 ;0
L 1.77866004 -2.04223996 1.83786004 -2.04223996 0 P 0 ;0
L 1.77831004 -2.04123996 1.83658996 -2.04123996 0 P 0 ;0
L 1.77796004 -2.04023996 1.83536004 -2.04023996 0 P 0 ;0
L 1.77761004 -2.03923996 1.83428002 -2.03923996 0 P 0 ;0
L 1.77733996 -2.03823996 1.83321998 -2.03823996 0 P 0 ;0
L 1.77706998 -2.03723996 1.83236998 -2.03723996 0 P 0 ;0
L 1.7768 -2.03623996 1.83171004 -2.03623996 0 P 0 ;0
L 1.7766 -2.03523996 1.83121004 -2.03523996 0 P 0 ;0
L 1.77641004 -2.03423996 1.83085 -2.03423996 0 P 0 ;0
L 1.77621004 -2.03323996 1.83071004 -2.03323996 0 P 0 ;0
L 1.77608002 -2.03223996 1.83076998 -2.03223996 0 P 0 ;0
L 1.77596004 -2.03123996 1.83106004 -2.03123996 0 P 0 ;0
L 1.77583996 -2.03023996 1.83158996 -2.03023996 0 P 0 ;0
L 1.77576004 -2.02923996 1.83238002 -2.02923996 0 P 0 ;0
L 1.7757 -2.02823996 1.83356998 -2.02823996 0 P 0 ;0
L 1.7757 -2.02723996 1.83591998 -2.02723996 0 P 0 ;0
L 1.77571998 -2.02623996 1.87495 -2.02623996 0 P 0 ;0
L 1.7758 -2.02523996 1.87485 -2.02523996 0 P 0 ;0
L 1.77588996 -2.02423996 1.87475 -2.02423996 0 P 0 ;0
L 1.77605 -2.02323996 1.87465 -2.02323996 0 P 0 ;0
L 1.77621004 -2.02223996 1.87455 -2.02223996 0 P 0 ;0
L 1.7764 -2.02123996 1.87445 -2.02123996 0 P 0 ;0
L 1.77665 -2.02023996 1.87433996 -2.02023996 0 P 0 ;0
L 1.7769 -2.01923996 1.87425 -2.01923996 0 P 0 ;0
L 1.7772 -2.01823996 1.87413996 -2.01823996 0 P 0 ;0
L 1.77753002 -2.01723996 1.87405 -2.01723996 0 P 0 ;0
L 1.77786004 -2.01623996 1.87393996 -2.01623996 0 P 0 ;0
L 1.77823002 -2.01523996 1.87383996 -2.01523996 0 P 0 ;0
L 1.77863996 -2.01423996 1.87373996 -2.01423996 0 P 0 ;0
L 1.77903996 -2.01323996 1.87363996 -2.01323996 0 P 0 ;0
L 1.7795 -2.01223996 1.87353996 -2.01223996 0 P 0 ;0
L 1.77998996 -2.01123996 1.87343996 -2.01123996 0 P 0 ;0
L 1.78046998 -2.01023996 1.87333002 -2.01023996 0 P 0 ;0
L 1.78103996 -2.00923996 1.87323002 -2.00923996 0 P 0 ;0
L 1.78161004 -2.00823996 1.87311998 -2.00823996 0 P 0 ;0
L 1.78221004 -2.00723996 1.87301998 -2.00723996 0 P 0 ;0
L 1.78288002 -2.00623996 1.87291998 -2.00623996 0 P 0 ;0
L 1.64213996 -2.14795 1.70566004 -2.14795 0 P 0 ;0
L 1.64518996 -2.14695 1.7062 -2.14695 0 P 0 ;0
L 1.64728996 -2.14595 1.70673996 -2.14595 0 P 0 ;0
L 1.64906998 -2.14495 1.70728002 -2.14495 0 P 0 ;0
L 1.65058002 -2.14395 1.70783002 -2.14395 0 P 0 ;0
L 1.6519 -2.14295 1.70836998 -2.14295 0 P 0 ;0
L 1.65311998 -2.14195 1.70881998 -2.14195 0 P 0 ;0
L 1.65416998 -2.14095 1.70926998 -2.14095 0 P 0 ;0
L 1.65508996 -2.13995 1.70973002 -2.13995 0 P 0 ;0
L 1.65588002 -2.13895 1.71018002 -2.13895 0 P 0 ;0
L 1.65658002 -2.13795 1.71063002 -2.13795 0 P 0 ;0
L 1.65726998 -2.13695 1.71108996 -2.13695 0 P 0 ;0
L 1.65791998 -2.13595 1.71153996 -2.13595 0 P 0 ;0
L 1.65853002 -2.13495 1.71198996 -2.13495 0 P 0 ;0
L 1.65913002 -2.13395 1.71245 -2.13395 0 P 0 ;0
L 1.65968002 -2.13295 1.7129 -2.13295 0 P 0 ;0
L 1.66021998 -2.13195 1.71331004 -2.13195 0 P 0 ;0
L 1.66071998 -2.13095 1.71371998 -2.13095 0 P 0 ;0
L 1.66121004 -2.12995 1.71411998 -2.12995 0 P 0 ;0
L 1.66166998 -2.12895 1.71453002 -2.12895 0 P 0 ;0
L 1.66201004 -2.12795 1.71493996 -2.12795 0 P 0 ;0
L 1.66223996 -2.12695 1.71533996 -2.12695 0 P 0 ;0
L 1.66235 -2.12595 1.71575 -2.12595 0 P 0 ;0
L 1.66236004 -2.12495 1.71615 -2.12495 0 P 0 ;0
L 1.66228002 -2.12395 1.71656004 -2.12395 0 P 0 ;0
L 1.66211998 -2.12295 1.71696004 -2.12295 0 P 0 ;0
L 1.66188002 -2.12195 1.71736004 -2.12195 0 P 0 ;0
L 1.66156004 -2.12095 1.71776998 -2.12095 0 P 0 ;0
L 1.66121004 -2.11995 1.71818002 -2.11995 0 P 0 ;0
L 1.66086998 -2.11895 1.71858002 -2.11895 0 P 0 ;0
L 1.66053002 -2.11795 1.71898996 -2.11795 0 P 0 ;0
L 1.66018002 -2.11695 1.71938996 -2.11695 0 P 0 ;0
L 1.65983996 -2.11595 1.7198 -2.11595 0 P 0 ;0
L 1.65948996 -2.11495 1.7202 -2.11495 0 P 0 ;0
L 1.65913996 -2.11395 1.72061004 -2.11395 0 P 0 ;0
L 1.6588 -2.11295 1.72101004 -2.11295 0 P 0 ;0
L 1.65846004 -2.11195 1.72141998 -2.11195 0 P 0 ;0
L 1.65811004 -2.11095 1.72181998 -2.11095 0 P 0 ;0
L 1.65776998 -2.10995 1.72223002 -2.10995 0 P 0 ;0
L 1.65741998 -2.10895 1.72263002 -2.10895 0 P 0 ;0
L 1.65708002 -2.10795 1.72303996 -2.10795 0 P 0 ;0
L 1.65673002 -2.10695 1.72343996 -2.10695 0 P 0 ;0
L 1.65638996 -2.10595 1.72385 -2.10595 0 P 0 ;0
L 1.65605 -2.10495 1.72425 -2.10495 0 P 0 ;0
L 1.6557 -2.10395 1.72466004 -2.10395 0 P 0 ;0
L 1.65536004 -2.10295 1.72506998 -2.10295 0 P 0 ;0
L 1.65501004 -2.10195 1.72546998 -2.10195 0 P 0 ;0
L 1.65466998 -2.10095 1.72588002 -2.10095 0 P 0 ;0
L 1.65431998 -2.09995 1.72628002 -2.09995 0 P 0 ;0
L 1.65398002 -2.09895 1.72668996 -2.09895 0 P 0 ;0
L 1.65363002 -2.09795 1.72708996 -2.09795 0 P 0 ;0
L 1.65328996 -2.09695 1.72748996 -2.09695 0 P 0 ;0
L 1.65293996 -2.09595 1.7279 -2.09595 0 P 0 ;0
L 1.6526 -2.09495 1.72831004 -2.09495 0 P 0 ;0
L 1.65225 -2.09395 1.72871004 -2.09395 0 P 0 ;0
L 1.65191004 -2.09295 1.72911998 -2.09295 0 P 0 ;0
L 1.65156998 -2.09195 1.72951998 -2.09195 0 P 0 ;0
L 1.65121998 -2.09095 1.72993002 -2.09095 0 P 0 ;0
L 1.65088002 -2.08995 1.73033002 -2.08995 0 P 0 ;0
L 1.65053002 -2.08895 1.73073996 -2.08895 0 P 0 ;0
L 1.65018996 -2.08795 1.73113996 -2.08795 0 P 0 ;0
L 1.64983996 -2.08695 1.73155 -2.08695 0 P 0 ;0
L 1.6495 -2.08595 1.73195 -2.08595 0 P 0 ;0
L 1.64915 -2.08495 1.73236004 -2.08495 0 P 0 ;0
L 1.64881004 -2.08395 1.73276004 -2.08395 0 P 0 ;0
L 1.81726998 -1.98915 1.81196004 -1.9899 0 P 0 ;0
L 1.81196004 -1.9899 1.80668996 -1.99096998 0 P 0 ;0
L 1.80668996 -1.99096998 1.8019 -1.99226004 0 P 0 ;0
L 1.8019 -1.99226004 1.79718996 -1.99391004 0 P 0 ;0
L 1.79718996 -1.99391004 1.79316004 -1.99568002 0 P 0 ;0
L 1.79316004 -1.99568002 1.78926998 -1.99778002 0 P 0 ;0
L 1.78926998 -1.99778002 1.78771004 -1.99878002 0 P 0 ;0
L 1.78771004 -1.99878002 1.78623002 -1.99988002 0 P 0 ;0
L 1.78623002 -1.99988002 1.78481004 -2.00108002 0 P 0 ;0
L 1.78481004 -2.00108002 1.78346998 -2.00238996 0 P 0 ;0
L 1.78346998 -2.00238996 1.78228996 -2.00371998 0 P 0 ;0
L 1.78228996 -2.00371998 1.78121004 -2.00513002 0 P 0 ;0
L 1.78121004 -2.00513002 1.78023002 -2.00661004 0 P 0 ;0
L 1.78023002 -2.00661004 1.77868002 -2.00933996 0 P 0 ;0
L 1.77868002 -2.00933996 1.77731998 -2.01216998 0 P 0 ;0
L 1.77731998 -2.01216998 1.77611004 -2.01516004 0 P 0 ;0
L 1.77611004 -2.01516004 1.77508996 -2.01823002 0 P 0 ;0
L 1.77508996 -2.01823002 1.77436998 -2.02111004 0 P 0 ;0
L 1.77436998 -2.02111004 1.77388996 -2.02406004 0 P 0 ;0
L 1.77388996 -2.02406004 1.77371998 -2.02603996 0 P 0 ;0
L 1.77371998 -2.02603996 1.77368996 -2.02801998 0 P 0 ;0
L 1.77368996 -2.02801998 1.7738 -2.03001998 0 P 0 ;0
L 1.7738 -2.03001998 1.7742 -2.03338996 0 P 0 ;0
L 1.7742 -2.03338996 1.77485 -2.03671004 0 P 0 ;0
L 1.77485 -2.03671004 1.77573002 -2.03993996 0 P 0 ;0
L 1.77573002 -2.03993996 1.77683996 -2.04308002 0 P 0 ;0
L 1.77683996 -2.04308002 1.7776 -2.04481998 0 P 0 ;0
L 1.7776 -2.04481998 1.7785 -2.04648996 0 P 0 ;0
L 1.7785 -2.04648996 1.77953002 -2.04808996 0 P 0 ;0
L 1.77953002 -2.04808996 1.78061004 -2.04953996 0 P 0 ;0
L 1.78061004 -2.04953996 1.78181004 -2.05091004 0 P 0 ;0
L 1.78181004 -2.05091004 1.78311004 -2.05218996 0 P 0 ;0
L 1.78311004 -2.05218996 1.78988996 -2.05801998 0 P 0 ;0
L 1.78988996 -2.05801998 1.79883996 -2.06491004 0 P 0 ;0
L 1.79883996 -2.06491004 1.80976998 -2.07261004 0 P 0 ;0
L 1.80976998 -2.07261004 1.81753002 -2.07823002 0 P 0 ;0
L 1.81753002 -2.07823002 1.81896998 -2.07943002 0 P 0 ;0
L 1.81896998 -2.07943002 1.82033002 -2.08073002 0 P 0 ;0
L 1.82033002 -2.08073002 1.82156998 -2.08213996 0 P 0 ;0
L 1.82156998 -2.08213996 1.82186004 -2.08251004 0 P 0 ;0
L 1.82186004 -2.08251004 1.82211004 -2.0829 0 P 0 ;0
L 1.82211004 -2.0829 1.82233002 -2.08331004 0 P 0 ;0
L 1.82233002 -2.08331004 1.82253002 -2.08373996 0 P 0 ;0
L 1.82253002 -2.08373996 1.82268002 -2.08418002 0 P 0 ;0
L 1.82268002 -2.08418002 1.82281004 -2.08463002 0 P 0 ;0
L 1.82281004 -2.08463002 1.8229 -2.0851 0 P 0 ;0
L 1.8229 -2.0851 1.82293002 -2.08533996 0 P 0 ;0
L 1.82293002 -2.08533996 1.82293996 -2.08558996 0 P 0 ;0
L 1.82293996 -2.08558996 1.82291998 -2.08583996 0 P 0 ;0
L 1.82291998 -2.08583996 1.82288002 -2.08608002 0 P 0 ;0
L 1.82288002 -2.08608002 1.82283002 -2.08631998 0 P 0 ;0
L 1.82283002 -2.08631998 1.82275 -2.08656004 0 P 0 ;0
L 1.82275 -2.08656004 1.82265 -2.08678996 0 P 0 ;0
L 1.82265 -2.08678996 1.82253996 -2.087 0 P 0 ;0
L 1.82253996 -2.087 1.8224 -2.08721004 0 P 0 ;0
L 1.8224 -2.08721004 1.82225 -2.08741004 0 P 0 ;0
L 1.82225 -2.08741004 1.82208996 -2.08758996 0 P 0 ;0
L 1.82208996 -2.08758996 1.8216 -2.08803996 0 P 0 ;0
L 1.8216 -2.08803996 1.82106998 -2.08845 0 P 0 ;0
L 1.82106998 -2.08845 1.82051004 -2.08881004 0 P 0 ;0
L 1.82051004 -2.08881004 1.81991998 -2.08911998 0 P 0 ;0
L 1.81991998 -2.08911998 1.81931004 -2.08936998 0 P 0 ;0
L 1.81931004 -2.08936998 1.81868002 -2.08958002 0 P 0 ;0
L 1.81868002 -2.08958002 1.81803002 -2.08973002 0 P 0 ;0
L 1.81803002 -2.08973002 1.81736004 -2.08981998 0 P 0 ;0
L 1.81736004 -2.08981998 1.81293002 -2.09001998 0 P 0 ;0
L 1.81293002 -2.09001998 1.80846998 -2.08986004 0 P 0 ;0
L 1.80846998 -2.08986004 1.80256998 -2.08923002 0 P 0 ;0
L 1.80256998 -2.08923002 1.79668002 -2.08818996 0 P 0 ;0
L 1.79668002 -2.08818996 1.78223002 -2.08458002 0 P 0 ;0
L 1.78223002 -2.08458002 1.77788996 -2.08338002 0 P 0 ;0
L 1.77788996 -2.08338002 1.77415 -2.08246004 0 P 0 ;0
L 1.77415 -2.08246004 1.77095 -2.08175 0 P 0 ;0
L 1.77095 -2.08175 1.7709 -2.08173996 0 P 0 ;0
L 1.7709 -2.08173996 1.77076998 -2.08173996 0 P 0 ;0
L 1.77076998 -2.08173996 1.77068996 -2.08176004 0 P 0 ;0
L 1.77068996 -2.08176004 1.77053002 -2.08183996 0 P 0 ;0
L 1.77053002 -2.08183996 1.77043002 -2.08193996 0 P 0 ;0
L 1.77043002 -2.08193996 1.77036998 -2.08201998 0 P 0 ;0
L 1.77036998 -2.08201998 1.77031998 -2.08211998 0 P 0 ;0
L 1.77031998 -2.08211998 1.7703 -2.08216998 0 P 0 ;0
L 1.7703 -2.08216998 1.77028996 -2.08223002 0 P 0 ;0
L 1.77028996 -2.08223002 1.77028002 -2.08228002 0 P 0 ;0
L 1.77028002 -2.08228002 1.77028002 -2.08238996 0 P 0 ;0
L 1.77028002 -2.08238996 1.77056998 -2.08838996 0 P 0 ;0
L 1.77056998 -2.08838996 1.77096004 -2.09526004 0 P 0 ;0
L 1.77096004 -2.09526004 1.77153996 -2.1033 0 P 0 ;0
L 1.77153996 -2.1033 1.77236004 -2.11291004 0 P 0 ;0
L 1.77236004 -2.11291004 1.77311004 -2.1194 0 P 0 ;0
L 1.77311004 -2.1194 1.77383002 -2.12398002 0 P 0 ;0
L 1.77383002 -2.12398002 1.77386004 -2.12411004 0 P 0 ;0
L 1.77386004 -2.12411004 1.7739 -2.12423002 0 P 0 ;0
L 1.7739 -2.12423002 1.77395 -2.12436004 0 P 0 ;0
L 1.77395 -2.12436004 1.77401004 -2.12448002 0 P 0 ;0
L 1.77401004 -2.12448002 1.77408002 -2.12458996 0 P 0 ;0
L 1.77408002 -2.12458996 1.77416004 -2.1247 0 P 0 ;0
L 1.77416004 -2.1247 1.77425 -2.1248 0 P 0 ;0
L 1.77425 -2.1248 1.77435 -2.12488996 0 P 0 ;0
L 1.77435 -2.12488996 1.77445 -2.12496998 0 P 0 ;0
L 1.77445 -2.12496998 1.77456998 -2.12505 0 P 0 ;0
L 1.77456998 -2.12505 1.77571004 -2.12568996 0 P 0 ;0
L 1.77571004 -2.12568996 1.7769 -2.12623996 0 P 0 ;0
L 1.7769 -2.12623996 1.77813002 -2.12668996 0 P 0 ;0
L 1.77813002 -2.12668996 1.7794 -2.12703996 0 P 0 ;0
L 1.7794 -2.12703996 1.78068996 -2.12728996 0 P 0 ;0
L 1.78068996 -2.12728996 1.79791998 -2.12951004 0 P 0 ;0
L 1.79791998 -2.12951004 1.81536004 -2.13106004 0 P 0 ;0
L 1.81536004 -2.13106004 1.82125 -2.13123996 0 P 0 ;0
L 1.82125 -2.13123996 1.82716004 -2.13098996 0 P 0 ;0
L 1.82716004 -2.13098996 1.83583996 -2.12998002 0 P 0 ;0
L 1.83583996 -2.12998002 1.84445 -2.12836004 0 P 0 ;0
L 1.84445 -2.12836004 1.84911998 -2.12711004 0 P 0 ;0
L 1.84911998 -2.12711004 1.85366004 -2.12548002 0 P 0 ;0
L 1.85366004 -2.12548002 1.85806998 -2.12348002 0 P 0 ;0
L 1.85806998 -2.12348002 1.86078996 -2.12196998 0 P 0 ;0
L 1.86078996 -2.12196998 1.8634 -2.12026998 0 P 0 ;0
L 1.8634 -2.12026998 1.86586998 -2.11836998 0 P 0 ;0
L 1.86586998 -2.11836998 1.86821004 -2.11628002 0 P 0 ;0
L 1.86821004 -2.11628002 1.87026004 -2.11413002 0 P 0 ;0
L 1.87026004 -2.11413002 1.8721 -2.11181998 0 P 0 ;0
L 1.8721 -2.11181998 1.87375 -2.10936004 0 P 0 ;0
L 1.87375 -2.10936004 1.87516998 -2.10673996 0 P 0 ;0
L 1.87516998 -2.10673996 1.87605 -2.10483996 0 P 0 ;0
L 1.87605 -2.10483996 1.87683996 -2.10291004 0 P 0 ;0
L 1.87683996 -2.10291004 1.8772 -2.10188002 0 P 0 ;0
L 1.8772 -2.10188002 1.87748996 -2.10083002 0 P 0 ;0
L 1.87748996 -2.10083002 1.87771004 -2.09976998 0 P 0 ;0
L 1.87771004 -2.09976998 1.87798002 -2.09788996 0 P 0 ;0
L 1.87798002 -2.09788996 1.87811998 -2.09601004 0 P 0 ;0
L 1.87811998 -2.09601004 1.87821004 -2.08966998 0 P 0 ;0
L 1.87821004 -2.08966998 1.8781 -2.08353996 0 P 0 ;0
L 1.8781 -2.08353996 1.87798002 -2.08166004 0 P 0 ;0
L 1.87798002 -2.08166004 1.87773002 -2.07976998 0 P 0 ;0
L 1.87773002 -2.07976998 1.87753002 -2.07873996 0 P 0 ;0
L 1.87753002 -2.07873996 1.87726998 -2.07773996 0 P 0 ;0
L 1.87726998 -2.07773996 1.87695 -2.07673996 0 P 0 ;0
L 1.87695 -2.07673996 1.87628996 -2.07505 0 P 0 ;0
L 1.87628996 -2.07505 1.87553002 -2.07338002 0 P 0 ;0
L 1.87553002 -2.07338002 1.87441004 -2.07133996 0 P 0 ;0
L 1.87441004 -2.07133996 1.87313996 -2.06938002 0 P 0 ;0
L 1.87313996 -2.06938002 1.87171004 -2.06751004 0 P 0 ;0
L 1.87171004 -2.06751004 1.8688 -2.06416004 0 P 0 ;0
L 1.8688 -2.06416004 1.86566998 -2.06095 0 P 0 ;0
L 1.86566998 -2.06095 1.86181998 -2.05741998 0 P 0 ;0
L 1.86181998 -2.05741998 1.85778002 -2.05406998 0 P 0 ;0
L 1.85778002 -2.05406998 1.84833996 -2.04715 0 P 0 ;0
L 1.84833996 -2.04715 1.83913996 -2.0407 0 P 0 ;0
L 1.83913996 -2.0407 1.83686004 -2.0389 0 P 0 ;0
L 1.83686004 -2.0389 1.83471998 -2.03691998 0 P 0 ;0
L 1.83471998 -2.03691998 1.83428002 -2.03643002 0 P 0 ;0
L 1.83428002 -2.03643002 1.83386998 -2.0359 0 P 0 ;0
L 1.83386998 -2.0359 1.83351004 -2.03535 0 P 0 ;0
L 1.83351004 -2.03535 1.83318996 -2.03476004 0 P 0 ;0
L 1.83318996 -2.03476004 1.83291998 -2.03415 0 P 0 ;0
L 1.83291998 -2.03415 1.83283996 -2.03393996 0 P 0 ;0
L 1.83283996 -2.03393996 1.83278002 -2.03371004 0 P 0 ;0
L 1.83278002 -2.03371004 1.83273002 -2.03348996 0 P 0 ;0
L 1.83273002 -2.03348996 1.83271004 -2.03326004 0 P 0 ;0
L 1.83271004 -2.03326004 1.8327 -2.03303002 0 P 0 ;0
L 1.8327 -2.03303002 1.83271004 -2.0328 0 P 0 ;0
L 1.83271004 -2.0328 1.83275 -2.03258002 0 P 0 ;0
L 1.83275 -2.03258002 1.83278996 -2.03235 0 P 0 ;0
L 1.83278996 -2.03235 1.83286004 -2.03213002 0 P 0 ;0
L 1.83286004 -2.03213002 1.83293996 -2.03191998 0 P 0 ;0
L 1.83293996 -2.03191998 1.83305 -2.03171004 0 P 0 ;0
L 1.83305 -2.03171004 1.83325 -2.03135 0 P 0 ;0
L 1.83325 -2.03135 1.83348996 -2.03101998 0 P 0 ;0
L 1.83348996 -2.03101998 1.83375 -2.03071004 0 P 0 ;0
L 1.83375 -2.03071004 1.83403002 -2.03041004 0 P 0 ;0
L 1.83403002 -2.03041004 1.83433996 -2.03015 0 P 0 ;0
L 1.83433996 -2.03015 1.83466998 -2.02991004 0 P 0 ;0
L 1.83466998 -2.02991004 1.83501998 -2.02968996 0 P 0 ;0
L 1.83501998 -2.02968996 1.83538002 -2.02951004 0 P 0 ;0
L 1.83538002 -2.02951004 1.83576004 -2.02936004 0 P 0 ;0
L 1.83576004 -2.02936004 1.83615 -2.02923996 0 P 0 ;0
L 1.83615 -2.02923996 1.83655 -2.02915 0 P 0 ;0
L 1.83655 -2.02915 1.8392 -2.02873996 0 P 0 ;0
L 1.8392 -2.02873996 1.84188002 -2.0285 0 P 0 ;0
L 1.84188002 -2.0285 1.84458002 -2.02841004 0 P 0 ;0
L 1.84458002 -2.02841004 1.84993996 -2.02858002 0 P 0 ;0
L 1.84993996 -2.02858002 1.85526998 -2.02916004 0 P 0 ;0
L 1.85526998 -2.02916004 1.86155 -2.03023002 0 P 0 ;0
L 1.86155 -2.03023002 1.86778002 -2.03158002 0 P 0 ;0
L 1.86778002 -2.03158002 1.8713 -2.03238996 0 P 0 ;0
L 1.8713 -2.03238996 1.87428996 -2.03303002 0 P 0 ;0
L 1.87428996 -2.03303002 1.8769 -2.03356004 0 P 0 ;0
L 1.8769 -2.03356004 1.87691998 -2.03356998 0 P 0 ;0
L 1.87691998 -2.03356998 1.87696004 -2.03356998 0 P 0 ;0
L 1.87696004 -2.03356998 1.87696998 -2.03356004 0 P 0 ;0
L 1.87696998 -2.03356004 1.87701004 -2.03356004 0 P 0 ;0
L 1.87701004 -2.03356004 1.87703996 -2.03353996 0 P 0 ;0
L 1.87703996 -2.03353996 1.87706004 -2.03353002 0 P 0 ;0
L 1.87706004 -2.03353002 1.87706998 -2.03351998 0 P 0 ;0
L 1.87706998 -2.03351998 1.87708996 -2.03351004 0 P 0 ;0
L 1.87708996 -2.03351004 1.8771 -2.03348996 0 P 0 ;0
L 1.8771 -2.03348996 1.87711004 -2.03348002 0 P 0 ;0
L 1.87711004 -2.03348002 1.87721998 -2.0333 0 P 0 ;0
L 1.87721998 -2.0333 1.87731998 -2.0331 0 P 0 ;0
L 1.87731998 -2.0331 1.8774 -2.0329 0 P 0 ;0
L 1.8774 -2.0329 1.87746004 -2.03268996 0 P 0 ;0
L 1.87746004 -2.03268996 1.87751004 -2.03248002 0 P 0 ;0
L 1.87751004 -2.03248002 1.87753002 -2.03226998 0 P 0 ;0
L 1.87753002 -2.03226998 1.87753996 -2.03205 0 P 0 ;0
L 1.87753996 -2.03205 1.87753002 -2.03183002 0 P 0 ;0
L 1.87753002 -2.03183002 1.87565 -2.01323996 0 P 0 ;0
L 1.87565 -2.01323996 1.87371004 -1.99451998 0 P 0 ;0
L 1.87371004 -1.99451998 1.8737 -1.99438996 0 P 0 ;0
L 1.8737 -1.99438996 1.87366998 -1.99426998 0 P 0 ;0
L 1.87366998 -1.99426998 1.87363002 -1.99415 0 P 0 ;0
L 1.87363002 -1.99415 1.87358002 -1.99403002 0 P 0 ;0
L 1.87358002 -1.99403002 1.87351998 -1.99391004 0 P 0 ;0
L 1.87351998 -1.99391004 1.87346004 -1.9938 0 P 0 ;0
L 1.87346004 -1.9938 1.87338002 -1.9937 0 P 0 ;0
L 1.87338002 -1.9937 1.87328996 -1.9936 0 P 0 ;0
L 1.87328996 -1.9936 1.8732 -1.99351004 0 P 0 ;0
L 1.8732 -1.99351004 1.8731 -1.99343002 0 P 0 ;0
L 1.8731 -1.99343002 1.87298996 -1.99335 0 P 0 ;0
L 1.87298996 -1.99335 1.87248002 -1.99305 0 P 0 ;0
L 1.87248002 -1.99305 1.87193996 -1.99278002 0 P 0 ;0
L 1.87193996 -1.99278002 1.87136998 -1.99256998 0 P 0 ;0
L 1.87136998 -1.99256998 1.87078996 -1.99241004 0 P 0 ;0
L 1.87078996 -1.99241004 1.8702 -1.9923 0 P 0 ;0
L 1.8702 -1.9923 1.85876004 -1.99076004 0 P 0 ;0
L 1.85876004 -1.99076004 1.84691998 -1.98943002 0 P 0 ;0
L 1.84691998 -1.98943002 1.83693002 -1.98876004 0 P 0 ;0
L 1.83693002 -1.98876004 1.8318 -1.98863002 0 P 0 ;0
L 1.8318 -1.98863002 1.82623002 -1.98866998 0 P 0 ;0
L 1.82623002 -1.98866998 1.82106004 -1.98883996 0 P 0 ;0
L 1.82106004 -1.98883996 1.81726998 -1.98915 0 P 0 ;0
L 1.78061004 -2.12523996 1.84838002 -2.12523996 0 P 0 ;0
L 1.77733002 -2.12423996 1.85121004 -2.12423996 0 P 0 ;0
L 1.77573996 -2.12323996 1.85376998 -2.12323996 0 P 0 ;0
L 1.77558002 -2.12223996 1.85596998 -2.12223996 0 P 0 ;0
L 1.77541998 -2.12123996 1.85798996 -2.12123996 0 P 0 ;0
L 1.77526998 -2.12023996 1.85978996 -2.12023996 0 P 0 ;0
L 1.77511004 -2.11923996 1.86131998 -2.11923996 0 P 0 ;0
L 1.77498996 -2.11823996 1.86276004 -2.11823996 0 P 0 ;0
L 1.77486998 -2.11723996 1.86406998 -2.11723996 0 P 0 ;0
L 1.77475 -2.11623996 1.86526004 -2.11623996 0 P 0 ;0
L 1.77463996 -2.11523996 1.86638002 -2.11523996 0 P 0 ;0
L 1.77451998 -2.11423996 1.8674 -2.11423996 0 P 0 ;0
L 1.77441004 -2.11323996 1.86835 -2.11323996 0 P 0 ;0
L 1.77431004 -2.11223996 1.86921004 -2.11223996 0 P 0 ;0
L 1.77421998 -2.11123996 1.87001004 -2.11123996 0 P 0 ;0
L 1.77413996 -2.11023996 1.87075 -2.11023996 0 P 0 ;0
L 1.77405 -2.10923996 1.87141998 -2.10923996 0 P 0 ;0
L 1.77396998 -2.10823996 1.87208002 -2.10823996 0 P 0 ;0
L 1.77388002 -2.10723996 1.87261998 -2.10723996 0 P 0 ;0
L 1.7738 -2.10623996 1.87316998 -2.10623996 0 P 0 ;0
L 1.77371004 -2.10523996 1.87366004 -2.10523996 0 P 0 ;0
L 1.77363002 -2.10423996 1.87411998 -2.10423996 0 P 0 ;0
L 1.77353996 -2.10323996 1.87453996 -2.10323996 0 P 0 ;0
L 1.77346998 -2.10223996 1.87495 -2.10223996 0 P 0 ;0
L 1.7734 -2.10123996 1.8753 -2.10123996 0 P 0 ;0
L 1.77333002 -2.10023996 1.87556998 -2.10023996 0 P 0 ;0
L 1.77325 -2.09923996 1.87576998 -2.09923996 0 P 0 ;0
L 1.77318002 -2.09823996 1.87591998 -2.09823996 0 P 0 ;0
L 1.77311004 -2.09723996 1.87603002 -2.09723996 0 P 0 ;0
L 1.77303996 -2.09623996 1.8761 -2.09623996 0 P 0 ;0
L 1.77296998 -2.09523996 1.87613002 -2.09523996 0 P 0 ;0
L 1.77291004 -2.09423996 1.87613996 -2.09423996 0 P 0 ;0
L 1.77285 -2.09323996 1.87616004 -2.09323996 0 P 0 ;0
L 1.77278996 -2.09223996 1.87616998 -2.09223996 0 P 0 ;0
L 1.77273002 -2.09123996 1.80256998 -2.09123996 0 P 0 ;0
L 1.77268002 -2.09023996 1.7968 -2.09023996 0 P 0 ;0
L 1.77261998 -2.08923996 1.79263002 -2.08923996 0 P 0 ;0
L 1.77256004 -2.08823996 1.78861998 -2.08823996 0 P 0 ;0
L 1.77251004 -2.08723996 1.7846 -2.08723996 0 P 0 ;0
L 1.77246004 -2.08623996 1.7807 -2.08623996 0 P 0 ;0
L 1.77241998 -2.08523996 1.77705 -2.08523996 0 P 0 ;0
L 1.77236998 -2.08423996 1.77293996 -2.08423996 0 P 0 ;0
L 1.62463996 -2.18195 1.65948996 -2.18195 0 P 0 ;0
L 1.61963996 -2.18095 1.66483002 -2.18095 0 P 0 ;0
L 1.61818002 -1.99795 1.6724 -1.99795 0 P 0 ;0
L 1.61778996 -1.99695 1.67218002 -1.99695 0 P 0 ;0
L 1.6174 -1.99595 1.67196004 -1.99595 0 P 0 ;0
L 1.61701004 -1.99495 1.67173996 -1.99495 0 P 0 ;0
L 1.61391998 -2.15695 1.70026004 -2.15695 0 P 0 ;0
L 1.61386004 -2.15595 1.70088002 -2.15595 0 P 0 ;0
L 1.61381004 -2.15495 1.70151004 -2.15495 0 P 0 ;0
L 1.61375 -2.15395 1.70213996 -2.15395 0 P 0 ;0
L 1.6137 -2.15295 1.70276004 -2.15295 0 P 0 ;0
L 1.61365 -2.15195 1.70338996 -2.15195 0 P 0 ;0
L 1.6136 -2.15095 1.70401004 -2.15095 0 P 0 ;0
L 1.61355 -2.14995 1.70456998 -2.14995 0 P 0 ;0
L 1.61348996 -2.14895 1.70511998 -2.14895 0 P 0 ;0
L 1.61343996 -2.14795 1.61738002 -2.14795 0 P 0 ;0
L 1.55341004 -2.08286998 1.60538002 -2.08286998 0 P 0 ;0
L 1.55286004 -2.08186998 1.60526998 -2.08186998 0 P 0 ;0
L 1.5521 -2.08086998 1.6051 -2.08086998 0 P 0 ;0
L 1.55126998 -2.07986998 1.6049 -2.07986998 0 P 0 ;0
L 1.55033996 -2.07886998 1.60463996 -2.07886998 0 P 0 ;0
L 1.54928996 -2.07786998 1.60433002 -2.07786998 0 P 0 ;0
L 1.54806998 -2.07686998 1.60398996 -2.07686998 0 P 0 ;0
L 1.5467 -2.07586998 1.60356998 -2.07586998 0 P 0 ;0
L 1.54531004 -2.07486998 1.6031 -2.07486998 0 P 0 ;0
L 1.54391004 -2.07386998 1.60258996 -2.07386998 0 P 0 ;0
L 1.54251004 -2.07286998 1.60201004 -2.07286998 0 P 0 ;0
L 1.54111998 -2.07186998 1.60138002 -2.07186998 0 P 0 ;0
L 1.53971998 -2.07086998 1.60068002 -2.07086998 0 P 0 ;0
L 1.53833002 -2.06986998 1.59993002 -2.06986998 0 P 0 ;0
L 1.53693002 -2.06886998 1.59908002 -2.06886998 0 P 0 ;0
L 1.53556004 -2.06786998 1.59821004 -2.06786998 0 P 0 ;0
L 1.53418996 -2.06686998 1.59733996 -2.06686998 0 P 0 ;0
L 1.53281998 -2.06586998 1.59646998 -2.06586998 0 P 0 ;0
L 1.53145 -2.06486998 1.5955 -2.06486998 0 P 0 ;0
L 1.53008002 -2.06386998 1.59453002 -2.06386998 0 P 0 ;0
L 1.52871004 -2.06286998 1.59356004 -2.06286998 0 P 0 ;0
L 1.52733996 -2.06186998 1.59253002 -2.06186998 0 P 0 ;0
L 1.52596998 -2.06086998 1.59145 -2.06086998 0 P 0 ;0
L 1.5246 -2.05986998 1.59038002 -2.05986998 0 P 0 ;0
L 1.52323002 -2.05886998 1.5893 -2.05886998 0 P 0 ;0
L 1.52186004 -2.05786998 1.58813996 -2.05786998 0 P 0 ;0
L 1.52053996 -2.05686998 1.58696004 -2.05686998 0 P 0 ;0
L 1.51935 -2.05586998 1.58576998 -2.05586998 0 P 0 ;0
L 1.51816004 -2.05486998 1.58456998 -2.05486998 0 P 0 ;0
L 1.51706998 -2.05386998 1.58321004 -2.05386998 0 P 0 ;0
L 1.51603996 -2.05286998 1.58185 -2.05286998 0 P 0 ;0
L 1.51501998 -2.05186998 1.58048996 -2.05186998 0 P 0 ;0
L 1.51408996 -2.05086998 1.57913002 -2.05086998 0 P 0 ;0
L 1.5132 -2.04986998 1.57776998 -2.04986998 0 P 0 ;0
L 1.51231998 -2.04886998 1.57641998 -2.04886998 0 P 0 ;0
L 1.51151004 -2.04786998 1.57505 -2.04786998 0 P 0 ;0
L 1.51075 -2.04686998 1.57365 -2.04686998 0 P 0 ;0
L 1.51008002 -2.04586998 1.57223002 -2.04586998 0 P 0 ;0
L 1.50945 -2.04486998 1.57081004 -2.04486998 0 P 0 ;0
L 1.50888002 -2.04386998 1.56938996 -2.04386998 0 P 0 ;0
L 1.50836004 -2.04286998 1.56796998 -2.04286998 0 P 0 ;0
L 1.5079 -2.04186998 1.56655 -2.04186998 0 P 0 ;0
L 1.50748002 -2.04086998 1.56518996 -2.04086998 0 P 0 ;0
L 1.50708996 -2.03986998 1.564 -2.03986998 0 P 0 ;0
L 1.50676004 -2.03886998 1.56296998 -2.03886998 0 P 0 ;0
L 1.50641998 -2.03786998 1.56206004 -2.03786998 0 P 0 ;0
L 1.50616998 -2.03686998 1.56125 -2.03686998 0 P 0 ;0
L 1.50591004 -2.03586998 1.56066998 -2.03586998 0 P 0 ;0
L 1.5057 -2.03486998 1.56031998 -2.03486998 0 P 0 ;0
L 1.50551998 -2.03386998 1.56016004 -2.03386998 0 P 0 ;0
L 1.50533996 -2.03286998 1.56016998 -2.03286998 0 P 0 ;0
L 1.50523996 -2.03186998 1.56036004 -2.03186998 0 P 0 ;0
L 1.50513002 -2.03086998 1.56071998 -2.03086998 0 P 0 ;0
L 1.50506998 -2.02986998 1.56131004 -2.02986998 0 P 0 ;0
L 1.50503996 -2.02886998 1.5622 -2.02886998 0 P 0 ;0
L 1.50501004 -2.02786998 1.56355 -2.02786998 0 P 0 ;0
L 1.50501998 -2.02686998 1.5657 -2.02686998 0 P 0 ;0
L 1.50506998 -2.02586998 1.60378996 -2.02586998 0 P 0 ;0
L 1.50511998 -2.02486998 1.60371004 -2.02486998 0 P 0 ;0
L 1.50521004 -2.02386998 1.60363996 -2.02386998 0 P 0 ;0
L 1.50533996 -2.02286998 1.60356998 -2.02286998 0 P 0 ;0
L 1.50546998 -2.02186998 1.6035 -2.02186998 0 P 0 ;0
L 1.50563996 -2.02086998 1.60343002 -2.02086998 0 P 0 ;0
L 1.50585 -2.01986998 1.60336004 -2.01986998 0 P 0 ;0
L 1.50606004 -2.01886998 1.60328996 -2.01886998 0 P 0 ;0
L 1.50633002 -2.01786998 1.60321998 -2.01786998 0 P 0 ;0
L 1.50661998 -2.01686998 1.60315 -2.01686998 0 P 0 ;0
L 1.50691004 -2.01586998 1.60308002 -2.01586998 0 P 0 ;0
L 1.50726998 -2.01486998 1.603 -2.01486998 0 P 0 ;0
L 1.50766004 -2.01386998 1.60293002 -2.01386998 0 P 0 ;0
L 1.50808996 -2.01286998 1.60285 -2.01286998 0 P 0 ;0
L 1.50856998 -2.01186998 1.60278002 -2.01186998 0 P 0 ;0
L 1.50908996 -2.01086998 1.6027 -2.01086998 0 P 0 ;0
L 1.50966004 -2.00986998 1.60261998 -2.00986998 0 P 0 ;0
L 1.51028996 -2.00886998 1.60255 -2.00886998 0 P 0 ;0
L 1.51096998 -2.00786998 1.60246998 -2.00786998 0 P 0 ;0
L 1.51171998 -2.00686998 1.6024 -2.00686998 0 P 0 ;0
L 1.51253996 -2.00586998 1.60233002 -2.00586998 0 P 0 ;0
L 1.51343996 -2.00486998 1.60225 -2.00486998 0 P 0 ;0
L 1.5144 -2.00386998 1.60218002 -2.00386998 0 P 0 ;0
L 1.51551998 -2.00286998 1.6021 -2.00286998 0 P 0 ;0
L 1.51663996 -2.00186998 1.60203002 -2.00186998 0 P 0 ;0
L 1.51795 -2.00086998 1.60195 -2.00086998 0 P 0 ;0
L 1.51928996 -1.99986998 1.60183996 -1.99986998 0 P 0 ;0
L 1.52086998 -1.99886998 1.60173002 -1.99886998 0 P 0 ;0
L 1.52258996 -1.99786998 1.60156998 -1.99786998 0 P 0 ;0
L 1.52451004 -1.99686998 1.60138996 -1.99686998 0 P 0 ;0
L 1.52686998 -1.99586998 1.60106998 -1.99586998 0 P 0 ;0
L 1.52976004 -1.99486998 1.59943996 -1.99486998 0 P 0 ;0
L 1.53283002 -1.99386998 1.59543002 -1.99386998 0 P 0 ;0
L 1.53678996 -1.99286998 1.59003996 -1.99286998 0 P 0 ;0
L 1.54173996 -1.99186998 1.58073996 -1.99186998 0 P 0 ;0
L 1.55036998 -1.99086998 1.56493002 -1.99086998 0 P 0 ;0
L 1.6036 -2.03086998 1.60413996 -2.03086998 0 P 0 ;0
L 1.59891004 -2.02986998 1.60406998 -2.02986998 0 P 0 ;0
L 1.59435 -2.02886998 1.604 -2.02886998 0 P 0 ;0
L 1.58838996 -2.02786998 1.60393002 -2.02786998 0 P 0 ;0
L 1.57981004 -2.02686998 1.60386004 -2.02686998 0 P 0 ;0
L 1.54575 -1.98923996 1.53931998 -1.99021998 0 P 0 ;0
L 1.53931998 -1.99021998 1.53298996 -1.99171998 0 P 0 ;0
L 1.53298996 -1.99171998 1.52678996 -1.99373996 0 P 0 ;0
L 1.52678996 -1.99373996 1.52376998 -1.995 0 P 0 ;0
L 1.52376998 -1.995 1.52086998 -1.99651004 0 P 0 ;0
L 1.52086998 -1.99651004 1.5181 -1.99826004 0 P 0 ;0
L 1.5181 -1.99826004 1.51548002 -2.00023002 0 P 0 ;0
L 1.51548002 -2.00023002 1.51301004 -2.00243002 0 P 0 ;0
L 1.51301004 -2.00243002 1.51128996 -2.00423002 0 P 0 ;0
L 1.51128996 -2.00423002 1.50971998 -2.00616004 0 P 0 ;0
L 1.50971998 -2.00616004 1.50831004 -2.00821004 0 P 0 ;0
L 1.50831004 -2.00821004 1.50706998 -2.01036998 0 P 0 ;0
L 1.50706998 -2.01036998 1.50598996 -2.01261998 0 P 0 ;0
L 1.50598996 -2.01261998 1.50508996 -2.01496998 0 P 0 ;0
L 1.50508996 -2.01496998 1.5042 -2.01801004 0 P 0 ;0
L 1.5042 -2.01801004 1.50355 -2.02111004 0 P 0 ;0
L 1.50355 -2.02111004 1.50313996 -2.02426004 0 P 0 ;0
L 1.50313996 -2.02426004 1.50298996 -2.02743002 0 P 0 ;0
L 1.50298996 -2.02743002 1.50308996 -2.03063002 0 P 0 ;0
L 1.50308996 -2.03063002 1.50338002 -2.03326998 0 P 0 ;0
L 1.50338002 -2.03326998 1.50385 -2.03588002 0 P 0 ;0
L 1.50385 -2.03588002 1.50451004 -2.03845 0 P 0 ;0
L 1.50451004 -2.03845 1.50535 -2.04096998 0 P 0 ;0
L 1.50535 -2.04096998 1.50633002 -2.0433 0 P 0 ;0
L 1.50633002 -2.0433 1.5075 -2.04553002 0 P 0 ;0
L 1.5075 -2.04553002 1.50883996 -2.04766998 0 P 0 ;0
L 1.50883996 -2.04766998 1.51036998 -2.04968996 0 P 0 ;0
L 1.51036998 -2.04968996 1.51323002 -2.05291998 0 P 0 ;0
L 1.51323002 -2.05291998 1.51631998 -2.05593996 0 P 0 ;0
L 1.51631998 -2.05593996 1.51961998 -2.05871004 0 P 0 ;0
L 1.51961998 -2.05871004 1.53591004 -2.0706 0 P 0 ;0
L 1.53591004 -2.0706 1.54668002 -2.07831004 0 P 0 ;0
L 1.54668002 -2.07831004 1.54793996 -2.07933996 0 P 0 ;0
L 1.54793996 -2.07933996 1.54911998 -2.08046998 0 P 0 ;0
L 1.54911998 -2.08046998 1.55021004 -2.08168002 0 P 0 ;0
L 1.55021004 -2.08168002 1.5512 -2.08298996 0 P 0 ;0
L 1.5512 -2.08298996 1.55136004 -2.08323002 0 P 0 ;0
L 1.55136004 -2.08323002 1.5515 -2.08348002 0 P 0 ;0
L 1.5515 -2.08348002 1.55161004 -2.08373996 0 P 0 ;0
L 1.55161004 -2.08373996 1.5517 -2.08401998 0 P 0 ;0
L 1.5517 -2.08401998 1.55176998 -2.0843 0 P 0 ;0
L 1.55176998 -2.0843 1.55181004 -2.08458002 0 P 0 ;0
L 1.55181004 -2.08458002 1.55183002 -2.08486998 0 P 0 ;0
L 1.55183002 -2.08486998 1.55181998 -2.08516004 0 P 0 ;0
L 1.55181998 -2.08516004 1.55178996 -2.08545 0 P 0 ;0
L 1.55178996 -2.08545 1.55173996 -2.08573002 0 P 0 ;0
L 1.55173996 -2.08573002 1.55166004 -2.086 0 P 0 ;0
L 1.55166004 -2.086 1.55156004 -2.08628002 0 P 0 ;0
L 1.55156004 -2.08628002 1.55136998 -2.08666998 0 P 0 ;0
L 1.55136998 -2.08666998 1.55115 -2.08703996 0 P 0 ;0
L 1.55115 -2.08703996 1.5509 -2.08738996 0 P 0 ;0
L 1.5509 -2.08738996 1.55063002 -2.08771998 0 P 0 ;0
L 1.55063002 -2.08771998 1.55033002 -2.08803002 0 P 0 ;0
L 1.55033002 -2.08803002 1.55 -2.08831004 0 P 0 ;0
L 1.55 -2.08831004 1.54966004 -2.08856004 0 P 0 ;0
L 1.54966004 -2.08856004 1.54928996 -2.08878996 0 P 0 ;0
L 1.54928996 -2.08878996 1.5489 -2.08898996 0 P 0 ;0
L 1.5489 -2.08898996 1.54786004 -2.08941004 0 P 0 ;0
L 1.54786004 -2.08941004 1.54678996 -2.08973996 0 P 0 ;0
L 1.54678996 -2.08973996 1.54568002 -2.08998002 0 P 0 ;0
L 1.54568002 -2.08998002 1.54456998 -2.09011998 0 P 0 ;0
L 1.54456998 -2.09011998 1.54343996 -2.09016998 0 P 0 ;0
L 1.54343996 -2.09016998 1.53906998 -2.09003002 0 P 0 ;0
L 1.53906998 -2.09003002 1.53468002 -2.08961998 0 P 0 ;0
L 1.53468002 -2.08961998 1.52908996 -2.08878996 0 P 0 ;0
L 1.52908996 -2.08878996 1.52351004 -2.08766004 0 P 0 ;0
L 1.52351004 -2.08766004 1.51005 -2.08418996 0 P 0 ;0
L 1.51005 -2.08418996 1.50631004 -2.08318002 0 P 0 ;0
L 1.50631004 -2.08318002 1.50308002 -2.08238996 0 P 0 ;0
L 1.50308002 -2.08238996 1.50033996 -2.08183002 0 P 0 ;0
L 1.50033996 -2.08183002 1.5003 -2.08181998 0 P 0 ;0
L 1.5003 -2.08181998 1.50016004 -2.08181998 0 P 0 ;0
L 1.50016004 -2.08181998 1.50011998 -2.08183002 0 P 0 ;0
L 1.50011998 -2.08183002 1.50006998 -2.08183996 0 P 0 ;0
L 1.50006998 -2.08183996 1.50003002 -2.08186004 0 P 0 ;0
L 1.50003002 -2.08186004 1.49998996 -2.08186998 0 P 0 ;0
L 1.49998996 -2.08186998 1.49995 -2.08188996 0 P 0 ;0
L 1.49995 -2.08188996 1.49991004 -2.08191998 0 P 0 ;0
L 1.49991004 -2.08191998 1.49988002 -2.08195 0 P 0 ;0
L 1.49988002 -2.08195 1.49983996 -2.08198002 0 P 0 ;0
L 1.49983996 -2.08198002 1.4997 -2.08213996 0 P 0 ;0
L 1.4997 -2.08213996 1.49956004 -2.08231998 0 P 0 ;0
L 1.49956004 -2.08231998 1.49943996 -2.0825 0 P 0 ;0
L 1.49943996 -2.0825 1.49933996 -2.0827 0 P 0 ;0
L 1.49933996 -2.0827 1.49925 -2.0829 0 P 0 ;0
L 1.49925 -2.0829 1.49918996 -2.08311004 0 P 0 ;0
L 1.49918996 -2.08311004 1.49913996 -2.08333002 0 P 0 ;0
L 1.49913996 -2.08333002 1.49911004 -2.08355 0 P 0 ;0
L 1.49911004 -2.08355 1.4991 -2.08376998 0 P 0 ;0
L 1.4991 -2.08376998 1.49911004 -2.08398996 0 P 0 ;0
L 1.49911004 -2.08398996 1.50071004 -2.10395 0 P 0 ;0
L 1.50071004 -2.10395 1.5024 -2.12403996 0 P 0 ;0
L 1.5024 -2.12403996 1.50241998 -2.12418002 0 P 0 ;0
L 1.50241998 -2.12418002 1.50246004 -2.12431004 0 P 0 ;0
L 1.50246004 -2.12431004 1.50248996 -2.12445 0 P 0 ;0
L 1.50248996 -2.12445 1.50255 -2.12456998 0 P 0 ;0
L 1.50255 -2.12456998 1.50261004 -2.1247 0 P 0 ;0
L 1.50261004 -2.1247 1.50276998 -2.12491998 0 P 0 ;0
L 1.50276998 -2.12491998 1.50286004 -2.12501998 0 P 0 ;0
L 1.50286004 -2.12501998 1.50296998 -2.12511998 0 P 0 ;0
L 1.50296998 -2.12511998 1.50308002 -2.12521004 0 P 0 ;0
L 1.50308002 -2.12521004 1.50318996 -2.12528002 0 P 0 ;0
L 1.50318996 -2.12528002 1.50331998 -2.12535 0 P 0 ;0
L 1.50331998 -2.12535 1.50343996 -2.1254 0 P 0 ;0
L 1.50343996 -2.1254 1.50391998 -2.12556004 0 P 0 ;0
L 1.50391998 -2.12556004 1.5044 -2.12568996 0 P 0 ;0
L 1.5044 -2.12568996 1.50848002 -2.12648996 0 P 0 ;0
L 1.50848002 -2.12648996 1.51328996 -2.12738002 0 P 0 ;0
L 1.51328996 -2.12738002 1.51873996 -2.12833996 0 P 0 ;0
L 1.51873996 -2.12833996 1.52606004 -2.12945 0 P 0 ;0
L 1.52606004 -2.12945 1.53343996 -2.13023002 0 P 0 ;0
L 1.53343996 -2.13023002 1.54886998 -2.13086998 0 P 0 ;0
L 1.54886998 -2.13086998 1.56305 -2.1303 0 P 0 ;0
L 1.56305 -2.1303 1.56666004 -2.12988996 0 P 0 ;0
L 1.56666004 -2.12988996 1.57023002 -2.12926998 0 P 0 ;0
L 1.57023002 -2.12926998 1.5738 -2.12843002 0 P 0 ;0
L 1.5738 -2.12843002 1.57945 -2.12668996 0 P 0 ;0
L 1.57945 -2.12668996 1.58498002 -2.12456998 0 P 0 ;0
L 1.58498002 -2.12456998 1.58793996 -2.12318002 0 P 0 ;0
L 1.58793996 -2.12318002 1.59078996 -2.12156004 0 P 0 ;0
L 1.59078996 -2.12156004 1.59348996 -2.11971998 0 P 0 ;0
L 1.59348996 -2.11971998 1.59525 -2.11833002 0 P 0 ;0
L 1.59525 -2.11833002 1.5969 -2.11681998 0 P 0 ;0
L 1.5969 -2.11681998 1.59846004 -2.11521004 0 P 0 ;0
L 1.59846004 -2.11521004 1.59991004 -2.11348002 0 P 0 ;0
L 1.59991004 -2.11348002 1.60175 -2.11093996 0 P 0 ;0
L 1.60175 -2.11093996 1.60338002 -2.10826998 0 P 0 ;0
L 1.60338002 -2.10826998 1.60481004 -2.10548002 0 P 0 ;0
L 1.60481004 -2.10548002 1.60573002 -2.10321004 0 P 0 ;0
L 1.60573002 -2.10321004 1.60646004 -2.10088002 0 P 0 ;0
L 1.60646004 -2.10088002 1.60698002 -2.09848996 0 P 0 ;0
L 1.60698002 -2.09848996 1.60756004 -2.09421998 0 P 0 ;0
L 1.60756004 -2.09421998 1.6078 -2.08991004 0 P 0 ;0
L 1.6078 -2.08991004 1.60768996 -2.08565 0 P 0 ;0
L 1.60768996 -2.08565 1.60723002 -2.08141998 0 P 0 ;0
L 1.60723002 -2.08141998 1.60691998 -2.07968002 0 P 0 ;0
L 1.60691998 -2.07968002 1.60646998 -2.07796998 0 P 0 ;0
L 1.60646998 -2.07796998 1.60591998 -2.0763 0 P 0 ;0
L 1.60591998 -2.0763 1.60523002 -2.07466998 0 P 0 ;0
L 1.60523002 -2.07466998 1.60411998 -2.07246998 0 P 0 ;0
L 1.60411998 -2.07246998 1.60281004 -2.07038002 0 P 0 ;0
L 1.60281004 -2.07038002 1.60131998 -2.06838996 0 P 0 ;0
L 1.60131998 -2.06838996 1.59803996 -2.06461998 0 P 0 ;0
L 1.59803996 -2.06461998 1.59455 -2.06101998 0 P 0 ;0
L 1.59455 -2.06101998 1.59031998 -2.05708996 0 P 0 ;0
L 1.59031998 -2.05708996 1.58586004 -2.05333996 0 P 0 ;0
L 1.58586004 -2.05333996 1.57588002 -2.04598996 0 P 0 ;0
L 1.57588002 -2.04598996 1.56685 -2.03963996 0 P 0 ;0
L 1.56685 -2.03963996 1.56578002 -2.03878996 0 P 0 ;0
L 1.56578002 -2.03878996 1.56476998 -2.03786004 0 P 0 ;0
L 1.56476998 -2.03786004 1.56383002 -2.03686998 0 P 0 ;0
L 1.56383002 -2.03686998 1.56295 -2.0358 0 P 0 ;0
L 1.56295 -2.0358 1.56276998 -2.03555 0 P 0 ;0
L 1.56276998 -2.03555 1.56261004 -2.03528002 0 P 0 ;0
L 1.56261004 -2.03528002 1.56246998 -2.035 0 P 0 ;0
L 1.56246998 -2.035 1.56236004 -2.03471998 0 P 0 ;0
L 1.56236004 -2.03471998 1.56226998 -2.03441998 0 P 0 ;0
L 1.56226998 -2.03441998 1.5622 -2.03411998 0 P 0 ;0
L 1.5622 -2.03411998 1.56216004 -2.03381998 0 P 0 ;0
L 1.56216004 -2.03381998 1.56213996 -2.03351004 0 P 0 ;0
L 1.56213996 -2.03351004 1.56215 -2.0332 0 P 0 ;0
L 1.56215 -2.0332 1.56218002 -2.03288996 0 P 0 ;0
L 1.56218002 -2.03288996 1.56225 -2.03253996 0 P 0 ;0
L 1.56225 -2.03253996 1.56233996 -2.03221004 0 P 0 ;0
L 1.56233996 -2.03221004 1.56246004 -2.03186998 0 P 0 ;0
L 1.56246004 -2.03186998 1.56261004 -2.03156004 0 P 0 ;0
L 1.56261004 -2.03156004 1.56278996 -2.03125 0 P 0 ;0
L 1.56278996 -2.03125 1.56298002 -2.03096004 0 P 0 ;0
L 1.56298002 -2.03096004 1.56321004 -2.03068996 0 P 0 ;0
L 1.56321004 -2.03068996 1.56345 -2.03043996 0 P 0 ;0
L 1.56345 -2.03043996 1.56371004 -2.0302 0 P 0 ;0
L 1.56371004 -2.0302 1.56416004 -2.02986004 0 P 0 ;0
L 1.56416004 -2.02986004 1.56463002 -2.02955 0 P 0 ;0
L 1.56463002 -2.02955 1.56511998 -2.02928002 0 P 0 ;0
L 1.56511998 -2.02928002 1.56561998 -2.02903002 0 P 0 ;0
L 1.56561998 -2.02903002 1.56611998 -2.02883996 0 P 0 ;0
L 1.56611998 -2.02883996 1.56663996 -2.02866998 0 P 0 ;0
L 1.56663996 -2.02866998 1.56716004 -2.02855 0 P 0 ;0
L 1.56716004 -2.02855 1.5677 -2.02846998 0 P 0 ;0
L 1.5677 -2.02846998 1.56926998 -2.02835 0 P 0 ;0
L 1.56926998 -2.02835 1.57085 -2.02833996 0 P 0 ;0
L 1.57085 -2.02833996 1.57725 -2.02866998 0 P 0 ;0
L 1.57725 -2.02866998 1.58205 -2.02906004 0 P 0 ;0
L 1.58205 -2.02906004 1.58746998 -2.02975 0 P 0 ;0
L 1.58746998 -2.02975 1.59271004 -2.03056998 0 P 0 ;0
L 1.59271004 -2.03056998 1.59681004 -2.03143002 0 P 0 ;0
L 1.59681004 -2.03143002 1.60016004 -2.03221998 0 P 0 ;0
L 1.60016004 -2.03221998 1.60308002 -2.03281004 0 P 0 ;0
L 1.60308002 -2.03281004 1.60553996 -2.03323996 0 P 0 ;0
L 1.60553996 -2.03323996 1.60568996 -2.03323996 0 P 0 ;0
L 1.60568996 -2.03323996 1.60576998 -2.03321998 0 P 0 ;0
L 1.60576998 -2.03321998 1.60586004 -2.03316004 0 P 0 ;0
L 1.60586004 -2.03316004 1.6059 -2.03313996 0 P 0 ;0
L 1.6059 -2.03313996 1.60591998 -2.03311004 0 P 0 ;0
L 1.60591998 -2.03311004 1.60598996 -2.03303996 0 P 0 ;0
L 1.60598996 -2.03303996 1.60605 -2.03296998 0 P 0 ;0
L 1.60605 -2.03296998 1.6061 -2.03288996 0 P 0 ;0
L 1.6061 -2.03288996 1.60618002 -2.03273002 0 P 0 ;0
L 1.60618002 -2.03273002 1.60621004 -2.03263002 0 P 0 ;0
L 1.60621004 -2.03263002 1.60623002 -2.03253996 0 P 0 ;0
L 1.60623002 -2.03253996 1.60625 -2.03236004 0 P 0 ;0
L 1.60625 -2.03236004 1.60623996 -2.03226004 0 P 0 ;0
L 1.60623996 -2.03226004 1.60508002 -2.01578002 0 P 0 ;0
L 1.60508002 -2.01578002 1.60393996 -2.00068002 0 P 0 ;0
L 1.60393996 -2.00068002 1.60368002 -1.99833996 0 P 0 ;0
L 1.60368002 -1.99833996 1.60326998 -1.99601004 0 P 0 ;0
L 1.60326998 -1.99601004 1.60321004 -1.99576998 0 P 0 ;0
L 1.60321004 -1.99576998 1.60313996 -1.99553002 0 P 0 ;0
L 1.60313996 -1.99553002 1.60303996 -1.9953 0 P 0 ;0
L 1.60303996 -1.9953 1.60293002 -1.99508002 0 P 0 ;0
L 1.60293002 -1.99508002 1.60281004 -1.99486004 0 P 0 ;0
L 1.60281004 -1.99486004 1.60261998 -1.9946 0 P 0 ;0
L 1.60261998 -1.9946 1.60241004 -1.99435 0 P 0 ;0
L 1.60241004 -1.99435 1.60218002 -1.99411998 0 P 0 ;0
L 1.60218002 -1.99411998 1.60191998 -1.99391004 0 P 0 ;0
L 1.60191998 -1.99391004 1.60161004 -1.99368996 0 P 0 ;0
L 1.60161004 -1.99368996 1.60128996 -1.99348996 0 P 0 ;0
L 1.60128996 -1.99348996 1.60095 -1.99331998 0 P 0 ;0
L 1.60095 -1.99331998 1.6006 -1.99316004 0 P 0 ;0
L 1.6006 -1.99316004 1.59966004 -1.99283002 0 P 0 ;0
L 1.59966004 -1.99283002 1.59871004 -1.99255 0 P 0 ;0
L 1.59871004 -1.99255 1.5933 -1.99135 0 P 0 ;0
L 1.5933 -1.99135 1.5878 -1.9905 0 P 0 ;0
L 1.5878 -1.9905 1.57285 -1.98915 0 P 0 ;0
L 1.57285 -1.98915 1.55763996 -1.98861004 0 P 0 ;0
L 1.55763996 -1.98861004 1.55171004 -1.98876004 0 P 0 ;0
L 1.55171004 -1.98876004 1.54575 -1.98923996 0 P 0 ;0
L 1.53011998 -2.12786998 1.5666 -2.12786998 0 P 0 ;0
L 1.52236004 -2.12686998 1.57168002 -2.12686998 0 P 0 ;0
L 1.51621998 -2.12586998 1.5753 -2.12586998 0 P 0 ;0
L 1.51071004 -2.12486998 1.57856004 -2.12486998 0 P 0 ;0
L 1.50553002 -2.12386998 1.58121004 -2.12386998 0 P 0 ;0
L 1.50431004 -2.12286998 1.58381998 -2.12286998 0 P 0 ;0
L 1.50423002 -2.12186998 1.58601998 -2.12186998 0 P 0 ;0
L 1.50413996 -2.12086998 1.58796004 -2.12086998 0 P 0 ;0
L 1.50406004 -2.11986998 1.58971004 -2.11986998 0 P 0 ;0
L 1.50396998 -2.11886998 1.59118002 -2.11886998 0 P 0 ;0
L 1.50388996 -2.11786998 1.5926 -2.11786998 0 P 0 ;0
L 1.50381004 -2.11686998 1.59386004 -2.11686998 0 P 0 ;0
L 1.50371998 -2.11586998 1.59496998 -2.11586998 0 P 0 ;0
L 1.50363996 -2.11486998 1.59601004 -2.11486998 0 P 0 ;0
L 1.50355 -2.11386998 1.59696998 -2.11386998 0 P 0 ;0
L 1.50346998 -2.11286998 1.59781004 -2.11286998 0 P 0 ;0
L 1.50338002 -2.11186998 1.5986 -2.11186998 0 P 0 ;0
L 1.5033 -2.11086998 1.59933002 -2.11086998 0 P 0 ;0
L 1.50321004 -2.10986998 1.60005 -2.10986998 0 P 0 ;0
L 1.50313002 -2.10886998 1.60066998 -2.10886998 0 P 0 ;0
L 1.50305 -2.10786998 1.60128002 -2.10786998 0 P 0 ;0
L 1.50296004 -2.10686998 1.60185 -2.10686998 0 P 0 ;0
L 1.50288002 -2.10586998 1.60236004 -2.10586998 0 P 0 ;0
L 1.50278996 -2.10486998 1.60286998 -2.10486998 0 P 0 ;0
L 1.50271004 -2.10386998 1.6033 -2.10386998 0 P 0 ;0
L 1.50263002 -2.10286998 1.60371004 -2.10286998 0 P 0 ;0
L 1.50255 -2.10186998 1.60405 -2.10186998 0 P 0 ;0
L 1.50246998 -2.10086998 1.60436004 -2.10086998 0 P 0 ;0
L 1.50238996 -2.09986998 1.60463002 -2.09986998 0 P 0 ;0
L 1.50231004 -2.09886998 1.60485 -2.09886998 0 P 0 ;0
L 1.50223002 -2.09786998 1.60505 -2.09786998 0 P 0 ;0
L 1.50215 -2.09686998 1.60518002 -2.09686998 0 P 0 ;0
L 1.50206998 -2.09586998 1.60531998 -2.09586998 0 P 0 ;0
L 1.50198996 -2.09486998 1.60545 -2.09486998 0 P 0 ;0
L 1.50191004 -2.09386998 1.60558002 -2.09386998 0 P 0 ;0
L 1.50183002 -2.09286998 1.60563002 -2.09286998 0 P 0 ;0
L 1.50175 -2.09186998 1.53725 -2.09186998 0 P 0 ;0
L 1.54638996 -2.09186998 1.60568996 -2.09186998 0 P 0 ;0
L 1.50166998 -2.09086998 1.5295 -2.09086998 0 P 0 ;0
L 1.54956998 -2.09086998 1.60573996 -2.09086998 0 P 0 ;0
L 1.50158996 -2.08986998 1.52436004 -2.08986998 0 P 0 ;0
L 1.55125 -2.08986998 1.60578996 -2.08986998 0 P 0 ;0
L 1.50151004 -2.08886998 1.52021004 -2.08886998 0 P 0 ;0
L 1.55226998 -2.08886998 1.60576998 -2.08886998 0 P 0 ;0
L 1.50143002 -2.08786998 1.51633002 -2.08786998 0 P 0 ;0
L 1.55298002 -2.08786998 1.60573996 -2.08786998 0 P 0 ;0
L 1.50133996 -2.08686998 1.51246004 -2.08686998 0 P 0 ;0
L 1.55346998 -2.08686998 1.60571998 -2.08686998 0 P 0 ;0
L 1.50126998 -2.08586998 1.50861998 -2.08586998 0 P 0 ;0
L 1.55375 -2.08586998 1.60568996 -2.08586998 0 P 0 ;0
L 1.50118002 -2.08486998 1.50481004 -2.08486998 0 P 0 ;0
L 1.55383002 -2.08486998 1.60558996 -2.08486998 0 P 0 ;0
L 1.55371998 -2.08386998 1.60548996 -2.08386998 0 P 0 ;0
L 1.54886998 -2.12886998 1.53358996 -2.12823996 0 P 0 ;0
L 1.53358996 -2.12823996 1.52631998 -2.12746998 0 P 0 ;0
L 1.52631998 -2.12746998 1.51906004 -2.12636998 0 P 0 ;0
L 1.51906004 -2.12636998 1.51363002 -2.12541004 0 P 0 ;0
L 1.51363002 -2.12541004 1.50886998 -2.12451998 0 P 0 ;0
L 1.50886998 -2.12451998 1.50483996 -2.12373996 0 P 0 ;0
L 1.50483996 -2.12373996 1.50448996 -2.12365 0 P 0 ;0
L 1.50448996 -2.12365 1.50438002 -2.12361004 0 P 0 ;0
L 1.50438002 -2.12361004 1.5027 -2.10378002 0 P 0 ;0
L 1.5027 -2.10378002 1.50111998 -2.08403002 0 P 0 ;0
L 1.50111998 -2.08403002 1.50263996 -2.08433996 0 P 0 ;0
L 1.50263996 -2.08433996 1.50581004 -2.08511004 0 P 0 ;0
L 1.50581004 -2.08511004 1.50955 -2.08611998 0 P 0 ;0
L 1.50955 -2.08611998 1.52306004 -2.08961004 0 P 0 ;0
L 1.52306004 -2.08961004 1.52311004 -2.08961998 0 P 0 ;0
L 1.52311004 -2.08961998 1.52875 -2.09076004 0 P 0 ;0
L 1.52875 -2.09076004 1.5288 -2.09076004 0 P 0 ;0
L 1.5288 -2.09076004 1.53443996 -2.09161004 0 P 0 ;0
L 1.53443996 -2.09161004 1.53893996 -2.09203002 0 P 0 ;0
L 1.53893996 -2.09203002 1.54346004 -2.09216998 0 P 0 ;0
L 1.54346004 -2.09216998 1.54473996 -2.09211004 0 P 0 ;0
L 1.54473996 -2.09211004 1.54603002 -2.09195 0 P 0 ;0
L 1.54603002 -2.09195 1.54728996 -2.09166998 0 P 0 ;0
L 1.54728996 -2.09166998 1.54853002 -2.09128996 0 P 0 ;0
L 1.54853002 -2.09128996 1.54973002 -2.09081004 0 P 0 ;0
L 1.54973002 -2.09081004 1.55026998 -2.09053996 0 P 0 ;0
L 1.55026998 -2.09053996 1.55076998 -2.09023002 0 P 0 ;0
L 1.55076998 -2.09023002 1.55118002 -2.08991998 0 P 0 ;0
L 1.55118002 -2.08991998 1.55118002 -2.08991004 0 P 0 ;0
L 1.55118002 -2.08991004 1.5512 -2.08991004 0 P 0 ;0
L 1.5512 -2.08991004 1.55125 -2.08986998 0 P 0 ;0
L 1.55125 -2.08986998 1.55131004 -2.08981998 0 P 0 ;0
L 1.55131004 -2.08981998 1.55126998 -2.08978002 0 P 0 ;0
L 1.55126998 -2.08978002 1.55136004 -2.08978002 0 P 0 ;0
L 1.55136004 -2.08978002 1.5517 -2.08948996 0 P 0 ;0
L 1.5517 -2.08948996 1.55206004 -2.08911998 0 P 0 ;0
L 1.55206004 -2.08911998 1.55205 -2.08911004 0 P 0 ;0
L 1.55205 -2.08911004 1.55206004 -2.08911004 0 P 0 ;0
L 1.55206004 -2.08911004 1.55211998 -2.08906004 0 P 0 ;0
L 1.55211998 -2.08906004 1.55248996 -2.08861004 0 P 0 ;0
L 1.55248996 -2.08861004 1.55283996 -2.08811998 0 P 0 ;0
L 1.55283996 -2.08811998 1.55313996 -2.08761004 0 P 0 ;0
L 1.55313996 -2.08761004 1.5534 -2.08706998 0 P 0 ;0
L 1.5534 -2.08706998 1.55356004 -2.08663002 0 P 0 ;0
L 1.55356004 -2.08663002 1.55368996 -2.08618996 0 P 0 ;0
L 1.55368996 -2.08618996 1.55376998 -2.08573996 0 P 0 ;0
L 1.55376998 -2.08573996 1.55378002 -2.08565 0 P 0 ;0
L 1.55378002 -2.08565 1.55381998 -2.08528002 0 P 0 ;0
L 1.55381998 -2.08528002 1.55383002 -2.08481998 0 P 0 ;0
L 1.55383002 -2.08481998 1.5538 -2.08436998 0 P 0 ;0
L 1.5538 -2.08436998 1.55373002 -2.08391998 0 P 0 ;0
L 1.55373002 -2.08391998 1.55361998 -2.08346998 0 P 0 ;0
L 1.55361998 -2.08346998 1.55348002 -2.08303996 0 P 0 ;0
L 1.55348002 -2.08303996 1.5533 -2.08261004 0 P 0 ;0
L 1.5533 -2.08261004 1.55308996 -2.08221004 0 P 0 ;0
L 1.55308996 -2.08221004 1.55283996 -2.08183002 0 P 0 ;0
L 1.55283996 -2.08183002 1.55175 -2.0804 0 P 0 ;0
L 1.55175 -2.0804 1.55055 -2.07908002 0 P 0 ;0
L 1.55055 -2.07908002 1.54926004 -2.07783996 0 P 0 ;0
L 1.54926004 -2.07783996 1.54788996 -2.07671998 0 P 0 ;0
L 1.54788996 -2.07671998 1.53706998 -2.06898002 0 P 0 ;0
L 1.53706998 -2.06898002 1.52085 -2.05713996 0 P 0 ;0
L 1.52085 -2.05713996 1.51766004 -2.05445 0 P 0 ;0
L 1.51766004 -2.05445 1.51468002 -2.05153996 0 P 0 ;0
L 1.51468002 -2.05153996 1.51191998 -2.04841998 0 P 0 ;0
L 1.51191998 -2.04841998 1.51048996 -2.04651998 0 P 0 ;0
L 1.51048996 -2.04651998 1.50923002 -2.04453002 0 P 0 ;0
L 1.50923002 -2.04453002 1.50813996 -2.04245 0 P 0 ;0
L 1.50813996 -2.04245 1.50721998 -2.04026004 0 P 0 ;0
L 1.50721998 -2.04026004 1.50643002 -2.03788002 0 P 0 ;0
L 1.50643002 -2.03788002 1.50581004 -2.03545 0 P 0 ;0
L 1.50581004 -2.03545 1.50536004 -2.03298996 0 P 0 ;0
L 1.50536004 -2.03298996 1.50508996 -2.0305 0 P 0 ;0
L 1.50508996 -2.0305 1.50498996 -2.02745 0 P 0 ;0
L 1.50498996 -2.02745 1.50513996 -2.02443996 0 P 0 ;0
L 1.50513996 -2.02443996 1.50551998 -2.02145 0 P 0 ;0
L 1.50551998 -2.02145 1.50613996 -2.0185 0 P 0 ;0
L 1.50613996 -2.0185 1.50698996 -2.01561004 0 P 0 ;0
L 1.50698996 -2.01561004 1.50783002 -2.01341004 0 P 0 ;0
L 1.50783002 -2.01341004 1.50883002 -2.0113 0 P 0 ;0
L 1.50883002 -2.0113 1.51 -2.00928002 0 P 0 ;0
L 1.51 -2.00928002 1.51133002 -2.00736004 0 P 0 ;0
L 1.51133002 -2.00736004 1.5128 -2.00555 0 P 0 ;0
L 1.5128 -2.00555 1.5144 -2.00386004 0 P 0 ;0
L 1.5144 -2.00386004 1.51675 -2.00176998 0 P 0 ;0
L 1.51675 -2.00176998 1.51923002 -1.9999 0 P 0 ;0
L 1.51923002 -1.9999 1.52186004 -1.99823996 0 P 0 ;0
L 1.52186004 -1.99823996 1.52461998 -1.99681004 0 P 0 ;0
L 1.52461998 -1.99681004 1.52748996 -1.99561004 0 P 0 ;0
L 1.52748996 -1.99561004 1.53353002 -1.99363996 0 P 0 ;0
L 1.53353002 -1.99363996 1.5397 -1.99218002 0 P 0 ;0
L 1.5397 -1.99218002 1.54598002 -1.99123002 0 P 0 ;0
L 1.54598002 -1.99123002 1.55181004 -1.99075 0 P 0 ;0
L 1.55181004 -1.99075 1.55763002 -1.99061998 0 P 0 ;0
L 1.55763002 -1.99061998 1.57273002 -1.99113996 0 P 0 ;0
L 1.57273002 -1.99113996 1.58755 -1.99248996 0 P 0 ;0
L 1.58755 -1.99248996 1.59293002 -1.99331998 0 P 0 ;0
L 1.59293002 -1.99331998 1.59821004 -1.99448996 0 P 0 ;0
L 1.59821004 -1.99448996 1.59905 -1.99473002 0 P 0 ;0
L 1.59905 -1.99473002 1.59986004 -1.99501998 0 P 0 ;0
L 1.59986004 -1.99501998 1.60008002 -1.99511998 0 P 0 ;0
L 1.60008002 -1.99511998 1.6003 -1.99523002 0 P 0 ;0
L 1.6003 -1.99523002 1.60051004 -1.99536004 0 P 0 ;0
L 1.60051004 -1.99536004 1.60071004 -1.9955 0 P 0 ;0
L 1.60071004 -1.9955 1.60083002 -1.99561004 0 P 0 ;0
L 1.60083002 -1.99561004 1.60093996 -1.99571004 0 P 0 ;0
L 1.60093996 -1.99571004 1.60103996 -1.99583002 0 P 0 ;0
L 1.60103996 -1.99583002 1.60111998 -1.99595 0 P 0 ;0
L 1.60111998 -1.99595 1.60116998 -1.99601998 0 P 0 ;0
L 1.60116998 -1.99601998 1.60121004 -1.99611004 0 P 0 ;0
L 1.60121004 -1.99611004 1.60125 -1.99621004 0 P 0 ;0
L 1.60125 -1.99621004 1.60128002 -1.9963 0 P 0 ;0
L 1.60128002 -1.9963 1.60131004 -1.99641004 0 P 0 ;0
L 1.60131004 -1.99641004 1.6017 -1.99861998 0 P 0 ;0
L 1.6017 -1.99861998 1.60195 -2.00086998 0 P 0 ;0
L 1.60195 -2.00086998 1.60308002 -2.01593002 0 P 0 ;0
L 1.60308002 -2.01593002 1.60415 -2.03096998 0 P 0 ;0
L 1.60415 -2.03096998 1.60345 -2.03083996 0 P 0 ;0
L 1.60345 -2.03083996 1.60058996 -2.03026004 0 P 0 ;0
L 1.60058996 -2.03026004 1.59723002 -2.02948002 0 P 0 ;0
L 1.59723002 -2.02948002 1.59721998 -2.02948002 0 P 0 ;0
L 1.59721998 -2.02948002 1.59306998 -2.0286 0 P 0 ;0
L 1.59306998 -2.0286 1.58776004 -2.02776998 0 P 0 ;0
L 1.58776004 -2.02776998 1.58226004 -2.02708002 0 P 0 ;0
L 1.58226004 -2.02708002 1.57738002 -2.02666998 0 P 0 ;0
L 1.57738002 -2.02666998 1.5709 -2.02633996 0 P 0 ;0
L 1.5709 -2.02633996 1.56918996 -2.02635 0 P 0 ;0
L 1.56918996 -2.02635 1.56746998 -2.02648996 0 P 0 ;0
L 1.56746998 -2.02648996 1.56678996 -2.02658996 0 P 0 ;0
L 1.56678996 -2.02658996 1.56611998 -2.02673996 0 P 0 ;0
L 1.56611998 -2.02673996 1.56546004 -2.02695 0 P 0 ;0
L 1.56546004 -2.02695 1.56481998 -2.0272 0 P 0 ;0
L 1.56481998 -2.0272 1.56418996 -2.0275 0 P 0 ;0
L 1.56418996 -2.0275 1.56358002 -2.02785 0 P 0 ;0
L 1.56358002 -2.02785 1.563 -2.02823002 0 P 0 ;0
L 1.563 -2.02823002 1.56245 -2.02865 0 P 0 ;0
L 1.56245 -2.02865 1.56206998 -2.02898996 0 P 0 ;0
L 1.56206998 -2.02898996 1.56171004 -2.02936004 0 P 0 ;0
L 1.56171004 -2.02936004 1.56138002 -2.02976004 0 P 0 ;0
L 1.56138002 -2.02976004 1.56108996 -2.03018996 0 P 0 ;0
L 1.56108996 -2.03018996 1.56083002 -2.03063996 0 P 0 ;0
L 1.56083002 -2.03063996 1.56061998 -2.0311 0 P 0 ;0
L 1.56061998 -2.0311 1.56043996 -2.03158996 0 P 0 ;0
L 1.56043996 -2.03158996 1.5603 -2.03208002 0 P 0 ;0
L 1.5603 -2.03208002 1.5602 -2.0326 0 P 0 ;0
L 1.5602 -2.0326 1.56015 -2.03308002 0 P 0 ;0
L 1.56015 -2.03308002 1.56013996 -2.03353996 0 P 0 ;0
L 1.56013996 -2.03353996 1.56016004 -2.03391004 0 P 0 ;0
L 1.56016004 -2.03391004 1.56048002 -2.03391004 0 P 0 ;0
L 1.56048002 -2.03391004 1.56016004 -2.03393002 0 P 0 ;0
L 1.56016004 -2.03393002 1.56016998 -2.03401004 0 P 0 ;0
L 1.56016998 -2.03401004 1.56023002 -2.03448002 0 P 0 ;0
L 1.56023002 -2.03448002 1.56025 -2.03456004 0 P 0 ;0
L 1.56025 -2.03456004 1.56033002 -2.03493002 0 P 0 ;0
L 1.56033002 -2.03493002 1.56046998 -2.03538002 0 P 0 ;0
L 1.56046998 -2.03538002 1.56063996 -2.03581998 0 P 0 ;0
L 1.56063996 -2.03581998 1.56085 -2.03623996 0 P 0 ;0
L 1.56085 -2.03623996 1.56108996 -2.03663996 0 P 0 ;0
L 1.56108996 -2.03663996 1.56136004 -2.03701998 0 P 0 ;0
L 1.56136004 -2.03701998 1.56233002 -2.03818996 0 P 0 ;0
L 1.56233002 -2.03818996 1.56336998 -2.03928996 0 P 0 ;0
L 1.56336998 -2.03928996 1.56448002 -2.04031004 0 P 0 ;0
L 1.56448002 -2.04031004 1.56566004 -2.04123996 0 P 0 ;0
L 1.56566004 -2.04123996 1.57471004 -2.04761998 0 P 0 ;0
L 1.57471004 -2.04761998 1.58461998 -2.05491004 0 P 0 ;0
L 1.58461998 -2.05491004 1.58898996 -2.05858996 0 P 0 ;0
L 1.58898996 -2.05858996 1.59315 -2.06245 0 P 0 ;0
L 1.59315 -2.06245 1.59656998 -2.06596998 0 P 0 ;0
L 1.59656998 -2.06596998 1.59976004 -2.06965 0 P 0 ;0
L 1.59976004 -2.06965 1.60116004 -2.07151004 0 P 0 ;0
L 1.60116004 -2.07151004 1.60238002 -2.07346004 0 P 0 ;0
L 1.60238002 -2.07346004 1.60341998 -2.0755 0 P 0 ;0
L 1.60341998 -2.0755 1.60403996 -2.077 0 P 0 ;0
L 1.60403996 -2.077 1.60456004 -2.07853996 0 P 0 ;0
L 1.60456004 -2.07853996 1.60496004 -2.08011004 0 P 0 ;0
L 1.60496004 -2.08011004 1.60525 -2.0817 0 P 0 ;0
L 1.60525 -2.0817 1.60568996 -2.08578002 0 P 0 ;0
L 1.60568996 -2.08578002 1.60578996 -2.08988002 0 P 0 ;0
L 1.60578996 -2.08988002 1.60556998 -2.09403002 0 P 0 ;0
L 1.60556998 -2.09403002 1.60501004 -2.09813996 0 P 0 ;0
L 1.60501004 -2.09813996 1.60451998 -2.10036998 0 P 0 ;0
L 1.60451998 -2.10036998 1.60383996 -2.10253996 0 P 0 ;0
L 1.60383996 -2.10253996 1.60298996 -2.10465 0 P 0 ;0
L 1.60298996 -2.10465 1.60163996 -2.1073 0 P 0 ;0
L 1.60163996 -2.1073 1.60008002 -2.10983002 0 P 0 ;0
L 1.60008002 -2.10983002 1.59833002 -2.11225 0 P 0 ;0
L 1.59833002 -2.11225 1.59696998 -2.11386998 0 P 0 ;0
L 1.59696998 -2.11386998 1.59551004 -2.11538996 0 P 0 ;0
L 1.59551004 -2.11538996 1.59395 -2.1168 0 P 0 ;0
L 1.59395 -2.1168 1.59231004 -2.11811004 0 P 0 ;0
L 1.59231004 -2.11811004 1.58973002 -2.11986004 0 P 0 ;0
L 1.58973002 -2.11986004 1.58701998 -2.1214 0 P 0 ;0
L 1.58701998 -2.1214 1.5842 -2.12273002 0 P 0 ;0
L 1.5842 -2.12273002 1.5788 -2.1248 0 P 0 ;0
L 1.5788 -2.1248 1.57326998 -2.12648996 0 P 0 ;0
L 1.57326998 -2.12648996 1.56983002 -2.12731004 0 P 0 ;0
L 1.56983002 -2.12731004 1.56638002 -2.12791004 0 P 0 ;0
L 1.56638002 -2.12791004 1.56288996 -2.1283 0 P 0 ;0
L 1.56288996 -2.1283 1.54886998 -2.12886998 0 P 0 ;0
L 1.35851998 -2.06545 1.47866004 -2.06545 0 P 0 ;0
L 1.35936004 -2.06445 1.47871004 -2.06445 0 P 0 ;0
L 1.36041004 -2.06345 1.47875 -2.06345 0 P 0 ;0
L 1.36163996 -2.06245 1.4788 -2.06245 0 P 0 ;0
L 1.36293996 -2.06145 1.47883996 -2.06145 0 P 0 ;0
L 1.36436004 -2.06045 1.47888996 -2.06045 0 P 0 ;0
L 1.36598002 -2.05945 1.47893996 -2.05945 0 P 0 ;0
L 1.36776004 -2.05845 1.47898996 -2.05845 0 P 0 ;0
L 1.36971004 -2.05745 1.47903002 -2.05745 0 P 0 ;0
L 1.37166004 -2.05645 1.47908002 -2.05645 0 P 0 ;0
L 1.37391004 -2.05545 1.47911998 -2.05545 0 P 0 ;0
L 1.37616998 -2.05445 1.47916998 -2.05445 0 P 0 ;0
L 1.37873002 -2.05345 1.47921004 -2.05345 0 P 0 ;0
L 1.38136004 -2.05245 1.47926004 -2.05245 0 P 0 ;0
L 1.36875 -2.03345 1.37108996 -2.03345 0 P 0 ;0
L 1.36886004 -2.03245 1.37385 -2.03245 0 P 0 ;0
L 1.36896998 -2.03145 1.37678002 -2.03145 0 P 0 ;0
L 1.36908996 -2.03045 1.3797 -2.03045 0 P 0 ;0
L 1.36921004 -2.02945 1.38261998 -2.02945 0 P 0 ;0
L 1.36933002 -2.02845 1.38638996 -2.02845 0 P 0 ;0
L 1.36946004 -2.02745 1.39023996 -2.02745 0 P 0 ;0
L 1.36958002 -2.02645 1.39503002 -2.02645 0 P 0 ;0
L 1.3697 -2.02545 1.40068002 -2.02545 0 P 0 ;0
L 1.36981998 -2.02445 1.41053996 -2.02445 0 P 0 ;0
L 1.36993996 -2.02345 1.47993996 -2.02345 0 P 0 ;0
L 1.37008002 -2.02245 1.47988002 -2.02245 0 P 0 ;0
L 1.37021004 -2.02145 1.47978002 -2.02145 0 P 0 ;0
L 1.37033996 -2.02045 1.47968002 -2.02045 0 P 0 ;0
L 1.37046998 -2.01945 1.47953002 -2.01945 0 P 0 ;0
L 1.3706 -2.01845 1.47936004 -2.01845 0 P 0 ;0
L 1.37073002 -2.01745 1.47918002 -2.01745 0 P 0 ;0
L 1.37086004 -2.01645 1.47893002 -2.01645 0 P 0 ;0
L 1.37098996 -2.01545 1.47868002 -2.01545 0 P 0 ;0
L 1.37113002 -2.01445 1.4784 -2.01445 0 P 0 ;0
L 1.37126998 -2.01345 1.47806004 -2.01345 0 P 0 ;0
L 1.3714 -2.01245 1.47773002 -2.01245 0 P 0 ;0
L 1.37153996 -2.01145 1.47733002 -2.01145 0 P 0 ;0
L 1.37168002 -2.01045 1.47691004 -2.01045 0 P 0 ;0
L 1.37181004 -2.00945 1.47641004 -2.00945 0 P 0 ;0
L 1.37195 -2.00845 1.47588996 -2.00845 0 P 0 ;0
L 1.37208002 -2.00745 1.47528002 -2.00745 0 P 0 ;0
L 1.37221004 -2.00645 1.47463996 -2.00645 0 P 0 ;0
L 1.37235 -2.00545 1.47391998 -2.00545 0 P 0 ;0
L 1.37248996 -2.00445 1.47311004 -2.00445 0 P 0 ;0
L 1.37261998 -2.00345 1.47225 -2.00345 0 P 0 ;0
L 1.37276004 -2.00245 1.47126998 -2.00245 0 P 0 ;0
L 1.3729 -2.00145 1.4702 -2.00145 0 P 0 ;0
L 1.37303002 -2.00045 1.46903996 -2.00045 0 P 0 ;0
L 1.37316998 -1.99945 1.46775 -1.99945 0 P 0 ;0
L 1.3733 -1.99845 1.46625 -1.99845 0 P 0 ;0
L 1.37343996 -1.99745 1.46455 -1.99745 0 P 0 ;0
L 1.37356998 -1.99645 1.46253996 -1.99645 0 P 0 ;0
L 1.37753002 -1.99545 1.46041004 -1.99545 0 P 0 ;0
L 1.38218996 -1.99445 1.45781004 -1.99445 0 P 0 ;0
L 1.42925 -2.08345 1.47785 -2.08345 0 P 0 ;0
L 1.42931998 -2.08245 1.47788996 -2.08245 0 P 0 ;0
L 1.42938002 -2.08145 1.47793002 -2.08145 0 P 0 ;0
L 1.42945 -2.08045 1.47796998 -2.08045 0 P 0 ;0
L 1.42951004 -2.07945 1.47801004 -2.07945 0 P 0 ;0
L 1.42958002 -2.07845 1.47806004 -2.07845 0 P 0 ;0
L 1.42963996 -2.07745 1.4781 -2.07745 0 P 0 ;0
L 1.4297 -2.07645 1.47815 -2.07645 0 P 0 ;0
L 1.42976998 -2.07545 1.4782 -2.07545 0 P 0 ;0
L 1.42983002 -2.07445 1.47825 -2.07445 0 P 0 ;0
L 1.4299 -2.07345 1.47828996 -2.07345 0 P 0 ;0
L 1.42963996 -2.07245 1.47833996 -2.07245 0 P 0 ;0
L 1.42918996 -2.07145 1.47838002 -2.07145 0 P 0 ;0
L 1.38425 -2.05145 1.47931004 -2.05145 0 P 0 ;0
L 1.38731998 -2.05045 1.47933996 -2.05045 0 P 0 ;0
L 1.39088002 -2.04945 1.47938002 -2.04945 0 P 0 ;0
L 1.3947 -2.04845 1.47941004 -2.04845 0 P 0 ;0
L 1.39851004 -2.04745 1.47945 -2.04745 0 P 0 ;0
L 1.40233002 -2.04645 1.47948002 -2.04645 0 P 0 ;0
L 1.40608002 -2.04545 1.47951004 -2.04545 0 P 0 ;0
L 1.40983002 -2.04445 1.47955 -2.04445 0 P 0 ;0
L 1.41306998 -2.04345 1.47958996 -2.04345 0 P 0 ;0
L 1.41591998 -2.04245 1.47961998 -2.04245 0 P 0 ;0
L 1.41876998 -2.04145 1.47965 -2.04145 0 P 0 ;0
L 1.42133996 -2.04045 1.47968996 -2.04045 0 P 0 ;0
L 1.42361998 -2.03945 1.47971998 -2.03945 0 P 0 ;0
L 1.42591004 -2.03845 1.47975 -2.03845 0 P 0 ;0
L 1.42805 -2.03745 1.47978002 -2.03745 0 P 0 ;0
L 1.42936004 -2.03645 1.47981004 -2.03645 0 P 0 ;0
L 1.43003002 -2.03545 1.47983002 -2.03545 0 P 0 ;0
L 1.43081998 -2.03445 1.47986004 -2.03445 0 P 0 ;0
L 1.43121004 -2.03345 1.47988002 -2.03345 0 P 0 ;0
L 1.43141998 -2.03245 1.4799 -2.03245 0 P 0 ;0
L 1.43146998 -2.03145 1.47993002 -2.03145 0 P 0 ;0
L 1.43136004 -2.03045 1.47996004 -2.03045 0 P 0 ;0
L 1.43108002 -2.02945 1.47998002 -2.02945 0 P 0 ;0
L 1.4306 -2.02845 1.48001004 -2.02845 0 P 0 ;0
L 1.42986998 -2.02745 1.48001004 -2.02745 0 P 0 ;0
L 1.42875 -2.02645 1.47998996 -2.02645 0 P 0 ;0
L 1.42658996 -2.02545 1.47996998 -2.02545 0 P 0 ;0
L 1.42203996 -2.02445 1.47996004 -2.02445 0 P 0 ;0
L 1.38748002 -1.99345 1.45483002 -1.99345 0 P 0 ;0
L 1.39331998 -1.99245 1.45108996 -1.99245 0 P 0 ;0
L 1.40051004 -1.99145 1.44503002 -1.99145 0 P 0 ;0
L 1.38096998 -2.12745 1.4051 -2.12745 0 P 0 ;0
L 1.37671004 -2.12645 1.41113996 -2.12645 0 P 0 ;0
L 1.3736 -2.12545 1.41238996 -2.12545 0 P 0 ;0
L 1.37096998 -2.12445 1.41268002 -2.12445 0 P 0 ;0
L 1.36876998 -2.12345 1.41296998 -2.12345 0 P 0 ;0
L 1.36685 -2.12245 1.41326998 -2.12245 0 P 0 ;0
L 1.36516004 -2.12145 1.41356004 -2.12145 0 P 0 ;0
L 1.36366004 -2.12045 1.41385 -2.12045 0 P 0 ;0
L 1.36225 -2.11945 1.41413996 -2.11945 0 P 0 ;0
L 1.361 -2.11845 1.41443002 -2.11845 0 P 0 ;0
L 1.35983002 -2.11745 1.41471998 -2.11745 0 P 0 ;0
L 1.35876004 -2.11645 1.41501004 -2.11645 0 P 0 ;0
L 1.42661998 -2.12445 1.47693002 -2.12445 0 P 0 ;0
L 1.42665 -2.12345 1.47693002 -2.12345 0 P 0 ;0
L 1.4267 -2.12245 1.47693002 -2.12245 0 P 0 ;0
L 1.42675 -2.12145 1.47693002 -2.12145 0 P 0 ;0
L 1.42681004 -2.12045 1.47693002 -2.12045 0 P 0 ;0
L 1.42686998 -2.11945 1.47693002 -2.11945 0 P 0 ;0
L 1.42691998 -2.11845 1.47693002 -2.11845 0 P 0 ;0
L 1.42698996 -2.11745 1.47693002 -2.11745 0 P 0 ;0
L 1.42705 -2.11645 1.47693002 -2.11645 0 P 0 ;0
L 1.42711004 -2.11545 1.47693002 -2.11545 0 P 0 ;0
L 1.42716998 -2.11445 1.47693002 -2.11445 0 P 0 ;0
L 1.42723002 -2.11345 1.47693996 -2.11345 0 P 0 ;0
L 1.4273 -2.11245 1.47695 -2.11245 0 P 0 ;0
L 1.42736998 -2.11145 1.47696004 -2.11145 0 P 0 ;0
L 1.42743996 -2.11045 1.47698002 -2.11045 0 P 0 ;0
L 1.42751004 -2.10945 1.47698996 -2.10945 0 P 0 ;0
L 1.42758002 -2.10845 1.47701004 -2.10845 0 P 0 ;0
L 1.42765 -2.10745 1.47703002 -2.10745 0 P 0 ;0
L 1.42771004 -2.10645 1.47703996 -2.10645 0 P 0 ;0
L 1.42778002 -2.10545 1.47706998 -2.10545 0 P 0 ;0
L 1.42783996 -2.10445 1.4771 -2.10445 0 P 0 ;0
L 1.42791004 -2.10345 1.47713002 -2.10345 0 P 0 ;0
L 1.42798002 -2.10245 1.47716004 -2.10245 0 P 0 ;0
L 1.42805 -2.10145 1.4772 -2.10145 0 P 0 ;0
L 1.42811004 -2.10045 1.47723002 -2.10045 0 P 0 ;0
L 1.40953002 -2.09945 1.41973002 -2.09945 0 P 0 ;0
L 1.42818002 -2.09945 1.47726004 -2.09945 0 P 0 ;0
L 1.41618002 -2.09845 1.41996998 -2.09845 0 P 0 ;0
L 1.42825 -2.09845 1.47728996 -2.09845 0 P 0 ;0
L 1.42831998 -2.09745 1.47733002 -2.09745 0 P 0 ;0
L 1.42838996 -2.09645 1.47736004 -2.09645 0 P 0 ;0
L 1.42846004 -2.09545 1.47738996 -2.09545 0 P 0 ;0
L 1.42851998 -2.09445 1.47741998 -2.09445 0 P 0 ;0
L 1.42858996 -2.09345 1.47746004 -2.09345 0 P 0 ;0
L 1.42866004 -2.09245 1.4775 -2.09245 0 P 0 ;0
L 1.42873002 -2.09145 1.47753996 -2.09145 0 P 0 ;0
L 1.42878996 -2.09045 1.47758002 -2.09045 0 P 0 ;0
L 1.42886004 -2.08945 1.47761998 -2.08945 0 P 0 ;0
L 1.42893002 -2.08845 1.47766004 -2.08845 0 P 0 ;0
L 1.42898996 -2.08745 1.4777 -2.08745 0 P 0 ;0
L 1.42906004 -2.08645 1.47773002 -2.08645 0 P 0 ;0
L 1.42911998 -2.08545 1.47776998 -2.08545 0 P 0 ;0
L 1.42918996 -2.08445 1.47781004 -2.08445 0 P 0 ;0
L 1.61686004 -2.17995 1.66846004 -2.17995 0 P 0 ;0
L 1.61591004 -2.17895 1.67158996 -2.17895 0 P 0 ;0
L 1.61553996 -2.17795 1.67431998 -2.17795 0 P 0 ;0
L 1.61526998 -2.17695 1.67675 -2.17695 0 P 0 ;0
L 1.61508002 -2.17595 1.67903996 -2.17595 0 P 0 ;0
L 1.61496998 -2.17495 1.68108002 -2.17495 0 P 0 ;0
L 1.61491004 -2.17395 1.68295 -2.17395 0 P 0 ;0
L 1.61485 -2.17295 1.68458996 -2.17295 0 P 0 ;0
L 1.61478996 -2.17195 1.6861 -2.17195 0 P 0 ;0
L 1.61473002 -2.17095 1.6875 -2.17095 0 P 0 ;0
L 1.61466998 -2.16995 1.68876998 -2.16995 0 P 0 ;0
L 1.61461004 -2.16895 1.68998002 -2.16895 0 P 0 ;0
L 1.61455 -2.16795 1.69108002 -2.16795 0 P 0 ;0
L 1.61448996 -2.16695 1.69211998 -2.16695 0 P 0 ;0
L 1.61443002 -2.16595 1.69316004 -2.16595 0 P 0 ;0
L 1.61436998 -2.16495 1.69411998 -2.16495 0 P 0 ;0
L 1.61431004 -2.16395 1.69498996 -2.16395 0 P 0 ;0
L 1.61425 -2.16295 1.69586004 -2.16295 0 P 0 ;0
L 1.61418996 -2.16195 1.69673002 -2.16195 0 P 0 ;0
L 1.61413002 -2.16095 1.69746998 -2.16095 0 P 0 ;0
L 1.61406998 -2.15995 1.6982 -2.15995 0 P 0 ;0
L 1.61401998 -2.15895 1.69893996 -2.15895 0 P 0 ;0
L 1.61396998 -2.15795 1.69963002 -2.15795 0 P 0 ;0
L 1.64433002 -2.18295 1.63151004 -2.18271004 0 P 0 ;0
L 1.63151004 -2.18271004 1.62658002 -2.18226998 0 P 0 ;0
L 1.62658002 -2.18226998 1.62168996 -2.18146998 0 P 0 ;0
L 1.62168996 -2.18146998 1.6201 -2.1811 0 P 0 ;0
L 1.6201 -2.1811 1.61853996 -2.18061004 0 P 0 ;0
L 1.61853996 -2.18061004 1.61701004 -2.18001998 0 P 0 ;0
L 1.61701004 -2.18001998 1.61686004 -2.17995 0 P 0 ;0
L 1.61686004 -2.17995 1.61671004 -2.17986998 0 P 0 ;0
L 1.61671004 -2.17986998 1.61656998 -2.17976998 0 P 0 ;0
L 1.61656998 -2.17976998 1.61643996 -2.17966998 0 P 0 ;0
L 1.61643996 -2.17966998 1.61631998 -2.17955 0 P 0 ;0
L 1.61631998 -2.17955 1.61621004 -2.17943002 0 P 0 ;0
L 1.61621004 -2.17943002 1.6161 -2.1793 0 P 0 ;0
L 1.6161 -2.1793 1.61601004 -2.17915 0 P 0 ;0
L 1.61601004 -2.17915 1.61593002 -2.179 0 P 0 ;0
L 1.61593002 -2.179 1.61586004 -2.17885 0 P 0 ;0
L 1.61586004 -2.17885 1.61553002 -2.17791004 0 P 0 ;0
L 1.61553002 -2.17791004 1.61526998 -2.17696004 0 P 0 ;0
L 1.61526998 -2.17696004 1.61508996 -2.17598996 0 P 0 ;0
L 1.61508996 -2.17598996 1.61496998 -2.17496998 0 P 0 ;0
L 1.61496998 -2.17496998 1.61408002 -2.16011004 0 P 0 ;0
L 1.61408002 -2.16011004 1.61341998 -2.14758996 0 P 0 ;0
L 1.61341998 -2.14758996 1.6202 -2.14821004 0 P 0 ;0
L 1.6202 -2.14821004 1.62023002 -2.14821004 0 P 0 ;0
L 1.62023002 -2.14821004 1.63216998 -2.14893996 0 P 0 ;0
L 1.63216998 -2.14893996 1.6349 -2.14893002 0 P 0 ;0
L 1.6349 -2.14893002 1.63761998 -2.14873002 0 P 0 ;0
L 1.63761998 -2.14873002 1.64031998 -2.14835 0 P 0 ;0
L 1.64031998 -2.14835 1.64198996 -2.14798996 0 P 0 ;0
L 1.64198996 -2.14798996 1.64363002 -2.14751998 0 P 0 ;0
L 1.64363002 -2.14751998 1.64523002 -2.14693002 0 P 0 ;0
L 1.64523002 -2.14693002 1.64678996 -2.14623002 0 P 0 ;0
L 1.64678996 -2.14623002 1.64888002 -2.14506998 0 P 0 ;0
L 1.64888002 -2.14506998 1.65086998 -2.14376004 0 P 0 ;0
L 1.65086998 -2.14376004 1.65093996 -2.14371004 0 P 0 ;0
L 1.65093996 -2.14371004 1.65275 -2.14228996 0 P 0 ;0
L 1.65275 -2.14228996 1.6539 -2.14123996 0 P 0 ;0
L 1.6539 -2.14123996 1.65496004 -2.14011004 0 P 0 ;0
L 1.65496004 -2.14011004 1.65591998 -2.13891004 0 P 0 ;0
L 1.65591998 -2.13891004 1.65755 -2.13653996 0 P 0 ;0
L 1.65755 -2.13653996 1.65901998 -2.13415 0 P 0 ;0
L 1.65901998 -2.13415 1.65903002 -2.13413002 0 P 0 ;0
L 1.65903002 -2.13413002 1.66035 -2.13171998 0 P 0 ;0
L 1.66035 -2.13171998 1.66155 -2.12925 0 P 0 ;0
L 1.66155 -2.12925 1.66183996 -2.12851998 0 P 0 ;0
L 1.66183996 -2.12851998 1.66206998 -2.12776004 0 P 0 ;0
L 1.66206998 -2.12776004 1.66223996 -2.12696998 0 P 0 ;0
L 1.66223996 -2.12696998 1.66233996 -2.12618002 0 P 0 ;0
L 1.66233996 -2.12618002 1.66236998 -2.12538996 0 P 0 ;0
L 1.66236998 -2.12538996 1.66233002 -2.12436004 0 P 0 ;0
L 1.66233002 -2.12436004 1.66221004 -2.12335 0 P 0 ;0
L 1.66221004 -2.12335 1.662 -2.12235 0 P 0 ;0
L 1.662 -2.12235 1.66171004 -2.12141004 0 P 0 ;0
L 1.66171004 -2.12141004 1.64438996 -2.07113002 0 P 0 ;0
L 1.64438996 -2.07113002 1.62871998 -2.02606004 0 P 0 ;0
L 1.62871998 -2.02606004 1.62116004 -2.00558996 0 P 0 ;0
L 1.62116004 -2.00558996 1.62116004 -2.00556998 0 P 0 ;0
L 1.62116004 -2.00556998 1.61681004 -1.99443996 0 P 0 ;0
L 1.61681004 -1.99443996 1.67163002 -1.99443996 0 P 0 ;0
L 1.67163002 -1.99443996 1.67301004 -2.00076004 0 P 0 ;0
L 1.67301004 -2.00076004 1.67613002 -2.01341998 0 P 0 ;0
L 1.67613002 -2.01341998 1.68331004 -2.03931998 0 P 0 ;0
L 1.68331004 -2.03931998 1.69153002 -2.06856998 0 P 0 ;0
L 1.69153002 -2.06856998 1.6916 -2.06876004 0 P 0 ;0
L 1.6916 -2.06876004 1.69168996 -2.06896998 0 P 0 ;0
L 1.69168996 -2.06896998 1.69181004 -2.06918002 0 P 0 ;0
L 1.69181004 -2.06918002 1.69193002 -2.06936998 0 P 0 ;0
L 1.69193002 -2.06936998 1.69208002 -2.06956004 0 P 0 ;0
L 1.69208002 -2.06956004 1.69223996 -2.06973002 0 P 0 ;0
L 1.69223996 -2.06973002 1.69241998 -2.06988002 0 P 0 ;0
L 1.69241998 -2.06988002 1.6926 -2.07001998 0 P 0 ;0
L 1.6926 -2.07001998 1.6928 -2.07015 0 P 0 ;0
L 1.6928 -2.07015 1.69301004 -2.07025 0 P 0 ;0
L 1.69301004 -2.07025 1.69323002 -2.07033996 0 P 0 ;0
L 1.69323002 -2.07033996 1.69346004 -2.07041004 0 P 0 ;0
L 1.69346004 -2.07041004 1.69368002 -2.07045 0 P 0 ;0
L 1.69368002 -2.07045 1.69391998 -2.07048002 0 P 0 ;0
L 1.69391998 -2.07048002 1.69413996 -2.07048996 0 P 0 ;0
L 1.69413996 -2.07048996 1.6944 -2.07048002 0 P 0 ;0
L 1.6944 -2.07048002 1.69465 -2.07045 0 P 0 ;0
L 1.69465 -2.07045 1.69488996 -2.07038996 0 P 0 ;0
L 1.69488996 -2.07038996 1.69513996 -2.07031998 0 P 0 ;0
L 1.69513996 -2.07031998 1.69536998 -2.07021998 0 P 0 ;0
L 1.69536998 -2.07021998 1.69558996 -2.0701 0 P 0 ;0
L 1.69558996 -2.0701 1.69581004 -2.06996998 0 P 0 ;0
L 1.69581004 -2.06996998 1.69601004 -2.06981998 0 P 0 ;0
L 1.69601004 -2.06981998 1.6962 -2.06965 0 P 0 ;0
L 1.6962 -2.06965 1.69636998 -2.06946004 0 P 0 ;0
L 1.69636998 -2.06946004 1.69653002 -2.06926004 0 P 0 ;0
L 1.69653002 -2.06926004 1.69666004 -2.06905 0 P 0 ;0
L 1.69666004 -2.06905 1.69678996 -2.06883002 0 P 0 ;0
L 1.69678996 -2.06883002 1.69688002 -2.0686 0 P 0 ;0
L 1.69688002 -2.0686 1.69695 -2.0684 0 P 0 ;0
L 1.69695 -2.0684 1.70426004 -2.04365 0 P 0 ;0
L 1.70426004 -2.04365 1.70426004 -2.04363002 0 P 0 ;0
L 1.70426004 -2.04363002 1.71066998 -2.0213 0 P 0 ;0
L 1.71066998 -2.0213 1.71068002 -2.02126004 0 P 0 ;0
L 1.71068002 -2.02126004 1.71431998 -2.00693996 0 P 0 ;0
L 1.71431998 -2.00693996 1.71706004 -1.99496998 0 P 0 ;0
L 1.71706004 -1.99496998 1.74335 -1.9947 0 P 0 ;0
L 1.74335 -1.9947 1.75403002 -1.99461004 0 P 0 ;0
L 1.75403002 -1.99461004 1.76301004 -1.99465 0 P 0 ;0
L 1.76301004 -1.99465 1.76886004 -1.99471004 0 P 0 ;0
L 1.76886004 -1.99471004 1.76883996 -1.99476004 0 P 0 ;0
L 1.76883996 -1.99476004 1.74021004 -2.06556004 0 P 0 ;0
L 1.74021004 -2.06556004 1.71298002 -2.13276998 0 P 0 ;0
L 1.71298002 -2.13276998 1.70836998 -2.14293996 0 P 0 ;0
L 1.70836998 -2.14293996 1.70413996 -2.15076004 0 P 0 ;0
L 1.70413996 -2.15076004 1.69941998 -2.15828996 0 P 0 ;0
L 1.69941998 -2.15828996 1.6967 -2.16198996 0 P 0 ;0
L 1.6967 -2.16198996 1.6937 -2.16541998 0 P 0 ;0
L 1.6937 -2.16541998 1.69041998 -2.1686 0 P 0 ;0
L 1.69041998 -2.1686 1.68793996 -2.17063002 0 P 0 ;0
L 1.68793996 -2.17063002 1.68535 -2.17248002 0 P 0 ;0
L 1.68535 -2.17248002 1.68263996 -2.17413996 0 P 0 ;0
L 1.68263996 -2.17413996 1.67981004 -2.17561004 0 P 0 ;0
L 1.67981004 -2.17561004 1.67525 -2.17761004 0 P 0 ;0
L 1.67525 -2.17761004 1.6706 -2.17931998 0 P 0 ;0
L 1.6706 -2.17931998 1.66586004 -2.18073002 0 P 0 ;0
L 1.66586004 -2.18073002 1.66141998 -2.1817 0 P 0 ;0
L 1.66141998 -2.1817 1.65691998 -2.18228996 0 P 0 ;0
L 1.65691998 -2.18228996 1.64433002 -2.18295 0 P 0 ;0
L 1.61928996 -2.00628002 1.62683996 -2.02673002 0 P 0 ;0
L 1.62683996 -2.02673002 1.6425 -2.07178002 0 P 0 ;0
L 1.6425 -2.07178002 1.65981004 -2.12201998 0 P 0 ;0
L 1.65981004 -2.12201998 1.66006004 -2.12283996 0 P 0 ;0
L 1.66006004 -2.12283996 1.66023002 -2.12368002 0 P 0 ;0
L 1.66023002 -2.12368002 1.66033996 -2.12451998 0 P 0 ;0
L 1.66033996 -2.12451998 1.66036998 -2.12538002 0 P 0 ;0
L 1.66036998 -2.12538002 1.66033996 -2.12601004 0 P 0 ;0
L 1.66033996 -2.12601004 1.66026998 -2.12663996 0 P 0 ;0
L 1.66026998 -2.12663996 1.66013996 -2.12725 0 P 0 ;0
L 1.66013996 -2.12725 1.65995 -2.12786004 0 P 0 ;0
L 1.65995 -2.12786004 1.65971004 -2.12843996 0 P 0 ;0
L 1.65971004 -2.12843996 1.65856998 -2.1308 0 P 0 ;0
L 1.65856998 -2.1308 1.6573 -2.13313002 0 P 0 ;0
L 1.6573 -2.13313002 1.65586998 -2.13545 0 P 0 ;0
L 1.65586998 -2.13545 1.65431004 -2.13771998 0 P 0 ;0
L 1.65431004 -2.13771998 1.65343996 -2.1388 0 P 0 ;0
L 1.65343996 -2.1388 1.65248996 -2.13981998 0 P 0 ;0
L 1.65248996 -2.13981998 1.65146004 -2.14076004 0 P 0 ;0
L 1.65146004 -2.14076004 1.64971004 -2.14213002 0 P 0 ;0
L 1.64971004 -2.14213002 1.64785 -2.14336004 0 P 0 ;0
L 1.64785 -2.14336004 1.64588996 -2.14443996 0 P 0 ;0
L 1.64588996 -2.14443996 1.64446998 -2.14508002 0 P 0 ;0
L 1.64446998 -2.14508002 1.64301004 -2.14561998 0 P 0 ;0
L 1.64301004 -2.14561998 1.64151004 -2.14605 0 P 0 ;0
L 1.64151004 -2.14605 1.63996998 -2.14636998 0 P 0 ;0
L 1.63996998 -2.14636998 1.63741004 -2.14673996 0 P 0 ;0
L 1.63741004 -2.14673996 1.63483002 -2.14693002 0 P 0 ;0
L 1.63483002 -2.14693002 1.63223002 -2.14693996 0 P 0 ;0
L 1.63223002 -2.14693996 1.62036004 -2.14621998 0 P 0 ;0
L 1.62036004 -2.14621998 1.6113 -2.14538002 0 P 0 ;0
L 1.6113 -2.14538002 1.61208996 -2.16023002 0 P 0 ;0
L 1.61208996 -2.16023002 1.61298002 -2.17515 0 P 0 ;0
L 1.61298002 -2.17515 1.6131 -2.17628002 0 P 0 ;0
L 1.6131 -2.17628002 1.61331998 -2.17741004 0 P 0 ;0
L 1.61331998 -2.17741004 1.61361998 -2.17851004 0 P 0 ;0
L 1.61361998 -2.17851004 1.614 -2.17958996 0 P 0 ;0
L 1.614 -2.17958996 1.61413996 -2.17988996 0 P 0 ;0
L 1.61413996 -2.17988996 1.61428996 -2.18018002 0 P 0 ;0
L 1.61428996 -2.18018002 1.61446998 -2.18045 0 P 0 ;0
L 1.61446998 -2.18045 1.61466998 -2.18071004 0 P 0 ;0
L 1.61466998 -2.18071004 1.61488996 -2.18095 0 P 0 ;0
L 1.61488996 -2.18095 1.61511998 -2.18116998 0 P 0 ;0
L 1.61511998 -2.18116998 1.61538002 -2.18138002 0 P 0 ;0
L 1.61538002 -2.18138002 1.61565 -2.18156004 0 P 0 ;0
L 1.61565 -2.18156004 1.61593002 -2.18173002 0 P 0 ;0
L 1.61593002 -2.18173002 1.61623002 -2.18186004 0 P 0 ;0
L 1.61623002 -2.18186004 1.61788002 -2.1825 0 P 0 ;0
L 1.61788002 -2.1825 1.61956998 -2.18301998 0 P 0 ;0
L 1.61956998 -2.18301998 1.6213 -2.18343002 0 P 0 ;0
L 1.6213 -2.18343002 1.62633002 -2.18426004 0 P 0 ;0
L 1.62633002 -2.18426004 1.6314 -2.18471004 0 P 0 ;0
L 1.6314 -2.18471004 1.64436004 -2.18495 0 P 0 ;0
L 1.64436004 -2.18495 1.65711004 -2.18428002 0 P 0 ;0
L 1.65711004 -2.18428002 1.66176998 -2.18366998 0 P 0 ;0
L 1.66176998 -2.18366998 1.66636004 -2.18266998 0 P 0 ;0
L 1.66636004 -2.18266998 1.67123002 -2.18121004 0 P 0 ;0
L 1.67123002 -2.18121004 1.676 -2.17946998 0 P 0 ;0
L 1.676 -2.17946998 1.68068002 -2.17741998 0 P 0 ;0
L 1.68068002 -2.17741998 1.68361998 -2.17588002 0 P 0 ;0
L 1.68361998 -2.17588002 1.68646004 -2.17415 0 P 0 ;0
L 1.68646004 -2.17415 1.68916004 -2.17221998 0 P 0 ;0
L 1.68916004 -2.17221998 1.69175 -2.17008996 0 P 0 ;0
L 1.69175 -2.17008996 1.69515 -2.1668 0 P 0 ;0
L 1.69515 -2.1668 1.69826004 -2.16323996 0 P 0 ;0
L 1.69826004 -2.16323996 1.70108002 -2.15941998 0 P 0 ;0
L 1.70108002 -2.15941998 1.70586004 -2.15176998 0 P 0 ;0
L 1.70586004 -2.15176998 1.71016004 -2.14383002 0 P 0 ;0
L 1.71016004 -2.14383002 1.71481998 -2.13356004 0 P 0 ;0
L 1.71481998 -2.13356004 1.74206998 -2.06631004 0 P 0 ;0
L 1.74206998 -2.06631004 1.77071004 -1.99548002 0 P 0 ;0
L 1.77071004 -1.99548002 1.77088002 -1.99498996 0 P 0 ;0
L 1.77088002 -1.99498996 1.77101998 -1.99448996 0 P 0 ;0
L 1.77101998 -1.99448996 1.77111998 -1.99398996 0 P 0 ;0
L 1.77111998 -1.99398996 1.77118002 -1.99346998 0 P 0 ;0
L 1.77118002 -1.99346998 1.7712 -1.99295 0 P 0 ;0
L 1.7712 -1.99295 1.7712 -1.99293002 0 P 0 ;0
L 1.7712 -1.99293002 1.77118996 -1.99286998 0 P 0 ;0
L 1.77118996 -1.99286998 1.77118002 -1.99286004 0 P 0 ;0
L 1.77118002 -1.99286004 1.77118002 -1.99283996 0 P 0 ;0
L 1.77118002 -1.99283996 1.77111004 -1.99276998 0 P 0 ;0
L 1.77111004 -1.99276998 1.77106998 -1.99275 0 P 0 ;0
L 1.77106998 -1.99275 1.77106004 -1.99273996 0 P 0 ;0
L 1.77106004 -1.99273996 1.771 -1.99273002 0 P 0 ;0
L 1.771 -1.99273002 1.77098002 -1.99273002 0 P 0 ;0
L 1.77098002 -1.99273002 1.76301004 -1.99265 0 P 0 ;0
L 1.76301004 -1.99265 1.75401998 -1.99261004 0 P 0 ;0
L 1.75401998 -1.99261004 1.74333002 -1.9927 0 P 0 ;0
L 1.74333002 -1.9927 1.71546004 -1.99298996 0 P 0 ;0
L 1.71546004 -1.99298996 1.71236998 -2.00646998 0 P 0 ;0
L 1.71236998 -2.00646998 1.70873996 -2.02078002 0 P 0 ;0
L 1.70873996 -2.02078002 1.70233996 -2.04308002 0 P 0 ;0
L 1.70233996 -2.04308002 1.69505 -2.0678 0 P 0 ;0
L 1.69505 -2.0678 1.69501998 -2.06788002 0 P 0 ;0
L 1.69501998 -2.06788002 1.69498996 -2.06795 0 P 0 ;0
L 1.69498996 -2.06795 1.69495 -2.06801998 0 P 0 ;0
L 1.69495 -2.06801998 1.69485 -2.06816004 0 P 0 ;0
L 1.69485 -2.06816004 1.69478996 -2.06821998 0 P 0 ;0
L 1.69478996 -2.06821998 1.69466998 -2.06831998 0 P 0 ;0
L 1.69466998 -2.06831998 1.69453002 -2.0684 0 P 0 ;0
L 1.69453002 -2.0684 1.69445 -2.06843002 0 P 0 ;0
L 1.69445 -2.06843002 1.69438002 -2.06846004 0 P 0 ;0
L 1.69438002 -2.06846004 1.69428996 -2.06846998 0 P 0 ;0
L 1.69428996 -2.06846998 1.69421004 -2.06848996 0 P 0 ;0
L 1.69421004 -2.06848996 1.69406998 -2.06848996 0 P 0 ;0
L 1.69406998 -2.06848996 1.69395 -2.06846998 0 P 0 ;0
L 1.69395 -2.06846998 1.69383002 -2.06843002 0 P 0 ;0
L 1.69383002 -2.06843002 1.69373002 -2.06836998 0 P 0 ;0
L 1.69373002 -2.06836998 1.69363002 -2.06828996 0 P 0 ;0
L 1.69363002 -2.06828996 1.69358996 -2.06823996 0 P 0 ;0
L 1.69358996 -2.06823996 1.69355 -2.0682 0 P 0 ;0
L 1.69355 -2.0682 1.69351998 -2.06815 0 P 0 ;0
L 1.69351998 -2.06815 1.69346004 -2.06803996 0 P 0 ;0
L 1.69346004 -2.06803996 1.69343996 -2.06798002 0 P 0 ;0
L 1.69343996 -2.06798002 1.68523002 -2.03878002 0 P 0 ;0
L 1.68523002 -2.03878002 1.67806998 -2.01291998 0 P 0 ;0
L 1.67806998 -2.01291998 1.67496004 -2.00031004 0 P 0 ;0
L 1.67496004 -2.00031004 1.67323002 -1.99243996 0 P 0 ;0
L 1.67323002 -1.99243996 1.61388002 -1.99243996 0 P 0 ;0
L 1.61388002 -1.99243996 1.61928996 -2.00628002 0 P 0 ;0
L 1.35018002 -2.08345 1.39488996 -2.08345 0 P 0 ;0
L 1.35026004 -2.08245 1.39586004 -2.08245 0 P 0 ;0
L 1.35041004 -2.08145 1.39708996 -2.08145 0 P 0 ;0
L 1.35058996 -2.08045 1.39853002 -2.08045 0 P 0 ;0
L 1.35083996 -2.07945 1.40031998 -2.07945 0 P 0 ;0
L 1.35116998 -2.07845 1.40271004 -2.07845 0 P 0 ;0
L 1.35158002 -2.07745 1.40561998 -2.07745 0 P 0 ;0
L 1.35203002 -2.07645 1.4092 -2.07645 0 P 0 ;0
L 1.35248002 -2.07545 1.41288996 -2.07545 0 P 0 ;0
L 1.35293002 -2.07445 1.4164 -2.07445 0 P 0 ;0
L 1.35338996 -2.07345 1.41975 -2.07345 0 P 0 ;0
L 1.35393996 -2.07245 1.42293996 -2.07245 0 P 0 ;0
L 1.35448996 -2.07145 1.42606998 -2.07145 0 P 0 ;0
L 1.35505 -2.07045 1.47843002 -2.07045 0 P 0 ;0
L 1.3557 -2.06945 1.47846998 -2.06945 0 P 0 ;0
L 1.35635 -2.06845 1.47851998 -2.06845 0 P 0 ;0
L 1.35701998 -2.06745 1.47856998 -2.06745 0 P 0 ;0
L 1.35776998 -2.06645 1.47861004 -2.06645 0 P 0 ;0
L 1.29346998 -2.00516004 1.33388996 -2.00516004 0 P 0 ;0
L 1.29448996 -2.00416004 1.33385 -2.00416004 0 P 0 ;0
L 1.29551004 -2.00316004 1.33381004 -2.00316004 0 P 0 ;0
L 1.29653996 -2.00216004 1.33376004 -2.00216004 0 P 0 ;0
L 1.29756004 -2.00116004 1.33371004 -2.00116004 0 P 0 ;0
L 1.29861998 -2.00016004 1.33366004 -2.00016004 0 P 0 ;0
L 1.29973002 -1.99916004 1.3336 -1.99916004 0 P 0 ;0
L 1.30101004 -1.99816004 1.33355 -1.99816004 0 P 0 ;0
L 1.30238996 -1.99716004 1.3335 -1.99716004 0 P 0 ;0
L 1.30393996 -1.99616004 1.33345 -1.99616004 0 P 0 ;0
L 1.30571004 -1.99516004 1.33338996 -1.99516004 0 P 0 ;0
L 1.3077 -1.99416004 1.33333002 -1.99416004 0 P 0 ;0
L 1.31001004 -1.99316004 1.33328002 -1.99316004 0 P 0 ;0
L 1.31288002 -1.99216004 1.33321998 -1.99216004 0 P 0 ;0
L 1.31688996 -1.99116004 1.33316004 -1.99116004 0 P 0 ;0
L 1.39798996 -1.98971998 1.39326998 -1.99043002 0 P 0 ;0
L 1.39326998 -1.99043002 1.38806998 -1.9913 0 P 0 ;0
L 1.38806998 -1.9913 1.38316004 -1.9922 0 P 0 ;0
L 1.38316004 -1.9922 1.37946004 -1.99296998 0 P 0 ;0
L 1.37946004 -1.99296998 1.3718 -1.99466998 0 P 0 ;0
L 1.3718 -1.99466998 1.36896004 -2.01553996 0 P 0 ;0
L 1.36896004 -2.01553996 1.36791004 -2.02358996 0 P 0 ;0
L 1.36791004 -2.02358996 1.36708002 -2.03043002 0 P 0 ;0
L 1.36708002 -2.03043002 1.36638996 -2.03646004 0 P 0 ;0
L 1.36638996 -2.03646004 1.36638002 -2.03648996 0 P 0 ;0
L 1.36638002 -2.03648996 1.36638996 -2.03653002 0 P 0 ;0
L 1.36638996 -2.03653002 1.36638996 -2.03656998 0 P 0 ;0
L 1.36638996 -2.03656998 1.3664 -2.03663996 0 P 0 ;0
L 1.3664 -2.03663996 1.36641998 -2.03666998 0 P 0 ;0
L 1.36641998 -2.03666998 1.36643002 -2.03671004 0 P 0 ;0
L 1.36643002 -2.03671004 1.36648996 -2.0368 0 P 0 ;0
L 1.36648996 -2.0368 1.36656004 -2.03686004 0 P 0 ;0
L 1.36656004 -2.03686004 1.3666 -2.03688996 0 P 0 ;0
L 1.3666 -2.03688996 1.36663002 -2.03691004 0 P 0 ;0
L 1.36663002 -2.03691004 1.36666004 -2.03691004 0 P 0 ;0
L 1.36666004 -2.03691004 1.36671004 -2.03693002 0 P 0 ;0
L 1.36671004 -2.03693002 1.36676998 -2.03693002 0 P 0 ;0
L 1.36676998 -2.03693002 1.36685 -2.03691998 0 P 0 ;0
L 1.36685 -2.03691998 1.36895 -2.03628002 0 P 0 ;0
L 1.36895 -2.03628002 1.37143002 -2.03545 0 P 0 ;0
L 1.37143002 -2.03545 1.37428996 -2.03441004 0 P 0 ;0
L 1.37428996 -2.03441004 1.38346004 -2.03126998 0 P 0 ;0
L 1.38346004 -2.03126998 1.39251998 -2.02891998 0 P 0 ;0
L 1.39251998 -2.02891998 1.40156004 -2.02731998 0 P 0 ;0
L 1.40156004 -2.02731998 1.41068002 -2.02643996 0 P 0 ;0
L 1.41068002 -2.02643996 1.41566998 -2.02628002 0 P 0 ;0
L 1.41566998 -2.02628002 1.42066004 -2.02633996 0 P 0 ;0
L 1.42066004 -2.02633996 1.42221004 -2.02646998 0 P 0 ;0
L 1.42221004 -2.02646998 1.42375 -2.02671998 0 P 0 ;0
L 1.42375 -2.02671998 1.42525 -2.0271 0 P 0 ;0
L 1.42525 -2.0271 1.42671998 -2.02761004 0 P 0 ;0
L 1.42671998 -2.02761004 1.42706004 -2.02776004 0 P 0 ;0
L 1.42706004 -2.02776004 1.42738002 -2.02793002 0 P 0 ;0
L 1.42738002 -2.02793002 1.42768002 -2.02813996 0 P 0 ;0
L 1.42768002 -2.02813996 1.42796998 -2.02836004 0 P 0 ;0
L 1.42796998 -2.02836004 1.42823002 -2.02861004 0 P 0 ;0
L 1.42823002 -2.02861004 1.42848002 -2.02888996 0 P 0 ;0
L 1.42848002 -2.02888996 1.4287 -2.02918002 0 P 0 ;0
L 1.4287 -2.02918002 1.42888996 -2.02948996 0 P 0 ;0
L 1.42888996 -2.02948996 1.42906004 -2.02981004 0 P 0 ;0
L 1.42906004 -2.02981004 1.4292 -2.03015 0 P 0 ;0
L 1.4292 -2.03015 1.42931998 -2.0305 0 P 0 ;0
L 1.42931998 -2.0305 1.4294 -2.03086004 0 P 0 ;0
L 1.4294 -2.03086004 1.42945 -2.03121998 0 P 0 ;0
L 1.42945 -2.03121998 1.42946998 -2.03158002 0 P 0 ;0
L 1.42946998 -2.03158002 1.42946004 -2.03195 0 P 0 ;0
L 1.42946004 -2.03195 1.42941998 -2.03231004 0 P 0 ;0
L 1.42941998 -2.03231004 1.42935 -2.03266998 0 P 0 ;0
L 1.42935 -2.03266998 1.42925 -2.03301998 0 P 0 ;0
L 1.42925 -2.03301998 1.42911998 -2.03336004 0 P 0 ;0
L 1.42911998 -2.03336004 1.42896004 -2.03368996 0 P 0 ;0
L 1.42896004 -2.03368996 1.42875 -2.03405 0 P 0 ;0
L 1.42875 -2.03405 1.42851004 -2.03438996 0 P 0 ;0
L 1.42851004 -2.03438996 1.42825 -2.03471004 0 P 0 ;0
L 1.42825 -2.03471004 1.42796004 -2.03501004 0 P 0 ;0
L 1.42796004 -2.03501004 1.42765 -2.03528996 0 P 0 ;0
L 1.42765 -2.03528996 1.42731998 -2.03553996 0 P 0 ;0
L 1.42731998 -2.03553996 1.42696998 -2.03576004 0 P 0 ;0
L 1.42696998 -2.03576004 1.4266 -2.03596004 0 P 0 ;0
L 1.4266 -2.03596004 1.41951004 -2.03906004 0 P 0 ;0
L 1.41951004 -2.03906004 1.4109 -2.04208996 0 P 0 ;0
L 1.4109 -2.04208996 1.40178002 -2.04451998 0 P 0 ;0
L 1.40178002 -2.04451998 1.3878 -2.04818996 0 P 0 ;0
L 1.3878 -2.04818996 1.38176998 -2.05015 0 P 0 ;0
L 1.38176998 -2.05015 1.3758 -2.05243002 0 P 0 ;0
L 1.3758 -2.05243002 1.37086998 -2.0546 0 P 0 ;0
L 1.37086998 -2.0546 1.36603996 -2.05708002 0 P 0 ;0
L 1.36603996 -2.05708002 1.36356004 -2.05856004 0 P 0 ;0
L 1.36356004 -2.05856004 1.36118996 -2.06023002 0 P 0 ;0
L 1.36118996 -2.06023002 1.35895 -2.06206004 0 P 0 ;0
L 1.35895 -2.06206004 1.35805 -2.06291004 0 P 0 ;0
L 1.35805 -2.06291004 1.35721998 -2.06385 0 P 0 ;0
L 1.35721998 -2.06385 1.35518996 -2.06655 0 P 0 ;0
L 1.35518996 -2.06655 1.3532 -2.06961998 0 P 0 ;0
L 1.3532 -2.06961998 1.35156004 -2.07263002 0 P 0 ;0
L 1.35156004 -2.07263002 1.34951004 -2.07718002 0 P 0 ;0
L 1.34951004 -2.07718002 1.34911004 -2.07825 0 P 0 ;0
L 1.34911004 -2.07825 1.34878996 -2.07935 0 P 0 ;0
L 1.34878996 -2.07935 1.34853002 -2.08046998 0 P 0 ;0
L 1.34853002 -2.08046998 1.34825 -2.08238002 0 P 0 ;0
L 1.34825 -2.08238002 1.34811998 -2.08431004 0 P 0 ;0
L 1.34811998 -2.08431004 1.348 -2.09128996 0 P 0 ;0
L 1.348 -2.09128996 1.3481 -2.09761004 0 P 0 ;0
L 1.3481 -2.09761004 1.34823002 -2.09961004 0 P 0 ;0
L 1.34823002 -2.09961004 1.34846998 -2.10161004 0 P 0 ;0
L 1.34846998 -2.10161004 1.34876998 -2.10321998 0 P 0 ;0
L 1.34876998 -2.10321998 1.3492 -2.10478996 0 P 0 ;0
L 1.3492 -2.10478996 1.3498 -2.10648996 0 P 0 ;0
L 1.3498 -2.10648996 1.3505 -2.10815 0 P 0 ;0
L 1.3505 -2.10815 1.35178996 -2.11066004 0 P 0 ;0
L 1.35178996 -2.11066004 1.35328002 -2.11305 0 P 0 ;0
L 1.35328002 -2.11305 1.35496998 -2.1153 0 P 0 ;0
L 1.35496998 -2.1153 1.35685 -2.1174 0 P 0 ;0
L 1.35685 -2.1174 1.35891998 -2.11933996 0 P 0 ;0
L 1.35891998 -2.11933996 1.36126998 -2.12121998 0 P 0 ;0
L 1.36126998 -2.12121998 1.36373996 -2.12293002 0 P 0 ;0
L 1.36373996 -2.12293002 1.36633002 -2.12446004 0 P 0 ;0
L 1.36633002 -2.12446004 1.36901004 -2.1258 0 P 0 ;0
L 1.36901004 -2.1258 1.3718 -2.12695 0 P 0 ;0
L 1.3718 -2.12695 1.37578996 -2.12828002 0 P 0 ;0
L 1.37578996 -2.12828002 1.37986998 -2.12928996 0 P 0 ;0
L 1.37986998 -2.12928996 1.38401998 -2.12998996 0 P 0 ;0
L 1.38401998 -2.12998996 1.3882 -2.13036004 0 P 0 ;0
L 1.3882 -2.13036004 1.39443002 -2.13045 0 P 0 ;0
L 1.39443002 -2.13045 1.40066004 -2.13006998 0 P 0 ;0
L 1.40066004 -2.13006998 1.40685 -2.12923002 0 P 0 ;0
L 1.40685 -2.12923002 1.41371004 -2.12801998 0 P 0 ;0
L 1.41371004 -2.12801998 1.41583002 -2.12081004 0 P 0 ;0
L 1.41583002 -2.12081004 1.41953996 -2.10798996 0 P 0 ;0
L 1.41953996 -2.10798996 1.42135 -2.10126998 0 P 0 ;0
L 1.42135 -2.10126998 1.42236998 -2.097 0 P 0 ;0
L 1.42236998 -2.097 1.42238996 -2.09691004 0 P 0 ;0
L 1.42238996 -2.09691004 1.4224 -2.09681998 0 P 0 ;0
L 1.4224 -2.09681998 1.4224 -2.09673996 0 P 0 ;0
L 1.4224 -2.09673996 1.42238002 -2.09656004 0 P 0 ;0
L 1.42238002 -2.09656004 1.42235 -2.09648002 0 P 0 ;0
L 1.42235 -2.09648002 1.42233002 -2.09638996 0 P 0 ;0
L 1.42233002 -2.09638996 1.42225 -2.09623002 0 P 0 ;0
L 1.42225 -2.09623002 1.4222 -2.09616004 0 P 0 ;0
L 1.4222 -2.09616004 1.42213996 -2.09608996 0 P 0 ;0
L 1.42213996 -2.09608996 1.42208996 -2.09601998 0 P 0 ;0
L 1.42208996 -2.09601998 1.42203996 -2.09598996 0 P 0 ;0
L 1.42203996 -2.09598996 1.42198996 -2.09595 0 P 0 ;0
L 1.42198996 -2.09595 1.42188996 -2.09588996 0 P 0 ;0
L 1.42188996 -2.09588996 1.42183002 -2.09586004 0 P 0 ;0
L 1.42183002 -2.09586004 1.42178002 -2.09585 0 P 0 ;0
L 1.42178002 -2.09585 1.42171998 -2.09583002 0 P 0 ;0
L 1.42171998 -2.09583002 1.42166004 -2.09581998 0 P 0 ;0
L 1.42166004 -2.09581998 1.42153996 -2.09581998 0 P 0 ;0
L 1.42153996 -2.09581998 1.41978002 -2.09591004 0 P 0 ;0
L 1.41978002 -2.09591004 1.41763996 -2.09615 0 P 0 ;0
L 1.41763996 -2.09615 1.41521998 -2.09658002 0 P 0 ;0
L 1.41521998 -2.09658002 1.4107 -2.09733002 0 P 0 ;0
L 1.4107 -2.09733002 1.40613002 -2.09775 0 P 0 ;0
L 1.40613002 -2.09775 1.40481004 -2.09778002 0 P 0 ;0
L 1.40481004 -2.09778002 1.40348996 -2.09771998 0 P 0 ;0
L 1.40348996 -2.09771998 1.40216998 -2.09756004 0 P 0 ;0
L 1.40216998 -2.09756004 1.40086998 -2.0973 0 P 0 ;0
L 1.40086998 -2.0973 1.39958996 -2.09695 0 P 0 ;0
L 1.39958996 -2.09695 1.39895 -2.09671998 0 P 0 ;0
L 1.39895 -2.09671998 1.39831998 -2.09643002 0 P 0 ;0
L 1.39831998 -2.09643002 1.39773002 -2.0961 0 P 0 ;0
L 1.39773002 -2.0961 1.39716004 -2.09571004 0 P 0 ;0
L 1.39716004 -2.09571004 1.39663002 -2.09528002 0 P 0 ;0
L 1.39663002 -2.09528002 1.39613996 -2.0948 0 P 0 ;0
L 1.39613996 -2.0948 1.39568002 -2.09428002 0 P 0 ;0
L 1.39568002 -2.09428002 1.39533996 -2.09381998 0 P 0 ;0
L 1.39533996 -2.09381998 1.39505 -2.09333996 0 P 0 ;0
L 1.39505 -2.09333996 1.39478996 -2.09281998 0 P 0 ;0
L 1.39478996 -2.09281998 1.39456998 -2.09228996 0 P 0 ;0
L 1.39456998 -2.09228996 1.3944 -2.09173996 0 P 0 ;0
L 1.3944 -2.09173996 1.39428002 -2.09118996 0 P 0 ;0
L 1.39428002 -2.09118996 1.39421004 -2.09061998 0 P 0 ;0
L 1.39421004 -2.09061998 1.39418002 -2.09003996 0 P 0 ;0
L 1.39418002 -2.09003996 1.39421004 -2.08943002 0 P 0 ;0
L 1.39421004 -2.08943002 1.39428002 -2.08883002 0 P 0 ;0
L 1.39428002 -2.08883002 1.39441004 -2.08823002 0 P 0 ;0
L 1.39441004 -2.08823002 1.3946 -2.08765 0 P 0 ;0
L 1.3946 -2.08765 1.39483002 -2.08708002 0 P 0 ;0
L 1.39483002 -2.08708002 1.39511004 -2.08653996 0 P 0 ;0
L 1.39511004 -2.08653996 1.39555 -2.08583996 0 P 0 ;0
L 1.39555 -2.08583996 1.39603996 -2.08518002 0 P 0 ;0
L 1.39603996 -2.08518002 1.39658002 -2.08456004 0 P 0 ;0
L 1.39658002 -2.08456004 1.39716004 -2.08396998 0 P 0 ;0
L 1.39716004 -2.08396998 1.39778002 -2.08343002 0 P 0 ;0
L 1.39778002 -2.08343002 1.39878996 -2.08266998 0 P 0 ;0
L 1.39878996 -2.08266998 1.39985 -2.08196998 0 P 0 ;0
L 1.39985 -2.08196998 1.40096004 -2.08135 0 P 0 ;0
L 1.40096004 -2.08135 1.40211998 -2.08081004 0 P 0 ;0
L 1.40211998 -2.08081004 1.40503002 -2.07971004 0 P 0 ;0
L 1.40503002 -2.07971004 1.40801998 -2.07881998 0 P 0 ;0
L 1.40801998 -2.07881998 1.41128996 -2.07796004 0 P 0 ;0
L 1.41128996 -2.07796004 1.41506004 -2.07691998 0 P 0 ;0
L 1.41506004 -2.07691998 1.41871998 -2.07585 0 P 0 ;0
L 1.41871998 -2.07585 1.42165 -2.07495 0 P 0 ;0
L 1.42165 -2.07495 1.42791998 -2.07295 0 P 0 ;0
L 1.42791998 -2.07295 1.42731998 -2.08241004 0 P 0 ;0
L 1.42731998 -2.08241004 1.42701004 -2.08708002 0 P 0 ;0
L 1.42701004 -2.08708002 1.42658002 -2.09353996 0 P 0 ;0
L 1.42658002 -2.09353996 1.4261 -2.10055 0 P 0 ;0
L 1.4261 -2.10055 1.42566998 -2.10706004 0 P 0 ;0
L 1.42566998 -2.10706004 1.42525 -2.11306004 0 P 0 ;0
L 1.42525 -2.11306004 1.42491998 -2.11851998 0 P 0 ;0
L 1.42491998 -2.11851998 1.42466004 -2.1231 0 P 0 ;0
L 1.42466004 -2.1231 1.42461004 -2.12471004 0 P 0 ;0
L 1.42461004 -2.12471004 1.4246 -2.12716004 0 P 0 ;0
L 1.4246 -2.12716004 1.47893002 -2.12716004 0 P 0 ;0
L 1.47893002 -2.12716004 1.47893002 -2.11358002 0 P 0 ;0
L 1.47893002 -2.11358002 1.47905 -2.10616998 0 P 0 ;0
L 1.47905 -2.10616998 1.47943996 -2.09385 0 P 0 ;0
L 1.47943996 -2.09385 1.48 -2.07968996 0 P 0 ;0
L 1.48 -2.07968996 1.48066004 -2.0655 0 P 0 ;0
L 1.48066004 -2.0655 1.4813 -2.05168996 0 P 0 ;0
L 1.4813 -2.05168996 1.48175 -2.03873996 0 P 0 ;0
L 1.48175 -2.03873996 1.48201998 -2.02785 0 P 0 ;0
L 1.48201998 -2.02785 1.48191998 -2.02286004 0 P 0 ;0
L 1.48191998 -2.02286004 1.48165 -2.01995 0 P 0 ;0
L 1.48165 -2.01995 1.48115 -2.01708002 0 P 0 ;0
L 1.48115 -2.01708002 1.48043996 -2.01425 0 P 0 ;0
L 1.48043996 -2.01425 1.47951004 -2.01146998 0 P 0 ;0
L 1.47951004 -2.01146998 1.47866998 -2.00946998 0 P 0 ;0
L 1.47866998 -2.00946998 1.47768002 -2.00753996 0 P 0 ;0
L 1.47768002 -2.00753996 1.47655 -2.00568002 0 P 0 ;0
L 1.47655 -2.00568002 1.47528002 -2.00391998 0 P 0 ;0
L 1.47528002 -2.00391998 1.47388002 -2.00225 0 P 0 ;0
L 1.47388002 -2.00225 1.47228996 -2.00063002 0 P 0 ;0
L 1.47228996 -2.00063002 1.4706 -1.99911998 0 P 0 ;0
L 1.4706 -1.99911998 1.4688 -1.99773002 0 P 0 ;0
L 1.4688 -1.99773002 1.46691004 -1.99648002 0 P 0 ;0
L 1.46691004 -1.99648002 1.46491998 -1.99535 0 P 0 ;0
L 1.46491998 -1.99535 1.46098996 -1.99351004 0 P 0 ;0
L 1.46098996 -1.99351004 1.45693002 -1.99196998 0 P 0 ;0
L 1.45693002 -1.99196998 1.45276004 -1.99076004 0 P 0 ;0
L 1.45276004 -1.99076004 1.44953996 -1.99006004 0 P 0 ;0
L 1.44953996 -1.99006004 1.44628996 -1.98956004 0 P 0 ;0
L 1.44628996 -1.98956004 1.44298002 -1.98923996 0 P 0 ;0
L 1.44298002 -1.98923996 1.42695 -1.98856998 0 P 0 ;0
L 1.42695 -1.98856998 1.41038996 -1.98865 0 P 0 ;0
L 1.41038996 -1.98865 1.4042 -1.98901004 0 P 0 ;0
L 1.4042 -1.98901004 1.39798996 -1.98971998 0 P 0 ;0
L 1.35778996 -2.11545 1.4153 -2.11545 0 P 0 ;0
L 1.35688996 -2.11445 1.41558996 -2.11445 0 P 0 ;0
L 1.35608002 -2.11345 1.41588002 -2.11345 0 P 0 ;0
L 1.35533002 -2.11245 1.41616998 -2.11245 0 P 0 ;0
L 1.35463996 -2.11145 1.41646004 -2.11145 0 P 0 ;0
L 1.35401004 -2.11045 1.41675 -2.11045 0 P 0 ;0
L 1.35341004 -2.10945 1.41703996 -2.10945 0 P 0 ;0
L 1.3529 -2.10845 1.41733002 -2.10845 0 P 0 ;0
L 1.35238002 -2.10745 1.41761998 -2.10745 0 P 0 ;0
L 1.35195 -2.10645 1.41788002 -2.10645 0 P 0 ;0
L 1.35155 -2.10545 1.41816004 -2.10545 0 P 0 ;0
L 1.3512 -2.10445 1.41841998 -2.10445 0 P 0 ;0
L 1.35091004 -2.10345 1.41868996 -2.10345 0 P 0 ;0
L 1.35066004 -2.10245 1.41896004 -2.10245 0 P 0 ;0
L 1.35046998 -2.10145 1.41923002 -2.10145 0 P 0 ;0
L 1.35033996 -2.10045 1.41948996 -2.10045 0 P 0 ;0
L 1.35021998 -2.09945 1.40141004 -2.09945 0 P 0 ;0
L 1.35016004 -2.09845 1.39791004 -2.09845 0 P 0 ;0
L 1.3501 -2.09745 1.39616004 -2.09745 0 P 0 ;0
L 1.35008002 -2.09645 1.39496004 -2.09645 0 P 0 ;0
L 1.35006998 -2.09545 1.39406004 -2.09545 0 P 0 ;0
L 1.35005 -2.09445 1.39338002 -2.09445 0 P 0 ;0
L 1.35003996 -2.09345 1.39288002 -2.09345 0 P 0 ;0
L 1.35001998 -2.09245 1.39253002 -2.09245 0 P 0 ;0
L 1.35001004 -2.09145 1.3923 -2.09145 0 P 0 ;0
L 1.35001998 -2.09045 1.3922 -2.09045 0 P 0 ;0
L 1.35003002 -2.08945 1.3922 -2.08945 0 P 0 ;0
L 1.35005 -2.08845 1.39231998 -2.08845 0 P 0 ;0
L 1.35006998 -2.08745 1.39256004 -2.08745 0 P 0 ;0
L 1.35008002 -2.08645 1.39293002 -2.08645 0 P 0 ;0
L 1.3501 -2.08545 1.39343002 -2.08545 0 P 0 ;0
L 1.35011004 -2.08445 1.39408996 -2.08445 0 P 0 ;0
L 1.39438002 -2.12845 1.3883 -2.12836004 0 P 0 ;0
L 1.3883 -2.12836004 1.38426998 -2.128 0 P 0 ;0
L 1.38426998 -2.128 1.38028002 -2.12733002 0 P 0 ;0
L 1.38028002 -2.12733002 1.37635 -2.12636004 0 P 0 ;0
L 1.37635 -2.12636004 1.37248996 -2.12508002 0 P 0 ;0
L 1.37248996 -2.12508002 1.36983996 -2.12398002 0 P 0 ;0
L 1.36983996 -2.12398002 1.36728996 -2.1227 0 P 0 ;0
L 1.36728996 -2.1227 1.36481998 -2.12123996 0 P 0 ;0
L 1.36481998 -2.12123996 1.36246004 -2.11961004 0 P 0 ;0
L 1.36246004 -2.11961004 1.36023002 -2.11781998 0 P 0 ;0
L 1.36023002 -2.11781998 1.35828996 -2.116 0 P 0 ;0
L 1.35828996 -2.116 1.35651998 -2.11403002 0 P 0 ;0
L 1.35651998 -2.11403002 1.35493002 -2.11191004 0 P 0 ;0
L 1.35493002 -2.11191004 1.35353002 -2.10966998 0 P 0 ;0
L 1.35353002 -2.10966998 1.35231004 -2.10731004 0 P 0 ;0
L 1.35231004 -2.10731004 1.35166998 -2.10576998 0 P 0 ;0
L 1.35166998 -2.10576998 1.35111004 -2.1042 0 P 0 ;0
L 1.35111004 -2.1042 1.35071998 -2.10276004 0 P 0 ;0
L 1.35071998 -2.10276004 1.35045 -2.1013 0 P 0 ;0
L 1.35045 -2.1013 1.35021998 -2.09943002 0 P 0 ;0
L 1.35021998 -2.09943002 1.3501 -2.09753002 0 P 0 ;0
L 1.3501 -2.09753002 1.35001004 -2.09128002 0 P 0 ;0
L 1.35001004 -2.09128002 1.35011998 -2.0844 0 P 0 ;0
L 1.35011998 -2.0844 1.35023996 -2.08258996 0 P 0 ;0
L 1.35023996 -2.08258996 1.3505 -2.08083996 0 P 0 ;0
L 1.3505 -2.08083996 1.35071998 -2.07985 0 P 0 ;0
L 1.35071998 -2.07985 1.35101004 -2.07888002 0 P 0 ;0
L 1.35101004 -2.07888002 1.35136004 -2.07793002 0 P 0 ;0
L 1.35136004 -2.07793002 1.35335 -2.07351998 0 P 0 ;0
L 1.35335 -2.07351998 1.35491998 -2.07065 0 P 0 ;0
L 1.35491998 -2.07065 1.35683002 -2.0677 0 P 0 ;0
L 1.35683002 -2.0677 1.35876998 -2.06511004 0 P 0 ;0
L 1.35876998 -2.06511004 1.35948996 -2.0643 0 P 0 ;0
L 1.35948996 -2.0643 1.36026998 -2.06356004 0 P 0 ;0
L 1.36026998 -2.06356004 1.3624 -2.06181998 0 P 0 ;0
L 1.3624 -2.06181998 1.36465 -2.06023996 0 P 0 ;0
L 1.36465 -2.06023996 1.36701004 -2.05883002 0 P 0 ;0
L 1.36701004 -2.05883002 1.37173002 -2.05641004 0 P 0 ;0
L 1.37173002 -2.05641004 1.37656004 -2.05426998 0 P 0 ;0
L 1.37656004 -2.05426998 1.38243002 -2.05203996 0 P 0 ;0
L 1.38243002 -2.05203996 1.38836004 -2.0501 0 P 0 ;0
L 1.38836004 -2.0501 1.4023 -2.04645 0 P 0 ;0
L 1.4023 -2.04645 1.41148996 -2.044 0 P 0 ;0
L 1.41148996 -2.044 1.42016998 -2.04095 0 P 0 ;0
L 1.42016998 -2.04095 1.42016998 -2.04093996 0 P 0 ;0
L 1.42016998 -2.04093996 1.42021004 -2.04093996 0 P 0 ;0
L 1.42021004 -2.04093996 1.42023996 -2.04093002 0 P 0 ;0
L 1.42023996 -2.04093002 1.42746998 -2.03776004 0 P 0 ;0
L 1.42746998 -2.03776004 1.42753002 -2.03773002 0 P 0 ;0
L 1.42753002 -2.03773002 1.42796998 -2.03748996 0 P 0 ;0
L 1.42796998 -2.03748996 1.42846004 -2.03718996 0 P 0 ;0
L 1.42846004 -2.03718996 1.42891998 -2.03683996 0 P 0 ;0
L 1.42891998 -2.03683996 1.42935 -2.03646004 0 P 0 ;0
L 1.42935 -2.03646004 1.42975 -2.03603996 0 P 0 ;0
L 1.42975 -2.03603996 1.43011004 -2.0356 0 P 0 ;0
L 1.43011004 -2.0356 1.43016004 -2.03553002 0 P 0 ;0
L 1.43016004 -2.03553002 1.4299 -2.03535 0 P 0 ;0
L 1.4299 -2.03535 1.43028002 -2.03535 0 P 0 ;0
L 1.43028002 -2.03535 1.43043996 -2.03513002 0 P 0 ;0
L 1.43043996 -2.03513002 1.43048002 -2.03506004 0 P 0 ;0
L 1.43048002 -2.03506004 1.43041998 -2.03501998 0 P 0 ;0
L 1.43041998 -2.03501998 1.4305 -2.03501998 0 P 0 ;0
L 1.4305 -2.03501998 1.43073002 -2.03463002 0 P 0 ;0
L 1.43073002 -2.03463002 1.43096004 -2.03415 0 P 0 ;0
L 1.43096004 -2.03415 1.43115 -2.03365 0 P 0 ;0
L 1.43115 -2.03365 1.4313 -2.03313002 0 P 0 ;0
L 1.4313 -2.03313002 1.4314 -2.03261004 0 P 0 ;0
L 1.4314 -2.03261004 1.43146004 -2.03208002 0 P 0 ;0
L 1.43146004 -2.03208002 1.43146998 -2.03155 0 P 0 ;0
L 1.43146998 -2.03155 1.43143996 -2.03101004 0 P 0 ;0
L 1.43143996 -2.03101004 1.43143002 -2.03093002 0 P 0 ;0
L 1.43143002 -2.03093002 1.43136004 -2.03048996 0 P 0 ;0
L 1.43136004 -2.03048996 1.43125 -2.02996998 0 P 0 ;0
L 1.43125 -2.02996998 1.43108002 -2.02946004 0 P 0 ;0
L 1.43108002 -2.02946004 1.43086998 -2.02896004 0 P 0 ;0
L 1.43086998 -2.02896004 1.43063002 -2.02848996 0 P 0 ;0
L 1.43063002 -2.02848996 1.43033996 -2.02803996 0 P 0 ;0
L 1.43033996 -2.02803996 1.43001998 -2.02761004 0 P 0 ;0
L 1.43001998 -2.02761004 1.42966004 -2.02721004 0 P 0 ;0
L 1.42966004 -2.02721004 1.42928002 -2.02685 0 P 0 ;0
L 1.42928002 -2.02685 1.42886004 -2.02651998 0 P 0 ;0
L 1.42886004 -2.02651998 1.42841998 -2.02623002 0 P 0 ;0
L 1.42841998 -2.02623002 1.42795 -2.02596998 0 P 0 ;0
L 1.42795 -2.02596998 1.42746004 -2.02575 0 P 0 ;0
L 1.42746004 -2.02575 1.42583002 -2.02518002 0 P 0 ;0
L 1.42583002 -2.02518002 1.42416004 -2.02476004 0 P 0 ;0
L 1.42416004 -2.02476004 1.42245 -2.02448002 0 P 0 ;0
L 1.42245 -2.02448002 1.42075 -2.02435 0 P 0 ;0
L 1.42075 -2.02435 1.41565 -2.02428002 0 P 0 ;0
L 1.41565 -2.02428002 1.4156 -2.02428002 0 P 0 ;0
L 1.4156 -2.02428002 1.41055 -2.02445 0 P 0 ;0
L 1.41055 -2.02445 1.41048002 -2.02445 0 P 0 ;0
L 1.41048002 -2.02445 1.40128996 -2.02533996 0 P 0 ;0
L 1.40128996 -2.02533996 1.39208996 -2.02696998 0 P 0 ;0
L 1.39208996 -2.02696998 1.38288002 -2.02936004 0 P 0 ;0
L 1.38288002 -2.02936004 1.37363002 -2.03251998 0 P 0 ;0
L 1.37363002 -2.03251998 1.37076998 -2.03356004 0 P 0 ;0
L 1.37076998 -2.03356004 1.36865 -2.03426998 0 P 0 ;0
L 1.36865 -2.03426998 1.36906004 -2.03066998 0 P 0 ;0
L 1.36906004 -2.03066998 1.36988996 -2.02383996 0 P 0 ;0
L 1.36988996 -2.02383996 1.37095 -2.01581004 0 P 0 ;0
L 1.37095 -2.01581004 1.37358996 -1.99631998 0 P 0 ;0
L 1.37358996 -1.99631998 1.37988002 -1.99491998 0 P 0 ;0
L 1.37988002 -1.99491998 1.38353996 -1.99416998 0 P 0 ;0
L 1.38353996 -1.99416998 1.38841998 -1.99326998 0 P 0 ;0
L 1.38841998 -1.99326998 1.39358002 -1.9924 0 P 0 ;0
L 1.39358002 -1.9924 1.39825 -1.9917 0 P 0 ;0
L 1.39825 -1.9917 1.40436998 -1.991 0 P 0 ;0
L 1.40436998 -1.991 1.41045 -1.99065 0 P 0 ;0
L 1.41045 -1.99065 1.42691004 -1.99056998 0 P 0 ;0
L 1.42691004 -1.99056998 1.44283996 -1.99123996 0 P 0 ;0
L 1.44283996 -1.99123996 1.44603996 -1.99153996 0 P 0 ;0
L 1.44603996 -1.99153996 1.44918002 -1.99203002 0 P 0 ;0
L 1.44918002 -1.99203002 1.45226004 -1.9927 0 P 0 ;0
L 1.45226004 -1.9927 1.4563 -1.99386998 0 P 0 ;0
L 1.4563 -1.99386998 1.46021004 -1.99535 0 P 0 ;0
L 1.46021004 -1.99535 1.464 -1.99713002 0 P 0 ;0
L 1.464 -1.99713002 1.46586004 -1.99818996 0 P 0 ;0
L 1.46586004 -1.99818996 1.46763996 -1.99936004 0 P 0 ;0
L 1.46763996 -1.99936004 1.46931998 -2.00066004 0 P 0 ;0
L 1.46931998 -2.00066004 1.47091004 -2.00206998 0 P 0 ;0
L 1.47091004 -2.00206998 1.47238996 -2.00358996 0 P 0 ;0
L 1.47238996 -2.00358996 1.4737 -2.00515 0 P 0 ;0
L 1.4737 -2.00515 1.47488002 -2.00678996 0 P 0 ;0
L 1.47488002 -2.00678996 1.47593996 -2.00851004 0 P 0 ;0
L 1.47593996 -2.00851004 1.47686004 -2.01031004 0 P 0 ;0
L 1.47686004 -2.01031004 1.47763996 -2.01216998 0 P 0 ;0
L 1.47763996 -2.01216998 1.47851998 -2.01481004 0 P 0 ;0
L 1.47851998 -2.01481004 1.47918996 -2.01748996 0 P 0 ;0
L 1.47918996 -2.01748996 1.47966004 -2.02021998 0 P 0 ;0
L 1.47966004 -2.02021998 1.47993002 -2.02296998 0 P 0 ;0
L 1.47993002 -2.02296998 1.48001998 -2.02783996 0 P 0 ;0
L 1.48001998 -2.02783996 1.47975 -2.03868996 0 P 0 ;0
L 1.47975 -2.03868996 1.4793 -2.05161004 0 P 0 ;0
L 1.4793 -2.05161004 1.47866004 -2.06543002 0 P 0 ;0
L 1.47866004 -2.06543002 1.47801004 -2.07961004 0 P 0 ;0
L 1.47801004 -2.07961004 1.47743996 -2.09378996 0 P 0 ;0
L 1.47743996 -2.09378996 1.47705 -2.10613002 0 P 0 ;0
L 1.47705 -2.10613002 1.47693002 -2.11356004 0 P 0 ;0
L 1.47693002 -2.11356004 1.47693002 -2.12516004 0 P 0 ;0
L 1.47693002 -2.12516004 1.42661004 -2.12516004 0 P 0 ;0
L 1.42661004 -2.12516004 1.42661004 -2.12473996 0 P 0 ;0
L 1.42661004 -2.12473996 1.42666004 -2.12318002 0 P 0 ;0
L 1.42666004 -2.12318002 1.42691004 -2.11863996 0 P 0 ;0
L 1.42691004 -2.11863996 1.42725 -2.1132 0 P 0 ;0
L 1.42725 -2.1132 1.42766004 -2.1072 0 P 0 ;0
L 1.42766004 -2.1072 1.42766004 -2.10718996 0 P 0 ;0
L 1.42766004 -2.10718996 1.4281 -2.10068996 0 P 0 ;0
L 1.4281 -2.10068996 1.42858002 -2.09368002 0 P 0 ;0
L 1.42858002 -2.09368002 1.42901004 -2.08721004 0 P 0 ;0
L 1.42901004 -2.08721004 1.42901004 -2.0872 0 P 0 ;0
L 1.42901004 -2.0872 1.42931004 -2.08256004 0 P 0 ;0
L 1.42931004 -2.08256004 1.42991998 -2.07308002 0 P 0 ;0
L 1.42991998 -2.07308002 1.42916004 -2.07136998 0 P 0 ;0
L 1.42916004 -2.07136998 1.42731998 -2.07105 0 P 0 ;0
L 1.42731998 -2.07105 1.42105 -2.07303996 0 P 0 ;0
L 1.42105 -2.07303996 1.41815 -2.07393002 0 P 0 ;0
L 1.41815 -2.07393002 1.41451004 -2.075 0 P 0 ;0
L 1.41451004 -2.075 1.41076004 -2.07603002 0 P 0 ;0
L 1.41076004 -2.07603002 1.40748002 -2.0769 0 P 0 ;0
L 1.40748002 -2.0769 1.40438996 -2.07781004 0 P 0 ;0
L 1.40438996 -2.07781004 1.40431998 -2.07783996 0 P 0 ;0
L 1.40431998 -2.07783996 1.40133996 -2.07896998 0 P 0 ;0
L 1.40133996 -2.07896998 1.40005 -2.07956998 0 P 0 ;0
L 1.40005 -2.07956998 1.39881998 -2.08026004 0 P 0 ;0
L 1.39881998 -2.08026004 1.39763996 -2.08103002 0 P 0 ;0
L 1.39763996 -2.08103002 1.39651998 -2.08188002 0 P 0 ;0
L 1.39651998 -2.08188002 1.39578996 -2.08251004 0 P 0 ;0
L 1.39578996 -2.08251004 1.39573996 -2.08256004 0 P 0 ;0
L 1.39573996 -2.08256004 1.3951 -2.08318996 0 P 0 ;0
L 1.3951 -2.08318996 1.39446998 -2.08393002 0 P 0 ;0
L 1.39446998 -2.08393002 1.3939 -2.08471004 0 P 0 ;0
L 1.3939 -2.08471004 1.39336998 -2.08553996 0 P 0 ;0
L 1.39336998 -2.08553996 1.39301004 -2.08623996 0 P 0 ;0
L 1.39301004 -2.08623996 1.39271004 -2.08696998 0 P 0 ;0
L 1.39271004 -2.08696998 1.39248002 -2.08771998 0 P 0 ;0
L 1.39248002 -2.08771998 1.39231004 -2.08848996 0 P 0 ;0
L 1.39231004 -2.08848996 1.39221004 -2.08926004 0 P 0 ;0
L 1.39221004 -2.08926004 1.39218002 -2.09003996 0 P 0 ;0
L 1.39218002 -2.09003996 1.39221004 -2.0908 0 P 0 ;0
L 1.39221004 -2.0908 1.39231004 -2.09153002 0 P 0 ;0
L 1.39231004 -2.09153002 1.39246998 -2.09226004 0 P 0 ;0
L 1.39246998 -2.09226004 1.39268996 -2.09296998 0 P 0 ;0
L 1.39268996 -2.09296998 1.39296004 -2.09365 0 P 0 ;0
L 1.39296004 -2.09365 1.3933 -2.09431004 0 P 0 ;0
L 1.3933 -2.09431004 1.39368996 -2.09493996 0 P 0 ;0
L 1.39368996 -2.09493996 1.39411998 -2.09553996 0 P 0 ;0
L 1.39411998 -2.09553996 1.39468996 -2.09618002 0 P 0 ;0
L 1.39468996 -2.09618002 1.3953 -2.09678002 0 P 0 ;0
L 1.3953 -2.09678002 1.39596004 -2.09731998 0 P 0 ;0
L 1.39596004 -2.09731998 1.39666998 -2.0978 0 P 0 ;0
L 1.39666998 -2.0978 1.39673996 -2.09783996 0 P 0 ;0
L 1.39673996 -2.09783996 1.39741004 -2.09821998 0 P 0 ;0
L 1.39741004 -2.09821998 1.39748996 -2.09825 0 P 0 ;0
L 1.39748996 -2.09825 1.39818996 -2.09856998 0 P 0 ;0
L 1.39818996 -2.09856998 1.39898996 -2.09886004 0 P 0 ;0
L 1.39898996 -2.09886004 1.39906998 -2.09888002 0 P 0 ;0
L 1.39906998 -2.09888002 1.40043996 -2.09888002 0 P 0 ;0
L 1.40043996 -2.09888002 1.40033996 -2.09923002 0 P 0 ;0
L 1.40033996 -2.09923002 1.40041998 -2.09925 0 P 0 ;0
L 1.40041998 -2.09925 1.40186004 -2.09953002 0 P 0 ;0
L 1.40186004 -2.09953002 1.40331004 -2.09971004 0 P 0 ;0
L 1.40331004 -2.09971004 1.40478002 -2.09978002 0 P 0 ;0
L 1.40478002 -2.09978002 1.40625 -2.09975 0 P 0 ;0
L 1.40625 -2.09975 1.41096004 -2.09931004 0 P 0 ;0
L 1.41096004 -2.09931004 1.41556998 -2.09855 0 P 0 ;0
L 1.41556998 -2.09855 1.41791998 -2.09813002 0 P 0 ;0
L 1.41791998 -2.09813002 1.41995 -2.09791004 0 P 0 ;0
L 1.41995 -2.09791004 1.4201 -2.0979 0 P 0 ;0
L 1.4201 -2.0979 1.41941004 -2.10078002 0 P 0 ;0
L 1.41941004 -2.10078002 1.41761004 -2.10745 0 P 0 ;0
L 1.41761004 -2.10745 1.41391004 -2.12025 0 P 0 ;0
L 1.41391004 -2.12025 1.41215 -2.12626998 0 P 0 ;0
L 1.41215 -2.12626998 1.40655 -2.12725 0 P 0 ;0
L 1.40655 -2.12725 1.40046004 -2.12808002 0 P 0 ;0
L 1.40046004 -2.12808002 1.39438002 -2.12845 0 P 0 ;0
L 1.15303002 -2.08283002 1.20788996 -2.08283002 0 P 0 ;0
L 1.15398996 -2.08183002 1.20795 -2.08183002 0 P 0 ;0
L 1.15483002 -2.08083002 1.208 -2.08083002 0 P 0 ;0
L 1.15555 -2.07983002 1.20805 -2.07983002 0 P 0 ;0
L 1.15621998 -2.07883002 1.2081 -2.07883002 0 P 0 ;0
L 1.15681998 -2.07783002 1.20816004 -2.07783002 0 P 0 ;0
L 1.15733002 -2.07683002 1.20821004 -2.07683002 0 P 0 ;0
L 1.15778996 -2.07583002 1.20826004 -2.07583002 0 P 0 ;0
L 1.15818002 -2.07483002 1.20831004 -2.07483002 0 P 0 ;0
L 1.15853996 -2.07383002 1.20836998 -2.07383002 0 P 0 ;0
L 1.15881998 -2.07283002 1.20841998 -2.07283002 0 P 0 ;0
L 1.1591 -2.07183002 1.20846998 -2.07183002 0 P 0 ;0
L 1.15938002 -2.07083002 1.20853002 -2.07083002 0 P 0 ;0
L 1.1596 -2.06983002 1.20858002 -2.06983002 0 P 0 ;0
L 1.15981004 -2.06883002 1.20863996 -2.06883002 0 P 0 ;0
L 1.16001004 -2.06783002 1.20868996 -2.06783002 0 P 0 ;0
L 1.1602 -2.06683002 1.20875 -2.06683002 0 P 0 ;0
L 1.16033996 -2.06583002 1.2088 -2.06583002 0 P 0 ;0
L 1.16048996 -2.06483002 1.20886004 -2.06483002 0 P 0 ;0
L 1.16063996 -2.06383002 1.20891998 -2.06383002 0 P 0 ;0
L 1.16078002 -2.06283002 1.20896998 -2.06283002 0 P 0 ;0
L 1.16088996 -2.06183002 1.20903002 -2.06183002 0 P 0 ;0
L 1.16098996 -2.06083002 1.20908002 -2.06083002 0 P 0 ;0
L 1.16108996 -2.05983002 1.20913996 -2.05983002 0 P 0 ;0
L 1.16118002 -2.05883002 1.20918996 -2.05883002 0 P 0 ;0
L 1.16128002 -2.05783002 1.20925 -2.05783002 0 P 0 ;0
L 1.16133996 -2.05683002 1.2093 -2.05683002 0 P 0 ;0
L 1.1614 -2.05583002 1.20936004 -2.05583002 0 P 0 ;0
L 1.16146004 -2.05483002 1.20941004 -2.05483002 0 P 0 ;0
L 1.16151998 -2.05383002 1.20946998 -2.05383002 0 P 0 ;0
L 1.16158002 -2.05283002 1.20951998 -2.05283002 0 P 0 ;0
L 1.16163996 -2.05183002 1.20958002 -2.05183002 0 P 0 ;0
L 1.1617 -2.05083002 1.20963996 -2.05083002 0 P 0 ;0
L 1.16175 -2.04983002 1.2097 -2.04983002 0 P 0 ;0
L 1.16181004 -2.04883002 1.20975 -2.04883002 0 P 0 ;0
L 1.16186998 -2.04783002 1.20981004 -2.04783002 0 P 0 ;0
L 1.16193002 -2.04683002 1.20986998 -2.04683002 0 P 0 ;0
L 1.16198996 -2.04583002 1.20993002 -2.04583002 0 P 0 ;0
L 1.16205 -2.04483002 1.20998996 -2.04483002 0 P 0 ;0
L 1.16211004 -2.04383002 1.21005 -2.04383002 0 P 0 ;0
L 1.16215 -2.04283002 1.2101 -2.04283002 0 P 0 ;0
L 1.1622 -2.04183002 1.21016004 -2.04183002 0 P 0 ;0
L 1.16225 -2.04083002 1.21021998 -2.04083002 0 P 0 ;0
L 1.16228996 -2.03983002 1.21028002 -2.03983002 0 P 0 ;0
L 1.16233996 -2.03883002 1.21033996 -2.03883002 0 P 0 ;0
L 1.16238002 -2.03783002 1.2104 -2.03783002 0 P 0 ;0
L 1.16243002 -2.03683002 1.21046004 -2.03683002 0 P 0 ;0
L 1.16246998 -2.03583002 1.21051004 -2.03583002 0 P 0 ;0
L 1.16251998 -2.03483002 1.21056998 -2.03483002 0 P 0 ;0
L 1.16256998 -2.03383002 1.21063996 -2.03383002 0 P 0 ;0
L 1.16261004 -2.03283002 1.2107 -2.03283002 0 P 0 ;0
L 1.16266004 -2.03183002 1.21076004 -2.03183002 0 P 0 ;0
L 1.1627 -2.03083002 1.21083002 -2.03083002 0 P 0 ;0
L 1.16015 -1.97631004 1.17066004 -1.97631004 0 P 0 ;0
L 1.15961998 -1.97531004 1.17026004 -1.97531004 0 P 0 ;0
L 1.1591 -1.97431004 1.16986998 -1.97431004 0 P 0 ;0
L 1.15856998 -1.97331004 1.16946998 -1.97331004 0 P 0 ;0
L 1.15803996 -1.97231004 1.16903002 -1.97231004 0 P 0 ;0
L 1.15746998 -1.97131004 1.16858996 -1.97131004 0 P 0 ;0
L 1.1569 -1.97031004 1.16815 -1.97031004 0 P 0 ;0
L 1.15631998 -1.96931004 1.16771004 -1.96931004 0 P 0 ;0
L 1.15573996 -1.96831004 1.16726998 -1.96831004 0 P 0 ;0
L 1.15516004 -1.96731004 1.16681998 -1.96731004 0 P 0 ;0
L 1.15458996 -1.96631004 1.16638002 -1.96631004 0 P 0 ;0
L 1.15398002 -1.96531004 1.16593996 -1.96531004 0 P 0 ;0
L 1.1533 -1.96431004 1.16548996 -1.96431004 0 P 0 ;0
L 1.15261998 -1.96331004 1.16503002 -1.96331004 0 P 0 ;0
L 1.15193996 -1.96231004 1.16448002 -1.96231004 0 P 0 ;0
L 1.15126004 -1.96131004 1.16393002 -1.96131004 0 P 0 ;0
L 1.15058002 -1.96031004 1.16338002 -1.96031004 0 P 0 ;0
L 1.1499 -1.95931004 1.16283002 -1.95931004 0 P 0 ;0
L 1.1491 -1.95831004 1.16228996 -1.95831004 0 P 0 ;0
L 1.14831004 -1.95731004 1.16173996 -1.95731004 0 P 0 ;0
L 1.14751004 -1.95631004 1.16118996 -1.95631004 0 P 0 ;0
L 1.14671004 -1.95531004 1.16063996 -1.95531004 0 P 0 ;0
L 1.14591998 -1.95431004 1.16008996 -1.95431004 0 P 0 ;0
L 1.14511998 -1.95331004 1.15943996 -1.95331004 0 P 0 ;0
L 1.1442 -1.95231004 1.15878002 -1.95231004 0 P 0 ;0
L 1.14326998 -1.95131004 1.15811004 -1.95131004 0 P 0 ;0
L 1.14233996 -1.95031004 1.15745 -1.95031004 0 P 0 ;0
L 1.14141004 -1.94931004 1.15678002 -1.94931004 0 P 0 ;0
L 1.14048996 -1.94831004 1.15611998 -1.94831004 0 P 0 ;0
L 1.1395 -1.94731004 1.15545 -1.94731004 0 P 0 ;0
L 1.13843002 -1.94631004 1.15478996 -1.94631004 0 P 0 ;0
L 1.13736004 -1.94531004 1.15411998 -1.94531004 0 P 0 ;0
L 1.13628996 -1.94431004 1.15333002 -1.94431004 0 P 0 ;0
L 1.13521004 -1.94331004 1.15253002 -1.94331004 0 P 0 ;0
L 1.13413996 -1.94231004 1.15173996 -1.94231004 0 P 0 ;0
L 1.13306998 -1.94131004 1.15093996 -1.94131004 0 P 0 ;0
L 1.132 -1.94031004 1.15013996 -1.94031004 0 P 0 ;0
L 1.13081004 -1.93931004 1.14935 -1.93931004 0 P 0 ;0
L 1.12958002 -1.93831004 1.14855 -1.93831004 0 P 0 ;0
L 1.12833996 -1.93731004 1.14775 -1.93731004 0 P 0 ;0
L 1.1271 -1.93631004 1.14688996 -1.93631004 0 P 0 ;0
L 1.12586004 -1.93531004 1.14593996 -1.93531004 0 P 0 ;0
L 1.12461998 -1.93431004 1.14498996 -1.93431004 0 P 0 ;0
L 1.12338002 -1.93331004 1.14405 -1.93331004 0 P 0 ;0
L 1.12203002 -1.93231004 1.1431 -1.93231004 0 P 0 ;0
L 1.1206 -1.93131004 1.14216004 -1.93131004 0 P 0 ;0
L 1.11916004 -1.93031004 1.14121004 -1.93031004 0 P 0 ;0
L 1.11771998 -1.92931004 1.14026998 -1.92931004 0 P 0 ;0
L 1.11628996 -1.92831004 1.13931998 -1.92831004 0 P 0 ;0
L 1.11483996 -1.92731004 1.13838002 -1.92731004 0 P 0 ;0
L 1.11338996 -1.92631004 1.13743002 -1.92631004 0 P 0 ;0
L 1.11171998 -1.92531004 1.13648996 -1.92531004 0 P 0 ;0
L 1.11005 -1.92431004 1.13538002 -1.92431004 0 P 0 ;0
L 1.10838002 -1.92331004 1.13426998 -1.92331004 0 P 0 ;0
L 1.1067 -1.92231004 1.13315 -1.92231004 0 P 0 ;0
L 1.10503002 -1.92131004 1.13203002 -1.92131004 0 P 0 ;0
L 1.10336004 -1.92031004 1.13091998 -1.92031004 0 P 0 ;0
L 1.1015 -1.91931004 1.1298 -1.91931004 0 P 0 ;0
L 1.09955 -1.91831004 1.12868002 -1.91831004 0 P 0 ;0
L 1.16275 -2.02983002 1.21088996 -2.02983002 0 P 0 ;0
L 1.16278996 -2.02883002 1.21095 -2.02883002 0 P 0 ;0
L 1.16283996 -2.02783002 1.21101004 -2.02783002 0 P 0 ;0
L 1.16226998 -2.02683002 1.21108002 -2.02683002 0 P 0 ;0
L 1.16153996 -2.02583002 1.21113996 -2.02583002 0 P 0 ;0
L 1.15846004 -2.02483002 1.2112 -2.02483002 0 P 0 ;0
L 1.10036004 -2.00383002 1.21255 -2.00383002 0 P 0 ;0
L 1.10226004 -2.00283002 1.2126 -2.00283002 0 P 0 ;0
L 1.10433996 -2.00183002 1.21266998 -2.00183002 0 P 0 ;0
L 1.1065 -2.00083002 1.21273002 -2.00083002 0 P 0 ;0
L 1.10886998 -1.99983002 1.21278996 -1.99983002 0 P 0 ;0
L 1.11138002 -1.99883002 1.21285 -1.99883002 0 P 0 ;0
L 1.11436998 -1.99783002 1.21288002 -1.99783002 0 P 0 ;0
L 1.11748996 -1.99683002 1.21255 -1.99683002 0 P 0 ;0
L 1.12061998 -1.99583002 1.2089 -1.99583002 0 P 0 ;0
L 1.12433996 -1.99483002 1.2036 -1.99483002 0 P 0 ;0
L 1.12863996 -1.99383002 1.19728002 -1.99383002 0 P 0 ;0
L 1.13295 -1.99283002 1.19096998 -1.99283002 0 P 0 ;0
L 1.13985 -1.99183002 1.18111998 -1.99183002 0 P 0 ;0
L 1.14948002 -1.99083002 1.1651 -1.99083002 0 P 0 ;0
L 1.24218002 -2.08316004 1.29143996 -2.08316004 0 P 0 ;0
L 1.24223002 -2.08216004 1.29151004 -2.08216004 0 P 0 ;0
L 1.24228002 -2.08116004 1.29158996 -2.08116004 0 P 0 ;0
L 1.24233996 -2.08016004 1.29166004 -2.08016004 0 P 0 ;0
L 1.24238996 -2.07916004 1.29173002 -2.07916004 0 P 0 ;0
L 1.24245 -2.07816004 1.29181004 -2.07816004 0 P 0 ;0
L 1.2425 -2.07716004 1.29188002 -2.07716004 0 P 0 ;0
L 1.24256004 -2.07616004 1.29195 -2.07616004 0 P 0 ;0
L 1.24261004 -2.07516004 1.29203002 -2.07516004 0 P 0 ;0
L 1.24266998 -2.07416004 1.2921 -2.07416004 0 P 0 ;0
L 1.24271998 -2.07316004 1.29216998 -2.07316004 0 P 0 ;0
L 1.24278002 -2.07216004 1.29223996 -2.07216004 0 P 0 ;0
L 1.24283002 -2.07116004 1.29231998 -2.07116004 0 P 0 ;0
L 1.24288002 -2.07016004 1.29238996 -2.07016004 0 P 0 ;0
L 1.24293002 -2.06916004 1.29246004 -2.06916004 0 P 0 ;0
L 1.24296998 -2.06816004 1.29253002 -2.06816004 0 P 0 ;0
L 1.24301998 -2.06716004 1.29261004 -2.06716004 0 P 0 ;0
L 1.24306004 -2.06616004 1.2927 -2.06616004 0 P 0 ;0
L 1.24311004 -2.06516004 1.29281004 -2.06516004 0 P 0 ;0
L 1.24315 -2.06416004 1.29291998 -2.06416004 0 P 0 ;0
L 1.2432 -2.06316004 1.29303002 -2.06316004 0 P 0 ;0
L 1.24323996 -2.06216004 1.29315 -2.06216004 0 P 0 ;0
L 1.24328996 -2.06116004 1.29331998 -2.06116004 0 P 0 ;0
L 1.24333002 -2.06016004 1.2935 -2.06016004 0 P 0 ;0
L 1.24338002 -2.05916004 1.29366998 -2.05916004 0 P 0 ;0
L 1.24341998 -2.05816004 1.29385 -2.05816004 0 P 0 ;0
L 1.24346998 -2.05716004 1.29408996 -2.05716004 0 P 0 ;0
L 1.24351004 -2.05616004 1.29433996 -2.05616004 0 P 0 ;0
L 1.24355 -2.05516004 1.29458996 -2.05516004 0 P 0 ;0
L 1.2436 -2.05416004 1.29485 -2.05416004 0 P 0 ;0
L 1.24363996 -2.05316004 1.29516998 -2.05316004 0 P 0 ;0
L 1.24368996 -2.05216004 1.29551998 -2.05216004 0 P 0 ;0
L 1.24373002 -2.05116004 1.29586004 -2.05116004 0 P 0 ;0
L 1.24378002 -2.05016004 1.29621004 -2.05016004 0 P 0 ;0
L 1.24383002 -2.04916004 1.29663996 -2.04916004 0 P 0 ;0
L 1.24386998 -2.04816004 1.29708002 -2.04816004 0 P 0 ;0
L 1.24391004 -2.04716004 1.29753002 -2.04716004 0 P 0 ;0
L 1.24396004 -2.04616004 1.29796998 -2.04616004 0 P 0 ;0
L 1.244 -2.04516004 1.29851004 -2.04516004 0 P 0 ;0
L 1.24405 -2.04416004 1.2991 -2.04416004 0 P 0 ;0
L 1.24408996 -2.04316004 1.29975 -2.04316004 0 P 0 ;0
L 1.24413996 -2.04216004 1.3005 -2.04216004 0 P 0 ;0
L 1.24418002 -2.04116004 1.30131998 -2.04116004 0 P 0 ;0
L 1.24423002 -2.04016004 1.30223002 -2.04016004 0 P 0 ;0
L 1.24426998 -2.03916004 1.30326998 -2.03916004 0 P 0 ;0
L 1.24431998 -2.03816004 1.30446004 -2.03816004 0 P 0 ;0
L 1.24436004 -2.03716004 1.30581998 -2.03716004 0 P 0 ;0
L 1.24441004 -2.03616004 1.30738002 -2.03616004 0 P 0 ;0
L 1.24445 -2.03516004 1.30923002 -2.03516004 0 P 0 ;0
L 1.24448996 -2.03416004 1.31156004 -2.03416004 0 P 0 ;0
L 1.24453996 -2.03316004 1.31478996 -2.03316004 0 P 0 ;0
L 1.24458996 -2.03216004 1.32013002 -2.03216004 0 P 0 ;0
L 1.24461998 -2.03116004 1.33481004 -2.03116004 0 P 0 ;0
L 1.24463996 -2.03016004 1.33478002 -2.03016004 0 P 0 ;0
L 1.24466004 -2.02916004 1.33473996 -2.02916004 0 P 0 ;0
L 1.24468002 -2.02816004 1.33471004 -2.02816004 0 P 0 ;0
L 1.2447 -2.02716004 1.33468002 -2.02716004 0 P 0 ;0
L 1.24471998 -2.02616004 1.33463996 -2.02616004 0 P 0 ;0
L 1.24473996 -2.02516004 1.3346 -2.02516004 0 P 0 ;0
L 1.24476004 -2.02416004 1.33456998 -2.02416004 0 P 0 ;0
L 1.24478002 -2.02316004 1.33453002 -2.02316004 0 P 0 ;0
L 1.2448 -2.02216004 1.3345 -2.02216004 0 P 0 ;0
L 1.24481998 -2.02116004 1.33446998 -2.02116004 0 P 0 ;0
L 1.24483996 -2.02016004 1.33443002 -2.02016004 0 P 0 ;0
L 1.24486004 -2.01916004 1.3344 -2.01916004 0 P 0 ;0
L 1.24488002 -2.01816004 1.33436004 -2.01816004 0 P 0 ;0
L 1.2449 -2.01716004 1.33433002 -2.01716004 0 P 0 ;0
L 1.24491998 -2.01616004 1.33428996 -2.01616004 0 P 0 ;0
L 1.24493996 -2.01516004 1.33426004 -2.01516004 0 P 0 ;0
L 1.24496004 -2.01416004 1.33421998 -2.01416004 0 P 0 ;0
L 1.24498002 -2.01316004 1.33418996 -2.01316004 0 P 0 ;0
L 1.245 -2.01216004 1.33415 -2.01216004 0 P 0 ;0
L 1.24501998 -2.01116004 1.33411998 -2.01116004 0 P 0 ;0
L 1.24503996 -2.01016004 1.33408002 -2.01016004 0 P 0 ;0
L 1.24506004 -2.00916004 1.33403996 -2.00916004 0 P 0 ;0
L 1.24508002 -2.00816004 1.334 -2.00816004 0 P 0 ;0
L 1.2451 -2.00716004 1.33396004 -2.00716004 0 P 0 ;0
L 1.24511998 -2.00616004 1.33393002 -2.00616004 0 P 0 ;0
L 1.24513996 -2.00516004 1.29098996 -2.00516004 0 P 0 ;0
L 1.24513996 -2.00416004 1.29033002 -2.00416004 0 P 0 ;0
L 1.24513996 -2.00316004 1.29005 -2.00316004 0 P 0 ;0
L 1.24513996 -2.00216004 1.29005 -2.00216004 0 P 0 ;0
L 1.24513996 -2.00116004 1.29005 -2.00116004 0 P 0 ;0
L 1.24515 -2.00016004 1.29005 -2.00016004 0 P 0 ;0
L 1.24515 -1.99916004 1.29005 -1.99916004 0 P 0 ;0
L 1.24515 -1.99816004 1.29005 -1.99816004 0 P 0 ;0
L 1.24515 -1.99716004 1.29005 -1.99716004 0 P 0 ;0
L 1.24515 -1.99616004 1.29005 -1.99616004 0 P 0 ;0
L 1.24515 -1.99516004 1.29005 -1.99516004 0 P 0 ;0
L 1.16085 -2.02753002 1.1601 -2.04393002 0 P 0 ;0
L 1.1601 -2.04393002 1.15928996 -2.05771998 0 P 0 ;0
L 1.15928996 -2.05771998 1.15883996 -2.06228002 0 P 0 ;0
L 1.15883996 -2.06228002 1.15818002 -2.06681998 0 P 0 ;0
L 1.15818002 -2.06681998 1.15751004 -2.07006998 0 P 0 ;0
L 1.15751004 -2.07006998 1.15661004 -2.07328996 0 P 0 ;0
L 1.15661004 -2.07328996 1.15616004 -2.07453996 0 P 0 ;0
L 1.15616004 -2.07453996 1.15563002 -2.07576998 0 P 0 ;0
L 1.15563002 -2.07576998 1.15501998 -2.07696004 0 P 0 ;0
L 1.15501998 -2.07696004 1.15433002 -2.0781 0 P 0 ;0
L 1.15433002 -2.0781 1.1534 -2.07941998 0 P 0 ;0
L 1.1534 -2.07941998 1.15236004 -2.08066004 0 P 0 ;0
L 1.15236004 -2.08066004 1.15123002 -2.08181998 0 P 0 ;0
L 1.15123002 -2.08181998 1.15001004 -2.08286998 0 P 0 ;0
L 1.15001004 -2.08286998 1.14871004 -2.08383002 0 P 0 ;0
L 1.14871004 -2.08383002 1.14733002 -2.08468002 0 P 0 ;0
L 1.14733002 -2.08468002 1.14591004 -2.0854 0 P 0 ;0
L 1.14591004 -2.0854 1.14443996 -2.086 0 P 0 ;0
L 1.14443996 -2.086 1.14291004 -2.08648002 0 P 0 ;0
L 1.14291004 -2.08648002 1.14136004 -2.08683002 0 P 0 ;0
L 1.14136004 -2.08683002 1.13976998 -2.08703996 0 P 0 ;0
L 1.13976998 -2.08703996 1.13816004 -2.08713002 0 P 0 ;0
L 1.13816004 -2.08713002 1.13656998 -2.08708002 0 P 0 ;0
L 1.13656998 -2.08708002 1.13498996 -2.0869 0 P 0 ;0
L 1.13498996 -2.0869 1.13341998 -2.08658996 0 P 0 ;0
L 1.13341998 -2.08658996 1.13188996 -2.08615 0 P 0 ;0
L 1.13188996 -2.08615 1.1304 -2.08558996 0 P 0 ;0
L 1.1304 -2.08558996 1.12895 -2.08488996 0 P 0 ;0
L 1.12895 -2.08488996 1.12756998 -2.08408002 0 P 0 ;0
L 1.12756998 -2.08408002 1.12625 -2.08315 0 P 0 ;0
L 1.12625 -2.08315 1.12501004 -2.08211998 0 P 0 ;0
L 1.12501004 -2.08211998 1.12386004 -2.081 0 P 0 ;0
L 1.12386004 -2.081 1.12281004 -2.07978002 0 P 0 ;0
L 1.12281004 -2.07978002 1.12183996 -2.07846998 0 P 0 ;0
L 1.12183996 -2.07846998 1.1211 -2.07726004 0 P 0 ;0
L 1.1211 -2.07726004 1.12046998 -2.07598996 0 P 0 ;0
L 1.12046998 -2.07598996 1.11996004 -2.07466998 0 P 0 ;0
L 1.11996004 -2.07466998 1.11955 -2.07331004 0 P 0 ;0
L 1.11955 -2.07331004 1.11926998 -2.07191004 0 P 0 ;0
L 1.11926998 -2.07191004 1.11868002 -2.06693996 0 P 0 ;0
L 1.11868002 -2.06693996 1.11848002 -2.06191004 0 P 0 ;0
L 1.11848002 -2.06191004 1.11871004 -2.05668002 0 P 0 ;0
L 1.11871004 -2.05668002 1.11936004 -2.05148002 0 P 0 ;0
L 1.11936004 -2.05148002 1.11978996 -2.04936998 0 P 0 ;0
L 1.11978996 -2.04936998 1.12036998 -2.0473 0 P 0 ;0
L 1.12036998 -2.0473 1.12108996 -2.04528002 0 P 0 ;0
L 1.12108996 -2.04528002 1.12196004 -2.04331998 0 P 0 ;0
L 1.12196004 -2.04331998 1.1229 -2.04153996 0 P 0 ;0
L 1.1229 -2.04153996 1.12396998 -2.03985 0 P 0 ;0
L 1.12396998 -2.03985 1.12516998 -2.03823002 0 P 0 ;0
L 1.12516998 -2.03823002 1.12735 -2.03573996 0 P 0 ;0
L 1.12735 -2.03573996 1.12973002 -2.03345 0 P 0 ;0
L 1.12973002 -2.03345 1.13223996 -2.03141998 0 P 0 ;0
L 1.13223996 -2.03141998 1.13491998 -2.02961004 0 P 0 ;0
L 1.13491998 -2.02961004 1.13611004 -2.02893002 0 P 0 ;0
L 1.13611004 -2.02893002 1.13735 -2.02833996 0 P 0 ;0
L 1.13735 -2.02833996 1.13861998 -2.02781998 0 P 0 ;0
L 1.13861998 -2.02781998 1.13993996 -2.0274 0 P 0 ;0
L 1.13993996 -2.0274 1.14191004 -2.02693002 0 P 0 ;0
L 1.14191004 -2.02693002 1.14391004 -2.02663002 0 P 0 ;0
L 1.14391004 -2.02663002 1.14935 -2.02626004 0 P 0 ;0
L 1.14935 -2.02626004 1.15471004 -2.0263 0 P 0 ;0
L 1.15471004 -2.0263 1.15591004 -2.02638996 0 P 0 ;0
L 1.15591004 -2.02638996 1.1571 -2.02656998 0 P 0 ;0
L 1.1571 -2.02656998 1.15828002 -2.02683996 0 P 0 ;0
L 1.15828002 -2.02683996 1.16085 -2.02753002 0 P 0 ;0
L 1.13876998 -2.14783002 1.20233002 -2.14783002 0 P 0 ;0
L 1.14236998 -2.14683002 1.20266004 -2.14683002 0 P 0 ;0
L 1.14481004 -2.14583002 1.20296004 -2.14583002 0 P 0 ;0
L 1.1467 -2.14483002 1.20325 -2.14483002 0 P 0 ;0
L 1.14826004 -2.14383002 1.20353002 -2.14383002 0 P 0 ;0
L 1.1496 -2.14283002 1.20373996 -2.14283002 0 P 0 ;0
L 1.15078996 -2.14183002 1.20395 -2.14183002 0 P 0 ;0
L 1.15186004 -2.14083002 1.20415 -2.14083002 0 P 0 ;0
L 1.15278996 -2.13983002 1.20431998 -2.13983002 0 P 0 ;0
L 1.15361998 -2.13883002 1.20446004 -2.13883002 0 P 0 ;0
L 1.15436004 -2.13783002 1.20458002 -2.13783002 0 P 0 ;0
L 1.155 -2.13683002 1.20466998 -2.13683002 0 P 0 ;0
L 1.15556998 -2.13583002 1.20475 -2.13583002 0 P 0 ;0
L 1.15608996 -2.13483002 1.20481998 -2.13483002 0 P 0 ;0
L 1.15653996 -2.13383002 1.20488996 -2.13383002 0 P 0 ;0
L 1.15691004 -2.13283002 1.20496004 -2.13283002 0 P 0 ;0
L 1.15723996 -2.13183002 1.20503002 -2.13183002 0 P 0 ;0
L 1.15751998 -2.13083002 1.2051 -2.13083002 0 P 0 ;0
L 1.15773002 -2.12983002 1.20516004 -2.12983002 0 P 0 ;0
L 1.15793002 -2.12883002 1.20523002 -2.12883002 0 P 0 ;0
L 1.15806004 -2.12783002 1.2053 -2.12783002 0 P 0 ;0
L 1.15816998 -2.12683002 1.20536998 -2.12683002 0 P 0 ;0
L 1.15821004 -2.12583002 1.20543996 -2.12583002 0 P 0 ;0
L 1.11716004 -2.12483002 1.12726004 -2.12483002 0 P 0 ;0
L 1.15823996 -2.12483002 1.20551004 -2.12483002 0 P 0 ;0
L 1.10911998 -2.12383002 1.1352 -2.12383002 0 P 0 ;0
L 1.15821998 -2.12383002 1.20556998 -2.12383002 0 P 0 ;0
L 1.10468996 -2.12283002 1.14018996 -2.12283002 0 P 0 ;0
L 1.1582 -2.12283002 1.20563996 -2.12283002 0 P 0 ;0
L 1.10131004 -2.12183002 1.14366998 -2.12183002 0 P 0 ;0
L 1.15818002 -2.12183002 1.2057 -2.12183002 0 P 0 ;0
L 1.15808996 -2.12083002 1.20576004 -2.12083002 0 P 0 ;0
L 1.15781004 -2.11983002 1.20583002 -2.11983002 0 P 0 ;0
L 1.15721004 -2.11883002 1.20588002 -2.11883002 0 P 0 ;0
L 1.14146004 -2.08883002 1.20758002 -2.08883002 0 P 0 ;0
L 1.14525 -2.08783002 1.20763002 -2.08783002 0 P 0 ;0
L 1.14751004 -2.08683002 1.20768002 -2.08683002 0 P 0 ;0
L 1.14928002 -2.08583002 1.20773002 -2.08583002 0 P 0 ;0
L 1.15073002 -2.08483002 1.20778996 -2.08483002 0 P 0 ;0
L 1.15196004 -2.08383002 1.20783996 -2.08383002 0 P 0 ;0
L 1.13818996 -2.08913002 1.13826998 -2.08913002 0 P 0 ;0
L 1.13826998 -2.08913002 1.13988002 -2.08903996 0 P 0 ;0
L 1.13988002 -2.08903996 1.13996004 -2.08903996 0 P 0 ;0
L 1.13996004 -2.08903996 1.14001004 -2.08903002 0 P 0 ;0
L 1.14001004 -2.08903002 1.14005 -2.08901998 0 P 0 ;0
L 1.14005 -2.08901998 1.14163002 -2.08881004 0 P 0 ;0
L 1.14163002 -2.08881004 1.14166998 -2.0888 0 P 0 ;0
L 1.14166998 -2.0888 1.14171004 -2.0888 0 P 0 ;0
L 1.14171004 -2.0888 1.14178996 -2.08878002 0 P 0 ;0
L 1.14178996 -2.08878002 1.14335 -2.08843002 0 P 0 ;0
L 1.14335 -2.08843002 1.14351004 -2.08838996 0 P 0 ;0
L 1.14351004 -2.08838996 1.14503002 -2.08791004 0 P 0 ;0
L 1.14503002 -2.08791004 1.14511004 -2.08788996 0 P 0 ;0
L 1.14511004 -2.08788996 1.14515 -2.08786998 0 P 0 ;0
L 1.14515 -2.08786998 1.14518996 -2.08786004 0 P 0 ;0
L 1.14518996 -2.08786004 1.14666004 -2.08725 0 P 0 ;0
L 1.14666004 -2.08725 1.14673996 -2.08721998 0 P 0 ;0
L 1.14673996 -2.08721998 1.14678002 -2.0872 0 P 0 ;0
L 1.14678002 -2.0872 1.14681998 -2.08718996 0 P 0 ;0
L 1.14681998 -2.08718996 1.14823996 -2.08646998 0 P 0 ;0
L 1.14823996 -2.08646998 1.14826998 -2.08645 0 P 0 ;0
L 1.14826998 -2.08645 1.14835 -2.08641004 0 P 0 ;0
L 1.14835 -2.08641004 1.14838002 -2.08638002 0 P 0 ;0
L 1.14838002 -2.08638002 1.14976004 -2.08553002 0 P 0 ;0
L 1.14976004 -2.08553002 1.14978996 -2.08551004 0 P 0 ;0
L 1.14978996 -2.08551004 1.14983002 -2.08548996 0 P 0 ;0
L 1.14983002 -2.08548996 1.14988996 -2.08543996 0 P 0 ;0
L 1.14988996 -2.08543996 1.1512 -2.08448996 0 P 0 ;0
L 1.1512 -2.08448996 1.15126004 -2.08443996 0 P 0 ;0
L 1.15126004 -2.08443996 1.15128996 -2.08441004 0 P 0 ;0
L 1.15128996 -2.08441004 1.15131998 -2.08438996 0 P 0 ;0
L 1.15131998 -2.08438996 1.15253996 -2.08333002 0 P 0 ;0
L 1.15253996 -2.08333002 1.15256998 -2.0833 0 P 0 ;0
L 1.15256998 -2.0833 1.1526 -2.08328002 0 P 0 ;0
L 1.1526 -2.08328002 1.15263002 -2.08323996 0 P 0 ;0
L 1.15263002 -2.08323996 1.15266004 -2.08321998 0 P 0 ;0
L 1.15266004 -2.08321998 1.15378996 -2.08206004 0 P 0 ;0
L 1.15378996 -2.08206004 1.15376004 -2.08203996 0 P 0 ;0
L 1.15376004 -2.08203996 1.15381998 -2.08203996 0 P 0 ;0
L 1.15381998 -2.08203996 1.15383996 -2.082 0 P 0 ;0
L 1.15383996 -2.082 1.15386998 -2.08196998 0 P 0 ;0
L 1.15386998 -2.08196998 1.1539 -2.08195 0 P 0 ;0
L 1.1539 -2.08195 1.15493002 -2.08071004 0 P 0 ;0
L 1.15493002 -2.08071004 1.15493002 -2.0807 0 P 0 ;0
L 1.15493002 -2.0807 1.15496004 -2.08066998 0 P 0 ;0
L 1.15496004 -2.08066998 1.15498002 -2.08063996 0 P 0 ;0
L 1.15498002 -2.08063996 1.15501004 -2.08061004 0 P 0 ;0
L 1.15501004 -2.08061004 1.15503002 -2.08058002 0 P 0 ;0
L 1.15503002 -2.08058002 1.15596004 -2.07926004 0 P 0 ;0
L 1.15596004 -2.07926004 1.15603996 -2.07913996 0 P 0 ;0
L 1.15603996 -2.07913996 1.15673002 -2.07798996 0 P 0 ;0
L 1.15673002 -2.07798996 1.15676998 -2.07793002 0 P 0 ;0
L 1.15676998 -2.07793002 1.15678996 -2.07786998 0 P 0 ;0
L 1.15678996 -2.07786998 1.15741004 -2.07668996 0 P 0 ;0
L 1.15741004 -2.07668996 1.15743996 -2.07663002 0 P 0 ;0
L 1.15743996 -2.07663002 1.15746004 -2.07656998 0 P 0 ;0
L 1.15746004 -2.07656998 1.15746998 -2.07656998 0 P 0 ;0
L 1.15746998 -2.07656998 1.158 -2.07533996 0 P 0 ;0
L 1.158 -2.07533996 1.15801004 -2.07531004 0 P 0 ;0
L 1.15801004 -2.07531004 1.15803002 -2.07528002 0 P 0 ;0
L 1.15803002 -2.07528002 1.15805 -2.07521998 0 P 0 ;0
L 1.15805 -2.07521998 1.15848996 -2.07396004 0 P 0 ;0
L 1.15848996 -2.07396004 1.15841004 -2.07393002 0 P 0 ;0
L 1.15841004 -2.07393002 1.15851004 -2.07393002 0 P 0 ;0
L 1.15851004 -2.07393002 1.15851998 -2.0739 0 P 0 ;0
L 1.15851998 -2.0739 1.15853002 -2.07386004 0 P 0 ;0
L 1.15853002 -2.07386004 1.15853996 -2.07383002 0 P 0 ;0
L 1.15853996 -2.07383002 1.15943996 -2.07061004 0 P 0 ;0
L 1.15943996 -2.07061004 1.15945 -2.07058002 0 P 0 ;0
L 1.15945 -2.07058002 1.15946004 -2.07053996 0 P 0 ;0
L 1.15946004 -2.07053996 1.15946998 -2.07051004 0 P 0 ;0
L 1.15946998 -2.07051004 1.15946998 -2.07046998 0 P 0 ;0
L 1.15946998 -2.07046998 1.16013996 -2.06723002 0 P 0 ;0
L 1.16013996 -2.06723002 1.16013996 -2.0672 0 P 0 ;0
L 1.16013996 -2.0672 1.16016004 -2.06713996 0 P 0 ;0
L 1.16016004 -2.06713996 1.16016004 -2.06711004 0 P 0 ;0
L 1.16016004 -2.06711004 1.16081998 -2.06256004 0 P 0 ;0
L 1.16081998 -2.06256004 1.16081998 -2.06253996 0 P 0 ;0
L 1.16081998 -2.06253996 1.16083002 -2.0625 0 P 0 ;0
L 1.16083002 -2.0625 1.16083002 -2.06246998 0 P 0 ;0
L 1.16083002 -2.06246998 1.16126998 -2.05791004 0 P 0 ;0
L 1.16126998 -2.05791004 1.16128002 -2.0579 0 P 0 ;0
L 1.16128002 -2.0579 1.16128002 -2.05783996 0 P 0 ;0
L 1.16128002 -2.05783996 1.1621 -2.04405 0 P 0 ;0
L 1.1621 -2.04405 1.1621 -2.04401998 0 P 0 ;0
L 1.1621 -2.04401998 1.16285 -2.02761998 0 P 0 ;0
L 1.16285 -2.02761998 1.16136998 -2.0256 0 P 0 ;0
L 1.16136998 -2.0256 1.15878996 -2.02491004 0 P 0 ;0
L 1.15878996 -2.02491004 1.15878002 -2.0249 0 P 0 ;0
L 1.15878002 -2.0249 1.15871998 -2.02488996 0 P 0 ;0
L 1.15871998 -2.02488996 1.15755 -2.02461998 0 P 0 ;0
L 1.15755 -2.02461998 1.15746998 -2.0246 0 P 0 ;0
L 1.15746998 -2.0246 1.1574 -2.0246 0 P 0 ;0
L 1.1574 -2.0246 1.15621004 -2.02441004 0 P 0 ;0
L 1.15621004 -2.02441004 1.15616998 -2.02441004 0 P 0 ;0
L 1.15616998 -2.02441004 1.1561 -2.0244 0 P 0 ;0
L 1.1561 -2.0244 1.15606004 -2.02438996 0 P 0 ;0
L 1.15606004 -2.02438996 1.15486004 -2.0243 0 P 0 ;0
L 1.15486004 -2.0243 1.15471998 -2.0243 0 P 0 ;0
L 1.15471998 -2.0243 1.14936004 -2.02426004 0 P 0 ;0
L 1.14936004 -2.02426004 1.14928996 -2.02426004 0 P 0 ;0
L 1.14928996 -2.02426004 1.14925 -2.02426998 0 P 0 ;0
L 1.14925 -2.02426998 1.14921004 -2.02426998 0 P 0 ;0
L 1.14921004 -2.02426998 1.14376998 -2.02463996 0 P 0 ;0
L 1.14376998 -2.02463996 1.1437 -2.02463996 0 P 0 ;0
L 1.1437 -2.02463996 1.14365 -2.02465 0 P 0 ;0
L 1.14365 -2.02465 1.14361004 -2.02465 0 P 0 ;0
L 1.14361004 -2.02465 1.14161998 -2.02495 0 P 0 ;0
L 1.14161998 -2.02495 1.14161004 -2.02495 0 P 0 ;0
L 1.14161004 -2.02495 1.14153002 -2.02496998 0 P 0 ;0
L 1.14153002 -2.02496998 1.14148996 -2.02496998 0 P 0 ;0
L 1.14148996 -2.02496998 1.14143996 -2.02498996 0 P 0 ;0
L 1.14143996 -2.02498996 1.13946998 -2.02545 0 P 0 ;0
L 1.13946998 -2.02545 1.13943996 -2.02546998 0 P 0 ;0
L 1.13943996 -2.02546998 1.1394 -2.02546998 0 P 0 ;0
L 1.1394 -2.02546998 1.13933002 -2.0255 0 P 0 ;0
L 1.13933002 -2.0255 1.13801004 -2.02591998 0 P 0 ;0
L 1.13801004 -2.02591998 1.13798002 -2.02593002 0 P 0 ;0
L 1.13798002 -2.02593002 1.13793996 -2.02593996 0 P 0 ;0
L 1.13793996 -2.02593996 1.13788002 -2.02596998 0 P 0 ;0
L 1.13788002 -2.02596998 1.1366 -2.02648002 0 P 0 ;0
L 1.1366 -2.02648002 1.13653996 -2.0265 0 P 0 ;0
L 1.13653996 -2.0265 1.13648002 -2.02653002 0 P 0 ;0
L 1.13648002 -2.02653002 1.13523996 -2.02713002 0 P 0 ;0
L 1.13523996 -2.02713002 1.13518002 -2.02716004 0 P 0 ;0
L 1.13518002 -2.02716004 1.13515 -2.02716998 0 P 0 ;0
L 1.13515 -2.02716998 1.13511998 -2.02718996 0 P 0 ;0
L 1.13511998 -2.02718996 1.13393002 -2.02786998 0 P 0 ;0
L 1.13393002 -2.02786998 1.13388996 -2.02788996 0 P 0 ;0
L 1.13388996 -2.02788996 1.1338 -2.02795 0 P 0 ;0
L 1.1338 -2.02795 1.13111998 -2.02976004 0 P 0 ;0
L 1.13111998 -2.02976004 1.13105 -2.02981004 0 P 0 ;0
L 1.13105 -2.02981004 1.13101004 -2.02983996 0 P 0 ;0
L 1.13101004 -2.02983996 1.13098002 -2.02986004 0 P 0 ;0
L 1.13098002 -2.02986004 1.12846998 -2.03188996 0 P 0 ;0
L 1.12846998 -2.03188996 1.12838002 -2.03198002 0 P 0 ;0
L 1.12838002 -2.03198002 1.12833996 -2.03201004 0 P 0 ;0
L 1.12833996 -2.03201004 1.12596004 -2.0343 0 P 0 ;0
L 1.12596004 -2.0343 1.12593996 -2.03433002 0 P 0 ;0
L 1.12593996 -2.03433002 1.1259 -2.03436004 0 P 0 ;0
L 1.1259 -2.03436004 1.12588002 -2.03438996 0 P 0 ;0
L 1.12588002 -2.03438996 1.12585 -2.03443002 0 P 0 ;0
L 1.12585 -2.03443002 1.12366998 -2.03691004 0 P 0 ;0
L 1.12366998 -2.03691004 1.12363996 -2.03695 0 P 0 ;0
L 1.12363996 -2.03695 1.12361998 -2.03698002 0 P 0 ;0
L 1.12361998 -2.03698002 1.12358996 -2.03701004 0 P 0 ;0
L 1.12358996 -2.03701004 1.12356998 -2.03703996 0 P 0 ;0
L 1.12356998 -2.03703996 1.12236998 -2.03865 0 P 0 ;0
L 1.12236998 -2.03865 1.12233996 -2.03868996 0 P 0 ;0
L 1.12233996 -2.03868996 1.12233002 -2.03871004 0 P 0 ;0
L 1.12233002 -2.03871004 1.12228996 -2.03878002 0 P 0 ;0
L 1.12228996 -2.03878002 1.12121004 -2.04046998 0 P 0 ;0
L 1.12121004 -2.04046998 1.12118996 -2.0405 0 P 0 ;0
L 1.12118996 -2.0405 1.12116998 -2.04053996 0 P 0 ;0
L 1.12116998 -2.04053996 1.12115 -2.04056998 0 P 0 ;0
L 1.12115 -2.04056998 1.12113996 -2.04061004 0 P 0 ;0
L 1.12113996 -2.04061004 1.12018996 -2.04238002 0 P 0 ;0
L 1.12018996 -2.04238002 1.12016004 -2.04245 0 P 0 ;0
L 1.12016004 -2.04245 1.12013996 -2.04248002 0 P 0 ;0
L 1.12013996 -2.04248002 1.12013002 -2.04251004 0 P 0 ;0
L 1.12013002 -2.04251004 1.11926004 -2.04446998 0 P 0 ;0
L 1.11926004 -2.04446998 1.11925 -2.0445 0 P 0 ;0
L 1.11925 -2.0445 1.11923002 -2.04453996 0 P 0 ;0
L 1.11923002 -2.04453996 1.11921998 -2.04458002 0 P 0 ;0
L 1.11921998 -2.04458002 1.11921004 -2.04461004 0 P 0 ;0
L 1.11921004 -2.04461004 1.11848002 -2.04663002 0 P 0 ;0
L 1.11848002 -2.04663002 1.11846998 -2.04666004 0 P 0 ;0
L 1.11846998 -2.04666004 1.11846004 -2.0467 0 P 0 ;0
L 1.11846004 -2.0467 1.11843996 -2.04676998 0 P 0 ;0
L 1.11843996 -2.04676998 1.11786004 -2.04883996 0 P 0 ;0
L 1.11786004 -2.04883996 1.11785 -2.04886998 0 P 0 ;0
L 1.11785 -2.04886998 1.11783996 -2.04891004 0 P 0 ;0
L 1.11783996 -2.04891004 1.11783996 -2.04893996 0 P 0 ;0
L 1.11783996 -2.04893996 1.11783002 -2.04896998 0 P 0 ;0
L 1.11783002 -2.04896998 1.11783002 -2.04898002 0 P 0 ;0
L 1.11783002 -2.04898002 1.1174 -2.05108002 0 P 0 ;0
L 1.1174 -2.05108002 1.1174 -2.05111998 0 P 0 ;0
L 1.1174 -2.05111998 1.11738996 -2.05116004 0 P 0 ;0
L 1.11738996 -2.05116004 1.11738002 -2.05118996 0 P 0 ;0
L 1.11738002 -2.05118996 1.11738002 -2.05123002 0 P 0 ;0
L 1.11738002 -2.05123002 1.11673002 -2.05643002 0 P 0 ;0
L 1.11673002 -2.05643002 1.11671998 -2.05646998 0 P 0 ;0
L 1.11671998 -2.05646998 1.11671998 -2.05655 0 P 0 ;0
L 1.11671998 -2.05655 1.11671004 -2.05658996 0 P 0 ;0
L 1.11671004 -2.05658996 1.11648996 -2.06181998 0 P 0 ;0
L 1.11648996 -2.06181998 1.11648002 -2.06186998 0 P 0 ;0
L 1.11648002 -2.06186998 1.11648002 -2.06195 0 P 0 ;0
L 1.11648002 -2.06195 1.11648996 -2.06198996 0 P 0 ;0
L 1.11648996 -2.06198996 1.11668002 -2.06696998 0 P 0 ;0
L 1.11668002 -2.06696998 1.11768002 -2.06696998 0 P 0 ;0
L 1.11768002 -2.06696998 1.11668002 -2.06701004 0 P 0 ;0
L 1.11668002 -2.06701004 1.11668002 -2.06713002 0 P 0 ;0
L 1.11668002 -2.06713002 1.11668996 -2.06716998 0 P 0 ;0
L 1.11668996 -2.06716998 1.11728002 -2.07215 0 P 0 ;0
L 1.11728002 -2.07215 1.11728996 -2.07218996 0 P 0 ;0
L 1.11728996 -2.07218996 1.11728996 -2.07223002 0 P 0 ;0
L 1.11728996 -2.07223002 1.11731004 -2.07231004 0 P 0 ;0
L 1.11731004 -2.07231004 1.11758996 -2.07371004 0 P 0 ;0
L 1.11758996 -2.07371004 1.1176 -2.07375 0 P 0 ;0
L 1.1176 -2.07375 1.11761004 -2.0738 0 P 0 ;0
L 1.11761004 -2.0738 1.11761998 -2.07383996 0 P 0 ;0
L 1.11761998 -2.07383996 1.11763996 -2.07388002 0 P 0 ;0
L 1.11763996 -2.07388002 1.11803996 -2.07523996 0 P 0 ;0
L 1.11803996 -2.07523996 1.11806004 -2.07531998 0 P 0 ;0
L 1.11806004 -2.07531998 1.11808002 -2.07536004 0 P 0 ;0
L 1.11808002 -2.07536004 1.11808996 -2.07541004 0 P 0 ;0
L 1.11808996 -2.07541004 1.11861004 -2.07673002 0 P 0 ;0
L 1.11861004 -2.07673002 1.11863996 -2.07681004 0 P 0 ;0
L 1.11863996 -2.07681004 1.11866004 -2.07683996 0 P 0 ;0
L 1.11866004 -2.07683996 1.11868002 -2.07688002 0 P 0 ;0
L 1.11868002 -2.07688002 1.11931004 -2.07815 0 P 0 ;0
L 1.11931004 -2.07815 1.11935 -2.07823002 0 P 0 ;0
L 1.11935 -2.07823002 1.1194 -2.0783 0 P 0 ;0
L 1.1194 -2.0783 1.12013996 -2.07951998 0 P 0 ;0
L 1.12013996 -2.07951998 1.12021004 -2.07961998 0 P 0 ;0
L 1.12021004 -2.07961998 1.12023002 -2.07965 0 P 0 ;0
L 1.12023002 -2.07965 1.12023002 -2.07966004 0 P 0 ;0
L 1.12023002 -2.07966004 1.1212 -2.08096998 0 P 0 ;0
L 1.1212 -2.08096998 1.12123996 -2.08103002 0 P 0 ;0
L 1.12123996 -2.08103002 1.12126998 -2.08106004 0 P 0 ;0
L 1.12126998 -2.08106004 1.12128996 -2.08108996 0 P 0 ;0
L 1.12128996 -2.08108996 1.12235 -2.08231004 0 P 0 ;0
L 1.12235 -2.08231004 1.12238002 -2.08233996 0 P 0 ;0
L 1.12238002 -2.08233996 1.1224 -2.08236998 0 P 0 ;0
L 1.1224 -2.08236998 1.12246004 -2.08243002 0 P 0 ;0
L 1.12246004 -2.08243002 1.12361004 -2.08355 0 P 0 ;0
L 1.12361004 -2.08355 1.12366998 -2.08361004 0 P 0 ;0
L 1.12366998 -2.08361004 1.1237 -2.08363002 0 P 0 ;0
L 1.1237 -2.08363002 1.12373002 -2.08366004 0 P 0 ;0
L 1.12373002 -2.08366004 1.12496998 -2.08468996 0 P 0 ;0
L 1.12496998 -2.08468996 1.125 -2.08471004 0 P 0 ;0
L 1.125 -2.08471004 1.12503002 -2.08473996 0 P 0 ;0
L 1.12503002 -2.08473996 1.12506998 -2.08476004 0 P 0 ;0
L 1.12506998 -2.08476004 1.1251 -2.08478996 0 P 0 ;0
L 1.1251 -2.08478996 1.12641998 -2.08571004 0 P 0 ;0
L 1.12641998 -2.08571004 1.12645 -2.08573002 0 P 0 ;0
L 1.12645 -2.08573002 1.12648002 -2.08576004 0 P 0 ;0
L 1.12648002 -2.08576004 1.12651004 -2.08578002 0 P 0 ;0
L 1.12651004 -2.08578002 1.12655 -2.0858 0 P 0 ;0
L 1.12655 -2.0858 1.12793996 -2.08661004 0 P 0 ;0
L 1.12793996 -2.08661004 1.12801004 -2.08665 0 P 0 ;0
L 1.12801004 -2.08665 1.12805 -2.08666998 0 P 0 ;0
L 1.12805 -2.08666998 1.12808002 -2.08668996 0 P 0 ;0
L 1.12808002 -2.08668996 1.12808996 -2.08668996 0 P 0 ;0
L 1.12808996 -2.08668996 1.12953996 -2.08738996 0 P 0 ;0
L 1.12953996 -2.08738996 1.12961998 -2.08743002 0 P 0 ;0
L 1.12961998 -2.08743002 1.12965 -2.08743996 0 P 0 ;0
L 1.12965 -2.08743996 1.1297 -2.08746004 0 P 0 ;0
L 1.1297 -2.08746004 1.13118002 -2.08801998 0 P 0 ;0
L 1.13118002 -2.08801998 1.13133996 -2.08808002 0 P 0 ;0
L 1.13133996 -2.08808002 1.13286998 -2.08851004 0 P 0 ;0
L 1.13286998 -2.08851004 1.13295 -2.08853996 0 P 0 ;0
L 1.13295 -2.08853996 1.13303996 -2.08855 0 P 0 ;0
L 1.13303996 -2.08855 1.1346 -2.08886004 0 P 0 ;0
L 1.1346 -2.08886004 1.13471998 -2.08888996 0 P 0 ;0
L 1.13471998 -2.08888996 1.13476004 -2.08888996 0 P 0 ;0
L 1.13476004 -2.08888996 1.13633996 -2.08906998 0 P 0 ;0
L 1.13633996 -2.08906998 1.13638996 -2.08908002 0 P 0 ;0
L 1.13638996 -2.08908002 1.13651004 -2.08908002 0 P 0 ;0
L 1.13651004 -2.08908002 1.1381 -2.08913002 0 P 0 ;0
L 1.1381 -2.08913002 1.13818996 -2.08913002 0 P 0 ;0
L 1.31623996 -1.98923996 1.3135 -1.98988002 0 P 0 ;0
L 1.3135 -1.98988002 1.31078996 -1.99071004 0 P 0 ;0
L 1.31078996 -1.99071004 1.30813002 -1.99175 0 P 0 ;0
L 1.30813002 -1.99175 1.30553996 -1.99296998 0 P 0 ;0
L 1.30553996 -1.99296998 1.30308996 -1.99431998 0 P 0 ;0
L 1.30308996 -1.99431998 1.30073996 -1.99585 0 P 0 ;0
L 1.30073996 -1.99585 1.29863996 -1.99746004 0 P 0 ;0
L 1.29863996 -1.99746004 1.29666004 -1.99923996 0 P 0 ;0
L 1.29666004 -1.99923996 1.29205 -2.00375 0 P 0 ;0
L 1.29205 -2.00375 1.29205 -1.99243996 0 P 0 ;0
L 1.29205 -1.99243996 1.24316004 -1.99243996 0 P 0 ;0
L 1.24316004 -1.99243996 1.24313996 -2.00521004 0 P 0 ;0
L 1.24313996 -2.00521004 1.24261004 -2.03151004 0 P 0 ;0
L 1.24261004 -2.03151004 1.24086998 -2.07046004 0 P 0 ;0
L 1.24086998 -2.07046004 1.23873996 -2.10921004 0 P 0 ;0
L 1.23873996 -2.10921004 1.23811998 -2.11641998 0 P 0 ;0
L 1.23811998 -2.11641998 1.23711998 -2.12361998 0 P 0 ;0
L 1.23711998 -2.12361998 1.23655 -2.12716004 0 P 0 ;0
L 1.23655 -2.12716004 1.29205 -2.12716004 0 P 0 ;0
L 1.29205 -2.12716004 1.29206998 -2.11766004 0 P 0 ;0
L 1.29206998 -2.11766004 1.29238996 -2.10283996 0 P 0 ;0
L 1.29238996 -2.10283996 1.29336004 -2.08431004 0 P 0 ;0
L 1.29336004 -2.08431004 1.29463996 -2.06673002 0 P 0 ;0
L 1.29463996 -2.06673002 1.29511004 -2.06253002 0 P 0 ;0
L 1.29511004 -2.06253002 1.29583996 -2.05836004 0 P 0 ;0
L 1.29583996 -2.05836004 1.29683002 -2.05446998 0 P 0 ;0
L 1.29683002 -2.05446998 1.29813996 -2.05068996 0 P 0 ;0
L 1.29813996 -2.05068996 1.29978002 -2.04701998 0 P 0 ;0
L 1.29978002 -2.04701998 1.30056998 -2.04556998 0 P 0 ;0
L 1.30056998 -2.04556998 1.30146998 -2.04418996 0 P 0 ;0
L 1.30146998 -2.04418996 1.30246998 -2.04288002 0 P 0 ;0
L 1.30246998 -2.04288002 1.30356998 -2.04165 0 P 0 ;0
L 1.30356998 -2.04165 1.30475 -2.0405 0 P 0 ;0
L 1.30475 -2.0405 1.30603996 -2.03945 0 P 0 ;0
L 1.30603996 -2.03945 1.30773996 -2.03826004 0 P 0 ;0
L 1.30773996 -2.03826004 1.30953002 -2.03723002 0 P 0 ;0
L 1.30953002 -2.03723002 1.31141004 -2.03635 0 P 0 ;0
L 1.31141004 -2.03635 1.31335 -2.03563002 0 P 0 ;0
L 1.31335 -2.03563002 1.31535 -2.03508002 0 P 0 ;0
L 1.31535 -2.03508002 1.31973996 -2.03423002 0 P 0 ;0
L 1.31973996 -2.03423002 1.32416004 -2.03366998 0 P 0 ;0
L 1.32416004 -2.03366998 1.32863002 -2.0334 0 P 0 ;0
L 1.32863002 -2.0334 1.33688002 -2.03318002 0 P 0 ;0
L 1.33688002 -2.03318002 1.33613002 -2.01151004 0 P 0 ;0
L 1.33613002 -2.01151004 1.33581004 -2.00315 0 P 0 ;0
L 1.33581004 -2.00315 1.33543996 -1.99596004 0 P 0 ;0
L 1.33543996 -1.99596004 1.33508002 -1.98971004 0 P 0 ;0
L 1.33508002 -1.98971004 1.33503996 -1.98945 0 P 0 ;0
L 1.33503996 -1.98945 1.335 -1.98931998 0 P 0 ;0
L 1.335 -1.98931998 1.33496004 -1.9892 0 P 0 ;0
L 1.33496004 -1.9892 1.3349 -1.98908002 0 P 0 ;0
L 1.3349 -1.98908002 1.33483996 -1.98896998 0 P 0 ;0
L 1.33483996 -1.98896998 1.33476998 -1.98886004 0 P 0 ;0
L 1.33476998 -1.98886004 1.33468996 -1.98876004 0 P 0 ;0
L 1.33468996 -1.98876004 1.3346 -1.98866998 0 P 0 ;0
L 1.3346 -1.98866998 1.33451004 -1.98858996 0 P 0 ;0
L 1.33451004 -1.98858996 1.3344 -1.98851998 0 P 0 ;0
L 1.3344 -1.98851998 1.3343 -1.98845 0 P 0 ;0
L 1.3343 -1.98845 1.33418002 -1.98838996 0 P 0 ;0
L 1.33418002 -1.98838996 1.33406998 -1.98833996 0 P 0 ;0
L 1.33406998 -1.98833996 1.33395 -1.9883 0 P 0 ;0
L 1.33395 -1.9883 1.33383002 -1.98828002 0 P 0 ;0
L 1.33383002 -1.98828002 1.3337 -1.98826004 0 P 0 ;0
L 1.3337 -1.98826004 1.33356998 -1.98825 0 P 0 ;0
L 1.33356998 -1.98825 1.32756998 -1.98823002 0 P 0 ;0
L 1.32756998 -1.98823002 1.32135 -1.98853996 0 P 0 ;0
L 1.32135 -1.98853996 1.31878996 -1.98881998 0 P 0 ;0
L 1.31878996 -1.98881998 1.31623996 -1.98923996 0 P 0 ;0
L 1.2389 -2.12516004 1.29006004 -2.12516004 0 P 0 ;0
L 1.23906998 -2.12416004 1.29006004 -2.12416004 0 P 0 ;0
L 1.23921004 -2.12316004 1.29006004 -2.12316004 0 P 0 ;0
L 1.23933996 -2.12216004 1.29006004 -2.12216004 0 P 0 ;0
L 1.23948996 -2.12116004 1.29006004 -2.12116004 0 P 0 ;0
L 1.23961998 -2.12016004 1.29006998 -2.12016004 0 P 0 ;0
L 1.23976004 -2.11916004 1.29006998 -2.11916004 0 P 0 ;0
L 1.2399 -2.11816004 1.29006998 -2.11816004 0 P 0 ;0
L 1.24003996 -2.11716004 1.29008002 -2.11716004 0 P 0 ;0
L 1.24015 -2.11616004 1.2901 -2.11616004 0 P 0 ;0
L 1.24023996 -2.11516004 1.29011998 -2.11516004 0 P 0 ;0
L 1.24033002 -2.11416004 1.29013996 -2.11416004 0 P 0 ;0
L 1.24041004 -2.11316004 1.29016004 -2.11316004 0 P 0 ;0
L 1.24048996 -2.11216004 1.29018996 -2.11216004 0 P 0 ;0
L 1.24058002 -2.11116004 1.29021004 -2.11116004 0 P 0 ;0
L 1.24066998 -2.11016004 1.29023002 -2.11016004 0 P 0 ;0
L 1.24075 -2.10916004 1.29025 -2.10916004 0 P 0 ;0
L 1.2408 -2.10816004 1.29026998 -2.10816004 0 P 0 ;0
L 1.24086004 -2.10716004 1.29028996 -2.10716004 0 P 0 ;0
L 1.24091004 -2.10616004 1.29031998 -2.10616004 0 P 0 ;0
L 1.24096998 -2.10516004 1.29033996 -2.10516004 0 P 0 ;0
L 1.24101998 -2.10416004 1.29036004 -2.10416004 0 P 0 ;0
L 1.24108002 -2.10316004 1.29038002 -2.10316004 0 P 0 ;0
L 1.24113002 -2.10216004 1.29041998 -2.10216004 0 P 0 ;0
L 1.24118002 -2.10116004 1.29046998 -2.10116004 0 P 0 ;0
L 1.24123996 -2.10016004 1.29053002 -2.10016004 0 P 0 ;0
L 1.24128996 -2.09916004 1.29058002 -2.09916004 0 P 0 ;0
L 1.24135 -2.09816004 1.29063002 -2.09816004 0 P 0 ;0
L 1.2414 -2.09716004 1.29068002 -2.09716004 0 P 0 ;0
L 1.24146004 -2.09616004 1.29073996 -2.09616004 0 P 0 ;0
L 1.24151004 -2.09516004 1.29078996 -2.09516004 0 P 0 ;0
L 1.24156998 -2.09416004 1.29083996 -2.09416004 0 P 0 ;0
L 1.24161998 -2.09316004 1.2909 -2.09316004 0 P 0 ;0
L 1.24168002 -2.09216004 1.29095 -2.09216004 0 P 0 ;0
L 1.24173002 -2.09116004 1.291 -2.09116004 0 P 0 ;0
L 1.24178996 -2.09016004 1.29105 -2.09016004 0 P 0 ;0
L 1.24183996 -2.08916004 1.2911 -2.08916004 0 P 0 ;0
L 1.2419 -2.08816004 1.29116004 -2.08816004 0 P 0 ;0
L 1.24196004 -2.08716004 1.29121004 -2.08716004 0 P 0 ;0
L 1.24201004 -2.08616004 1.29126998 -2.08616004 0 P 0 ;0
L 1.24206998 -2.08516004 1.29131998 -2.08516004 0 P 0 ;0
L 1.24211998 -2.08416004 1.29136998 -2.08416004 0 P 0 ;0
L 1.2389 -2.12516004 1.2391 -2.12393002 0 P 0 ;0
L 1.2391 -2.12393002 1.2391 -2.1239 0 P 0 ;0
L 1.2391 -2.1239 1.24011004 -2.11665 0 P 0 ;0
L 1.24011004 -2.11665 1.24073002 -2.10935 0 P 0 ;0
L 1.24073002 -2.10935 1.24073996 -2.10931998 0 P 0 ;0
L 1.24073996 -2.10931998 1.24286004 -2.07056004 0 P 0 ;0
L 1.24286004 -2.07056004 1.24461004 -2.03158002 0 P 0 ;0
L 1.24461004 -2.03158002 1.24513996 -2.00523002 0 P 0 ;0
L 1.24513996 -2.00523002 1.24515 -1.99443996 0 P 0 ;0
L 1.24515 -1.99443996 1.29005 -1.99443996 0 P 0 ;0
L 1.29005 -1.99443996 1.29005 -2.00375 0 P 0 ;0
L 1.29005 -2.00375 1.29128002 -2.0056 0 P 0 ;0
L 1.29128002 -2.0056 1.29345 -2.00518002 0 P 0 ;0
L 1.29345 -2.00518002 1.29803002 -2.0007 0 P 0 ;0
L 1.29803002 -2.0007 1.29991998 -1.999 0 P 0 ;0
L 1.29991998 -1.999 1.30188996 -1.99748996 0 P 0 ;0
L 1.30188996 -1.99748996 1.30411998 -1.99603996 0 P 0 ;0
L 1.30411998 -1.99603996 1.30645 -1.99475 0 P 0 ;0
L 1.30645 -1.99475 1.30891998 -1.99358996 0 P 0 ;0
L 1.30891998 -1.99358996 1.31145 -1.9926 0 P 0 ;0
L 1.31145 -1.9926 1.31401998 -1.99181004 0 P 0 ;0
L 1.31401998 -1.99181004 1.31663996 -1.9912 0 P 0 ;0
L 1.31663996 -1.9912 1.31906004 -1.9908 0 P 0 ;0
L 1.31906004 -1.9908 1.32151004 -1.99053002 0 P 0 ;0
L 1.32151004 -1.99053002 1.32761998 -1.99023002 0 P 0 ;0
L 1.32761998 -1.99023002 1.3331 -1.99025 0 P 0 ;0
L 1.3331 -1.99025 1.33345 -1.99608002 0 P 0 ;0
L 1.33345 -1.99608002 1.33381004 -2.00323002 0 P 0 ;0
L 1.33381004 -2.00323002 1.33413002 -2.01158996 0 P 0 ;0
L 1.33413002 -2.01158996 1.33413002 -2.0116 0 P 0 ;0
L 1.33413002 -2.0116 1.33481998 -2.03123002 0 P 0 ;0
L 1.33481998 -2.03123002 1.32853996 -2.0314 0 P 0 ;0
L 1.32853996 -2.0314 1.32398002 -2.03166998 0 P 0 ;0
L 1.32398002 -2.03166998 1.31941998 -2.03225 0 P 0 ;0
L 1.31941998 -2.03225 1.31488996 -2.03313002 0 P 0 ;0
L 1.31488996 -2.03313002 1.31273996 -2.03373002 0 P 0 ;0
L 1.31273996 -2.03373002 1.31063996 -2.0345 0 P 0 ;0
L 1.31063996 -2.0345 1.3086 -2.03545 0 P 0 ;0
L 1.3086 -2.03545 1.30666004 -2.03656998 0 P 0 ;0
L 1.30666004 -2.03656998 1.30658996 -2.03661998 0 P 0 ;0
L 1.30658996 -2.03661998 1.30483002 -2.03786004 0 P 0 ;0
L 1.30483002 -2.03786004 1.30341998 -2.03901004 0 P 0 ;0
L 1.30341998 -2.03901004 1.30336998 -2.03906004 0 P 0 ;0
L 1.30336998 -2.03906004 1.30211998 -2.04026004 0 P 0 ;0
L 1.30211998 -2.04026004 1.30093002 -2.0416 0 P 0 ;0
L 1.30093002 -2.0416 1.29983002 -2.04303996 0 P 0 ;0
L 1.29983002 -2.04303996 1.29978996 -2.0431 0 P 0 ;0
L 1.29978996 -2.0431 1.29885 -2.04453996 0 P 0 ;0
L 1.29885 -2.04453996 1.29798996 -2.04613002 0 P 0 ;0
L 1.29798996 -2.04613002 1.29631998 -2.04986998 0 P 0 ;0
L 1.29631998 -2.04986998 1.29628002 -2.04995 0 P 0 ;0
L 1.29628002 -2.04995 1.29625 -2.05003002 0 P 0 ;0
L 1.29625 -2.05003002 1.29491998 -2.0539 0 P 0 ;0
L 1.29491998 -2.0539 1.29388996 -2.05793996 0 P 0 ;0
L 1.29388996 -2.05793996 1.29386998 -2.05801998 0 P 0 ;0
L 1.29386998 -2.05801998 1.29313996 -2.06221004 0 P 0 ;0
L 1.29313996 -2.06221004 1.29313002 -2.06223996 0 P 0 ;0
L 1.29313002 -2.06223996 1.29311998 -2.0623 0 P 0 ;0
L 1.29311998 -2.0623 1.29265 -2.06655 0 P 0 ;0
L 1.29265 -2.06655 1.29136998 -2.08418996 0 P 0 ;0
L 1.29136998 -2.08418996 1.29038996 -2.10276998 0 P 0 ;0
L 1.29038996 -2.10276998 1.29006998 -2.11763002 0 P 0 ;0
L 1.29006998 -2.11763002 1.29006004 -2.12516004 0 P 0 ;0
L 1.29006004 -2.12516004 1.2389 -2.12516004 0 P 0 ;0
L 1.09846998 -2.00483002 1.21248002 -2.00483002 0 P 0 ;0
L 1.09838002 -2.12083002 1.14708002 -2.12083002 0 P 0 ;0
L 1.11933002 -2.18283002 1.15161998 -2.18283002 0 P 0 ;0
L 1.11001998 -2.18183002 1.15838002 -2.18183002 0 P 0 ;0
L 1.10246998 -2.18083002 1.16333996 -2.18083002 0 P 0 ;0
L 1.04061004 -1.89731004 1.09978002 -1.89731004 0 P 0 ;0
L 1.03565 -1.89631004 1.09821004 -1.89631004 0 P 0 ;0
L 1.03068996 -1.89531004 1.09661004 -1.89531004 0 P 0 ;0
L 1.02573002 -1.89431004 1.09475 -1.89431004 0 P 0 ;0
L 1.019 -1.89331004 1.09288002 -1.89331004 0 P 0 ;0
L 1.01163996 -1.89231004 1.09101998 -1.89231004 0 P 0 ;0
L 0.99518996 -1.89131004 1.08916004 -1.89131004 0 P 0 ;0
L 0.87011998 -1.88331004 1.07278996 -1.88331004 0 P 0 ;0
L 0.86963996 -1.88231004 1.07053002 -1.88231004 0 P 0 ;0
L 0.86916004 -1.88131004 1.06828002 -1.88131004 0 P 0 ;0
L 0.86863002 -1.88031004 1.06603002 -1.88031004 0 P 0 ;0
L 0.86806998 -1.87931004 1.06351004 -1.87931004 0 P 0 ;0
L 0.8675 -1.87831004 1.06076998 -1.87831004 0 P 0 ;0
L 0.86693002 -1.87731004 1.05803996 -1.87731004 0 P 0 ;0
L 0.86631004 -1.87631004 1.05531004 -1.87631004 0 P 0 ;0
L 0.86563996 -1.87531004 1.05256998 -1.87531004 0 P 0 ;0
L 0.86498002 -1.87431004 1.04983996 -1.87431004 0 P 0 ;0
L 0.86431998 -1.87331004 1.0471 -1.87331004 0 P 0 ;0
L 0.86356004 -1.87231004 1.04376004 -1.87231004 0 P 0 ;0
L 0.86278996 -1.87131004 1.04041998 -1.87131004 0 P 0 ;0
L 0.86203002 -1.87031004 1.03708002 -1.87031004 0 P 0 ;0
L 0.86118996 -1.86931004 1.03373996 -1.86931004 0 P 0 ;0
L 0.8603 -1.86831004 1.0304 -1.86831004 0 P 0 ;0
L 0.85941004 -1.86731004 1.02656998 -1.86731004 0 P 0 ;0
L 0.8585 -1.86631004 1.02231998 -1.86631004 0 P 0 ;0
L 0.85756998 -1.86531004 1.01806998 -1.86531004 0 P 0 ;0
L 0.85663002 -1.86431004 1.01381998 -1.86431004 0 P 0 ;0
L 0.85568996 -1.86331004 1.00931998 -1.86331004 0 P 0 ;0
L 0.85481004 -1.86231004 1.00335 -1.86231004 0 P 0 ;0
L 0.85916998 -1.86131004 0.99738002 -1.86131004 0 P 0 ;0
L 0.86716998 -1.86031004 0.99141998 -1.86031004 0 P 0 ;0
L 0.87476998 -1.89731004 0.89943002 -1.89731004 0 P 0 ;0
L 0.87453996 -1.89631004 0.90426004 -1.89631004 0 P 0 ;0
L 0.87431004 -1.89531004 0.9097 -1.89531004 0 P 0 ;0
L 0.87406998 -1.89431004 0.91608002 -1.89431004 0 P 0 ;0
L 0.87383002 -1.89331004 0.92246004 -1.89331004 0 P 0 ;0
L 0.87355 -1.89231004 0.93086004 -1.89231004 0 P 0 ;0
L 0.87323002 -1.89131004 0.95553002 -1.89131004 0 P 0 ;0
L 0.87291004 -1.89031004 1.08728996 -1.89031004 0 P 0 ;0
L 0.87258996 -1.88931004 1.08543002 -1.88931004 0 P 0 ;0
L 0.87223002 -1.88831004 1.08356998 -1.88831004 0 P 0 ;0
L 0.87183002 -1.88731004 1.0817 -1.88731004 0 P 0 ;0
L 0.87143002 -1.88631004 1.07955 -1.88631004 0 P 0 ;0
L 0.87103002 -1.88531004 1.07728996 -1.88531004 0 P 0 ;0
L 0.8706 -1.88431004 1.07503996 -1.88431004 0 P 0 ;0
L 0.87525 -1.85931004 0.98545 -1.85931004 0 P 0 ;0
L 0.88421004 -1.85831004 0.97621004 -1.85831004 0 P 0 ;0
L 0.89393002 -1.85731004 0.96606998 -1.85731004 0 P 0 ;0
L 0.9106 -1.85631004 0.95203002 -1.85631004 0 P 0 ;0
L 1.08716004 -1.91231004 1.12151004 -1.91231004 0 P 0 ;0
L 1.08486004 -1.91131004 1.12018996 -1.91131004 0 P 0 ;0
L 1.08256004 -1.91031004 1.11886004 -1.91031004 0 P 0 ;0
L 1.08023002 -1.90931004 1.11753996 -1.90931004 0 P 0 ;0
L 1.07738002 -1.90831004 1.11621004 -1.90831004 0 P 0 ;0
L 1.07453002 -1.90731004 1.11488996 -1.90731004 0 P 0 ;0
L 1.07168996 -1.90631004 1.11356998 -1.90631004 0 P 0 ;0
L 1.06883996 -1.90531004 1.11223996 -1.90531004 0 P 0 ;0
L 1.066 -1.90431004 1.11076998 -1.90431004 0 P 0 ;0
L 1.06315 -1.90331004 1.1092 -1.90331004 0 P 0 ;0
L 1.0599 -1.90231004 1.10763002 -1.90231004 0 P 0 ;0
L 1.05611998 -1.90131004 1.10606004 -1.90131004 0 P 0 ;0
L 1.05235 -1.90031004 1.10448996 -1.90031004 0 P 0 ;0
L 1.04856998 -1.89931004 1.10291998 -1.89931004 0 P 0 ;0
L 1.04478996 -1.89831004 1.10135 -1.89831004 0 P 0 ;0
L 0.98815 -2.08316004 1.03726998 -2.08316004 0 P 0 ;0
L 0.98818002 -2.08216004 1.03731004 -2.08216004 0 P 0 ;0
L 0.98821998 -2.08116004 1.03735 -2.08116004 0 P 0 ;0
L 0.98825 -2.08016004 1.03738996 -2.08016004 0 P 0 ;0
L 0.98828002 -2.07916004 1.03743002 -2.07916004 0 P 0 ;0
L 0.98831998 -2.07816004 1.03746998 -2.07816004 0 P 0 ;0
L 0.98835 -2.07716004 1.03751004 -2.07716004 0 P 0 ;0
L 0.98838002 -2.07616004 1.03755 -2.07616004 0 P 0 ;0
L 0.98841998 -2.07516004 1.03758002 -2.07516004 0 P 0 ;0
L 0.98845 -2.07416004 1.03761004 -2.07416004 0 P 0 ;0
L 0.98848002 -2.07316004 1.03763996 -2.07316004 0 P 0 ;0
L 0.98851004 -2.07216004 1.03768002 -2.07216004 0 P 0 ;0
L 0.98855 -2.07116004 1.03771004 -2.07116004 0 P 0 ;0
L 0.98858002 -2.07016004 1.03773996 -2.07016004 0 P 0 ;0
L 0.98858996 -2.06916004 1.03776998 -2.06916004 0 P 0 ;0
L 0.98858996 -2.06816004 1.0378 -2.06816004 0 P 0 ;0
L 0.98858996 -2.06716004 1.03783002 -2.06716004 0 P 0 ;0
L 0.98858002 -2.06616004 1.03786004 -2.06616004 0 P 0 ;0
L 0.98856998 -2.06516004 1.0379 -2.06516004 0 P 0 ;0
L 0.98856998 -2.06416004 1.03793002 -2.06416004 0 P 0 ;0
L 0.98856998 -2.06316004 1.03796004 -2.06316004 0 P 0 ;0
L 0.98856004 -2.06216004 1.03798996 -2.06216004 0 P 0 ;0
L 0.98855 -2.06116004 1.03801998 -2.06116004 0 P 0 ;0
L 0.98855 -2.06016004 1.03805 -2.06016004 0 P 0 ;0
L 0.98853996 -2.05916004 1.03808002 -2.05916004 0 P 0 ;0
L 0.98853996 -2.05816004 1.0381 -2.05816004 0 P 0 ;0
L 0.98853002 -2.05716004 1.03811998 -2.05716004 0 P 0 ;0
L 0.98848002 -2.05616004 1.03815 -2.05616004 0 P 0 ;0
L 0.98841004 -2.05516004 1.03818002 -2.05516004 0 P 0 ;0
L 0.98835 -2.05416004 1.0382 -2.05416004 0 P 0 ;0
L 0.98828002 -2.05316004 1.03821998 -2.05316004 0 P 0 ;0
L 0.98821004 -2.05216004 1.03825 -2.05216004 0 P 0 ;0
L 0.98815 -2.05116004 1.03826998 -2.05116004 0 P 0 ;0
L 0.98808996 -2.05016004 1.03828996 -2.05016004 0 P 0 ;0
L 0.98801998 -2.04916004 1.03831998 -2.04916004 0 P 0 ;0
L 0.98796004 -2.04816004 1.03833996 -2.04816004 0 P 0 ;0
L 0.98788996 -2.04716004 1.03836004 -2.04716004 0 P 0 ;0
L 0.98783002 -2.04616004 1.03838996 -2.04616004 0 P 0 ;0
L 0.98768996 -2.04516004 1.0384 -2.04516004 0 P 0 ;0
L 0.98756004 -2.04416004 1.03841004 -2.04416004 0 P 0 ;0
L 0.98738002 -2.04316004 1.03841998 -2.04316004 0 P 0 ;0
L 0.98716004 -2.04216004 1.03843002 -2.04216004 0 P 0 ;0
L 0.98691998 -2.04116004 1.03843996 -2.04116004 0 P 0 ;0
L 0.98661998 -2.04016004 1.03845 -2.04016004 0 P 0 ;0
L 0.98631998 -2.03916004 1.03846004 -2.03916004 0 P 0 ;0
L 0.98593996 -2.03816004 1.03846998 -2.03816004 0 P 0 ;0
L 0.98546998 -2.03716004 1.03848002 -2.03716004 0 P 0 ;0
L 0.98491004 -2.03616004 1.03846998 -2.03616004 0 P 0 ;0
L 0.98425 -2.03516004 1.03846004 -2.03516004 0 P 0 ;0
L 0.98346004 -2.03416004 1.03846004 -2.03416004 0 P 0 ;0
L 0.98251998 -2.03316004 1.03843996 -2.03316004 0 P 0 ;0
L 0.98138002 -2.03216004 1.03843002 -2.03216004 0 P 0 ;0
L 0.97998996 -2.03116004 1.03841998 -2.03116004 0 P 0 ;0
L 0.97813996 -2.03016004 1.03841004 -2.03016004 0 P 0 ;0
L 0.97491004 -2.02916004 1.0384 -2.02916004 0 P 0 ;0
L 0.94763996 -2.00716004 1.03293996 -2.00716004 0 P 0 ;0
L 0.94978996 -2.00616004 1.03231998 -2.00616004 0 P 0 ;0
L 0.95081004 -2.00516004 1.0317 -2.00516004 0 P 0 ;0
L 0.95183002 -2.00416004 1.03098002 -2.00416004 0 P 0 ;0
L 0.95285 -2.00316004 1.03023002 -2.00316004 0 P 0 ;0
L 0.95388996 -2.00216004 1.02936004 -2.00216004 0 P 0 ;0
L 0.95498002 -2.00116004 1.02841998 -2.00116004 0 P 0 ;0
L 0.95621998 -2.00016004 1.02738996 -2.00016004 0 P 0 ;0
L 0.95761998 -1.99916004 1.0262 -1.99916004 0 P 0 ;0
L 0.9592 -1.99816004 1.02486004 -1.99816004 0 P 0 ;0
L 0.96083996 -1.99716004 1.02335 -1.99716004 0 P 0 ;0
L 0.9627 -1.99616004 1.02161004 -1.99616004 0 P 0 ;0
L 0.96468996 -1.99516004 1.01951998 -1.99516004 0 P 0 ;0
L 0.96685 -1.99416004 1.01683002 -1.99416004 0 P 0 ;0
L 0.96936998 -1.99316004 1.01378002 -1.99316004 0 P 0 ;0
L 0.97236998 -1.99216004 1.00981004 -1.99216004 0 P 0 ;0
L 0.97676004 -1.99116004 1.00456998 -1.99116004 0 P 0 ;0
L 1.06713996 -2.08283002 1.12288002 -2.08283002 0 P 0 ;0
L 1.06698996 -2.08183002 1.12193996 -2.08183002 0 P 0 ;0
L 1.06686004 -2.08083002 1.12108996 -2.08083002 0 P 0 ;0
L 1.06673996 -2.07983002 1.12036004 -2.07983002 0 P 0 ;0
L 1.06661998 -2.07883002 1.11971998 -2.07883002 0 P 0 ;0
L 1.06653002 -2.07783002 1.11916004 -2.07783002 0 P 0 ;0
L 1.06648002 -2.07683002 1.11866004 -2.07683002 0 P 0 ;0
L 1.06641998 -2.07583002 1.11826004 -2.07583002 0 P 0 ;0
L 1.06636998 -2.07483002 1.11791998 -2.07483002 0 P 0 ;0
L 1.06631998 -2.07383002 1.11761998 -2.07383002 0 P 0 ;0
L 1.06626004 -2.07283002 1.11741998 -2.07283002 0 P 0 ;0
L 1.06621004 -2.07183002 1.11723996 -2.07183002 0 P 0 ;0
L 1.06616004 -2.07083002 1.11711998 -2.07083002 0 P 0 ;0
L 1.06616004 -2.06983002 1.11701004 -2.06983002 0 P 0 ;0
L 1.06616004 -2.06883002 1.11688996 -2.06883002 0 P 0 ;0
L 1.06616998 -2.06783002 1.11676998 -2.06783002 0 P 0 ;0
L 1.06618002 -2.06683002 1.11666998 -2.06683002 0 P 0 ;0
L 1.06618996 -2.06583002 1.11663002 -2.06583002 0 P 0 ;0
L 1.0662 -2.06483002 1.11658996 -2.06483002 0 P 0 ;0
L 1.06621004 -2.06383002 1.11656004 -2.06383002 0 P 0 ;0
L 1.06623002 -2.06283002 1.11651998 -2.06283002 0 P 0 ;0
L 1.06631004 -2.06183002 1.11648996 -2.06183002 0 P 0 ;0
L 1.06638002 -2.06083002 1.11653002 -2.06083002 0 P 0 ;0
L 1.06645 -2.05983002 1.11656998 -2.05983002 0 P 0 ;0
L 1.06651998 -2.05883002 1.11661998 -2.05883002 0 P 0 ;0
L 1.06658996 -2.05783002 1.11666004 -2.05783002 0 P 0 ;0
L 1.06666998 -2.05683002 1.11671004 -2.05683002 0 P 0 ;0
L 1.06673996 -2.05583002 1.11681004 -2.05583002 0 P 0 ;0
L 1.06686004 -2.05483002 1.11693002 -2.05483002 0 P 0 ;0
L 1.067 -2.05383002 1.11705 -2.05383002 0 P 0 ;0
L 1.06713996 -2.05283002 1.11718002 -2.05283002 0 P 0 ;0
L 1.06728002 -2.05183002 1.11731004 -2.05183002 0 P 0 ;0
L 1.06741998 -2.05083002 1.11746004 -2.05083002 0 P 0 ;0
L 1.06756004 -2.04983002 1.11766004 -2.04983002 0 P 0 ;0
L 1.0677 -2.04883002 1.11786004 -2.04883002 0 P 0 ;0
L 1.06786004 -2.04783002 1.11813996 -2.04783002 0 P 0 ;0
L 1.06806998 -2.04683002 1.11841998 -2.04683002 0 P 0 ;0
L 1.06828002 -2.04583002 1.11876998 -2.04583002 0 P 0 ;0
L 1.06848996 -2.04483002 1.11913002 -2.04483002 0 P 0 ;0
L 1.06871004 -2.04383002 1.11955 -2.04383002 0 P 0 ;0
L 1.06898996 -2.04283002 1.11998996 -2.04283002 0 P 0 ;0
L 1.06928002 -2.04183002 1.12048002 -2.04183002 0 P 0 ;0
L 1.06956004 -2.04083002 1.12101004 -2.04083002 0 P 0 ;0
L 1.06985 -2.03983002 1.12161998 -2.03983002 0 P 0 ;0
L 1.07021004 -2.03883002 1.12225 -2.03883002 0 P 0 ;0
L 1.07056998 -2.03783002 1.12298002 -2.03783002 0 P 0 ;0
L 1.07093002 -2.03683002 1.12373996 -2.03683002 0 P 0 ;0
L 1.07128996 -2.03583002 1.12461998 -2.03583002 0 P 0 ;0
L 1.07173002 -2.03483002 1.12548996 -2.03483002 0 P 0 ;0
L 1.07216998 -2.03383002 1.12646004 -2.03383002 0 P 0 ;0
L 1.07261998 -2.03283002 1.12748996 -2.03283002 0 P 0 ;0
L 1.07308002 -2.03183002 1.12855 -2.03183002 0 P 0 ;0
L 1.07361998 -2.03083002 1.12978996 -2.03083002 0 P 0 ;0
L 1.09761004 -1.91731004 1.12756998 -1.91731004 0 P 0 ;0
L 1.09566004 -1.91631004 1.12645 -1.91631004 0 P 0 ;0
L 1.09371004 -1.91531004 1.12533002 -1.91531004 0 P 0 ;0
L 1.09176004 -1.91431004 1.12416004 -1.91431004 0 P 0 ;0
L 1.08946004 -1.91331004 1.12283996 -1.91331004 0 P 0 ;0
L 1.07415 -2.02983002 1.13101998 -2.02983002 0 P 0 ;0
L 1.07468996 -2.02883002 1.13248996 -2.02883002 0 P 0 ;0
L 1.07528996 -2.02783002 1.134 -2.02783002 0 P 0 ;0
L 1.07591998 -2.02683002 1.13586004 -2.02683002 0 P 0 ;0
L 1.07656004 -2.02583002 1.13828996 -2.02583002 0 P 0 ;0
L 1.07721004 -2.02483002 1.14243002 -2.02483002 0 P 0 ;0
L 1.07795 -2.02383002 1.21126998 -2.02383002 0 P 0 ;0
L 1.07868002 -2.02283002 1.21133002 -2.02283002 0 P 0 ;0
L 1.07941998 -2.02183002 1.2114 -2.02183002 0 P 0 ;0
L 1.08021004 -2.02083002 1.21146004 -2.02083002 0 P 0 ;0
L 1.08103996 -2.01983002 1.21153002 -2.01983002 0 P 0 ;0
L 1.08186998 -2.01883002 1.2116 -2.01883002 0 P 0 ;0
L 1.08273002 -2.01783002 1.21166004 -2.01783002 0 P 0 ;0
L 1.08366998 -2.01683002 1.21173002 -2.01683002 0 P 0 ;0
L 1.0846 -2.01583002 1.2118 -2.01583002 0 P 0 ;0
L 1.08555 -2.01483002 1.21186004 -2.01483002 0 P 0 ;0
L 1.08661004 -2.01383002 1.21193002 -2.01383002 0 P 0 ;0
L 1.08766998 -2.01283002 1.21198996 -2.01283002 0 P 0 ;0
L 1.08873002 -2.01183002 1.21205 -2.01183002 0 P 0 ;0
L 1.0898 -2.01083002 1.21211998 -2.01083002 0 P 0 ;0
L 1.09098996 -2.00983002 1.21218002 -2.00983002 0 P 0 ;0
L 1.09225 -2.00883002 1.21223996 -2.00883002 0 P 0 ;0
L 1.09358996 -2.00783002 1.2123 -2.00783002 0 P 0 ;0
L 1.09506998 -2.00683002 1.21236004 -2.00683002 0 P 0 ;0
L 1.09668996 -2.00583002 1.21241998 -2.00583002 0 P 0 ;0
L 0.98546998 -2.12516004 1.03548996 -2.12516004 0 P 0 ;0
L 0.98558996 -2.12416004 1.03553996 -2.12416004 0 P 0 ;0
L 0.9857 -2.12316004 1.03558002 -2.12316004 0 P 0 ;0
L 0.98581004 -2.12216004 1.03561998 -2.12216004 0 P 0 ;0
L 0.98591004 -2.12116004 1.03566998 -2.12116004 0 P 0 ;0
L 0.98598996 -2.12016004 1.03571004 -2.12016004 0 P 0 ;0
L 0.98608002 -2.11916004 1.03575 -2.11916004 0 P 0 ;0
L 0.98616998 -2.11816004 1.0358 -2.11816004 0 P 0 ;0
L 0.98625 -2.11716004 1.03583996 -2.11716004 0 P 0 ;0
L 0.98633996 -2.11616004 1.03588002 -2.11616004 0 P 0 ;0
L 0.98641998 -2.11516004 1.03593002 -2.11516004 0 P 0 ;0
L 0.98651004 -2.11416004 1.03596998 -2.11416004 0 P 0 ;0
L 0.9866 -2.11316004 1.03601004 -2.11316004 0 P 0 ;0
L 0.98668002 -2.11216004 1.03605 -2.11216004 0 P 0 ;0
L 0.98676998 -2.11116004 1.0361 -2.11116004 0 P 0 ;0
L 0.98685 -2.11016004 1.03613996 -2.11016004 0 P 0 ;0
L 0.98693996 -2.10916004 1.03618002 -2.10916004 0 P 0 ;0
L 0.987 -2.10816004 1.03623002 -2.10816004 0 P 0 ;0
L 0.98705 -2.10716004 1.03626998 -2.10716004 0 P 0 ;0
L 0.9871 -2.10616004 1.03631004 -2.10616004 0 P 0 ;0
L 0.98716004 -2.10516004 1.03636004 -2.10516004 0 P 0 ;0
L 0.9872 -2.10416004 1.0364 -2.10416004 0 P 0 ;0
L 0.98725 -2.10316004 1.03643996 -2.10316004 0 P 0 ;0
L 0.98731004 -2.10216004 1.03648002 -2.10216004 0 P 0 ;0
L 0.98735 -2.10116004 1.03653002 -2.10116004 0 P 0 ;0
L 0.9874 -2.10016004 1.03656998 -2.10016004 0 P 0 ;0
L 0.98746004 -2.09916004 1.03661004 -2.09916004 0 P 0 ;0
L 0.98751004 -2.09816004 1.03666004 -2.09816004 0 P 0 ;0
L 0.98755 -2.09716004 1.0367 -2.09716004 0 P 0 ;0
L 0.9876 -2.09616004 1.03673996 -2.09616004 0 P 0 ;0
L 0.98766004 -2.09516004 1.03678996 -2.09516004 0 P 0 ;0
L 0.9877 -2.09416004 1.03683002 -2.09416004 0 P 0 ;0
L 0.98775 -2.09316004 1.03686998 -2.09316004 0 P 0 ;0
L 0.98781004 -2.09216004 1.03691998 -2.09216004 0 P 0 ;0
L 0.98785 -2.09116004 1.03696004 -2.09116004 0 P 0 ;0
L 0.9879 -2.09016004 1.037 -2.09016004 0 P 0 ;0
L 0.98796004 -2.08916004 1.03703996 -2.08916004 0 P 0 ;0
L 0.98798996 -2.08816004 1.03706998 -2.08816004 0 P 0 ;0
L 0.98801998 -2.08716004 1.03711004 -2.08716004 0 P 0 ;0
L 0.98805 -2.08616004 1.03715 -2.08616004 0 P 0 ;0
L 0.98808996 -2.08516004 1.03718996 -2.08516004 0 P 0 ;0
L 0.98811998 -2.08416004 1.03723002 -2.08416004 0 P 0 ;0
L 1.08216998 -2.15683002 1.19803996 -2.15683002 0 P 0 ;0
L 1.0821 -2.15583002 1.19861004 -2.15583002 0 P 0 ;0
L 1.08201998 -2.15483002 1.19918002 -2.15483002 0 P 0 ;0
L 1.08195 -2.15383002 1.1997 -2.15383002 0 P 0 ;0
L 1.08188996 -2.15283002 1.20018002 -2.15283002 0 P 0 ;0
L 1.08183002 -2.15183002 1.20066004 -2.15183002 0 P 0 ;0
L 1.08176998 -2.15083002 1.20113996 -2.15083002 0 P 0 ;0
L 1.08171998 -2.14983002 1.20153996 -2.14983002 0 P 0 ;0
L 1.08166004 -2.14883002 1.20193002 -2.14883002 0 P 0 ;0
L 1.0816 -2.14783002 1.11538996 -2.14783002 0 P 0 ;0
L 1.08155 -2.14683002 1.10903002 -2.14683002 0 P 0 ;0
L 1.0815 -2.14583002 1.10415 -2.14583002 0 P 0 ;0
L 1.08146004 -2.14483002 1.09953002 -2.14483002 0 P 0 ;0
L 1.08141004 -2.14383002 1.09563996 -2.14383002 0 P 0 ;0
L 1.08136004 -2.14283002 1.09183996 -2.14283002 0 P 0 ;0
L 1.08131004 -2.14183002 1.08821004 -2.14183002 0 P 0 ;0
L 1.08133002 -2.14083002 1.08471998 -2.14083002 0 P 0 ;0
L 1.09586998 -2.11983002 1.14965 -2.11983002 0 P 0 ;0
L 1.09361998 -2.11883002 1.15221998 -2.11883002 0 P 0 ;0
L 1.09158996 -2.11783002 1.20595 -2.11783002 0 P 0 ;0
L 1.08988002 -2.11683002 1.20601004 -2.11683002 0 P 0 ;0
L 1.08823996 -2.11583002 1.20606998 -2.11583002 0 P 0 ;0
L 1.08678996 -2.11483002 1.20613002 -2.11483002 0 P 0 ;0
L 1.08541004 -2.11383002 1.20618996 -2.11383002 0 P 0 ;0
L 1.08416998 -2.11283002 1.20625 -2.11283002 0 P 0 ;0
L 1.08295 -2.11183002 1.20631004 -2.11183002 0 P 0 ;0
L 1.08188002 -2.11083002 1.20638002 -2.11083002 0 P 0 ;0
L 1.08081998 -2.10983002 1.20643996 -2.10983002 0 P 0 ;0
L 1.07986004 -2.10883002 1.2065 -2.10883002 0 P 0 ;0
L 1.07895 -2.10783002 1.20656004 -2.10783002 0 P 0 ;0
L 1.07803002 -2.10683002 1.20661998 -2.10683002 0 P 0 ;0
L 1.07723996 -2.10583002 1.20666998 -2.10583002 0 P 0 ;0
L 1.07646004 -2.10483002 1.20671998 -2.10483002 0 P 0 ;0
L 1.07568002 -2.10383002 1.20678002 -2.10383002 0 P 0 ;0
L 1.075 -2.10283002 1.20683002 -2.10283002 0 P 0 ;0
L 1.07433002 -2.10183002 1.20688002 -2.10183002 0 P 0 ;0
L 1.07366998 -2.10083002 1.20693996 -2.10083002 0 P 0 ;0
L 1.07308996 -2.09983002 1.20698996 -2.09983002 0 P 0 ;0
L 1.07253002 -2.09883002 1.20705 -2.09883002 0 P 0 ;0
L 1.07198002 -2.09783002 1.2071 -2.09783002 0 P 0 ;0
L 1.07146998 -2.09683002 1.20715 -2.09683002 0 P 0 ;0
L 1.07101998 -2.09583002 1.2072 -2.09583002 0 P 0 ;0
L 1.07056998 -2.09483002 1.20726004 -2.09483002 0 P 0 ;0
L 1.07013002 -2.09383002 1.20731004 -2.09383002 0 P 0 ;0
L 1.06976998 -2.09283002 1.20736004 -2.09283002 0 P 0 ;0
L 1.06941998 -2.09183002 1.20741998 -2.09183002 0 P 0 ;0
L 1.06906004 -2.09083002 1.20746998 -2.09083002 0 P 0 ;0
L 1.06876004 -2.08983002 1.20753002 -2.08983002 0 P 0 ;0
L 1.06848996 -2.08883002 1.13443002 -2.08883002 0 P 0 ;0
L 1.06821998 -2.08783002 1.13068002 -2.08783002 0 P 0 ;0
L 1.06795 -2.08683002 1.12836998 -2.08683002 0 P 0 ;0
L 1.06771998 -2.08583002 1.1266 -2.08583002 0 P 0 ;0
L 1.06753002 -2.08483002 1.12516004 -2.08483002 0 P 0 ;0
L 1.06733002 -2.08383002 1.12393996 -2.08383002 0 P 0 ;0
L 0.90273996 -1.85456998 0.89068996 -1.85558002 0 P 0 ;0
L 0.89068996 -1.85558002 0.87421004 -1.85741998 0 P 0 ;0
L 0.87421004 -1.85741998 0.85783002 -1.85946998 0 P 0 ;0
L 0.85783002 -1.85946998 0.85526998 -1.8599 0 P 0 ;0
L 0.85526998 -1.8599 0.85276004 -1.86055 0 P 0 ;0
L 0.85276004 -1.86055 0.85255 -1.86063996 0 P 0 ;0
L 0.85255 -1.86063996 0.85248996 -1.86068996 0 P 0 ;0
L 0.85248996 -1.86068996 0.85243002 -1.86073002 0 P 0 ;0
L 0.85243002 -1.86073002 0.85238002 -1.86078002 0 P 0 ;0
L 0.85238002 -1.86078002 0.85233002 -1.86083996 0 P 0 ;0
L 0.85233002 -1.86083996 0.85225 -1.86096004 0 P 0 ;0
L 0.85225 -1.86096004 0.85218002 -1.8611 0 P 0 ;0
L 0.85218002 -1.8611 0.85216004 -1.86116998 0 P 0 ;0
L 0.85216004 -1.86116998 0.85215 -1.86123996 0 P 0 ;0
L 0.85215 -1.86123996 0.85213996 -1.86136998 0 P 0 ;0
L 0.85213996 -1.86136998 0.85213002 -1.86148996 0 P 0 ;0
L 0.85213002 -1.86148996 0.85213996 -1.86161998 0 P 0 ;0
L 0.85213996 -1.86161998 0.85215 -1.86173996 0 P 0 ;0
L 0.85215 -1.86173996 0.85218002 -1.86186998 0 P 0 ;0
L 0.85218002 -1.86186998 0.85221004 -1.86198996 0 P 0 ;0
L 0.85221004 -1.86198996 0.85225 -1.8621 0 P 0 ;0
L 0.85225 -1.8621 0.85231004 -1.86221998 0 P 0 ;0
L 0.85231004 -1.86221998 0.85236998 -1.86233002 0 P 0 ;0
L 0.85236998 -1.86233002 0.85281998 -1.863 0 P 0 ;0
L 0.85281998 -1.863 0.8533 -1.86363996 0 P 0 ;0
L 0.8533 -1.86363996 0.85383002 -1.86425 0 P 0 ;0
L 0.85383002 -1.86425 0.85736004 -1.86801998 0 P 0 ;0
L 0.85736004 -1.86801998 0.86013002 -1.87113002 0 P 0 ;0
L 0.86013002 -1.87113002 0.86266004 -1.87443002 0 P 0 ;0
L 0.86266004 -1.87443002 0.86501004 -1.87798996 0 P 0 ;0
L 0.86501004 -1.87798996 0.86711998 -1.88171004 0 P 0 ;0
L 0.86711998 -1.88171004 0.86896998 -1.88553996 0 P 0 ;0
L 0.86896998 -1.88553996 0.87055 -1.8895 0 P 0 ;0
L 0.87055 -1.8895 0.8718 -1.89343002 0 P 0 ;0
L 0.8718 -1.89343002 0.87276004 -1.89745 0 P 0 ;0
L 0.87276004 -1.89745 0.87371004 -1.90195 0 P 0 ;0
L 0.87371004 -1.90195 0.87383002 -1.90236004 0 P 0 ;0
L 0.87383002 -1.90236004 0.87396998 -1.90276004 0 P 0 ;0
L 0.87396998 -1.90276004 0.87416004 -1.90313996 0 P 0 ;0
L 0.87416004 -1.90313996 0.87436998 -1.90351004 0 P 0 ;0
L 0.87436998 -1.90351004 0.87443002 -1.9036 0 P 0 ;0
L 0.87443002 -1.9036 0.87456998 -1.90376004 0 P 0 ;0
L 0.87456998 -1.90376004 0.87465 -1.90381998 0 P 0 ;0
L 0.87465 -1.90381998 0.87473002 -1.90388996 0 P 0 ;0
L 0.87473002 -1.90388996 0.87481998 -1.90393996 0 P 0 ;0
L 0.87481998 -1.90393996 0.87491998 -1.90398996 0 P 0 ;0
L 0.87491998 -1.90398996 0.87501004 -1.90403002 0 P 0 ;0
L 0.87501004 -1.90403002 0.87521004 -1.90408996 0 P 0 ;0
L 0.87521004 -1.90408996 0.87531998 -1.9041 0 P 0 ;0
L 0.87531998 -1.9041 0.87573002 -1.90413002 0 P 0 ;0
L 0.87573002 -1.90413002 0.87613996 -1.90411998 0 P 0 ;0
L 0.87613996 -1.90411998 0.87653996 -1.90408002 0 P 0 ;0
L 0.87653996 -1.90408002 0.87695 -1.90401004 0 P 0 ;0
L 0.87695 -1.90401004 0.90756004 -1.89766998 0 P 0 ;0
L 0.90756004 -1.89766998 0.92603996 -1.89478002 0 P 0 ;0
L 0.92603996 -1.89478002 0.93486004 -1.89393996 0 P 0 ;0
L 0.93486004 -1.89393996 0.94371004 -1.8935 0 P 0 ;0
L 0.94371004 -1.8935 0.97045 -1.89308002 0 P 0 ;0
L 0.97045 -1.89308002 0.99468996 -1.89328996 0 P 0 ;0
L 0.99468996 -1.89328996 1.01021004 -1.89413996 0 P 0 ;0
L 1.01021004 -1.89413996 1.0241 -1.89601998 0 P 0 ;0
L 1.0241 -1.89601998 1.04188002 -1.89961004 0 P 0 ;0
L 1.04188002 -1.89961004 1.06095 -1.90466004 0 P 0 ;0
L 1.06095 -1.90466004 1.07963996 -1.91123002 0 P 0 ;0
L 1.07963996 -1.91123002 1.09093996 -1.91613002 0 P 0 ;0
L 1.09093996 -1.91613002 1.10186998 -1.92175 0 P 0 ;0
L 1.10186998 -1.92175 1.11243996 -1.92806998 0 P 0 ;0
L 1.11243996 -1.92806998 1.12163002 -1.93446998 0 P 0 ;0
L 1.12163002 -1.93446998 1.13033002 -1.94148996 0 P 0 ;0
L 1.13033002 -1.94148996 1.1385 -1.94911004 0 P 0 ;0
L 1.1385 -1.94911004 1.14358996 -1.9546 0 P 0 ;0
L 1.14358996 -1.9546 1.14825 -1.96045 0 P 0 ;0
L 1.14825 -1.96045 1.15246998 -1.96663002 0 P 0 ;0
L 1.15246998 -1.96663002 1.15623002 -1.97316004 0 P 0 ;0
L 1.15623002 -1.97316004 1.15895 -1.97831004 0 P 0 ;0
L 1.15895 -1.97831004 1.17358996 -1.97831004 0 P 0 ;0
L 1.17358996 -1.97831004 1.17135 -1.9726 0 P 0 ;0
L 1.17135 -1.9726 1.16696004 -1.96266998 0 P 0 ;0
L 1.16696004 -1.96266998 1.16171998 -1.95313002 0 P 0 ;0
L 1.16171998 -1.95313002 1.1557 -1.94406998 0 P 0 ;0
L 1.1557 -1.94406998 1.14885 -1.93548002 0 P 0 ;0
L 1.14885 -1.93548002 1.13778996 -1.92378002 0 P 0 ;0
L 1.13778996 -1.92378002 1.12576998 -1.91301998 0 P 0 ;0
L 1.12576998 -1.91301998 1.11283996 -1.90326004 0 P 0 ;0
L 1.11283996 -1.90326004 1.09783002 -1.89368996 0 P 0 ;0
L 1.09783002 -1.89368996 1.08213002 -1.88526998 0 P 0 ;0
L 1.08213002 -1.88526998 1.06576998 -1.87801004 0 P 0 ;0
L 1.06576998 -1.87801004 1.04776004 -1.87141998 0 P 0 ;0
L 1.04776004 -1.87141998 1.02938002 -1.86591998 0 P 0 ;0
L 1.02938002 -1.86591998 1.01058002 -1.8615 0 P 0 ;0
L 1.01058002 -1.8615 0.98441998 -1.85711004 0 P 0 ;0
L 0.98441998 -1.85711004 0.95781004 -1.85448996 0 P 0 ;0
L 0.95781004 -1.85448996 0.93061004 -1.85366004 0 P 0 ;0
L 0.93061004 -1.85366004 0.90273996 -1.85456998 0 P 0 ;0
L 1.16015 -1.97631004 1.15798002 -1.97218996 0 P 0 ;0
L 1.15798002 -1.97218996 1.15796004 -1.97216004 0 P 0 ;0
L 1.15796004 -1.97216004 1.15416004 -1.96556998 0 P 0 ;0
L 1.15416004 -1.96556998 1.15411998 -1.96551004 0 P 0 ;0
L 1.15411998 -1.96551004 1.14986004 -1.95926004 0 P 0 ;0
L 1.14986004 -1.95926004 1.14981998 -1.95921004 0 P 0 ;0
L 1.14981998 -1.95921004 1.14511004 -1.9533 0 P 0 ;0
L 1.14511004 -1.9533 1.13991998 -1.9477 0 P 0 ;0
L 1.13991998 -1.9477 1.13986004 -1.94765 0 P 0 ;0
L 1.13986004 -1.94765 1.13163996 -1.93998002 0 P 0 ;0
L 1.13163996 -1.93998002 1.12283002 -1.93286004 0 P 0 ;0
L 1.12283002 -1.93286004 1.11351998 -1.92638996 0 P 0 ;0
L 1.11351998 -1.92638996 1.10283996 -1.92 0 P 0 ;0
L 1.10283996 -1.92 1.0918 -1.91433002 0 P 0 ;0
L 1.0918 -1.91433002 1.08036998 -1.90936004 0 P 0 ;0
L 1.08036998 -1.90936004 1.06153002 -1.90273996 0 P 0 ;0
L 1.06153002 -1.90273996 1.06146004 -1.90273002 0 P 0 ;0
L 1.06146004 -1.90273002 1.04233002 -1.89766004 0 P 0 ;0
L 1.04233002 -1.89766004 1.02443002 -1.89405 0 P 0 ;0
L 1.02443002 -1.89405 1.0104 -1.89213996 0 P 0 ;0
L 1.0104 -1.89213996 0.99475 -1.89128996 0 P 0 ;0
L 0.99475 -1.89128996 0.97045 -1.89108002 0 P 0 ;0
L 0.97045 -1.89108002 0.94365 -1.8915 0 P 0 ;0
L 0.94365 -1.8915 0.94361998 -1.8915 0 P 0 ;0
L 0.94361998 -1.8915 0.93471998 -1.89195 0 P 0 ;0
L 0.93471998 -1.89195 0.92578996 -1.89278996 0 P 0 ;0
L 0.92578996 -1.89278996 0.9072 -1.89571004 0 P 0 ;0
L 0.9072 -1.89571004 0.87656998 -1.90203996 0 P 0 ;0
L 0.87656998 -1.90203996 0.87626998 -1.9021 0 P 0 ;0
L 0.87626998 -1.9021 0.87601998 -1.90211998 0 P 0 ;0
L 0.87601998 -1.90211998 0.87588996 -1.90213002 0 P 0 ;0
L 0.87588996 -1.90213002 0.87583002 -1.90198996 0 P 0 ;0
L 0.87583002 -1.90198996 0.87573002 -1.90175 0 P 0 ;0
L 0.87573002 -1.90175 0.87566004 -1.90146998 0 P 0 ;0
L 0.87566004 -1.90146998 0.87471004 -1.89701004 0 P 0 ;0
L 0.87471004 -1.89701004 0.8747 -1.89698996 0 P 0 ;0
L 0.8747 -1.89698996 0.87373002 -1.89288996 0 P 0 ;0
L 0.87373002 -1.89288996 0.87243002 -1.88881998 0 P 0 ;0
L 0.87243002 -1.88881998 0.8724 -1.88876004 0 P 0 ;0
L 0.8724 -1.88876004 0.8708 -1.88473996 0 P 0 ;0
L 0.8708 -1.88473996 0.8689 -1.88078002 0 P 0 ;0
L 0.8689 -1.88078002 0.86671998 -1.87693996 0 P 0 ;0
L 0.86671998 -1.87693996 0.86428996 -1.87326004 0 P 0 ;0
L 0.86428996 -1.87326004 0.86166998 -1.86985 0 P 0 ;0
L 0.86166998 -1.86985 0.85883996 -1.86668002 0 P 0 ;0
L 0.85883996 -1.86668002 0.85883002 -1.86666004 0 P 0 ;0
L 0.85883002 -1.86666004 0.85531998 -1.86291004 0 P 0 ;0
L 0.85531998 -1.86291004 0.85486004 -1.86238002 0 P 0 ;0
L 0.85486004 -1.86238002 0.85466004 -1.86211998 0 P 0 ;0
L 0.85466004 -1.86211998 0.8557 -1.86186004 0 P 0 ;0
L 0.8557 -1.86186004 0.85811998 -1.86145 0 P 0 ;0
L 0.85811998 -1.86145 0.87443996 -1.85941004 0 P 0 ;0
L 0.87443996 -1.85941004 0.89088996 -1.85756998 0 P 0 ;0
L 0.89088996 -1.85756998 0.90286004 -1.85656998 0 P 0 ;0
L 0.90286004 -1.85656998 0.93061004 -1.85566004 0 P 0 ;0
L 0.93061004 -1.85566004 0.95768002 -1.85648996 0 P 0 ;0
L 0.95768002 -1.85648996 0.98416004 -1.8591 0 P 0 ;0
L 0.98416004 -1.8591 1.01018996 -1.86346004 0 P 0 ;0
L 1.01018996 -1.86346004 1.02886004 -1.86785 0 P 0 ;0
L 1.02886004 -1.86785 1.04711998 -1.87331998 0 P 0 ;0
L 1.04711998 -1.87331998 1.06501004 -1.87986004 0 P 0 ;0
L 1.06501004 -1.87986004 1.08125 -1.88706998 0 P 0 ;0
L 1.08125 -1.88706998 1.09681004 -1.89541998 0 P 0 ;0
L 1.09681004 -1.89541998 1.1117 -1.9049 0 P 0 ;0
L 1.1117 -1.9049 1.1245 -1.91456998 0 P 0 ;0
L 1.1245 -1.91456998 1.13638996 -1.92521004 0 P 0 ;0
L 1.13638996 -1.92521004 1.14733996 -1.93678996 0 P 0 ;0
L 1.14733996 -1.93678996 1.15408002 -1.94525 0 P 0 ;0
L 1.15408002 -1.94525 1.16001004 -1.95416998 0 P 0 ;0
L 1.16001004 -1.95416998 1.16516004 -1.96355 0 P 0 ;0
L 1.16516004 -1.96355 1.1695 -1.97336998 0 P 0 ;0
L 1.1695 -1.97336998 1.17066004 -1.97631004 0 P 0 ;0
L 1.17066004 -1.97631004 1.16015 -1.97631004 0 P 0 ;0
L 0.87563002 -1.90131004 0.8801 -1.90131004 0 P 0 ;0
L 0.87541004 -1.90031004 0.88493996 -1.90031004 0 P 0 ;0
L 0.8752 -1.89931004 0.88976998 -1.89931004 0 P 0 ;0
L 0.87498996 -1.89831004 0.8946 -1.89831004 0 P 0 ;0
L 0.89423002 -2.08316004 0.94355 -2.08316004 0 P 0 ;0
L 0.89428996 -2.08216004 0.9436 -2.08216004 0 P 0 ;0
L 0.89435 -2.08116004 0.94365 -2.08116004 0 P 0 ;0
L 0.89441004 -2.08016004 0.9437 -2.08016004 0 P 0 ;0
L 0.89446004 -2.07916004 0.94375 -2.07916004 0 P 0 ;0
L 0.89451998 -2.07816004 0.94378996 -2.07816004 0 P 0 ;0
L 0.89458002 -2.07716004 0.94383996 -2.07716004 0 P 0 ;0
L 0.89463996 -2.07616004 0.94388996 -2.07616004 0 P 0 ;0
L 0.8947 -2.07516004 0.94393996 -2.07516004 0 P 0 ;0
L 0.89475 -2.07416004 0.94398002 -2.07416004 0 P 0 ;0
L 0.89481004 -2.07316004 0.94403002 -2.07316004 0 P 0 ;0
L 0.89486998 -2.07216004 0.94408002 -2.07216004 0 P 0 ;0
L 0.89493002 -2.07116004 0.94415 -2.07116004 0 P 0 ;0
L 0.89498996 -2.07016004 0.94426004 -2.07016004 0 P 0 ;0
L 0.89505 -2.06916004 0.94436998 -2.06916004 0 P 0 ;0
L 0.8951 -2.06816004 0.94448002 -2.06816004 0 P 0 ;0
L 0.89516004 -2.06716004 0.94458996 -2.06716004 0 P 0 ;0
L 0.89521998 -2.06616004 0.9447 -2.06616004 0 P 0 ;0
L 0.89526998 -2.06516004 0.94481004 -2.06516004 0 P 0 ;0
L 0.89531004 -2.06416004 0.94491998 -2.06416004 0 P 0 ;0
L 0.89535 -2.06316004 0.94503002 -2.06316004 0 P 0 ;0
L 0.8954 -2.06216004 0.94513996 -2.06216004 0 P 0 ;0
L 0.89543996 -2.06116004 0.94531998 -2.06116004 0 P 0 ;0
L 0.89548996 -2.06016004 0.94551004 -2.06016004 0 P 0 ;0
L 0.89553002 -2.05916004 0.9457 -2.05916004 0 P 0 ;0
L 0.89558002 -2.05816004 0.94588996 -2.05816004 0 P 0 ;0
L 0.89561998 -2.05716004 0.94608002 -2.05716004 0 P 0 ;0
L 0.89566998 -2.05616004 0.94626998 -2.05616004 0 P 0 ;0
L 0.89571004 -2.05516004 0.94646998 -2.05516004 0 P 0 ;0
L 0.89575 -2.05416004 0.94666004 -2.05416004 0 P 0 ;0
L 0.8958 -2.05316004 0.94685 -2.05316004 0 P 0 ;0
L 0.89583996 -2.05216004 0.94708002 -2.05216004 0 P 0 ;0
L 0.89588996 -2.05116004 0.94735 -2.05116004 0 P 0 ;0
L 0.89593996 -2.05016004 0.94761998 -2.05016004 0 P 0 ;0
L 0.89598002 -2.04916004 0.9479 -2.04916004 0 P 0 ;0
L 0.89601998 -2.04816004 0.94825 -2.04816004 0 P 0 ;0
L 0.89606998 -2.04716004 0.94858996 -2.04716004 0 P 0 ;0
L 0.89611004 -2.04616004 0.94893002 -2.04616004 0 P 0 ;0
L 0.89616004 -2.04516004 0.94935 -2.04516004 0 P 0 ;0
L 0.8962 -2.04416004 0.94976998 -2.04416004 0 P 0 ;0
L 0.89625 -2.04316004 0.9502 -2.04316004 0 P 0 ;0
L 0.89628002 -2.04216004 0.95068996 -2.04216004 0 P 0 ;0
L 0.89631004 -2.04116004 0.95118996 -2.04116004 0 P 0 ;0
L 0.89633996 -2.04016004 0.95168996 -2.04016004 0 P 0 ;0
L 0.89638002 -2.03916004 0.95228002 -2.03916004 0 P 0 ;0
L 0.89641004 -2.03816004 0.95291004 -2.03816004 0 P 0 ;0
L 0.89643996 -2.03716004 0.95363002 -2.03716004 0 P 0 ;0
L 0.89646998 -2.03616004 0.95445 -2.03616004 0 P 0 ;0
L 0.89651004 -2.03516004 0.95535 -2.03516004 0 P 0 ;0
L 0.89653996 -2.03416004 0.95636998 -2.03416004 0 P 0 ;0
L 0.89656998 -2.03316004 0.95756998 -2.03316004 0 P 0 ;0
L 0.8966 -2.03216004 0.95893996 -2.03216004 0 P 0 ;0
L 0.89663996 -2.03116004 0.96055 -2.03116004 0 P 0 ;0
L 0.89666998 -2.03016004 0.96278002 -2.03016004 0 P 0 ;0
L 0.8967 -2.02916004 0.96676004 -2.02916004 0 P 0 ;0
L 0.89673996 -2.02816004 1.03838996 -2.02816004 0 P 0 ;0
L 0.89676998 -2.02716004 1.03838002 -2.02716004 0 P 0 ;0
L 0.8968 -2.02616004 1.03833996 -2.02616004 0 P 0 ;0
L 0.89683996 -2.02516004 1.03828996 -2.02516004 0 P 0 ;0
L 0.89686998 -2.02416004 1.03823002 -2.02416004 0 P 0 ;0
L 0.8969 -2.02316004 1.03816004 -2.02316004 0 P 0 ;0
L 0.89693996 -2.02216004 1.0381 -2.02216004 0 P 0 ;0
L 0.89696998 -2.02116004 1.03803996 -2.02116004 0 P 0 ;0
L 0.897 -2.02016004 1.0379 -2.02016004 0 P 0 ;0
L 0.89703002 -2.01916004 1.03773996 -2.01916004 0 P 0 ;0
L 0.89706004 -2.01816004 1.03751998 -2.01816004 0 P 0 ;0
L 0.89708996 -2.01716004 1.03728002 -2.01716004 0 P 0 ;0
L 0.89711998 -2.01616004 1.03698996 -2.01616004 0 P 0 ;0
L 0.89713996 -2.01516004 1.03668002 -2.01516004 0 P 0 ;0
L 0.89716998 -2.01416004 1.03631004 -2.01416004 0 P 0 ;0
L 0.8972 -2.01316004 1.03591998 -2.01316004 0 P 0 ;0
L 0.89721998 -2.01216004 1.03548996 -2.01216004 0 P 0 ;0
L 0.89725 -2.01116004 1.03505 -2.01116004 0 P 0 ;0
L 0.89726998 -2.01016004 1.03458002 -2.01016004 0 P 0 ;0
L 0.8973 -2.00916004 1.03405 -2.00916004 0 P 0 ;0
L 0.89733002 -2.00816004 1.03351998 -2.00816004 0 P 0 ;0
L 0.89736004 -2.00716004 0.94676004 -2.00716004 0 P 0 ;0
L 0.89738002 -2.00616004 0.9461 -2.00616004 0 P 0 ;0
L 0.89741004 -2.00516004 0.94563996 -2.00516004 0 P 0 ;0
L 0.89743996 -2.00416004 0.94563996 -2.00416004 0 P 0 ;0
L 0.89746004 -2.00316004 0.94563996 -2.00316004 0 P 0 ;0
L 0.89748996 -2.00216004 0.94563996 -2.00216004 0 P 0 ;0
L 0.89751004 -2.00116004 0.94563996 -2.00116004 0 P 0 ;0
L 0.89753996 -2.00016004 0.94563996 -2.00016004 0 P 0 ;0
L 0.89756998 -1.99916004 0.94563996 -1.99916004 0 P 0 ;0
L 0.8976 -1.99816004 0.94563996 -1.99816004 0 P 0 ;0
L 0.89761998 -1.99716004 0.94563996 -1.99716004 0 P 0 ;0
L 0.89765 -1.99616004 0.94563996 -1.99616004 0 P 0 ;0
L 0.89768002 -1.99516004 0.94563996 -1.99516004 0 P 0 ;0
L 0.97546998 -1.98933996 0.97236998 -1.99006004 0 P 0 ;0
L 0.97236998 -1.99006004 0.96931998 -1.99103002 0 P 0 ;0
L 0.96931998 -1.99103002 0.96603002 -1.99233002 0 P 0 ;0
L 0.96603002 -1.99233002 0.96281004 -1.99383002 0 P 0 ;0
L 0.96281004 -1.99383002 0.95976004 -1.99546998 0 P 0 ;0
L 0.95976004 -1.99546998 0.95681004 -1.99728996 0 P 0 ;0
L 0.95681004 -1.99728996 0.95521004 -1.99841004 0 P 0 ;0
L 0.95521004 -1.99841004 0.95368996 -1.99963002 0 P 0 ;0
L 0.95368996 -1.99963002 0.95223996 -2.00095 0 P 0 ;0
L 0.95223996 -2.00095 0.94763996 -2.00546998 0 P 0 ;0
L 0.94763996 -2.00546998 0.94763996 -1.99243996 0 P 0 ;0
L 0.94763996 -1.99243996 0.89575 -1.99243996 0 P 0 ;0
L 0.89575 -1.99243996 0.89505 -2.01878002 0 P 0 ;0
L 0.89505 -2.01878002 0.89423996 -2.04316004 0 P 0 ;0
L 0.89423996 -2.04316004 0.89321998 -2.0661 0 P 0 ;0
L 0.89321998 -2.0661 0.89198996 -2.08728996 0 P 0 ;0
L 0.89198996 -2.08728996 0.89055 -2.1063 0 P 0 ;0
L 0.89055 -2.1063 0.88993996 -2.11358002 0 P 0 ;0
L 0.88993996 -2.11358002 0.88943002 -2.11988002 0 P 0 ;0
L 0.88943002 -2.11988002 0.88898996 -2.12533996 0 P 0 ;0
L 0.88898996 -2.12533996 0.88896004 -2.12613002 0 P 0 ;0
L 0.88896004 -2.12613002 0.88896998 -2.12621004 0 P 0 ;0
L 0.88896998 -2.12621004 0.88898002 -2.12625 0 P 0 ;0
L 0.88898002 -2.12625 0.88898996 -2.12628002 0 P 0 ;0
L 0.88898996 -2.12628002 0.88901998 -2.12636004 0 P 0 ;0
L 0.88901998 -2.12636004 0.88903996 -2.12638996 0 P 0 ;0
L 0.88903996 -2.12638996 0.88906998 -2.12641998 0 P 0 ;0
L 0.88906998 -2.12641998 0.88908996 -2.12645 0 P 0 ;0
L 0.88908996 -2.12645 0.88911998 -2.12646998 0 P 0 ;0
L 0.88911998 -2.12646998 0.88915 -2.1265 0 P 0 ;0
L 0.88915 -2.1265 0.88921004 -2.12653996 0 P 0 ;0
L 0.88921004 -2.12653996 0.88925 -2.12655 0 P 0 ;0
L 0.88925 -2.12655 0.88928002 -2.12656004 0 P 0 ;0
L 0.88928002 -2.12656004 0.88931998 -2.12658002 0 P 0 ;0
L 0.88931998 -2.12658002 0.8894 -2.12658002 0 P 0 ;0
L 0.8894 -2.12658002 0.89648002 -2.12686998 0 P 0 ;0
L 0.89648002 -2.12686998 0.90518996 -2.1271 0 P 0 ;0
L 0.90518996 -2.1271 0.9165 -2.12716004 0 P 0 ;0
L 0.9165 -2.12716004 0.94403996 -2.12716004 0 P 0 ;0
L 0.94403996 -2.12716004 0.94468996 -2.10135 0 P 0 ;0
L 0.94468996 -2.10135 0.9461 -2.07171998 0 P 0 ;0
L 0.9461 -2.07171998 0.94713002 -2.06233002 0 P 0 ;0
L 0.94713002 -2.06233002 0.9489 -2.05308002 0 P 0 ;0
L 0.9489 -2.05308002 0.94975 -2.04995 0 P 0 ;0
L 0.94975 -2.04995 0.9508 -2.04688996 0 P 0 ;0
L 0.9508 -2.04688996 0.95205 -2.0439 0 P 0 ;0
L 0.95205 -2.0439 0.95351004 -2.041 0 P 0 ;0
L 0.95351004 -2.041 0.9544 -2.03951004 0 P 0 ;0
L 0.9544 -2.03951004 0.95541998 -2.03811004 0 P 0 ;0
L 0.95541998 -2.03811004 0.95655 -2.03678996 0 P 0 ;0
L 0.95655 -2.03678996 0.95778996 -2.03556998 0 P 0 ;0
L 0.95778996 -2.03556998 0.95911998 -2.03446998 0 P 0 ;0
L 0.95911998 -2.03446998 0.96056998 -2.03346998 0 P 0 ;0
L 0.96056998 -2.03346998 0.96151004 -2.03291004 0 P 0 ;0
L 0.96151004 -2.03291004 0.96248996 -2.03243002 0 P 0 ;0
L 0.96248996 -2.03243002 0.96351004 -2.03201998 0 P 0 ;0
L 0.96351004 -2.03201998 0.96455 -2.03168996 0 P 0 ;0
L 0.96455 -2.03168996 0.96613002 -2.0313 0 P 0 ;0
L 0.96613002 -2.0313 0.96773002 -2.03101998 0 P 0 ;0
L 0.96773002 -2.03101998 0.96935 -2.03086004 0 P 0 ;0
L 0.96935 -2.03086004 0.97095 -2.03081004 0 P 0 ;0
L 0.97095 -2.03081004 0.97255 -2.03086998 0 P 0 ;0
L 0.97255 -2.03086998 0.97413002 -2.03105 0 P 0 ;0
L 0.97413002 -2.03105 0.97513002 -2.03123996 0 P 0 ;0
L 0.97513002 -2.03123996 0.9761 -2.03151004 0 P 0 ;0
L 0.9761 -2.03151004 0.97706004 -2.03186004 0 P 0 ;0
L 0.97706004 -2.03186004 0.97796998 -2.0323 0 P 0 ;0
L 0.97796998 -2.0323 0.97885 -2.0328 0 P 0 ;0
L 0.97885 -2.0328 0.97968002 -2.03336998 0 P 0 ;0
L 0.97968002 -2.03336998 0.98046998 -2.03398996 0 P 0 ;0
L 0.98046998 -2.03398996 0.98121998 -2.03468002 0 P 0 ;0
L 0.98121998 -2.03468002 0.98191004 -2.03541998 0 P 0 ;0
L 0.98191004 -2.03541998 0.98253996 -2.0362 0 P 0 ;0
L 0.98253996 -2.0362 0.9831 -2.03703002 0 P 0 ;0
L 0.9831 -2.03703002 0.9836 -2.03788996 0 P 0 ;0
L 0.9836 -2.03788996 0.98403996 -2.0388 0 P 0 ;0
L 0.98403996 -2.0388 0.9844 -2.03973996 0 P 0 ;0
L 0.9844 -2.03973996 0.98505 -2.04188996 0 P 0 ;0
L 0.98505 -2.04188996 0.98553002 -2.04408002 0 P 0 ;0
L 0.98553002 -2.04408002 0.98583002 -2.0463 0 P 0 ;0
L 0.98583002 -2.0463 0.98653002 -2.05705 0 P 0 ;0
L 0.98653002 -2.05705 0.9866 -2.06961004 0 P 0 ;0
L 0.9866 -2.06961004 0.98596004 -2.08908002 0 P 0 ;0
L 0.98596004 -2.08908002 0.98498002 -2.10858002 0 P 0 ;0
L 0.98498002 -2.10858002 0.98388002 -2.12146998 0 P 0 ;0
L 0.98388002 -2.12146998 0.98323002 -2.12716004 0 P 0 ;0
L 0.98323002 -2.12716004 1.03741004 -2.12716004 0 P 0 ;0
L 1.03741004 -2.12716004 1.03896004 -2.09103002 0 P 0 ;0
L 1.03896004 -2.09103002 1.03956004 -2.0759 0 P 0 ;0
L 1.03956004 -2.0759 1.04005 -2.06025 0 P 0 ;0
L 1.04005 -2.06025 1.04038996 -2.04626004 0 P 0 ;0
L 1.04038996 -2.04626004 1.04048002 -2.03698996 0 P 0 ;0
L 1.04048002 -2.03698996 1.04036998 -2.02651998 0 P 0 ;0
L 1.04036998 -2.02651998 1.04003996 -2.02096998 0 P 0 ;0
L 1.04003996 -2.02096998 1.03975 -2.01895 0 P 0 ;0
L 1.03975 -2.01895 1.0393 -2.01693996 0 P 0 ;0
L 1.0393 -2.01693996 1.03868996 -2.01483996 0 P 0 ;0
L 1.03868996 -2.01483996 1.03793996 -2.01278002 0 P 0 ;0
L 1.03793996 -2.01278002 1.03658996 -2.00968002 0 P 0 ;0
L 1.03658996 -2.00968002 1.03501004 -2.00668996 0 P 0 ;0
L 1.03501004 -2.00668996 1.0332 -2.0038 0 P 0 ;0
L 1.0332 -2.0038 1.03186998 -2.002 0 P 0 ;0
L 1.03186998 -2.002 1.0304 -2.0003 0 P 0 ;0
L 1.0304 -2.0003 1.0288 -1.99873002 0 P 0 ;0
L 1.0288 -1.99873002 1.02708002 -1.99728996 0 P 0 ;0
L 1.02708002 -1.99728996 1.02518002 -1.99593002 0 P 0 ;0
L 1.02518002 -1.99593002 1.02318002 -1.99471998 0 P 0 ;0
L 1.02318002 -1.99471998 1.0211 -1.99365 0 P 0 ;0
L 1.0211 -1.99365 1.01893002 -1.99273996 0 P 0 ;0
L 1.01893002 -1.99273996 1.01358996 -1.99098996 0 P 0 ;0
L 1.01358996 -1.99098996 1.0081 -1.98971004 0 P 0 ;0
L 1.0081 -1.98971004 1.00428996 -1.98908996 0 P 0 ;0
L 1.00428996 -1.98908996 1.00043996 -1.98868002 0 P 0 ;0
L 1.00043996 -1.98868002 0.99138002 -1.98826004 0 P 0 ;0
L 0.99138002 -1.98826004 0.98251998 -1.98846998 0 P 0 ;0
L 0.98251998 -1.98846998 0.97898996 -1.98878996 0 P 0 ;0
L 0.97898996 -1.98878996 0.97546998 -1.98933996 0 P 0 ;0
L 0.91651004 -2.12516004 0.94208996 -2.12516004 0 P 0 ;0
L 0.8911 -2.12416004 0.94211004 -2.12416004 0 P 0 ;0
L 0.89118002 -2.12316004 0.94213996 -2.12316004 0 P 0 ;0
L 0.89125 -2.12216004 0.94216004 -2.12216004 0 P 0 ;0
L 0.89133002 -2.12116004 0.94218996 -2.12116004 0 P 0 ;0
L 0.89141004 -2.12016004 0.94221004 -2.12016004 0 P 0 ;0
L 0.89148996 -2.11916004 0.94223996 -2.11916004 0 P 0 ;0
L 0.89156998 -2.11816004 0.94226998 -2.11816004 0 P 0 ;0
L 0.89166004 -2.11716004 0.94228996 -2.11716004 0 P 0 ;0
L 0.89173996 -2.11616004 0.94231004 -2.11616004 0 P 0 ;0
L 0.89181998 -2.11516004 0.94233996 -2.11516004 0 P 0 ;0
L 0.8919 -2.11416004 0.94236004 -2.11416004 0 P 0 ;0
L 0.89198002 -2.11316004 0.94238996 -2.11316004 0 P 0 ;0
L 0.89206998 -2.11216004 0.94241998 -2.11216004 0 P 0 ;0
L 0.89215 -2.11116004 0.94243996 -2.11116004 0 P 0 ;0
L 0.89223002 -2.11016004 0.94246998 -2.11016004 0 P 0 ;0
L 0.89231998 -2.10916004 0.94248996 -2.10916004 0 P 0 ;0
L 0.8924 -2.10816004 0.94251998 -2.10816004 0 P 0 ;0
L 0.89248002 -2.10716004 0.94255 -2.10716004 0 P 0 ;0
L 0.89256998 -2.10616004 0.94256998 -2.10616004 0 P 0 ;0
L 0.89263996 -2.10516004 0.94258996 -2.10516004 0 P 0 ;0
L 0.89271004 -2.10416004 0.94261998 -2.10416004 0 P 0 ;0
L 0.89278996 -2.10316004 0.94263996 -2.10316004 0 P 0 ;0
L 0.89286998 -2.10216004 0.94266998 -2.10216004 0 P 0 ;0
L 0.89293996 -2.10116004 0.9427 -2.10116004 0 P 0 ;0
L 0.89301998 -2.10016004 0.94275 -2.10016004 0 P 0 ;0
L 0.89308996 -2.09916004 0.94278996 -2.09916004 0 P 0 ;0
L 0.89316998 -2.09816004 0.94283996 -2.09816004 0 P 0 ;0
L 0.89325 -2.09716004 0.94288996 -2.09716004 0 P 0 ;0
L 0.89331998 -2.09616004 0.94293996 -2.09616004 0 P 0 ;0
L 0.8934 -2.09516004 0.94298002 -2.09516004 0 P 0 ;0
L 0.89346998 -2.09416004 0.94303002 -2.09416004 0 P 0 ;0
L 0.89355 -2.09316004 0.94308002 -2.09316004 0 P 0 ;0
L 0.89361998 -2.09216004 0.94313002 -2.09216004 0 P 0 ;0
L 0.8937 -2.09116004 0.94318002 -2.09116004 0 P 0 ;0
L 0.89378002 -2.09016004 0.94321998 -2.09016004 0 P 0 ;0
L 0.89385 -2.08916004 0.94326998 -2.08916004 0 P 0 ;0
L 0.89393002 -2.08816004 0.94331998 -2.08816004 0 P 0 ;0
L 0.894 -2.08716004 0.94336004 -2.08716004 0 P 0 ;0
L 0.89406004 -2.08616004 0.94341004 -2.08616004 0 P 0 ;0
L 0.89411998 -2.08516004 0.94346004 -2.08516004 0 P 0 ;0
L 0.89418002 -2.08416004 0.94351004 -2.08416004 0 P 0 ;0
L 0.91651004 -2.12516004 0.90521998 -2.1251 0 P 0 ;0
L 0.90521998 -2.1251 0.89655 -2.12486998 0 P 0 ;0
L 0.89655 -2.12486998 0.89106004 -2.12465 0 P 0 ;0
L 0.89106004 -2.12465 0.89141998 -2.12003996 0 P 0 ;0
L 0.89141998 -2.12003996 0.89193996 -2.11373996 0 P 0 ;0
L 0.89193996 -2.11373996 0.89253996 -2.10645 0 P 0 ;0
L 0.89253996 -2.10645 0.89398002 -2.08741998 0 P 0 ;0
L 0.89398002 -2.08741998 0.89521998 -2.06621998 0 P 0 ;0
L 0.89521998 -2.06621998 0.89521998 -2.06618996 0 P 0 ;0
L 0.89521998 -2.06618996 0.89623996 -2.04323002 0 P 0 ;0
L 0.89623996 -2.04323002 0.89703996 -2.01883002 0 P 0 ;0
L 0.89703996 -2.01883002 0.8977 -1.99443996 0 P 0 ;0
L 0.8977 -1.99443996 0.94563996 -1.99443996 0 P 0 ;0
L 0.94563996 -1.99443996 0.94563996 -2.00546998 0 P 0 ;0
L 0.94563996 -2.00546998 0.94686004 -2.00731004 0 P 0 ;0
L 0.94686004 -2.00731004 0.94903002 -2.00688996 0 P 0 ;0
L 0.94903002 -2.00688996 0.95361998 -2.00241004 0 P 0 ;0
L 0.95361998 -2.00241004 0.95498996 -2.00115 0 P 0 ;0
L 0.95498996 -2.00115 0.95641998 -2.00001004 0 P 0 ;0
L 0.95641998 -2.00001004 0.9579 -1.99896004 0 P 0 ;0
L 0.9579 -1.99896004 0.96076004 -1.9972 0 P 0 ;0
L 0.96076004 -1.9972 0.9637 -1.99561998 0 P 0 ;0
L 0.9637 -1.99561998 0.96683002 -1.99416998 0 P 0 ;0
L 0.96683002 -1.99416998 0.96998996 -1.99291998 0 P 0 ;0
L 0.96998996 -1.99291998 0.9729 -1.99198996 0 P 0 ;0
L 0.9729 -1.99198996 0.97586004 -1.9913 0 P 0 ;0
L 0.97586004 -1.9913 0.97923002 -1.99076998 0 P 0 ;0
L 0.97923002 -1.99076998 0.98263002 -1.99046998 0 P 0 ;0
L 0.98263002 -1.99046998 0.99136004 -1.99026004 0 P 0 ;0
L 0.99136004 -1.99026004 1.00028996 -1.99066998 0 P 0 ;0
L 1.00028996 -1.99066998 1.00403002 -1.99108002 0 P 0 ;0
L 1.00403002 -1.99108002 1.00771004 -1.99166998 0 P 0 ;0
L 1.00771004 -1.99166998 1.01305 -1.99291998 0 P 0 ;0
L 1.01305 -1.99291998 1.01823002 -1.99461998 0 P 0 ;0
L 1.01823002 -1.99461998 1.02026004 -1.99546998 0 P 0 ;0
L 1.02026004 -1.99546998 1.02221004 -1.99646998 0 P 0 ;0
L 1.02221004 -1.99646998 1.02408002 -1.9976 0 P 0 ;0
L 1.02408002 -1.9976 1.02585 -1.99886998 0 P 0 ;0
L 1.02585 -1.99886998 1.02746004 -2.00021004 0 P 0 ;0
L 1.02746004 -2.00021004 1.02893996 -2.00166998 0 P 0 ;0
L 1.02893996 -2.00166998 1.03031004 -2.00325 0 P 0 ;0
L 1.03031004 -2.00325 1.03155 -2.00493002 0 P 0 ;0
L 1.03155 -2.00493002 1.03326998 -2.00768002 0 P 0 ;0
L 1.03326998 -2.00768002 1.03478002 -2.01055 0 P 0 ;0
L 1.03478002 -2.01055 1.03608002 -2.01351998 0 P 0 ;0
L 1.03608002 -2.01351998 1.03678996 -2.01546998 0 P 0 ;0
L 1.03678996 -2.01546998 1.03736004 -2.01743002 0 P 0 ;0
L 1.03736004 -2.01743002 1.03778002 -2.0193 0 P 0 ;0
L 1.03778002 -2.0193 1.03805 -2.02116998 0 P 0 ;0
L 1.03805 -2.02116998 1.03836998 -2.02658996 0 P 0 ;0
L 1.03836998 -2.02658996 1.03848002 -2.03698996 0 P 0 ;0
L 1.03848002 -2.03698996 1.03838996 -2.04623002 0 P 0 ;0
L 1.03838996 -2.04623002 1.03805 -2.06018996 0 P 0 ;0
L 1.03805 -2.06018996 1.03756004 -2.07583002 0 P 0 ;0
L 1.03756004 -2.07583002 1.03696998 -2.09095 0 P 0 ;0
L 1.03696998 -2.09095 1.03548996 -2.12516004 0 P 0 ;0
L 1.03548996 -2.12516004 0.98546998 -2.12516004 0 P 0 ;0
L 0.98546998 -2.12516004 0.98586998 -2.12166004 0 P 0 ;0
L 0.98586998 -2.12166004 0.98696998 -2.10871998 0 P 0 ;0
L 0.98696998 -2.10871998 0.98796004 -2.08916004 0 P 0 ;0
L 0.98796004 -2.08916004 0.9886 -2.06963002 0 P 0 ;0
L 0.9886 -2.06963002 0.98853002 -2.05698002 0 P 0 ;0
L 0.98853002 -2.05698002 0.98781998 -2.0461 0 P 0 ;0
L 0.98781998 -2.0461 0.9875 -2.04373002 0 P 0 ;0
L 0.9875 -2.04373002 0.98748002 -2.04365 0 P 0 ;0
L 0.98748002 -2.04365 0.98698996 -2.04138996 0 P 0 ;0
L 0.98698996 -2.04138996 0.9863 -2.03908002 0 P 0 ;0
L 0.9863 -2.03908002 0.98588002 -2.038 0 P 0 ;0
L 0.98588002 -2.038 0.98538002 -2.03696004 0 P 0 ;0
L 0.98538002 -2.03696004 0.9848 -2.03596004 0 P 0 ;0
L 0.9848 -2.03596004 0.98413996 -2.03501004 0 P 0 ;0
L 0.98413996 -2.03501004 0.98341998 -2.03411004 0 P 0 ;0
L 0.98341998 -2.03411004 0.98336998 -2.03405 0 P 0 ;0
L 0.98336998 -2.03405 0.98263002 -2.03326004 0 P 0 ;0
L 0.98263002 -2.03326004 0.98176998 -2.03246998 0 P 0 ;0
L 0.98176998 -2.03246998 0.98086998 -2.03175 0 P 0 ;0
L 0.98086998 -2.03175 0.97991004 -2.0311 0 P 0 ;0
L 0.97991004 -2.0311 0.9789 -2.03051998 0 P 0 ;0
L 0.9789 -2.03051998 0.97783002 -2.03001998 0 P 0 ;0
L 0.97783002 -2.03001998 0.97673002 -2.02961004 0 P 0 ;0
L 0.97673002 -2.02961004 0.97663996 -2.02958002 0 P 0 ;0
L 0.97663996 -2.02958002 0.97558996 -2.02928996 0 P 0 ;0
L 0.97558996 -2.02928996 0.97443002 -2.02906998 0 P 0 ;0
L 0.97443002 -2.02906998 0.9727 -2.02888002 0 P 0 ;0
L 0.9727 -2.02888002 0.97261998 -2.02886998 0 P 0 ;0
L 0.97261998 -2.02886998 0.97096004 -2.02881004 0 P 0 ;0
L 0.97096004 -2.02881004 0.96921004 -2.02886004 0 P 0 ;0
L 0.96921004 -2.02886004 0.96745 -2.02903996 0 P 0 ;0
L 0.96745 -2.02903996 0.96571004 -2.02933996 0 P 0 ;0
L 0.96571004 -2.02933996 0.964 -2.02976004 0 P 0 ;0
L 0.964 -2.02976004 0.96283002 -2.03013996 0 P 0 ;0
L 0.96283002 -2.03013996 0.96168002 -2.0306 0 P 0 ;0
L 0.96168002 -2.0306 0.96056998 -2.03115 0 P 0 ;0
L 0.96056998 -2.03115 0.95948996 -2.03178002 0 P 0 ;0
L 0.95948996 -2.03178002 0.95791004 -2.03286998 0 P 0 ;0
L 0.95791004 -2.03286998 0.95645 -2.03408996 0 P 0 ;0
L 0.95645 -2.03408996 0.95508996 -2.03541998 0 P 0 ;0
L 0.95508996 -2.03541998 0.95383996 -2.03686998 0 P 0 ;0
L 0.95383996 -2.03686998 0.9538 -2.03693002 0 P 0 ;0
L 0.9538 -2.03693002 0.95273002 -2.03841004 0 P 0 ;0
L 0.95273002 -2.03841004 0.95175 -2.04003996 0 P 0 ;0
L 0.95175 -2.04003996 0.95023002 -2.04306004 0 P 0 ;0
L 0.95023002 -2.04306004 0.94896004 -2.04611004 0 P 0 ;0
L 0.94896004 -2.04611004 0.94893002 -2.04616998 0 P 0 ;0
L 0.94893002 -2.04616998 0.94783002 -2.04936004 0 P 0 ;0
L 0.94783002 -2.04936004 0.94695 -2.05263002 0 P 0 ;0
L 0.94695 -2.05263002 0.94515 -2.06203002 0 P 0 ;0
L 0.94515 -2.06203002 0.9441 -2.07156004 0 P 0 ;0
L 0.9441 -2.07156004 0.9427 -2.10128002 0 P 0 ;0
L 0.9427 -2.10128002 0.94208996 -2.12516004 0 P 0 ;0
L 0.94208996 -2.12516004 0.91651004 -2.12516004 0 P 0 ;0
L 0.93143002 -2.21261998 1.00578996 -2.21261998 0 P 0 ;0
L 0.94051004 -2.21161998 1.00803002 -2.21161998 0 P 0 ;0
L 0.94941998 -2.21061998 1.01026004 -2.21061998 0 P 0 ;0
L 0.9555 -2.20961998 1.0125 -2.20961998 0 P 0 ;0
L 0.96158002 -2.20861998 1.01473996 -2.20861998 0 P 0 ;0
L 0.96766004 -2.20761998 1.01696998 -2.20761998 0 P 0 ;0
L 0.97373002 -2.20661998 1.01921004 -2.20661998 0 P 0 ;0
L 0.97981004 -2.20561998 1.02145 -2.20561998 0 P 0 ;0
L 0.98498996 -2.20461998 1.02368996 -2.20461998 0 P 0 ;0
L 0.98973996 -2.20361998 1.02591998 -2.20361998 0 P 0 ;0
L 0.99448996 -2.20261998 1.02816004 -2.20261998 0 P 0 ;0
L 0.99923996 -2.20161998 1.0304 -2.20161998 0 P 0 ;0
L 1.00398996 -2.20061998 1.03243996 -2.20061998 0 P 0 ;0
L 1.00875 -2.19961998 1.0344 -2.19961998 0 P 0 ;0
L 1.01348996 -2.19861998 1.03636998 -2.19861998 0 P 0 ;0
L 1.0178 -2.19761998 1.03833996 -2.19761998 0 P 0 ;0
L 1.02168996 -2.19661998 1.04031004 -2.19661998 0 P 0 ;0
L 1.02558002 -2.19561998 1.04228002 -2.19561998 0 P 0 ;0
L 1.02946998 -2.19461998 1.04415 -2.19461998 0 P 0 ;0
L 1.03336004 -2.19361998 1.04596998 -2.19361998 0 P 0 ;0
L 1.03725 -2.19261998 1.04778996 -2.19261998 0 P 0 ;0
L 1.04113996 -2.19161998 1.0496 -2.19161998 0 P 0 ;0
L 1.14356998 -1.98926998 1.13261004 -1.99086004 0 P 0 ;0
L 1.13261004 -1.99086004 1.12165 -1.9934 0 P 0 ;0
L 1.12165 -1.9934 1.11125 -1.99673002 0 P 0 ;0
L 1.11125 -1.99673002 1.10658002 -1.99858996 0 P 0 ;0
L 1.10658002 -1.99858996 1.10198996 -2.00071004 0 P 0 ;0
L 1.10198996 -2.00071004 1.09653002 -2.00358996 0 P 0 ;0
L 1.09653002 -2.00358996 1.09436998 -2.00488996 0 P 0 ;0
L 1.09436998 -2.00488996 1.09226004 -2.00631004 0 P 0 ;0
L 1.09226004 -2.00631004 1.09028002 -2.00781004 0 P 0 ;0
L 1.09028002 -2.00781004 1.08836998 -2.00941998 0 P 0 ;0
L 1.08836998 -2.00941998 1.08405 -2.0135 0 P 0 ;0
L 1.08405 -2.0135 1.08096998 -2.01678996 0 P 0 ;0
L 1.08096998 -2.01678996 1.07808002 -2.02026998 0 P 0 ;0
L 1.07808002 -2.02026998 1.0754 -2.02393002 0 P 0 ;0
L 1.0754 -2.02393002 1.07313996 -2.02748002 0 P 0 ;0
L 1.07313996 -2.02748002 1.07116004 -2.03118996 0 P 0 ;0
L 1.07116004 -2.03118996 1.06943996 -2.03505 0 P 0 ;0
L 1.06943996 -2.03505 1.06795 -2.03918996 0 P 0 ;0
L 1.06795 -2.03918996 1.06673996 -2.04343996 0 P 0 ;0
L 1.06673996 -2.04343996 1.06583002 -2.04778002 0 P 0 ;0
L 1.06583002 -2.04778002 1.06476998 -2.05538996 0 P 0 ;0
L 1.06476998 -2.05538996 1.06421004 -2.06306004 0 P 0 ;0
L 1.06421004 -2.06306004 1.06415 -2.07076004 0 P 0 ;0
L 1.06415 -2.07076004 1.06456998 -2.0785 0 P 0 ;0
L 1.06456998 -2.0785 1.06508996 -2.08276004 0 P 0 ;0
L 1.06508996 -2.08276004 1.06591004 -2.08696004 0 P 0 ;0
L 1.06591004 -2.08696004 1.06703002 -2.09108002 0 P 0 ;0
L 1.06703002 -2.09108002 1.06833002 -2.09473002 0 P 0 ;0
L 1.06833002 -2.09473002 1.06991998 -2.09823996 0 P 0 ;0
L 1.06991998 -2.09823996 1.0718 -2.10161998 0 P 0 ;0
L 1.0718 -2.10161998 1.07398002 -2.10491998 0 P 0 ;0
L 1.07398002 -2.10491998 1.07641998 -2.10803002 0 P 0 ;0
L 1.07641998 -2.10803002 1.07908996 -2.11095 0 P 0 ;0
L 1.07908996 -2.11095 1.08175 -2.11345 0 P 0 ;0
L 1.08175 -2.11345 1.08458996 -2.11573996 0 P 0 ;0
L 1.08458996 -2.11573996 1.08758996 -2.1178 0 P 0 ;0
L 1.08758996 -2.1178 1.09073002 -2.11963996 0 P 0 ;0
L 1.09073002 -2.11963996 1.094 -2.12123996 0 P 0 ;0
L 1.094 -2.12123996 1.0986 -2.12306998 0 P 0 ;0
L 1.0986 -2.12306998 1.10331004 -2.12456004 0 P 0 ;0
L 1.10331004 -2.12456004 1.10811004 -2.12568996 0 P 0 ;0
L 1.10811004 -2.12568996 1.11298002 -2.12646998 0 P 0 ;0
L 1.11298002 -2.12646998 1.1182 -2.12693002 0 P 0 ;0
L 1.1182 -2.12693002 1.12343996 -2.12703002 0 P 0 ;0
L 1.12343996 -2.12703002 1.12866998 -2.12676004 0 P 0 ;0
L 1.12866998 -2.12676004 1.13388002 -2.12613002 0 P 0 ;0
L 1.13388002 -2.12613002 1.14086004 -2.12473996 0 P 0 ;0
L 1.14086004 -2.12473996 1.1477 -2.12273996 0 P 0 ;0
L 1.1477 -2.12273996 1.15433996 -2.12015 0 P 0 ;0
L 1.15433996 -2.12015 1.1545 -2.12008996 0 P 0 ;0
L 1.1545 -2.12008996 1.15466004 -2.12003996 0 P 0 ;0
L 1.15466004 -2.12003996 1.15483002 -2.12001004 0 P 0 ;0
L 1.15483002 -2.12001004 1.15498996 -2.11998996 0 P 0 ;0
L 1.15498996 -2.11998996 1.15533002 -2.11998996 0 P 0 ;0
L 1.15533002 -2.11998996 1.15538996 -2.12 0 P 0 ;0
L 1.15538996 -2.12 1.15545 -2.12001998 0 P 0 ;0
L 1.15545 -2.12001998 1.15551004 -2.12003002 0 P 0 ;0
L 1.15551004 -2.12003002 1.15556004 -2.12006004 0 P 0 ;0
L 1.15556004 -2.12006004 1.15561004 -2.12008002 0 P 0 ;0
L 1.15561004 -2.12008002 1.15566004 -2.12011004 0 P 0 ;0
L 1.15566004 -2.12011004 1.15571004 -2.12015 0 P 0 ;0
L 1.15571004 -2.12015 1.15575 -2.12018996 0 P 0 ;0
L 1.15575 -2.12018996 1.15578996 -2.12023996 0 P 0 ;0
L 1.15578996 -2.12023996 1.15583002 -2.12028002 0 P 0 ;0
L 1.15583002 -2.12028002 1.15586004 -2.12033996 0 P 0 ;0
L 1.15586004 -2.12033996 1.15588002 -2.12038996 0 P 0 ;0
L 1.15588002 -2.12038996 1.15591004 -2.12043996 0 P 0 ;0
L 1.15591004 -2.12043996 1.15601998 -2.12076004 0 P 0 ;0
L 1.15601998 -2.12076004 1.1561 -2.12108002 0 P 0 ;0
L 1.1561 -2.12108002 1.15616004 -2.12141998 0 P 0 ;0
L 1.15616004 -2.12141998 1.15618002 -2.12175 0 P 0 ;0
L 1.15618002 -2.12175 1.15623996 -2.12505 0 P 0 ;0
L 1.15623996 -2.12505 1.15616004 -2.12688002 0 P 0 ;0
L 1.15616004 -2.12688002 1.15593002 -2.12871004 0 P 0 ;0
L 1.15593002 -2.12871004 1.15553996 -2.13051998 0 P 0 ;0
L 1.15553996 -2.13051998 1.15516004 -2.1318 0 P 0 ;0
L 1.15516004 -2.1318 1.1547 -2.13305 0 P 0 ;0
L 1.1547 -2.13305 1.15415 -2.13426004 0 P 0 ;0
L 1.15415 -2.13426004 1.15351004 -2.13545 0 P 0 ;0
L 1.15351004 -2.13545 1.15278996 -2.1366 0 P 0 ;0
L 1.15278996 -2.1366 1.15198002 -2.13768996 0 P 0 ;0
L 1.15198002 -2.13768996 1.15111004 -2.13873002 0 P 0 ;0
L 1.15111004 -2.13873002 1.15016004 -2.13971004 0 P 0 ;0
L 1.15016004 -2.13971004 1.14876004 -2.14096004 0 P 0 ;0
L 1.14876004 -2.14096004 1.14726004 -2.1421 0 P 0 ;0
L 1.14726004 -2.1421 1.14566998 -2.14311004 0 P 0 ;0
L 1.14566998 -2.14311004 1.144 -2.144 0 P 0 ;0
L 1.144 -2.144 1.14226004 -2.14476004 0 P 0 ;0
L 1.14226004 -2.14476004 1.14046004 -2.14536998 0 P 0 ;0
L 1.14046004 -2.14536998 1.13863002 -2.14583002 0 P 0 ;0
L 1.13863002 -2.14583002 1.13676004 -2.14613996 0 P 0 ;0
L 1.13676004 -2.14613996 1.13041998 -2.14663996 0 P 0 ;0
L 1.13041998 -2.14663996 1.12403996 -2.1466 0 P 0 ;0
L 1.12403996 -2.1466 1.11621998 -2.14593996 0 P 0 ;0
L 1.11621998 -2.14593996 1.10843996 -2.14471004 0 P 0 ;0
L 1.10843996 -2.14471004 1.09946998 -2.14276998 0 P 0 ;0
L 1.09946998 -2.14276998 1.0905 -2.14041004 0 P 0 ;0
L 1.0905 -2.14041004 1.07963996 -2.13728996 0 P 0 ;0
L 1.07963996 -2.13728996 1.07936004 -2.1401 0 P 0 ;0
L 1.07936004 -2.1401 1.07931004 -2.14103996 0 P 0 ;0
L 1.07931004 -2.14103996 1.07931998 -2.14198002 0 P 0 ;0
L 1.07931998 -2.14198002 1.07956998 -2.14735 0 P 0 ;0
L 1.07956998 -2.14735 1.07993996 -2.15375 0 P 0 ;0
L 1.07993996 -2.15375 1.08045 -2.16081998 0 P 0 ;0
L 1.08045 -2.16081998 1.08181004 -2.17873002 0 P 0 ;0
L 1.08181004 -2.17873002 1.08996004 -2.18061004 0 P 0 ;0
L 1.08996004 -2.18061004 1.09951004 -2.18246004 0 P 0 ;0
L 1.09951004 -2.18246004 1.11243996 -2.18416998 0 P 0 ;0
L 1.11243996 -2.18416998 1.1254 -2.18543002 0 P 0 ;0
L 1.1254 -2.18543002 1.13508002 -2.18583002 0 P 0 ;0
L 1.13508002 -2.18583002 1.14765 -2.18528996 0 P 0 ;0
L 1.14765 -2.18528996 1.15368002 -2.18461004 0 P 0 ;0
L 1.15368002 -2.18461004 1.15971004 -2.18363996 0 P 0 ;0
L 1.15971004 -2.18363996 1.16521004 -2.18248002 0 P 0 ;0
L 1.16521004 -2.18248002 1.17063996 -2.18103002 0 P 0 ;0
L 1.17063996 -2.18103002 1.17528996 -2.17946998 0 P 0 ;0
L 1.17528996 -2.17946998 1.17978002 -2.17753996 0 P 0 ;0
L 1.17978002 -2.17753996 1.18216998 -2.1763 0 P 0 ;0
L 1.18216998 -2.1763 1.18446004 -2.17488996 0 P 0 ;0
L 1.18446004 -2.17488996 1.18663996 -2.17331004 0 P 0 ;0
L 1.18663996 -2.17331004 1.18871004 -2.17156004 0 P 0 ;0
L 1.18871004 -2.17156004 1.19161004 -2.16871998 0 P 0 ;0
L 1.19161004 -2.16871998 1.19431004 -2.16568996 0 P 0 ;0
L 1.19431004 -2.16568996 1.19678996 -2.16246998 0 P 0 ;0
L 1.19678996 -2.16246998 1.19908996 -2.15901998 0 P 0 ;0
L 1.19908996 -2.15901998 1.20113996 -2.15543996 0 P 0 ;0
L 1.20113996 -2.15543996 1.20295 -2.15171004 0 P 0 ;0
L 1.20295 -2.15171004 1.20435 -2.14815 0 P 0 ;0
L 1.20435 -2.14815 1.20543996 -2.14448996 0 P 0 ;0
L 1.20543996 -2.14448996 1.20621004 -2.14073996 0 P 0 ;0
L 1.20621004 -2.14073996 1.20651998 -2.13855 0 P 0 ;0
L 1.20651998 -2.13855 1.20671998 -2.13633996 0 P 0 ;0
L 1.20671998 -2.13633996 1.20761998 -2.12321004 0 P 0 ;0
L 1.20761998 -2.12321004 1.20858002 -2.10753996 0 P 0 ;0
L 1.20858002 -2.10753996 1.20951004 -2.09021998 0 P 0 ;0
L 1.20951004 -2.09021998 1.21048002 -2.07166004 0 P 0 ;0
L 1.21048002 -2.07166004 1.21156004 -2.05228002 0 P 0 ;0
L 1.21156004 -2.05228002 1.21258002 -2.03478996 0 P 0 ;0
L 1.21258002 -2.03478996 1.21333002 -2.02286004 0 P 0 ;0
L 1.21333002 -2.02286004 1.21393996 -2.01373996 0 P 0 ;0
L 1.21393996 -2.01373996 1.21443996 -2.00568996 0 P 0 ;0
L 1.21443996 -2.00568996 1.21485 -1.99883996 0 P 0 ;0
L 1.21485 -1.99883996 1.2149 -1.99721004 0 P 0 ;0
L 1.2149 -1.99721004 1.21488996 -1.99703996 0 P 0 ;0
L 1.21488996 -1.99703996 1.21486998 -1.99686004 0 P 0 ;0
L 1.21486998 -1.99686004 1.21483996 -1.99668996 0 P 0 ;0
L 1.21483996 -1.99668996 1.21478996 -1.99653002 0 P 0 ;0
L 1.21478996 -1.99653002 1.21473002 -1.99636998 0 P 0 ;0
L 1.21473002 -1.99636998 1.21466004 -1.99621004 0 P 0 ;0
L 1.21466004 -1.99621004 1.21458002 -1.99606004 0 P 0 ;0
L 1.21458002 -1.99606004 1.21448002 -1.99591004 0 P 0 ;0
L 1.21448002 -1.99591004 1.21433002 -1.99571998 0 P 0 ;0
L 1.21433002 -1.99571998 1.21416998 -1.99553996 0 P 0 ;0
L 1.21416998 -1.99553996 1.21398996 -1.99538002 0 P 0 ;0
L 1.21398996 -1.99538002 1.21378996 -1.99523996 0 P 0 ;0
L 1.21378996 -1.99523996 1.21358002 -1.99511004 0 P 0 ;0
L 1.21358002 -1.99511004 1.21336004 -1.995 0 P 0 ;0
L 1.21336004 -1.995 1.21261004 -1.99468996 0 P 0 ;0
L 1.21261004 -1.99468996 1.21183996 -1.99443996 0 P 0 ;0
L 1.21183996 -1.99443996 1.21105 -1.99423002 0 P 0 ;0
L 1.21105 -1.99423002 1.20593996 -1.99318002 0 P 0 ;0
L 1.20593996 -1.99318002 1.18996998 -1.99065 0 P 0 ;0
L 1.18996998 -1.99065 1.17318996 -1.98908002 0 P 0 ;0
L 1.17318996 -1.98908002 1.15718996 -1.98858002 0 P 0 ;0
L 1.15718996 -1.98858002 1.1504 -1.98876004 0 P 0 ;0
L 1.1504 -1.98876004 1.14356998 -1.98926998 0 P 0 ;0
L 1.04503996 -2.19061998 1.05141998 -2.19061998 0 P 0 ;0
L 1.04893002 -2.18961998 1.05323002 -2.18961998 0 P 0 ;0
L 1.05263002 -2.18861998 1.05503996 -2.18861998 0 P 0 ;0
L 1.05628996 -2.18761998 1.05676004 -2.18761998 0 P 0 ;0
L 1.09645 -2.17983002 1.16738002 -2.17983002 0 P 0 ;0
L 1.09126004 -2.17883002 1.17091004 -2.17883002 0 P 0 ;0
L 1.0868 -2.17783002 1.17386998 -2.17783002 0 P 0 ;0
L 1.08368002 -2.17683002 1.17636004 -2.17683002 0 P 0 ;0
L 1.0836 -2.17583002 1.1787 -2.17583002 0 P 0 ;0
L 1.08351998 -2.17483002 1.18066998 -2.17483002 0 P 0 ;0
L 1.08345 -2.17383002 1.18236998 -2.17383002 0 P 0 ;0
L 1.08336998 -2.17283002 1.1839 -2.17283002 0 P 0 ;0
L 1.08328996 -2.17183002 1.18526998 -2.17183002 0 P 0 ;0
L 1.08321998 -2.17083002 1.18646998 -2.17083002 0 P 0 ;0
L 1.08313996 -2.16983002 1.18761998 -2.16983002 0 P 0 ;0
L 1.08306998 -2.16883002 1.18863996 -2.16883002 0 P 0 ;0
L 1.08298996 -2.16783002 1.18966004 -2.16783002 0 P 0 ;0
L 1.08291998 -2.16683002 1.19061004 -2.16683002 0 P 0 ;0
L 1.08283996 -2.16583002 1.1915 -2.16583002 0 P 0 ;0
L 1.08276004 -2.16483002 1.19238996 -2.16483002 0 P 0 ;0
L 1.08268996 -2.16383002 1.19321004 -2.16383002 0 P 0 ;0
L 1.08261004 -2.16283002 1.19398002 -2.16283002 0 P 0 ;0
L 1.08253002 -2.16183002 1.19476004 -2.16183002 0 P 0 ;0
L 1.08246004 -2.16083002 1.19548002 -2.16083002 0 P 0 ;0
L 1.08238002 -2.15983002 1.19613996 -2.15983002 0 P 0 ;0
L 1.08231004 -2.15883002 1.19681004 -2.15883002 0 P 0 ;0
L 1.08223996 -2.15783002 1.19746004 -2.15783002 0 P 0 ;0
L 1.13506998 -2.18383002 1.12553002 -2.18343996 0 P 0 ;0
L 1.12553002 -2.18343996 1.11266004 -2.18218002 0 P 0 ;0
L 1.11266004 -2.18218002 1.09983002 -2.18048002 0 P 0 ;0
L 1.09983002 -2.18048002 1.09036998 -2.17866004 0 P 0 ;0
L 1.09036998 -2.17866004 1.0837 -2.17711004 0 P 0 ;0
L 1.0837 -2.17711004 1.08245 -2.16066998 0 P 0 ;0
L 1.08245 -2.16066998 1.08193996 -2.15361998 0 P 0 ;0
L 1.08193996 -2.15361998 1.08156998 -2.14726004 0 P 0 ;0
L 1.08156998 -2.14726004 1.08131998 -2.14191004 0 P 0 ;0
L 1.08131998 -2.14191004 1.08131004 -2.14108996 0 P 0 ;0
L 1.08131004 -2.14108996 1.08136004 -2.14026004 0 P 0 ;0
L 1.08136004 -2.14026004 1.0814 -2.13986998 0 P 0 ;0
L 1.0814 -2.13986998 1.08996004 -2.14233002 0 P 0 ;0
L 1.08996004 -2.14233002 1.08996998 -2.14233996 0 P 0 ;0
L 1.08996998 -2.14233996 1.08998996 -2.14233996 0 P 0 ;0
L 1.08998996 -2.14233996 1.099 -2.14471998 0 P 0 ;0
L 1.099 -2.14471998 1.10806998 -2.14668002 0 P 0 ;0
L 1.10806998 -2.14668002 1.11598002 -2.14791998 0 P 0 ;0
L 1.11598002 -2.14791998 1.12395 -2.1486 0 P 0 ;0
L 1.12395 -2.1486 1.13048996 -2.14863996 0 P 0 ;0
L 1.13048996 -2.14863996 1.137 -2.14811998 0 P 0 ;0
L 1.137 -2.14811998 1.13903002 -2.14778996 0 P 0 ;0
L 1.13903002 -2.14778996 1.14103002 -2.14728996 0 P 0 ;0
L 1.14103002 -2.14728996 1.14298002 -2.14661998 0 P 0 ;0
L 1.14298002 -2.14661998 1.14486998 -2.14581004 0 P 0 ;0
L 1.14486998 -2.14581004 1.14668002 -2.14483996 0 P 0 ;0
L 1.14668002 -2.14483996 1.1484 -2.14373996 0 P 0 ;0
L 1.1484 -2.14373996 1.15003002 -2.1425 0 P 0 ;0
L 1.15003002 -2.1425 1.15155 -2.14115 0 P 0 ;0
L 1.15155 -2.14115 1.1526 -2.14006998 0 P 0 ;0
L 1.1526 -2.14006998 1.15263996 -2.14001998 0 P 0 ;0
L 1.15263996 -2.14001998 1.15356004 -2.13893002 0 P 0 ;0
L 1.15356004 -2.13893002 1.15443996 -2.13771998 0 P 0 ;0
L 1.15443996 -2.13771998 1.15523002 -2.13646004 0 P 0 ;0
L 1.15523002 -2.13646004 1.15593996 -2.13515 0 P 0 ;0
L 1.15593996 -2.13515 1.15655 -2.13381004 0 P 0 ;0
L 1.15655 -2.13381004 1.15706004 -2.13243002 0 P 0 ;0
L 1.15706004 -2.13243002 1.15748002 -2.13101004 0 P 0 ;0
L 1.15748002 -2.13101004 1.1579 -2.12905 0 P 0 ;0
L 1.1579 -2.12905 1.15816004 -2.12706004 0 P 0 ;0
L 1.15816004 -2.12706004 1.15825 -2.12506998 0 P 0 ;0
L 1.15825 -2.12506998 1.15818002 -2.12165 0 P 0 ;0
L 1.15818002 -2.12165 1.15813996 -2.12118002 0 P 0 ;0
L 1.15813996 -2.12118002 1.15813002 -2.1211 0 P 0 ;0
L 1.15813002 -2.1211 1.15806004 -2.12068002 0 P 0 ;0
L 1.15806004 -2.12068002 1.15793996 -2.12018996 0 P 0 ;0
L 1.15793996 -2.12018996 1.15778002 -2.11973002 0 P 0 ;0
L 1.15778002 -2.11973002 1.1577 -2.11953002 0 P 0 ;0
L 1.1577 -2.11953002 1.15758996 -2.11933002 0 P 0 ;0
L 1.15758996 -2.11933002 1.15746998 -2.11913996 0 P 0 ;0
L 1.15746998 -2.11913996 1.15733002 -2.11895 0 P 0 ;0
L 1.15733002 -2.11895 1.15716998 -2.11878002 0 P 0 ;0
L 1.15716998 -2.11878002 1.157 -2.11863002 0 P 0 ;0
L 1.157 -2.11863002 1.15681998 -2.11848996 0 P 0 ;0
L 1.15681998 -2.11848996 1.15663002 -2.11836004 0 P 0 ;0
L 1.15663002 -2.11836004 1.15641998 -2.11825 0 P 0 ;0
L 1.15641998 -2.11825 1.15621004 -2.11816004 0 P 0 ;0
L 1.15621004 -2.11816004 1.15598996 -2.11808996 0 P 0 ;0
L 1.15598996 -2.11808996 1.15576998 -2.11803996 0 P 0 ;0
L 1.15576998 -2.11803996 1.15553002 -2.118 0 P 0 ;0
L 1.15553002 -2.118 1.15518002 -2.11798002 0 P 0 ;0
L 1.15518002 -2.11798002 1.15483996 -2.11798996 0 P 0 ;0
L 1.15483996 -2.11798996 1.15451004 -2.11803002 0 P 0 ;0
L 1.15451004 -2.11803002 1.15418002 -2.1181 0 P 0 ;0
L 1.15418002 -2.1181 1.15386004 -2.1182 0 P 0 ;0
L 1.15386004 -2.1182 1.15361004 -2.11828996 0 P 0 ;0
L 1.15361004 -2.11828996 1.14705 -2.12083996 0 P 0 ;0
L 1.14705 -2.12083996 1.14038996 -2.12278996 0 P 0 ;0
L 1.14038996 -2.12278996 1.13356004 -2.12416004 0 P 0 ;0
L 1.13356004 -2.12416004 1.1285 -2.12476998 0 P 0 ;0
L 1.1285 -2.12476998 1.12341004 -2.12501998 0 P 0 ;0
L 1.12341004 -2.12501998 1.11831004 -2.12493002 0 P 0 ;0
L 1.11831004 -2.12493002 1.11323002 -2.12448996 0 P 0 ;0
L 1.11323002 -2.12448996 1.10848996 -2.12373002 0 P 0 ;0
L 1.10848996 -2.12373002 1.10383996 -2.12263002 0 P 0 ;0
L 1.10383996 -2.12263002 1.09926998 -2.12118996 0 P 0 ;0
L 1.09926998 -2.12118996 1.09481004 -2.11941004 0 P 0 ;0
L 1.09481004 -2.11941004 1.09168002 -2.11788002 0 P 0 ;0
L 1.09168002 -2.11788002 1.08866004 -2.11611998 0 P 0 ;0
L 1.08866004 -2.11611998 1.08578002 -2.11413002 0 P 0 ;0
L 1.08578002 -2.11413002 1.08306998 -2.11193996 0 P 0 ;0
L 1.08306998 -2.11193996 1.08051998 -2.10955 0 P 0 ;0
L 1.08051998 -2.10955 1.07793996 -2.10673002 0 P 0 ;0
L 1.07793996 -2.10673002 1.07561004 -2.10373996 0 P 0 ;0
L 1.07561004 -2.10373996 1.07351004 -2.10058002 0 P 0 ;0
L 1.07351004 -2.10058002 1.07171004 -2.09733996 0 P 0 ;0
L 1.07171004 -2.09733996 1.07018002 -2.09396998 0 P 0 ;0
L 1.07018002 -2.09396998 1.06893996 -2.09048002 0 P 0 ;0
L 1.06893996 -2.09048002 1.06786004 -2.0865 0 P 0 ;0
L 1.06786004 -2.0865 1.06706004 -2.08243996 0 P 0 ;0
L 1.06706004 -2.08243996 1.06656004 -2.07833002 0 P 0 ;0
L 1.06656004 -2.07833002 1.06615 -2.07071004 0 P 0 ;0
L 1.06615 -2.07071004 1.06621004 -2.06313996 0 P 0 ;0
L 1.06621004 -2.06313996 1.06675 -2.0556 0 P 0 ;0
L 1.06675 -2.0556 1.0678 -2.04813002 0 P 0 ;0
L 1.0678 -2.04813002 1.06868996 -2.04391998 0 P 0 ;0
L 1.06868996 -2.04391998 1.06985 -2.03981004 0 P 0 ;0
L 1.06985 -2.03981004 1.0713 -2.03578996 0 P 0 ;0
L 1.0713 -2.03578996 1.07296004 -2.03206998 0 P 0 ;0
L 1.07296004 -2.03206998 1.07486998 -2.02848996 0 P 0 ;0
L 1.07486998 -2.02848996 1.07705 -2.02506004 0 P 0 ;0
L 1.07705 -2.02506004 1.07966004 -2.0215 0 P 0 ;0
L 1.07966004 -2.0215 1.08246998 -2.01811004 0 P 0 ;0
L 1.08246998 -2.01811004 1.08546998 -2.01491004 0 P 0 ;0
L 1.08546998 -2.01491004 1.0897 -2.01091004 0 P 0 ;0
L 1.0897 -2.01091004 1.09153002 -2.00936998 0 P 0 ;0
L 1.09153002 -2.00936998 1.09341998 -2.00793996 0 P 0 ;0
L 1.09341998 -2.00793996 1.09545 -2.00658002 0 P 0 ;0
L 1.09545 -2.00658002 1.09751004 -2.00533996 0 P 0 ;0
L 1.09751004 -2.00533996 1.10288002 -2.0025 0 P 0 ;0
L 1.10288002 -2.0025 1.10736998 -2.00043002 0 P 0 ;0
L 1.10736998 -2.00043002 1.11193002 -1.99861004 0 P 0 ;0
L 1.11193002 -1.99861004 1.12218002 -1.99533002 0 P 0 ;0
L 1.12218002 -1.99533002 1.13298002 -1.99281998 0 P 0 ;0
L 1.13298002 -1.99281998 1.14378996 -1.99126004 0 P 0 ;0
L 1.14378996 -1.99126004 1.1505 -1.99075 0 P 0 ;0
L 1.1505 -1.99075 1.15718002 -1.99058996 0 P 0 ;0
L 1.15718002 -1.99058996 1.17306998 -1.99108002 0 P 0 ;0
L 1.17306998 -1.99108002 1.18971998 -1.99263002 0 P 0 ;0
L 1.18971998 -1.99263002 1.20558002 -1.99515 0 P 0 ;0
L 1.20558002 -1.99515 1.21058996 -1.99618002 0 P 0 ;0
L 1.21058996 -1.99618002 1.21126998 -1.99636004 0 P 0 ;0
L 1.21126998 -1.99636004 1.21191998 -1.99656998 0 P 0 ;0
L 1.21191998 -1.99656998 1.21253002 -1.99681998 0 P 0 ;0
L 1.21253002 -1.99681998 1.21261004 -1.99686004 0 P 0 ;0
L 1.21261004 -1.99686004 1.21266004 -1.99688996 0 P 0 ;0
L 1.21266004 -1.99688996 1.21271998 -1.99693002 0 P 0 ;0
L 1.21271998 -1.99693002 1.21281998 -1.99703002 0 P 0 ;0
L 1.21281998 -1.99703002 1.21286004 -1.99708996 0 P 0 ;0
L 1.21286004 -1.99708996 1.21288002 -1.99711004 0 P 0 ;0
L 1.21288002 -1.99711004 1.21288002 -1.99711998 0 P 0 ;0
L 1.21288002 -1.99711998 1.21288996 -1.99715 0 P 0 ;0
L 1.21288996 -1.99715 1.2129 -1.99716998 0 P 0 ;0
L 1.2129 -1.99716998 1.2129 -1.99721998 0 P 0 ;0
L 1.2129 -1.99721998 1.21285 -1.99875 0 P 0 ;0
L 1.21285 -1.99875 1.21243996 -2.00556998 0 P 0 ;0
L 1.21243996 -2.00556998 1.21193996 -2.01361004 0 P 0 ;0
L 1.21193996 -2.01361004 1.21133996 -2.02273002 0 P 0 ;0
L 1.21133996 -2.02273002 1.21133996 -2.02273996 0 P 0 ;0
L 1.21133996 -2.02273996 1.21058996 -2.03468002 0 P 0 ;0
L 1.21058996 -2.03468002 1.20956004 -2.05216998 0 P 0 ;0
L 1.20956004 -2.05216998 1.20848996 -2.07156004 0 P 0 ;0
L 1.20848996 -2.07156004 1.20848996 -2.07156998 0 P 0 ;0
L 1.20848996 -2.07156998 1.20751004 -2.09011004 0 P 0 ;0
L 1.20751004 -2.09011004 1.20658996 -2.10743996 0 P 0 ;0
L 1.20658996 -2.10743996 1.20561998 -2.12308996 0 P 0 ;0
L 1.20561998 -2.12308996 1.20473002 -2.13618996 0 P 0 ;0
L 1.20473002 -2.13618996 1.20453002 -2.13831998 0 P 0 ;0
L 1.20453002 -2.13831998 1.20423996 -2.14041004 0 P 0 ;0
L 1.20423996 -2.14041004 1.2035 -2.144 0 P 0 ;0
L 1.2035 -2.144 1.20246004 -2.1475 0 P 0 ;0
L 1.20246004 -2.1475 1.20111998 -2.1509 0 P 0 ;0
L 1.20111998 -2.1509 1.19936998 -2.1545 0 P 0 ;0
L 1.19936998 -2.1545 1.19738002 -2.15796998 0 P 0 ;0
L 1.19738002 -2.15796998 1.19516004 -2.1613 0 P 0 ;0
L 1.19516004 -2.1613 1.19276998 -2.16441004 0 P 0 ;0
L 1.19276998 -2.16441004 1.19016004 -2.16733996 0 P 0 ;0
L 1.19016004 -2.16733996 1.18736004 -2.17008002 0 P 0 ;0
L 1.18736004 -2.17008002 1.1854 -2.17173996 0 P 0 ;0
L 1.1854 -2.17173996 1.18335 -2.17323002 0 P 0 ;0
L 1.18335 -2.17323002 1.18118002 -2.17456004 0 P 0 ;0
L 1.18118002 -2.17456004 1.17893002 -2.17573002 0 P 0 ;0
L 1.17893002 -2.17573002 1.17456998 -2.1776 0 P 0 ;0
L 1.17456998 -2.1776 1.17006998 -2.17911998 0 P 0 ;0
L 1.17006998 -2.17911998 1.16473996 -2.18053002 0 P 0 ;0
L 1.16473996 -2.18053002 1.15935 -2.18166998 0 P 0 ;0
L 1.15935 -2.18166998 1.15341998 -2.18263002 0 P 0 ;0
L 1.15341998 -2.18263002 1.1475 -2.18328996 0 P 0 ;0
L 1.1475 -2.18328996 1.13506998 -2.18383002 0 P 0 ;0
L 0.90491998 -2.21461998 1.00131004 -2.21461998 0 P 0 ;0
L 0.92235 -2.21361998 1.00355 -2.21361998 0 P 0 ;0
L 0.76925 -1.8965 0.85586998 -1.8965 0 P 0 ;0
L 0.76958996 -1.8955 0.85556004 -1.8955 0 P 0 ;0
L 0.76995 -1.8945 0.85521004 -1.8945 0 P 0 ;0
L 0.77031004 -1.8935 0.85486004 -1.8935 0 P 0 ;0
L 0.77071004 -1.8925 0.85443996 -1.8925 0 P 0 ;0
L 0.77115 -1.8915 0.85401004 -1.8915 0 P 0 ;0
L 0.7716 -1.8905 0.85355 -1.8905 0 P 0 ;0
L 0.77206004 -1.8895 0.85303002 -1.8895 0 P 0 ;0
L 0.7726 -1.8885 0.85251004 -1.8885 0 P 0 ;0
L 0.77313996 -1.8875 0.85198996 -1.8875 0 P 0 ;0
L 0.77368996 -1.8865 0.85138002 -1.8865 0 P 0 ;0
L 0.77433002 -1.8855 0.85073996 -1.8855 0 P 0 ;0
L 0.77496004 -1.8845 0.85011004 -1.8845 0 P 0 ;0
L 0.77561998 -1.8835 0.84943002 -1.8835 0 P 0 ;0
L 0.77636004 -1.8825 0.84866998 -1.8825 0 P 0 ;0
L 0.77711004 -1.8815 0.84791004 -1.8815 0 P 0 ;0
L 0.7779 -1.8805 0.84713002 -1.8805 0 P 0 ;0
L 0.77876998 -1.8795 0.84623002 -1.8795 0 P 0 ;0
L 0.77963996 -1.8785 0.84533002 -1.8785 0 P 0 ;0
L 0.7806 -1.8775 0.8444 -1.8775 0 P 0 ;0
L 0.78161004 -1.8765 0.84335 -1.8765 0 P 0 ;0
L 0.78265 -1.8755 0.84228996 -1.8755 0 P 0 ;0
L 0.78381998 -1.8745 0.84108996 -1.8745 0 P 0 ;0
L 0.78498996 -1.8735 0.83986998 -1.8735 0 P 0 ;0
L 0.78635 -1.8725 0.83848002 -1.8725 0 P 0 ;0
L 0.78773002 -1.8715 0.83706004 -1.8715 0 P 0 ;0
L 0.78933002 -1.8705 0.83541998 -1.8705 0 P 0 ;0
L 0.791 -1.8695 0.83366004 -1.8695 0 P 0 ;0
L 0.793 -1.8685 0.83171998 -1.8685 0 P 0 ;0
L 0.79525 -1.8675 0.82941998 -1.8675 0 P 0 ;0
L 0.79791998 -1.8665 0.82671004 -1.8665 0 P 0 ;0
L 0.80143996 -1.8655 0.82328996 -1.8655 0 P 0 ;0
L 0.80705 -1.8645 0.81776004 -1.8645 0 P 0 ;0
L 0.74543002 -1.89661998 0.75033002 -1.89661998 0 P 0 ;0
L 0.74751004 -1.89561998 0.75058996 -1.89561998 0 P 0 ;0
L 0.74958996 -1.89461998 0.75086004 -1.89461998 0 P 0 ;0
L 0.76733996 -1.9125 0.85751998 -1.9125 0 P 0 ;0
L 0.76728996 -1.9115 0.85756004 -1.9115 0 P 0 ;0
L 0.76723996 -1.9105 0.85758996 -1.9105 0 P 0 ;0
L 0.76721998 -1.9095 0.85763002 -1.9095 0 P 0 ;0
L 0.76725 -1.9085 0.85761004 -1.9085 0 P 0 ;0
L 0.76728002 -1.9075 0.85756998 -1.9075 0 P 0 ;0
L 0.76731004 -1.9065 0.85753002 -1.9065 0 P 0 ;0
L 0.76741998 -1.9055 0.85748996 -1.9055 0 P 0 ;0
L 0.76753996 -1.9045 0.85738002 -1.9045 0 P 0 ;0
L 0.76766004 -1.9035 0.85726004 -1.9035 0 P 0 ;0
L 0.76781998 -1.9025 0.85713996 -1.9025 0 P 0 ;0
L 0.76801998 -1.9015 0.85701004 -1.9015 0 P 0 ;0
L 0.76821004 -1.9005 0.85683002 -1.9005 0 P 0 ;0
L 0.76841998 -1.8995 0.85661998 -1.8995 0 P 0 ;0
L 0.7687 -1.8985 0.85641004 -1.8985 0 P 0 ;0
L 0.76896998 -1.8975 0.85613996 -1.8975 0 P 0 ;0
L 0.76751004 -2.08325 0.8416 -2.08325 0 P 0 ;0
L 0.76761998 -2.08225 0.84161998 -2.08225 0 P 0 ;0
L 0.76773996 -2.08125 0.84166998 -2.08125 0 P 0 ;0
L 0.76786004 -2.08025 0.84171998 -2.08025 0 P 0 ;0
L 0.76796998 -2.07925 0.84176998 -2.07925 0 P 0 ;0
L 0.76808002 -2.07825 0.84181004 -2.07825 0 P 0 ;0
L 0.76818002 -2.07725 0.84186004 -2.07725 0 P 0 ;0
L 0.76828996 -2.07625 0.8419 -2.07625 0 P 0 ;0
L 0.76838996 -2.07525 0.84195 -2.07525 0 P 0 ;0
L 0.76848996 -2.07425 0.842 -2.07425 0 P 0 ;0
L 0.7686 -2.07325 0.84205 -2.07325 0 P 0 ;0
L 0.7687 -2.07225 0.84208996 -2.07225 0 P 0 ;0
L 0.7688 -2.07125 0.84213996 -2.07125 0 P 0 ;0
L 0.7689 -2.07025 0.84218002 -2.07025 0 P 0 ;0
L 0.76901004 -2.06925 0.84223002 -2.06925 0 P 0 ;0
L 0.76911004 -2.06825 0.84228002 -2.06825 0 P 0 ;0
L 0.76921004 -2.06725 0.84233002 -2.06725 0 P 0 ;0
L 0.76931998 -2.06625 0.84236998 -2.06625 0 P 0 ;0
L 0.76941998 -2.06525 0.84241998 -2.06525 0 P 0 ;0
L 0.76948996 -2.06425 0.84246004 -2.06425 0 P 0 ;0
L 0.76956004 -2.06325 0.84251004 -2.06325 0 P 0 ;0
L 0.76963002 -2.06225 0.84256004 -2.06225 0 P 0 ;0
L 0.7697 -2.06125 0.8426 -2.06125 0 P 0 ;0
L 0.76976998 -2.06025 0.84265 -2.06025 0 P 0 ;0
L 0.76983996 -2.05925 0.8427 -2.05925 0 P 0 ;0
L 0.76991004 -2.05825 0.84273996 -2.05825 0 P 0 ;0
L 0.76996998 -2.05725 0.84278996 -2.05725 0 P 0 ;0
L 0.77001004 -2.05625 0.84283996 -2.05625 0 P 0 ;0
L 0.77003996 -2.05525 0.84288002 -2.05525 0 P 0 ;0
L 0.77008002 -2.05425 0.84295 -2.05425 0 P 0 ;0
L 0.77011998 -2.05325 0.84303996 -2.05325 0 P 0 ;0
L 0.77016004 -2.05225 0.84311998 -2.05225 0 P 0 ;0
L 0.77018996 -2.05125 0.84321004 -2.05125 0 P 0 ;0
L 0.77023002 -2.05025 0.8433 -2.05025 0 P 0 ;0
L 0.77026998 -2.04925 0.84338002 -2.04925 0 P 0 ;0
L 0.77031004 -2.04825 0.84346998 -2.04825 0 P 0 ;0
L 0.77033996 -2.04725 0.84356004 -2.04725 0 P 0 ;0
L 0.77038002 -2.04625 0.84363996 -2.04625 0 P 0 ;0
L 0.77041004 -2.04525 0.84373002 -2.04525 0 P 0 ;0
L 0.77043996 -2.04425 0.84381004 -2.04425 0 P 0 ;0
L 0.77046004 -2.04325 0.8439 -2.04325 0 P 0 ;0
L 0.77048002 -2.04225 0.84398996 -2.04225 0 P 0 ;0
L 0.77051004 -2.04125 0.84406998 -2.04125 0 P 0 ;0
L 0.77053002 -2.04025 0.84416004 -2.04025 0 P 0 ;0
L 0.77055 -2.03925 0.84425 -2.03925 0 P 0 ;0
L 0.77058002 -2.03825 0.84433002 -2.03825 0 P 0 ;0
L 0.7706 -2.03725 0.84441998 -2.03725 0 P 0 ;0
L 0.77061998 -2.03625 0.84451004 -2.03625 0 P 0 ;0
L 0.77065 -2.03525 0.84458996 -2.03525 0 P 0 ;0
L 0.77066998 -2.03425 0.84468002 -2.03425 0 P 0 ;0
L 0.7707 -2.03325 0.84476998 -2.03325 0 P 0 ;0
L 0.77071998 -2.03225 0.84485 -2.03225 0 P 0 ;0
L 0.77073002 -2.03125 0.84493996 -2.03125 0 P 0 ;0
L 0.77073996 -2.03025 0.84503002 -2.03025 0 P 0 ;0
L 0.79986004 -1.8638 0.79643996 -1.86486998 0 P 0 ;0
L 0.79643996 -1.86486998 0.79311998 -1.86621004 0 P 0 ;0
L 0.79311998 -1.86621004 0.78991004 -1.86781004 0 P 0 ;0
L 0.78991004 -1.86781004 0.78683996 -1.86966998 0 P 0 ;0
L 0.78683996 -1.86966998 0.78391998 -1.87178002 0 P 0 ;0
L 0.78391998 -1.87178002 0.78111998 -1.87416998 0 P 0 ;0
L 0.78111998 -1.87416998 0.7785 -1.87676004 0 P 0 ;0
L 0.7785 -1.87676004 0.77608002 -1.87953996 0 P 0 ;0
L 0.77608002 -1.87953996 0.77386998 -1.8825 0 P 0 ;0
L 0.77386998 -1.8825 0.77188002 -1.88561998 0 P 0 ;0
L 0.77188002 -1.88561998 0.77013996 -1.88886004 0 P 0 ;0
L 0.77013996 -1.88886004 0.76863996 -1.89221004 0 P 0 ;0
L 0.76863996 -1.89221004 0.7674 -1.89566998 0 P 0 ;0
L 0.7674 -1.89566998 0.76643002 -1.89921004 0 P 0 ;0
L 0.76643002 -1.89921004 0.76571004 -1.90283996 0 P 0 ;0
L 0.76571004 -1.90283996 0.76531004 -1.90636004 0 P 0 ;0
L 0.76531004 -1.90636004 0.7652 -1.90991004 0 P 0 ;0
L 0.7652 -1.90991004 0.76538996 -1.91345 0 P 0 ;0
L 0.76538996 -1.91345 0.76586998 -1.91696998 0 P 0 ;0
L 0.76586998 -1.91696998 0.76663996 -1.92046004 0 P 0 ;0
L 0.76663996 -1.92046004 0.76803002 -1.92493996 0 P 0 ;0
L 0.76803002 -1.92493996 0.76978002 -1.9293 0 P 0 ;0
L 0.76978002 -1.9293 0.77106998 -1.93193996 0 P 0 ;0
L 0.77106998 -1.93193996 0.77253002 -1.93448002 0 P 0 ;0
L 0.77253002 -1.93448002 0.77416004 -1.93693996 0 P 0 ;0
L 0.77416004 -1.93693996 0.77593002 -1.93923002 0 P 0 ;0
L 0.77593002 -1.93923002 0.77783996 -1.94141004 0 P 0 ;0
L 0.77783996 -1.94141004 0.77988996 -1.94345 0 P 0 ;0
L 0.77988996 -1.94345 0.78216004 -1.94545 0 P 0 ;0
L 0.78216004 -1.94545 0.78453996 -1.9473 0 P 0 ;0
L 0.78453996 -1.9473 0.78703002 -1.94901998 0 P 0 ;0
L 0.78703002 -1.94901998 0.79016998 -1.95088002 0 P 0 ;0
L 0.79016998 -1.95088002 0.79343996 -1.95248996 0 P 0 ;0
L 0.79343996 -1.95248996 0.79683002 -1.95383996 0 P 0 ;0
L 0.79683002 -1.95383996 0.80031998 -1.95491998 0 P 0 ;0
L 0.80031998 -1.95491998 0.80391004 -1.95573996 0 P 0 ;0
L 0.80391004 -1.95573996 0.80751998 -1.95626004 0 P 0 ;0
L 0.80751998 -1.95626004 0.81116004 -1.9565 0 P 0 ;0
L 0.81116004 -1.9565 0.81481004 -1.95646004 0 P 0 ;0
L 0.81481004 -1.95646004 0.81843996 -1.95613002 0 P 0 ;0
L 0.81843996 -1.95613002 0.82205 -1.95551004 0 P 0 ;0
L 0.82205 -1.95551004 0.82561998 -1.95461004 0 P 0 ;0
L 0.82561998 -1.95461004 0.82911004 -1.95345 0 P 0 ;0
L 0.82911004 -1.95345 0.83248996 -1.95201004 0 P 0 ;0
L 0.83248996 -1.95201004 0.83576004 -1.95031998 0 P 0 ;0
L 0.83576004 -1.95031998 0.83891998 -1.94836004 0 P 0 ;0
L 0.83891998 -1.94836004 0.84191998 -1.94616998 0 P 0 ;0
L 0.84191998 -1.94616998 0.84475 -1.94375 0 P 0 ;0
L 0.84475 -1.94375 0.84738996 -1.94113996 0 P 0 ;0
L 0.84738996 -1.94113996 0.84983002 -1.93833996 0 P 0 ;0
L 0.84983002 -1.93833996 0.85206998 -1.93533996 0 P 0 ;0
L 0.85206998 -1.93533996 0.8536 -1.93291998 0 P 0 ;0
L 0.8536 -1.93291998 0.85496004 -1.93041004 0 P 0 ;0
L 0.85496004 -1.93041004 0.85613996 -1.9278 0 P 0 ;0
L 0.85613996 -1.9278 0.85711998 -1.92511004 0 P 0 ;0
L 0.85711998 -1.92511004 0.85823002 -1.92123002 0 P 0 ;0
L 0.85823002 -1.92123002 0.85901998 -1.91726998 0 P 0 ;0
L 0.85901998 -1.91726998 0.85948996 -1.91323996 0 P 0 ;0
L 0.85948996 -1.91323996 0.85963996 -1.90918002 0 P 0 ;0
L 0.85963996 -1.90918002 0.85946998 -1.90513002 0 P 0 ;0
L 0.85946998 -1.90513002 0.85898002 -1.9011 0 P 0 ;0
L 0.85898002 -1.9011 0.85841998 -1.89826004 0 P 0 ;0
L 0.85841998 -1.89826004 0.85766004 -1.89546004 0 P 0 ;0
L 0.85766004 -1.89546004 0.85671004 -1.89273002 0 P 0 ;0
L 0.85671004 -1.89273002 0.85556998 -1.89006004 0 P 0 ;0
L 0.85556998 -1.89006004 0.85361998 -1.88631004 0 P 0 ;0
L 0.85361998 -1.88631004 0.85136004 -1.88273996 0 P 0 ;0
L 0.85136004 -1.88273996 0.84881004 -1.87938002 0 P 0 ;0
L 0.84881004 -1.87938002 0.84596998 -1.87623002 0 P 0 ;0
L 0.84596998 -1.87623002 0.84355 -1.87393996 0 P 0 ;0
L 0.84355 -1.87393996 0.84096998 -1.87181998 0 P 0 ;0
L 0.84096998 -1.87181998 0.83826004 -1.86988996 0 P 0 ;0
L 0.83826004 -1.86988996 0.83541004 -1.86815 0 P 0 ;0
L 0.83541004 -1.86815 0.83243996 -1.86661004 0 P 0 ;0
L 0.83243996 -1.86661004 0.82938996 -1.86531004 0 P 0 ;0
L 0.82938996 -1.86531004 0.82625 -1.86423002 0 P 0 ;0
L 0.82625 -1.86423002 0.82303996 -1.86336004 0 P 0 ;0
L 0.82303996 -1.86336004 0.81978002 -1.86273002 0 P 0 ;0
L 0.81978002 -1.86273002 0.81646998 -1.86233002 0 P 0 ;0
L 0.81646998 -1.86233002 0.81228996 -1.86215 0 P 0 ;0
L 0.81228996 -1.86215 0.80811004 -1.86233996 0 P 0 ;0
L 0.80811004 -1.86233996 0.80396004 -1.86288996 0 P 0 ;0
L 0.80396004 -1.86288996 0.79986004 -1.8638 0 P 0 ;0
L 0.80308996 -1.9535 0.82186004 -1.9535 0 P 0 ;0
L 0.79926004 -1.9525 0.82563996 -1.9525 0 P 0 ;0
L 0.79636004 -1.9515 0.82856998 -1.9515 0 P 0 ;0
L 0.79393002 -1.9505 0.83093996 -1.9505 0 P 0 ;0
L 0.7919 -1.9495 0.83298996 -1.9495 0 P 0 ;0
L 0.79008002 -1.9485 0.8349 -1.9485 0 P 0 ;0
L 0.78838996 -1.9475 0.83651004 -1.9475 0 P 0 ;0
L 0.7869 -1.9465 0.83806998 -1.9465 0 P 0 ;0
L 0.78548002 -1.9455 0.83943996 -1.9455 0 P 0 ;0
L 0.7842 -1.9445 0.84078996 -1.9445 0 P 0 ;0
L 0.78298002 -1.9435 0.84196998 -1.9435 0 P 0 ;0
L 0.78183996 -1.9425 0.84313996 -1.9425 0 P 0 ;0
L 0.78076998 -1.9415 0.84418996 -1.9415 0 P 0 ;0
L 0.77976004 -1.9405 0.8452 -1.9405 0 P 0 ;0
L 0.77883002 -1.9395 0.84616998 -1.9395 0 P 0 ;0
L 0.77793996 -1.9385 0.84703996 -1.9385 0 P 0 ;0
L 0.77711998 -1.9375 0.84791004 -1.9375 0 P 0 ;0
L 0.77635 -1.9365 0.84871004 -1.9365 0 P 0 ;0
L 0.77561004 -1.9355 0.84945 -1.9355 0 P 0 ;0
L 0.77493996 -1.9345 0.8502 -1.9345 0 P 0 ;0
L 0.77428002 -1.9335 0.85086998 -1.9335 0 P 0 ;0
L 0.7737 -1.9325 0.8515 -1.9325 0 P 0 ;0
L 0.77311998 -1.9315 0.8521 -1.9315 0 P 0 ;0
L 0.77258996 -1.9305 0.85263996 -1.9305 0 P 0 ;0
L 0.7721 -1.9295 0.85318002 -1.9295 0 P 0 ;0
L 0.77161004 -1.9285 0.85363002 -1.9285 0 P 0 ;0
L 0.77121004 -1.9275 0.85408002 -1.9275 0 P 0 ;0
L 0.77081004 -1.9265 0.85448002 -1.9265 0 P 0 ;0
L 0.77041004 -1.9255 0.85485 -1.9255 0 P 0 ;0
L 0.77001004 -1.9245 0.85521998 -1.9245 0 P 0 ;0
L 0.76968002 -1.9235 0.8555 -1.9235 0 P 0 ;0
L 0.76936998 -1.9225 0.85578996 -1.9225 0 P 0 ;0
L 0.76906004 -1.9215 0.85606998 -1.9215 0 P 0 ;0
L 0.76875 -1.9205 0.85633002 -1.9205 0 P 0 ;0
L 0.76848002 -1.9195 0.85653002 -1.9195 0 P 0 ;0
L 0.76826004 -1.9185 0.85673002 -1.9185 0 P 0 ;0
L 0.76803002 -1.9175 0.85693002 -1.9175 0 P 0 ;0
L 0.76783002 -1.9165 0.85708996 -1.9165 0 P 0 ;0
L 0.76768996 -1.9155 0.85721004 -1.9155 0 P 0 ;0
L 0.76755 -1.9145 0.85733002 -1.9145 0 P 0 ;0
L 0.76741998 -1.9135 0.85745 -1.9135 0 P 0 ;0
L 0.81121004 -1.9545 0.80773002 -1.95426998 0 P 0 ;0
L 0.80773002 -1.95426998 0.80426998 -1.95376998 0 P 0 ;0
L 0.80426998 -1.95376998 0.80083996 -1.95298996 0 P 0 ;0
L 0.80083996 -1.95298996 0.7975 -1.95195 0 P 0 ;0
L 0.7975 -1.95195 0.79426004 -1.95066004 0 P 0 ;0
L 0.79426004 -1.95066004 0.79111998 -1.94911998 0 P 0 ;0
L 0.79111998 -1.94911998 0.78811004 -1.94733002 0 P 0 ;0
L 0.78811004 -1.94733002 0.78573002 -1.94568996 0 P 0 ;0
L 0.78573002 -1.94568996 0.78343996 -1.9439 0 P 0 ;0
L 0.78343996 -1.9439 0.78126004 -1.94198996 0 P 0 ;0
L 0.78126004 -1.94198996 0.7793 -1.94003996 0 P 0 ;0
L 0.7793 -1.94003996 0.77746998 -1.93796004 0 P 0 ;0
L 0.77746998 -1.93796004 0.77578996 -1.93576998 0 P 0 ;0
L 0.77578996 -1.93576998 0.77423002 -1.93343002 0 P 0 ;0
L 0.77423002 -1.93343002 0.77283996 -1.931 0 P 0 ;0
L 0.77283996 -1.931 0.77161004 -1.92848996 0 P 0 ;0
L 0.77161004 -1.92848996 0.76991998 -1.92426998 0 P 0 ;0
L 0.76991998 -1.92426998 0.76858002 -1.91993996 0 P 0 ;0
L 0.76858002 -1.91993996 0.76783996 -1.91661998 0 P 0 ;0
L 0.76783996 -1.91661998 0.76738002 -1.91326998 0 P 0 ;0
L 0.76738002 -1.91326998 0.76721004 -1.90988996 0 P 0 ;0
L 0.76721004 -1.90988996 0.76731004 -1.90651004 0 P 0 ;0
L 0.76731004 -1.90651004 0.7677 -1.90315 0 P 0 ;0
L 0.7677 -1.90315 0.76838002 -1.89966998 0 P 0 ;0
L 0.76838002 -1.89966998 0.76931004 -1.89626998 0 P 0 ;0
L 0.76931004 -1.89626998 0.7705 -1.89296004 0 P 0 ;0
L 0.7705 -1.89296004 0.77193996 -1.88973996 0 P 0 ;0
L 0.77193996 -1.88973996 0.7736 -1.88663996 0 P 0 ;0
L 0.7736 -1.88663996 0.77551004 -1.88363996 0 P 0 ;0
L 0.77551004 -1.88363996 0.77763002 -1.8808 0 P 0 ;0
L 0.77763002 -1.8808 0.77996004 -1.87813002 0 P 0 ;0
L 0.77996004 -1.87813002 0.78246998 -1.87565 0 P 0 ;0
L 0.78246998 -1.87565 0.78516004 -1.87336004 0 P 0 ;0
L 0.78516004 -1.87336004 0.78795 -1.87133996 0 P 0 ;0
L 0.78795 -1.87133996 0.79088002 -1.86956004 0 P 0 ;0
L 0.79088002 -1.86956004 0.79393996 -1.86803002 0 P 0 ;0
L 0.79393996 -1.86803002 0.79711004 -1.86675 0 P 0 ;0
L 0.79711004 -1.86675 0.80038002 -1.86573002 0 P 0 ;0
L 0.80038002 -1.86573002 0.80431004 -1.86486004 0 P 0 ;0
L 0.80431004 -1.86486004 0.80828996 -1.86433996 0 P 0 ;0
L 0.80828996 -1.86433996 0.8123 -1.86416004 0 P 0 ;0
L 0.8123 -1.86416004 0.81631004 -1.86431998 0 P 0 ;0
L 0.81631004 -1.86431998 0.81946998 -1.86471004 0 P 0 ;0
L 0.81946998 -1.86471004 0.82258996 -1.86531004 0 P 0 ;0
L 0.82258996 -1.86531004 0.82566004 -1.86613996 0 P 0 ;0
L 0.82566004 -1.86613996 0.82866998 -1.86718002 0 P 0 ;0
L 0.82866998 -1.86718002 0.83158996 -1.86843002 0 P 0 ;0
L 0.83158996 -1.86843002 0.83443002 -1.86988996 0 P 0 ;0
L 0.83443002 -1.86988996 0.83716004 -1.87156004 0 P 0 ;0
L 0.83716004 -1.87156004 0.83976004 -1.87341004 0 P 0 ;0
L 0.83976004 -1.87341004 0.84223002 -1.87543996 0 P 0 ;0
L 0.84223002 -1.87543996 0.84453996 -1.87763002 0 P 0 ;0
L 0.84453996 -1.87763002 0.84726998 -1.88065 0 P 0 ;0
L 0.84726998 -1.88065 0.84971998 -1.88388002 0 P 0 ;0
L 0.84971998 -1.88388002 0.85188996 -1.88731004 0 P 0 ;0
L 0.85188996 -1.88731004 0.85376004 -1.89091004 0 P 0 ;0
L 0.85376004 -1.89091004 0.85483996 -1.89345 0 P 0 ;0
L 0.85483996 -1.89345 0.85575 -1.89605 0 P 0 ;0
L 0.85575 -1.89605 0.85646998 -1.89871004 0 P 0 ;0
L 0.85646998 -1.89871004 0.857 -1.90141004 0 P 0 ;0
L 0.857 -1.90141004 0.85748002 -1.9053 0 P 0 ;0
L 0.85748002 -1.9053 0.85763996 -1.90918996 0 P 0 ;0
L 0.85763996 -1.90918996 0.8575 -1.91308002 0 P 0 ;0
L 0.8575 -1.91308002 0.85703996 -1.91696004 0 P 0 ;0
L 0.85703996 -1.91696004 0.85628002 -1.92076004 0 P 0 ;0
L 0.85628002 -1.92076004 0.85521998 -1.92448996 0 P 0 ;0
L 0.85521998 -1.92448996 0.85428002 -1.92705 0 P 0 ;0
L 0.85428002 -1.92705 0.85316998 -1.92951998 0 P 0 ;0
L 0.85316998 -1.92951998 0.85188002 -1.93191004 0 P 0 ;0
L 0.85188002 -1.93191004 0.85041998 -1.9342 0 P 0 ;0
L 0.85041998 -1.9342 0.84826998 -1.93708002 0 P 0 ;0
L 0.84826998 -1.93708002 0.84593002 -1.93976998 0 P 0 ;0
L 0.84593002 -1.93976998 0.8434 -1.94228002 0 P 0 ;0
L 0.8434 -1.94228002 0.84068002 -1.9446 0 P 0 ;0
L 0.84068002 -1.9446 0.8378 -1.9467 0 P 0 ;0
L 0.8378 -1.9467 0.83476998 -1.94858002 0 P 0 ;0
L 0.83476998 -1.94858002 0.83163996 -1.9502 0 P 0 ;0
L 0.83163996 -1.9502 0.8284 -1.95158002 0 P 0 ;0
L 0.8284 -1.95158002 0.82506004 -1.95268996 0 P 0 ;0
L 0.82506004 -1.95268996 0.82163996 -1.95356004 0 P 0 ;0
L 0.82163996 -1.95356004 0.81818002 -1.95413996 0 P 0 ;0
L 0.81818002 -1.95413996 0.8147 -1.95446004 0 P 0 ;0
L 0.8147 -1.95446004 0.81121004 -1.9545 0 P 0 ;0
L 0.77075 -2.02925 0.84511004 -2.02925 0 P 0 ;0
L 0.77076004 -2.02825 0.8452 -2.02825 0 P 0 ;0
L 0.77076998 -2.02725 0.84528996 -2.02725 0 P 0 ;0
L 0.77078002 -2.02625 0.84536998 -2.02625 0 P 0 ;0
L 0.77078996 -2.02525 0.84548996 -2.02525 0 P 0 ;0
L 0.7708 -2.02425 0.84561998 -2.02425 0 P 0 ;0
L 0.77081004 -2.02325 0.84575 -2.02325 0 P 0 ;0
L 0.77081998 -2.02225 0.84588002 -2.02225 0 P 0 ;0
L 0.77083002 -2.02125 0.84601004 -2.02125 0 P 0 ;0
L 0.77083996 -2.02025 0.84613996 -2.02025 0 P 0 ;0
L 0.77085 -2.01925 0.84626004 -2.01925 0 P 0 ;0
L 0.77085 -2.01825 0.84638996 -2.01825 0 P 0 ;0
L 0.77085 -2.01725 0.84651998 -2.01725 0 P 0 ;0
L 0.77086004 -2.01625 0.84663996 -2.01625 0 P 0 ;0
L 0.77086004 -2.01525 0.84676998 -2.01525 0 P 0 ;0
L 0.77086004 -2.01425 0.8469 -2.01425 0 P 0 ;0
L 0.77086004 -2.01325 0.84703002 -2.01325 0 P 0 ;0
L 0.77086004 -2.01225 0.84716004 -2.01225 0 P 0 ;0
L 0.77086004 -2.01125 0.84728996 -2.01125 0 P 0 ;0
L 0.77086004 -2.01025 0.84741004 -2.01025 0 P 0 ;0
L 0.77086998 -2.00925 0.84753996 -2.00925 0 P 0 ;0
L 0.77086998 -2.00825 0.84766998 -2.00825 0 P 0 ;0
L 0.77086998 -2.00725 0.84778996 -2.00725 0 P 0 ;0
L 0.77086998 -2.00625 0.84791998 -2.00625 0 P 0 ;0
L 0.77086998 -2.00525 0.84805 -2.00525 0 P 0 ;0
L 0.77086998 -2.00425 0.84818002 -2.00425 0 P 0 ;0
L 0.77088002 -2.00325 0.84831004 -2.00325 0 P 0 ;0
L 0.77088002 -2.00225 0.84843996 -2.00225 0 P 0 ;0
L 0.77088002 -2.00125 0.84856004 -2.00125 0 P 0 ;0
L 0.77088002 -2.00025 0.84868996 -2.00025 0 P 0 ;0
L 0.77088002 -1.99925 0.84881998 -1.99925 0 P 0 ;0
L 0.77088002 -1.99825 0.84896004 -1.99825 0 P 0 ;0
L 0.77088002 -1.99725 0.84911004 -1.99725 0 P 0 ;0
L 0.77088996 -1.99625 0.84926998 -1.99625 0 P 0 ;0
L 0.77088996 -1.99525 0.84941998 -1.99525 0 P 0 ;0
L 0.77088996 -1.99425 0.84956998 -1.99425 0 P 0 ;0
L 0.77088996 -1.99325 0.84971998 -1.99325 0 P 0 ;0
L 0.77088996 -1.99225 0.84986998 -1.99225 0 P 0 ;0
L 0.77088996 -1.99125 0.85003002 -1.99125 0 P 0 ;0
L 0.7709 -1.99025 0.85018002 -1.99025 0 P 0 ;0
L 0.7709 -1.98925 0.85033002 -1.98925 0 P 0 ;0
L 0.76885 -2.01878002 0.76871998 -2.03201998 0 P 0 ;0
L 0.76871998 -2.03201998 0.7684 -2.04553996 0 P 0 ;0
L 0.7684 -2.04553996 0.76796004 -2.05751004 0 P 0 ;0
L 0.76796004 -2.05751004 0.76741004 -2.06523002 0 P 0 ;0
L 0.76741004 -2.06523002 0.76596004 -2.07933996 0 P 0 ;0
L 0.76596004 -2.07933996 0.7636 -2.09918002 0 P 0 ;0
L 0.7636 -2.09918002 0.76116004 -2.119 0 P 0 ;0
L 0.76116004 -2.119 0.76011998 -2.12526004 0 P 0 ;0
L 0.76011998 -2.12526004 0.75948996 -2.12825 0 P 0 ;0
L 0.75948996 -2.12825 0.84418002 -2.12825 0 P 0 ;0
L 0.84418002 -2.12825 0.84361998 -2.10788002 0 P 0 ;0
L 0.84361998 -2.10788002 0.8436 -2.08276004 0 P 0 ;0
L 0.8436 -2.08276004 0.8449 -2.05491998 0 P 0 ;0
L 0.8449 -2.05491998 0.84736004 -2.02641004 0 P 0 ;0
L 0.84736004 -2.02641004 0.85083996 -1.99923002 0 P 0 ;0
L 0.85083996 -1.99923002 0.85268996 -1.987 0 P 0 ;0
L 0.85268996 -1.987 0.7689 -1.987 0 P 0 ;0
L 0.7689 -1.987 0.76885 -2.01878002 0 P 0 ;0
L 0.76195 -2.12625 0.84211998 -2.12625 0 P 0 ;0
L 0.76213996 -2.12525 0.8421 -2.12525 0 P 0 ;0
L 0.76231004 -2.12425 0.84206998 -2.12425 0 P 0 ;0
L 0.76248002 -2.12325 0.84203996 -2.12325 0 P 0 ;0
L 0.76263996 -2.12225 0.84201004 -2.12225 0 P 0 ;0
L 0.76281004 -2.12125 0.84198996 -2.12125 0 P 0 ;0
L 0.76296998 -2.12025 0.84196004 -2.12025 0 P 0 ;0
L 0.76313996 -2.11925 0.84193002 -2.11925 0 P 0 ;0
L 0.76326998 -2.11825 0.8419 -2.11825 0 P 0 ;0
L 0.76338996 -2.11725 0.84188002 -2.11725 0 P 0 ;0
L 0.76351004 -2.11625 0.84185 -2.11625 0 P 0 ;0
L 0.76363996 -2.11525 0.84181998 -2.11525 0 P 0 ;0
L 0.76376004 -2.11425 0.84178996 -2.11425 0 P 0 ;0
L 0.76388002 -2.11325 0.84176998 -2.11325 0 P 0 ;0
L 0.76401004 -2.11225 0.84173996 -2.11225 0 P 0 ;0
L 0.76413002 -2.11125 0.84171004 -2.11125 0 P 0 ;0
L 0.76425 -2.11025 0.84168002 -2.11025 0 P 0 ;0
L 0.76438002 -2.10925 0.84166004 -2.10925 0 P 0 ;0
L 0.7645 -2.10825 0.84163002 -2.10825 0 P 0 ;0
L 0.76461998 -2.10725 0.84161998 -2.10725 0 P 0 ;0
L 0.76475 -2.10625 0.84161998 -2.10625 0 P 0 ;0
L 0.76486998 -2.10525 0.84161998 -2.10525 0 P 0 ;0
L 0.76498996 -2.10425 0.84161998 -2.10425 0 P 0 ;0
L 0.76511998 -2.10325 0.84161998 -2.10325 0 P 0 ;0
L 0.76523996 -2.10225 0.84161998 -2.10225 0 P 0 ;0
L 0.76536004 -2.10125 0.84161998 -2.10125 0 P 0 ;0
L 0.76548996 -2.10025 0.84161998 -2.10025 0 P 0 ;0
L 0.76561004 -2.09925 0.84161998 -2.09925 0 P 0 ;0
L 0.76573002 -2.09825 0.84161004 -2.09825 0 P 0 ;0
L 0.76583996 -2.09725 0.84161004 -2.09725 0 P 0 ;0
L 0.76596998 -2.09625 0.84161004 -2.09625 0 P 0 ;0
L 0.76608996 -2.09525 0.84161004 -2.09525 0 P 0 ;0
L 0.7662 -2.09425 0.84161004 -2.09425 0 P 0 ;0
L 0.76631998 -2.09325 0.84161004 -2.09325 0 P 0 ;0
L 0.76643996 -2.09225 0.84161004 -2.09225 0 P 0 ;0
L 0.76656004 -2.09125 0.84161004 -2.09125 0 P 0 ;0
L 0.76668002 -2.09025 0.84161004 -2.09025 0 P 0 ;0
L 0.76678996 -2.08925 0.84161004 -2.08925 0 P 0 ;0
L 0.76691998 -2.08825 0.84161004 -2.08825 0 P 0 ;0
L 0.76703002 -2.08725 0.84161004 -2.08725 0 P 0 ;0
L 0.76715 -2.08625 0.8416 -2.08625 0 P 0 ;0
L 0.76726998 -2.08525 0.8416 -2.08525 0 P 0 ;0
L 0.76738996 -2.08425 0.8416 -2.08425 0 P 0 ;0
L 0.76195 -2.12625 0.76208002 -2.12561998 0 P 0 ;0
L 0.76208002 -2.12561998 0.76313996 -2.11928996 0 P 0 ;0
L 0.76313996 -2.11928996 0.76558996 -2.09941998 0 P 0 ;0
L 0.76558996 -2.09941998 0.76558996 -2.09941004 0 P 0 ;0
L 0.76558996 -2.09941004 0.76793996 -2.07956004 0 P 0 ;0
L 0.76793996 -2.07956004 0.7694 -2.0654 0 P 0 ;0
L 0.7694 -2.0654 0.76941004 -2.06536004 0 P 0 ;0
L 0.76941004 -2.06536004 0.76996004 -2.05761998 0 P 0 ;0
L 0.76996004 -2.05761998 0.76996004 -2.05758996 0 P 0 ;0
L 0.76996004 -2.05758996 0.7704 -2.0456 0 P 0 ;0
L 0.7704 -2.0456 0.77071998 -2.03206004 0 P 0 ;0
L 0.77071998 -2.03206004 0.77085 -2.01878002 0 P 0 ;0
L 0.77085 -2.01878002 0.7709 -1.989 0 P 0 ;0
L 0.7709 -1.989 0.85036004 -1.989 0 P 0 ;0
L 0.85036004 -1.989 0.84886004 -1.99895 0 P 0 ;0
L 0.84886004 -1.99895 0.84538002 -2.02618996 0 P 0 ;0
L 0.84538002 -2.02618996 0.8429 -2.05478996 0 P 0 ;0
L 0.8429 -2.05478996 0.8416 -2.08271004 0 P 0 ;0
L 0.8416 -2.08271004 0.84161998 -2.10791004 0 P 0 ;0
L 0.84161998 -2.10791004 0.84211998 -2.12625 0 P 0 ;0
L 0.84211998 -2.12625 0.76195 -2.12625 0 P 0 ;0
L 0.71628996 -1.91261998 0.74938002 -1.91261998 0 P 0 ;0
L 0.71783002 -1.91161998 0.74933002 -1.91161998 0 P 0 ;0
L 0.71953002 -1.91061998 0.74931004 -1.91061998 0 P 0 ;0
L 0.72133002 -1.90961998 0.74928996 -1.90961998 0 P 0 ;0
L 0.72313996 -1.90861998 0.74926998 -1.90861998 0 P 0 ;0
L 0.72493996 -1.90761998 0.74928996 -1.90761998 0 P 0 ;0
L 0.72673996 -1.90661998 0.74931998 -1.90661998 0 P 0 ;0
L 0.72855 -1.90561998 0.74935 -1.90561998 0 P 0 ;0
L 0.73035 -1.90461998 0.74938996 -1.90461998 0 P 0 ;0
L 0.73215 -1.90361998 0.74946998 -1.90361998 0 P 0 ;0
L 0.73396004 -1.90261998 0.74953996 -1.90261998 0 P 0 ;0
L 0.73576004 -1.90161998 0.74961998 -1.90161998 0 P 0 ;0
L 0.73756998 -1.90061998 0.74973996 -1.90061998 0 P 0 ;0
L 0.73943002 -1.89961998 0.74986004 -1.89961998 0 P 0 ;0
L 0.74141998 -1.89861998 0.74998996 -1.89861998 0 P 0 ;0
L 0.74341004 -1.89761998 0.75015 -1.89761998 0 P 0 ;0
L 0.59843002 -2.08361998 0.6754 -2.08361998 0 P 0 ;0
L 0.59846004 -2.08261998 0.67538996 -2.08261998 0 P 0 ;0
L 0.59848002 -2.08161998 0.67538002 -2.08161998 0 P 0 ;0
L 0.59851004 -2.08061998 0.67538002 -2.08061998 0 P 0 ;0
L 0.59853002 -2.07961998 0.67546004 -2.07961998 0 P 0 ;0
L 0.59856004 -2.07861998 0.67553996 -2.07861998 0 P 0 ;0
L 0.59861998 -2.07761998 0.67561004 -2.07761998 0 P 0 ;0
L 0.5987 -2.07661998 0.67568996 -2.07661998 0 P 0 ;0
L 0.59878002 -2.07561998 0.67576004 -2.07561998 0 P 0 ;0
L 0.59885 -2.07461998 0.67583996 -2.07461998 0 P 0 ;0
L 0.59893002 -2.07361998 0.67591998 -2.07361998 0 P 0 ;0
L 0.59901004 -2.07261998 0.67598996 -2.07261998 0 P 0 ;0
L 0.59908002 -2.07161998 0.67606998 -2.07161998 0 P 0 ;0
L 0.59916004 -2.07061998 0.67613996 -2.07061998 0 P 0 ;0
L 0.59923002 -2.06961998 0.67621004 -2.06961998 0 P 0 ;0
L 0.59936004 -2.06861998 0.6763 -2.06861998 0 P 0 ;0
L 0.59948996 -2.06761998 0.67645 -2.06761998 0 P 0 ;0
L 0.59963002 -2.06661998 0.6766 -2.06661998 0 P 0 ;0
L 0.59976998 -2.06561998 0.67676004 -2.06561998 0 P 0 ;0
L 0.5999 -2.06461998 0.67691998 -2.06461998 0 P 0 ;0
L 0.60003002 -2.06361998 0.67706998 -2.06361998 0 P 0 ;0
L 0.60016998 -2.06261998 0.6773 -2.06261998 0 P 0 ;0
L 0.60031004 -2.06161998 0.67753002 -2.06161998 0 P 0 ;0
L 0.60051004 -2.06061998 0.67776004 -2.06061998 0 P 0 ;0
L 0.60071004 -2.05961998 0.67798996 -2.05961998 0 P 0 ;0
L 0.60091998 -2.05861998 0.67823002 -2.05861998 0 P 0 ;0
L 0.60111998 -2.05761998 0.67853002 -2.05761998 0 P 0 ;0
L 0.60133002 -2.05661998 0.67883996 -2.05661998 0 P 0 ;0
L 0.60153996 -2.05561998 0.67913996 -2.05561998 0 P 0 ;0
L 0.60173996 -2.05461998 0.67945 -2.05461998 0 P 0 ;0
L 0.60195 -2.05361998 0.67975 -2.05361998 0 P 0 ;0
L 0.60223002 -2.05261998 0.68006004 -2.05261998 0 P 0 ;0
L 0.60251004 -2.05161998 0.68036004 -2.05161998 0 P 0 ;0
L 0.60278996 -2.05061998 0.68066998 -2.05061998 0 P 0 ;0
L 0.60306004 -2.04961998 0.68096998 -2.04961998 0 P 0 ;0
L 0.60333996 -2.04861998 0.68135 -2.04861998 0 P 0 ;0
L 0.60361998 -2.04761998 0.68173002 -2.04761998 0 P 0 ;0
L 0.6039 -2.04661998 0.68211004 -2.04661998 0 P 0 ;0
L 0.60418002 -2.04561998 0.68248996 -2.04561998 0 P 0 ;0
L 0.60453002 -2.04461998 0.68288002 -2.04461998 0 P 0 ;0
L 0.60488002 -2.04361998 0.68326004 -2.04361998 0 P 0 ;0
L 0.60523002 -2.04261998 0.68363996 -2.04261998 0 P 0 ;0
L 0.60556998 -2.04161998 0.68401998 -2.04161998 0 P 0 ;0
L 0.60591998 -2.04061998 0.6844 -2.04061998 0 P 0 ;0
L 0.60626998 -2.03961998 0.68486004 -2.03961998 0 P 0 ;0
L 0.60661998 -2.03861998 0.68531998 -2.03861998 0 P 0 ;0
L 0.60698996 -2.03761998 0.68578002 -2.03761998 0 P 0 ;0
L 0.60743002 -2.03661998 0.68623996 -2.03661998 0 P 0 ;0
L 0.60786004 -2.03561998 0.6867 -2.03561998 0 P 0 ;0
L 0.60828996 -2.03461998 0.68716004 -2.03461998 0 P 0 ;0
L 0.60873002 -2.03361998 0.68761998 -2.03361998 0 P 0 ;0
L 0.60916004 -2.03261998 0.68808996 -2.03261998 0 P 0 ;0
L 0.60958996 -2.03161998 0.68856998 -2.03161998 0 P 0 ;0
L 0.61003002 -2.03061998 0.68911004 -2.03061998 0 P 0 ;0
L 0.61046004 -2.02961998 0.68965 -2.02961998 0 P 0 ;0
L 0.61088996 -2.02861998 0.69018996 -2.02861998 0 P 0 ;0
L 0.61133002 -2.02761998 0.69073002 -2.02761998 0 P 0 ;0
L 0.61176004 -2.02661998 0.69126998 -2.02661998 0 P 0 ;0
L 0.6122 -2.02561998 0.69181004 -2.02561998 0 P 0 ;0
L 0.61263002 -2.02461998 0.69235 -2.02461998 0 P 0 ;0
L 0.61306004 -2.02361998 0.69288002 -2.02361998 0 P 0 ;0
L 0.61348996 -2.02261998 0.69346998 -2.02261998 0 P 0 ;0
L 0.61393002 -2.02161998 0.69408996 -2.02161998 0 P 0 ;0
L 0.61436004 -2.02061998 0.6947 -2.02061998 0 P 0 ;0
L 0.61478996 -2.01961998 0.69531998 -2.01961998 0 P 0 ;0
L 0.61531004 -2.01861998 0.69593996 -2.01861998 0 P 0 ;0
L 0.61583996 -2.01761998 0.69656004 -2.01761998 0 P 0 ;0
L 0.61636004 -2.01661998 0.69718002 -2.01661998 0 P 0 ;0
L 0.61688002 -2.01561998 0.69778996 -2.01561998 0 P 0 ;0
L 0.6174 -2.01461998 0.69841998 -2.01461998 0 P 0 ;0
L 0.61791998 -2.01361998 0.69911998 -2.01361998 0 P 0 ;0
L 0.61843996 -2.01261998 0.69981998 -2.01261998 0 P 0 ;0
L 0.61896004 -2.01161998 0.70051998 -2.01161998 0 P 0 ;0
L 0.61948002 -2.01061998 0.70123002 -2.01061998 0 P 0 ;0
L 0.62 -2.00961998 0.70193002 -2.00961998 0 P 0 ;0
L 0.62051998 -2.00861998 0.70263002 -2.00861998 0 P 0 ;0
L 0.62103996 -2.00761998 0.70333002 -2.00761998 0 P 0 ;0
L 0.62163996 -2.00661998 0.70403996 -2.00661998 0 P 0 ;0
L 0.62225 -2.00561998 0.70483002 -2.00561998 0 P 0 ;0
L 0.62285 -2.00461998 0.70565 -2.00461998 0 P 0 ;0
L 0.62346004 -2.00361998 0.70646004 -2.00361998 0 P 0 ;0
L 0.62406004 -2.00261998 0.70726998 -2.00261998 0 P 0 ;0
L 0.62466004 -2.00161998 0.70808996 -2.00161998 0 P 0 ;0
L 0.62526998 -2.00061998 0.7089 -2.00061998 0 P 0 ;0
L 0.62586998 -1.99961998 0.70971004 -1.99961998 0 P 0 ;0
L 0.62648002 -1.99861998 0.71053002 -1.99861998 0 P 0 ;0
L 0.62708002 -1.99761998 0.71133996 -1.99761998 0 P 0 ;0
L 0.62768996 -1.99661998 0.71216004 -1.99661998 0 P 0 ;0
L 0.62831998 -1.99561998 0.71296998 -1.99561998 0 P 0 ;0
L 0.62901004 -1.99461998 0.71378996 -1.99461998 0 P 0 ;0
L 0.62971004 -1.99361998 0.71466004 -1.99361998 0 P 0 ;0
L 0.6304 -1.99261998 0.71561004 -1.99261998 0 P 0 ;0
L 0.6311 -1.99161998 0.71656998 -1.99161998 0 P 0 ;0
L 0.63178996 -1.99061998 0.71753002 -1.99061998 0 P 0 ;0
L 0.63248996 -1.98961998 0.71848996 -1.98961998 0 P 0 ;0
L 0.63318002 -1.98861998 0.71945 -1.98861998 0 P 0 ;0
L 0.63388002 -1.98761998 0.72041004 -1.98761998 0 P 0 ;0
L 0.63456998 -1.98661998 0.72136998 -1.98661998 0 P 0 ;0
L 0.63526998 -1.98561998 0.72233002 -1.98561998 0 P 0 ;0
L 0.63598002 -1.98461998 0.72328996 -1.98461998 0 P 0 ;0
L 0.63678996 -1.98361998 0.72425 -1.98361998 0 P 0 ;0
L 0.6376 -1.98261998 0.72521004 -1.98261998 0 P 0 ;0
L 0.63841004 -1.98161998 0.72628002 -1.98161998 0 P 0 ;0
L 0.63921998 -1.98061998 0.72738996 -1.98061998 0 P 0 ;0
L 0.64003002 -1.97961998 0.7285 -1.97961998 0 P 0 ;0
L 0.64083996 -1.97861998 0.72961004 -1.97861998 0 P 0 ;0
L 0.64165 -1.97761998 0.73071004 -1.97761998 0 P 0 ;0
L 0.64246004 -1.97661998 0.73181998 -1.97661998 0 P 0 ;0
L 0.64326998 -1.97561998 0.73293002 -1.97561998 0 P 0 ;0
L 0.64406998 -1.97461998 0.73403996 -1.97461998 0 P 0 ;0
L 0.64488002 -1.97361998 0.73515 -1.97361998 0 P 0 ;0
L 0.64568996 -1.97261998 0.73625 -1.97261998 0 P 0 ;0
L 0.6465 -1.97161998 0.73736004 -1.97161998 0 P 0 ;0
L 0.64731004 -1.97061998 0.73848002 -1.97061998 0 P 0 ;0
L 0.64811998 -1.96961998 0.73973002 -1.96961998 0 P 0 ;0
L 0.64893002 -1.96861998 0.74098996 -1.96861998 0 P 0 ;0
L 0.64981004 -1.96761998 0.74225 -1.96761998 0 P 0 ;0
L 0.65076004 -1.96661998 0.74351004 -1.96661998 0 P 0 ;0
L 0.65171004 -1.96561998 0.74476998 -1.96561998 0 P 0 ;0
L 0.65266998 -1.96461998 0.74603002 -1.96461998 0 P 0 ;0
L 0.65361998 -1.96361998 0.74728996 -1.96361998 0 P 0 ;0
L 0.65458002 -1.96261998 0.74855 -1.96261998 0 P 0 ;0
L 0.65553002 -1.96161998 0.74981004 -1.96161998 0 P 0 ;0
L 0.65648996 -1.96061998 0.75106004 -1.96061998 0 P 0 ;0
L 0.65743996 -1.95961998 0.75233996 -1.95961998 0 P 0 ;0
L 0.6584 -1.95861998 0.7537 -1.95861998 0 P 0 ;0
L 0.65935 -1.95761998 0.75506004 -1.95761998 0 P 0 ;0
L 0.66031004 -1.95661998 0.75641998 -1.95661998 0 P 0 ;0
L 0.66126004 -1.95561998 0.75778996 -1.95561998 0 P 0 ;0
L 0.66221004 -1.95461998 0.75916004 -1.95461998 0 P 0 ;0
L 0.66316998 -1.95361998 0.76053996 -1.95361998 0 P 0 ;0
L 0.66411998 -1.95261998 0.76193996 -1.95261998 0 P 0 ;0
L 0.66523002 -1.95161998 0.76333996 -1.95161998 0 P 0 ;0
L 0.66636004 -1.95061998 0.76406998 -1.95061998 0 P 0 ;0
L 0.66746998 -1.94961998 0.76355 -1.94961998 0 P 0 ;0
L 0.6686 -1.94861998 0.76291998 -1.94861998 0 P 0 ;0
L 0.66971004 -1.94761998 0.76226998 -1.94761998 0 P 0 ;0
L 0.67083996 -1.94661998 0.76161998 -1.94661998 0 P 0 ;0
L 0.67196004 -1.94561998 0.76096998 -1.94561998 0 P 0 ;0
L 0.67306998 -1.94461998 0.76033002 -1.94461998 0 P 0 ;0
L 0.6742 -1.94361998 0.75968996 -1.94361998 0 P 0 ;0
L 0.67531004 -1.94261998 0.75905 -1.94261998 0 P 0 ;0
L 0.67643996 -1.94161998 0.75846004 -1.94161998 0 P 0 ;0
L 0.67755 -1.94061998 0.75788996 -1.94061998 0 P 0 ;0
L 0.67868002 -1.93961998 0.75731998 -1.93961998 0 P 0 ;0
L 0.67978996 -1.93861998 0.75676998 -1.93861998 0 P 0 ;0
L 0.68091998 -1.93761998 0.75626998 -1.93761998 0 P 0 ;0
L 0.68221004 -1.93661998 0.75576998 -1.93661998 0 P 0 ;0
L 0.68353002 -1.93561998 0.75528002 -1.93561998 0 P 0 ;0
L 0.68483996 -1.93461998 0.75483996 -1.93461998 0 P 0 ;0
L 0.68616004 -1.93361998 0.75441004 -1.93361998 0 P 0 ;0
L 0.68746998 -1.93261998 0.75398002 -1.93261998 0 P 0 ;0
L 0.68878002 -1.93161998 0.7536 -1.93161998 0 P 0 ;0
L 0.6901 -1.93061998 0.75323996 -1.93061998 0 P 0 ;0
L 0.69141004 -1.92961998 0.75286998 -1.92961998 0 P 0 ;0
L 0.69271998 -1.92861998 0.75253996 -1.92861998 0 P 0 ;0
L 0.69403002 -1.92761998 0.75223002 -1.92761998 0 P 0 ;0
L 0.69535 -1.92661998 0.75193002 -1.92661998 0 P 0 ;0
L 0.69666004 -1.92561998 0.75163002 -1.92561998 0 P 0 ;0
L 0.69796998 -1.92461998 0.75138002 -1.92461998 0 P 0 ;0
L 0.69936998 -1.92361998 0.75113996 -1.92361998 0 P 0 ;0
L 0.70091004 -1.92261998 0.75088996 -1.92261998 0 P 0 ;0
L 0.70243996 -1.92161998 0.75066004 -1.92161998 0 P 0 ;0
L 0.70398002 -1.92061998 0.75046004 -1.92061998 0 P 0 ;0
L 0.70551998 -1.91961998 0.75026004 -1.91961998 0 P 0 ;0
L 0.70706004 -1.91861998 0.75006998 -1.91861998 0 P 0 ;0
L 0.7086 -1.91761998 0.7499 -1.91761998 0 P 0 ;0
L 0.71013996 -1.91661998 0.74976998 -1.91661998 0 P 0 ;0
L 0.71166998 -1.91561998 0.74961998 -1.91561998 0 P 0 ;0
L 0.71321004 -1.91461998 0.74951998 -1.91461998 0 P 0 ;0
L 0.71475 -1.91361998 0.74945 -1.91361998 0 P 0 ;0
L 0.61556998 -2.15661998 0.70655 -2.15661998 0 P 0 ;0
L 0.61503002 -2.15561998 0.7056 -2.15561998 0 P 0 ;0
L 0.61448996 -2.15461998 0.70465 -2.15461998 0 P 0 ;0
L 0.61395 -2.15361998 0.7037 -2.15361998 0 P 0 ;0
L 0.61341004 -2.15261998 0.70273996 -2.15261998 0 P 0 ;0
L 0.61286998 -2.15161998 0.70178996 -2.15161998 0 P 0 ;0
L 0.61233002 -2.15061998 0.70095 -2.15061998 0 P 0 ;0
L 0.61188002 -2.14961998 0.70015 -2.14961998 0 P 0 ;0
L 0.61143002 -2.14861998 0.69935 -2.14861998 0 P 0 ;0
L 0.61098002 -2.14761998 0.69855 -2.14761998 0 P 0 ;0
L 0.61053002 -2.14661998 0.69775 -2.14661998 0 P 0 ;0
L 0.61008002 -2.14561998 0.69695 -2.14561998 0 P 0 ;0
L 0.60963002 -2.14461998 0.69615 -2.14461998 0 P 0 ;0
L 0.60918002 -2.14361998 0.69535 -2.14361998 0 P 0 ;0
L 0.60873002 -2.14261998 0.69455 -2.14261998 0 P 0 ;0
L 0.60831004 -2.14161998 0.69381998 -2.14161998 0 P 0 ;0
L 0.60793996 -2.14061998 0.69315 -2.14061998 0 P 0 ;0
L 0.60756998 -2.13961998 0.69248002 -2.13961998 0 P 0 ;0
L 0.60721004 -2.13861998 0.69181004 -2.13861998 0 P 0 ;0
L 0.60683996 -2.13761998 0.69115 -2.13761998 0 P 0 ;0
L 0.60646998 -2.13661998 0.69048002 -2.13661998 0 P 0 ;0
L 0.60611004 -2.13561998 0.68981004 -2.13561998 0 P 0 ;0
L 0.60573996 -2.13461998 0.68918002 -2.13461998 0 P 0 ;0
L 0.60538002 -2.13361998 0.68863002 -2.13361998 0 P 0 ;0
L 0.60503996 -2.13261998 0.68808002 -2.13261998 0 P 0 ;0
L 0.60476004 -2.13161998 0.68753002 -2.13161998 0 P 0 ;0
L 0.60446998 -2.13061998 0.68698002 -2.13061998 0 P 0 ;0
L 0.60418002 -2.12961998 0.68643002 -2.12961998 0 P 0 ;0
L 0.6039 -2.12861998 0.68588002 -2.12861998 0 P 0 ;0
L 0.60361004 -2.12761998 0.68533002 -2.12761998 0 P 0 ;0
L 0.60331998 -2.12661998 0.68486004 -2.12661998 0 P 0 ;0
L 0.60303002 -2.12561998 0.68441998 -2.12561998 0 P 0 ;0
L 0.60275 -2.12461998 0.68396998 -2.12461998 0 P 0 ;0
L 0.60246004 -2.12361998 0.68353002 -2.12361998 0 P 0 ;0
L 0.60218002 -2.12261998 0.68308996 -2.12261998 0 P 0 ;0
L 0.60188996 -2.12161998 0.68263996 -2.12161998 0 P 0 ;0
L 0.60166998 -2.12061998 0.6822 -2.12061998 0 P 0 ;0
L 0.60145 -2.11961998 0.68176004 -2.11961998 0 P 0 ;0
L 0.60123002 -2.11861998 0.68138996 -2.11861998 0 P 0 ;0
L 0.60101004 -2.11761998 0.68105 -2.11761998 0 P 0 ;0
L 0.60078002 -2.11661998 0.68071004 -2.11661998 0 P 0 ;0
L 0.6006 -2.11561998 0.68036004 -2.11561998 0 P 0 ;0
L 0.60043002 -2.11461998 0.68001998 -2.11461998 0 P 0 ;0
L 0.60025 -2.11361998 0.67968002 -2.11361998 0 P 0 ;0
L 0.60008002 -2.11261998 0.67933002 -2.11261998 0 P 0 ;0
L 0.59991004 -2.11161998 0.67898996 -2.11161998 0 P 0 ;0
L 0.59976004 -2.11061998 0.6787 -2.11061998 0 P 0 ;0
L 0.59963996 -2.10961998 0.67845 -2.10961998 0 P 0 ;0
L 0.59951004 -2.10861998 0.6782 -2.10861998 0 P 0 ;0
L 0.59938002 -2.10761998 0.67795 -2.10761998 0 P 0 ;0
L 0.59925 -2.10661998 0.6777 -2.10661998 0 P 0 ;0
L 0.59913002 -2.10561998 0.67746004 -2.10561998 0 P 0 ;0
L 0.59905 -2.10461998 0.67721004 -2.10461998 0 P 0 ;0
L 0.59896998 -2.10361998 0.67696004 -2.10361998 0 P 0 ;0
L 0.59888002 -2.10261998 0.67671004 -2.10261998 0 P 0 ;0
L 0.5988 -2.10161998 0.67653996 -2.10161998 0 P 0 ;0
L 0.59871998 -2.10061998 0.67638002 -2.10061998 0 P 0 ;0
L 0.59866998 -2.09961998 0.67621004 -2.09961998 0 P 0 ;0
L 0.59863996 -2.09861998 0.67605 -2.09861998 0 P 0 ;0
L 0.59861004 -2.09761998 0.67588996 -2.09761998 0 P 0 ;0
L 0.59858996 -2.09661998 0.6758 -2.09661998 0 P 0 ;0
L 0.59856004 -2.09561998 0.67571004 -2.09561998 0 P 0 ;0
L 0.59853002 -2.09461998 0.67563002 -2.09461998 0 P 0 ;0
L 0.5985 -2.09361998 0.67553996 -2.09361998 0 P 0 ;0
L 0.59846998 -2.09261998 0.67546004 -2.09261998 0 P 0 ;0
L 0.59843996 -2.09161998 0.67546004 -2.09161998 0 P 0 ;0
L 0.59841998 -2.09061998 0.67545 -2.09061998 0 P 0 ;0
L 0.59838002 -2.08961998 0.67543996 -2.08961998 0 P 0 ;0
L 0.59836004 -2.08861998 0.67543002 -2.08861998 0 P 0 ;0
L 0.59833002 -2.08761998 0.67543002 -2.08761998 0 P 0 ;0
L 0.59835 -2.08661998 0.67541998 -2.08661998 0 P 0 ;0
L 0.59836998 -2.08561998 0.67541004 -2.08561998 0 P 0 ;0
L 0.5984 -2.08461998 0.67541004 -2.08461998 0 P 0 ;0
L 0.80005 -2.25161998 0.85543996 -2.25161998 0 P 0 ;0
L 0.78651998 -2.25061998 0.86596004 -2.25061998 0 P 0 ;0
L 0.77878996 -2.24961998 0.87636004 -2.24961998 0 P 0 ;0
L 0.77106004 -2.24861998 0.88285 -2.24861998 0 P 0 ;0
L 0.76398996 -2.24761998 0.88933996 -2.24761998 0 P 0 ;0
L 0.75891998 -2.24661998 0.89583996 -2.24661998 0 P 0 ;0
L 0.73781004 -1.8982 0.71738996 -1.90951998 0 P 0 ;0
L 0.71738996 -1.90951998 0.69766998 -1.92233996 0 P 0 ;0
L 0.69766998 -1.92233996 0.67971004 -1.93601998 0 P 0 ;0
L 0.67971004 -1.93601998 0.66278996 -1.95113002 0 P 0 ;0
L 0.66278996 -1.95113002 0.64786998 -1.96675 0 P 0 ;0
L 0.64786998 -1.96675 0.63423996 -1.98358996 0 P 0 ;0
L 0.63423996 -1.98358996 0.62643996 -1.99483002 0 P 0 ;0
L 0.62643996 -1.99483002 0.61933996 -2.00655 0 P 0 ;0
L 0.61933996 -2.00655 0.61298996 -2.01873996 0 P 0 ;0
L 0.61298996 -2.01873996 0.60503002 -2.03713002 0 P 0 ;0
L 0.60503002 -2.03713002 0.60225 -2.04506004 0 P 0 ;0
L 0.60225 -2.04506004 0.59998996 -2.05323002 0 P 0 ;0
L 0.59998996 -2.05323002 0.59833996 -2.0612 0 P 0 ;0
L 0.59833996 -2.0612 0.59725 -2.06928996 0 P 0 ;0
L 0.59725 -2.06928996 0.59656998 -2.07833996 0 P 0 ;0
L 0.59656998 -2.07833996 0.59633002 -2.0875 0 P 0 ;0
L 0.59633002 -2.0875 0.59668996 -2.10036998 0 P 0 ;0
L 0.59668996 -2.10036998 0.59715 -2.10596004 0 P 0 ;0
L 0.59715 -2.10596004 0.59786004 -2.11151004 0 P 0 ;0
L 0.59786004 -2.11151004 0.59878996 -2.11686998 0 P 0 ;0
L 0.59878996 -2.11686998 0.59996998 -2.1222 0 P 0 ;0
L 0.59996998 -2.1222 0.60326998 -2.13368996 0 P 0 ;0
L 0.60326998 -2.13368996 0.60656998 -2.1427 0 P 0 ;0
L 0.60656998 -2.1427 0.6105 -2.15143996 0 P 0 ;0
L 0.6105 -2.15143996 0.61505 -2.15988002 0 P 0 ;0
L 0.61505 -2.15988002 0.62023996 -2.16803996 0 P 0 ;0
L 0.62023996 -2.16803996 0.62828996 -2.17873002 0 P 0 ;0
L 0.62828996 -2.17873002 0.63718996 -2.18871004 0 P 0 ;0
L 0.63718996 -2.18871004 0.64693002 -2.19795 0 P 0 ;0
L 0.64693002 -2.19795 0.6582 -2.20701998 0 P 0 ;0
L 0.6582 -2.20701998 0.67011004 -2.21518996 0 P 0 ;0
L 0.67011004 -2.21518996 0.68261004 -2.22243002 0 P 0 ;0
L 0.68261004 -2.22243002 0.69673996 -2.22936004 0 P 0 ;0
L 0.69673996 -2.22936004 0.71123002 -2.23543996 0 P 0 ;0
L 0.71123002 -2.23543996 0.72611998 -2.24066998 0 P 0 ;0
L 0.72611998 -2.24066998 0.74536004 -2.24598996 0 P 0 ;0
L 0.74536004 -2.24598996 0.76493002 -2.24985 0 P 0 ;0
L 0.76493002 -2.24985 0.78671998 -2.25266998 0 P 0 ;0
L 0.78671998 -2.25266998 0.80863002 -2.25425 0 P 0 ;0
L 0.80863002 -2.25425 0.83146004 -2.25463002 0 P 0 ;0
L 0.83146004 -2.25463002 0.85418002 -2.25375 0 P 0 ;0
L 0.85418002 -2.25375 0.87641004 -2.25163996 0 P 0 ;0
L 0.87641004 -2.25163996 0.89853002 -2.24823002 0 P 0 ;0
L 0.89853002 -2.24823002 0.93045 -2.24101998 0 P 0 ;0
L 0.93045 -2.24101998 0.96466004 -2.23063002 0 P 0 ;0
L 0.96466004 -2.23063002 0.99911004 -2.2178 0 P 0 ;0
L 0.99911004 -2.2178 1.03183002 -2.20318002 0 P 0 ;0
L 1.03183002 -2.20318002 1.04391998 -2.19703002 0 P 0 ;0
L 1.04391998 -2.19703002 1.05581004 -2.19048996 0 P 0 ;0
L 1.05581004 -2.19048996 1.06676004 -2.18411998 0 P 0 ;0
L 1.06676004 -2.18411998 1.06681004 -2.18408996 0 P 0 ;0
L 1.06681004 -2.18408996 1.06685 -2.18405 0 P 0 ;0
L 1.06685 -2.18405 1.0669 -2.18401004 0 P 0 ;0
L 1.0669 -2.18401004 1.06693996 -2.18396998 0 P 0 ;0
L 1.06693996 -2.18396998 1.06696998 -2.18391998 0 P 0 ;0
L 1.06696998 -2.18391998 1.06701004 -2.18386998 0 P 0 ;0
L 1.06701004 -2.18386998 1.06703002 -2.18381998 0 P 0 ;0
L 1.06703002 -2.18381998 1.06706004 -2.18376004 0 P 0 ;0
L 1.06706004 -2.18376004 1.06706998 -2.18371004 0 P 0 ;0
L 1.06706998 -2.18371004 1.06708996 -2.18365 0 P 0 ;0
L 1.06708996 -2.18365 1.06708996 -2.18358996 0 P 0 ;0
L 1.06708996 -2.18358996 1.0671 -2.18353002 0 P 0 ;0
L 1.0671 -2.18353002 1.0671 -2.18346998 0 P 0 ;0
L 1.0671 -2.18346998 1.06708996 -2.18341004 0 P 0 ;0
L 1.06708996 -2.18341004 1.06706998 -2.18336004 0 P 0 ;0
L 1.06706998 -2.18336004 1.06706004 -2.1833 0 P 0 ;0
L 1.06706004 -2.1833 1.06703002 -2.18323996 0 P 0 ;0
L 1.06703002 -2.18323996 1.06701004 -2.18318996 0 P 0 ;0
L 1.06701004 -2.18318996 1.06696998 -2.18313996 0 P 0 ;0
L 1.06696998 -2.18313996 1.06693996 -2.18308996 0 P 0 ;0
L 1.06693996 -2.18308996 1.06688002 -2.18303002 0 P 0 ;0
L 1.06688002 -2.18303002 1.06678996 -2.18296998 0 P 0 ;0
L 1.06678996 -2.18296998 1.06673002 -2.18295 0 P 0 ;0
L 1.06673002 -2.18295 1.0667 -2.18295 0 P 0 ;0
L 1.0667 -2.18295 1.06666004 -2.18293996 0 P 0 ;0
L 1.06666004 -2.18293996 1.0666 -2.18293996 0 P 0 ;0
L 1.0666 -2.18293996 1.06656998 -2.18295 0 P 0 ;0
L 1.06656998 -2.18295 1.06653002 -2.18295 0 P 0 ;0
L 1.06653002 -2.18295 1.06153002 -2.1842 0 P 0 ;0
L 1.06153002 -2.1842 1.05583996 -2.18566998 0 P 0 ;0
L 1.05583996 -2.18566998 1.04916998 -2.1875 0 P 0 ;0
L 1.04916998 -2.1875 1.0153 -2.1962 0 P 0 ;0
L 1.0153 -2.1962 0.9814 -2.20333996 0 P 0 ;0
L 0.9814 -2.20333996 0.94881998 -2.2087 0 P 0 ;0
L 0.94881998 -2.2087 0.9189 -2.21198996 0 P 0 ;0
L 0.9189 -2.21198996 0.90113996 -2.21278996 0 P 0 ;0
L 0.90113996 -2.21278996 0.87738002 -2.21265 0 P 0 ;0
L 0.87738002 -2.21265 0.854 -2.21183002 0 P 0 ;0
L 0.854 -2.21183002 0.83788996 -2.21033996 0 P 0 ;0
L 0.83788996 -2.21033996 0.8174 -2.20693002 0 P 0 ;0
L 0.8174 -2.20693002 0.79708996 -2.2023 0 P 0 ;0
L 0.79708996 -2.2023 0.7769 -2.19641004 0 P 0 ;0
L 0.7769 -2.19641004 0.76433002 -2.19183996 0 P 0 ;0
L 0.76433002 -2.19183996 0.75208996 -2.18638002 0 P 0 ;0
L 0.75208996 -2.18638002 0.74026998 -2.18006998 0 P 0 ;0
L 0.74026998 -2.18006998 0.72886998 -2.17291004 0 P 0 ;0
L 0.72886998 -2.17291004 0.71961998 -2.16603002 0 P 0 ;0
L 0.71961998 -2.16603002 0.71098996 -2.15838996 0 P 0 ;0
L 0.71098996 -2.15838996 0.70303002 -2.15003002 0 P 0 ;0
L 0.70303002 -2.15003002 0.6958 -2.14098996 0 P 0 ;0
L 0.6958 -2.14098996 0.69106998 -2.1339 0 P 0 ;0
L 0.69106998 -2.1339 0.68696004 -2.12643002 0 P 0 ;0
L 0.68696004 -2.12643002 0.68351004 -2.11863002 0 P 0 ;0
L 0.68351004 -2.11863002 0.68073996 -2.11056004 0 P 0 ;0
L 0.68073996 -2.11056004 0.67866004 -2.10218996 0 P 0 ;0
L 0.67866004 -2.10218996 0.67788002 -2.09741998 0 P 0 ;0
L 0.67788002 -2.09741998 0.67746004 -2.0926 0 P 0 ;0
L 0.67746004 -2.0926 0.67738002 -2.08076004 0 P 0 ;0
L 0.67738002 -2.08076004 0.67828002 -2.06891004 0 P 0 ;0
L 0.67828002 -2.06891004 0.67903002 -2.06403996 0 P 0 ;0
L 0.67903002 -2.06403996 0.68013002 -2.05923996 0 P 0 ;0
L 0.68013002 -2.05923996 0.68288002 -2.05021998 0 P 0 ;0
L 0.68288002 -2.05021998 0.68623996 -2.04141004 0 P 0 ;0
L 0.68623996 -2.04141004 0.69018002 -2.03286004 0 P 0 ;0
L 0.69018002 -2.03286004 0.69486004 -2.02418002 0 P 0 ;0
L 0.69486004 -2.02418002 0.70003996 -2.0158 0 P 0 ;0
L 0.70003996 -2.0158 0.70573002 -2.00768996 0 P 0 ;0
L 0.70573002 -2.00768996 0.7158 -1.99531998 0 P 0 ;0
L 0.7158 -1.99531998 0.72681004 -1.98385 0 P 0 ;0
L 0.72681004 -1.98385 0.73971004 -1.9722 0 P 0 ;0
L 0.73971004 -1.9722 0.7533 -1.9614 0 P 0 ;0
L 0.7533 -1.9614 0.75753996 -1.95828002 0 P 0 ;0
L 0.75753996 -1.95828002 0.76138002 -1.95548002 0 P 0 ;0
L 0.76138002 -1.95548002 0.76463002 -1.95316004 0 P 0 ;0
L 0.76463002 -1.95316004 0.76516004 -1.95281004 0 P 0 ;0
L 0.76516004 -1.95281004 0.7657 -1.95248996 0 P 0 ;0
L 0.7657 -1.95248996 0.76578002 -1.95243996 0 P 0 ;0
L 0.76578002 -1.95243996 0.76586004 -1.95238002 0 P 0 ;0
L 0.76586004 -1.95238002 0.76593002 -1.95231998 0 P 0 ;0
L 0.76593002 -1.95231998 0.766 -1.95223996 0 P 0 ;0
L 0.766 -1.95223996 0.76606004 -1.95216998 0 P 0 ;0
L 0.76606004 -1.95216998 0.76616004 -1.95201004 0 P 0 ;0
L 0.76616004 -1.95201004 0.7662 -1.95191998 0 P 0 ;0
L 0.7662 -1.95191998 0.76626004 -1.95173996 0 P 0 ;0
L 0.76626004 -1.95173996 0.76628002 -1.95163996 0 P 0 ;0
L 0.76628002 -1.95163996 0.7663 -1.95143002 0 P 0 ;0
L 0.7663 -1.95143002 0.7663 -1.95121004 0 P 0 ;0
L 0.7663 -1.95121004 0.76628996 -1.951 0 P 0 ;0
L 0.76628996 -1.951 0.76625 -1.95078996 0 P 0 ;0
L 0.76625 -1.95078996 0.7662 -1.95058002 0 P 0 ;0
L 0.7662 -1.95058002 0.76613002 -1.95036998 0 P 0 ;0
L 0.76613002 -1.95036998 0.76583002 -1.94966998 0 P 0 ;0
L 0.76583002 -1.94966998 0.76548996 -1.94896998 0 P 0 ;0
L 0.76548996 -1.94896998 0.76508996 -1.9483 0 P 0 ;0
L 0.76508996 -1.9483 0.76253002 -1.94436004 0 P 0 ;0
L 0.76253002 -1.94436004 0.76056998 -1.94126998 0 P 0 ;0
L 0.76056998 -1.94126998 0.75871998 -1.93806004 0 P 0 ;0
L 0.75871998 -1.93806004 0.75716998 -1.93496998 0 P 0 ;0
L 0.75716998 -1.93496998 0.7558 -1.93178002 0 P 0 ;0
L 0.7558 -1.93178002 0.7546 -1.92853996 0 P 0 ;0
L 0.7546 -1.92853996 0.75358996 -1.92521004 0 P 0 ;0
L 0.75358996 -1.92521004 0.7527 -1.92161998 0 P 0 ;0
L 0.7527 -1.92161998 0.75196998 -1.91796004 0 P 0 ;0
L 0.75196998 -1.91796004 0.75155 -1.91496004 0 P 0 ;0
L 0.75155 -1.91496004 0.75133002 -1.91193002 0 P 0 ;0
L 0.75133002 -1.91193002 0.75126998 -1.9085 0 P 0 ;0
L 0.75126998 -1.9085 0.75136004 -1.90506004 0 P 0 ;0
L 0.75136004 -1.90506004 0.75161004 -1.90181998 0 P 0 ;0
L 0.75161004 -1.90181998 0.752 -1.8986 0 P 0 ;0
L 0.752 -1.8986 0.75228996 -1.89701998 0 P 0 ;0
L 0.75228996 -1.89701998 0.75268996 -1.89546998 0 P 0 ;0
L 0.75268996 -1.89546998 0.7532 -1.89395 0 P 0 ;0
L 0.7532 -1.89395 0.75358996 -1.89281998 0 P 0 ;0
L 0.75358996 -1.89281998 0.75373002 -1.89231998 0 P 0 ;0
L 0.75373002 -1.89231998 0.75383996 -1.8918 0 P 0 ;0
L 0.75383996 -1.8918 0.75391998 -1.89138996 0 P 0 ;0
L 0.75391998 -1.89138996 0.75396998 -1.89098996 0 P 0 ;0
L 0.75396998 -1.89098996 0.75396998 -1.89086004 0 P 0 ;0
L 0.75396998 -1.89086004 0.75393996 -1.89076998 0 P 0 ;0
L 0.75393996 -1.89076998 0.7539 -1.89071004 0 P 0 ;0
L 0.7539 -1.89071004 0.75386004 -1.89066998 0 P 0 ;0
L 0.75386004 -1.89066998 0.75381004 -1.89063002 0 P 0 ;0
L 0.75381004 -1.89063002 0.75378996 -1.89061004 0 P 0 ;0
L 0.75378996 -1.89061004 0.75373002 -1.89058996 0 P 0 ;0
L 0.75373002 -1.89058996 0.75368002 -1.89056998 0 P 0 ;0
L 0.75368002 -1.89056998 0.75356004 -1.89056998 0 P 0 ;0
L 0.75356004 -1.89056998 0.75346998 -1.8906 0 P 0 ;0
L 0.75346998 -1.8906 0.74898002 -1.8927 0 P 0 ;0
L 0.74898002 -1.8927 0.74383002 -1.89518002 0 P 0 ;0
L 0.74383002 -1.89518002 0.73781004 -1.8982 0 P 0 ;0
L 0.69776998 -2.22761998 0.96701004 -2.22761998 0 P 0 ;0
L 0.6957 -2.22661998 0.96968996 -2.22661998 0 P 0 ;0
L 0.69366998 -2.22561998 0.97238002 -2.22561998 0 P 0 ;0
L 0.69163002 -2.22461998 0.97506004 -2.22461998 0 P 0 ;0
L 0.68958996 -2.22361998 0.97775 -2.22361998 0 P 0 ;0
L 0.68756004 -2.22261998 0.98043002 -2.22261998 0 P 0 ;0
L 0.68551998 -2.22161998 0.98311004 -2.22161998 0 P 0 ;0
L 0.68348996 -2.22061998 0.9858 -2.22061998 0 P 0 ;0
L 0.68176998 -2.21961998 0.98848002 -2.21961998 0 P 0 ;0
L 0.68003996 -2.21861998 0.99116998 -2.21861998 0 P 0 ;0
L 0.67831004 -2.21761998 0.99385 -2.21761998 0 P 0 ;0
L 0.67658002 -2.21661998 0.99653996 -2.21661998 0 P 0 ;0
L 0.67485 -2.21561998 0.99908002 -2.21561998 0 P 0 ;0
L 0.67311998 -2.21461998 0.87665 -2.21461998 0 P 0 ;0
L 0.6714 -2.21361998 0.85166004 -2.21361998 0 P 0 ;0
L 0.6699 -2.21261998 0.84083002 -2.21261998 0 P 0 ;0
L 0.66845 -2.21161998 0.8334 -2.21161998 0 P 0 ;0
L 0.66698996 -2.21061998 0.8274 -2.21061998 0 P 0 ;0
L 0.66553002 -2.20961998 0.82138996 -2.20961998 0 P 0 ;0
L 0.66406998 -2.20861998 0.81583002 -2.20861998 0 P 0 ;0
L 0.66261998 -2.20761998 0.81143996 -2.20761998 0 P 0 ;0
L 0.66116004 -2.20661998 0.80706004 -2.20661998 0 P 0 ;0
L 0.6597 -2.20561998 0.80266998 -2.20561998 0 P 0 ;0
L 0.65841004 -2.20461998 0.79828996 -2.20461998 0 P 0 ;0
L 0.65716998 -2.20361998 0.79448996 -2.20361998 0 P 0 ;0
L 0.65593002 -2.20261998 0.79106004 -2.20261998 0 P 0 ;0
L 0.65468996 -2.20161998 0.78763996 -2.20161998 0 P 0 ;0
L 0.83143002 -2.25261998 0.80871998 -2.25225 0 P 0 ;0
L 0.80871998 -2.25225 0.78691998 -2.25066998 0 P 0 ;0
L 0.78691998 -2.25066998 0.76525 -2.24786998 0 P 0 ;0
L 0.76525 -2.24786998 0.74581998 -2.24403996 0 P 0 ;0
L 0.74581998 -2.24403996 0.72671004 -2.23876004 0 P 0 ;0
L 0.72671004 -2.23876004 0.71196004 -2.23356998 0 P 0 ;0
L 0.71196004 -2.23356998 0.69756998 -2.22753996 0 P 0 ;0
L 0.69756998 -2.22753996 0.68355 -2.22066004 0 P 0 ;0
L 0.68355 -2.22066004 0.67118002 -2.2135 0 P 0 ;0
L 0.67118002 -2.2135 0.65938996 -2.20541004 0 P 0 ;0
L 0.65938996 -2.20541004 0.64825 -2.19643996 0 P 0 ;0
L 0.64825 -2.19643996 0.63861998 -2.18731998 0 P 0 ;0
L 0.63861998 -2.18731998 0.62983002 -2.17746998 0 P 0 ;0
L 0.62983002 -2.17746998 0.62188996 -2.1669 0 P 0 ;0
L 0.62188996 -2.1669 0.61678002 -2.15886998 0 P 0 ;0
L 0.61678002 -2.15886998 0.6123 -2.15056004 0 P 0 ;0
L 0.6123 -2.15056004 0.60841998 -2.14193996 0 P 0 ;0
L 0.60841998 -2.14193996 0.60516998 -2.13306998 0 P 0 ;0
L 0.60516998 -2.13306998 0.60191004 -2.12171004 0 P 0 ;0
L 0.60191004 -2.12171004 0.60075 -2.11648002 0 P 0 ;0
L 0.60075 -2.11648002 0.59983996 -2.11121004 0 P 0 ;0
L 0.59983996 -2.11121004 0.59913996 -2.10576004 0 P 0 ;0
L 0.59913996 -2.10576004 0.59868996 -2.10026004 0 P 0 ;0
L 0.59868996 -2.10026004 0.59833002 -2.0875 0 P 0 ;0
L 0.59833002 -2.0875 0.59856998 -2.07843996 0 P 0 ;0
L 0.59856998 -2.07843996 0.59923996 -2.0695 0 P 0 ;0
L 0.59923996 -2.0695 0.60031998 -2.06153996 0 P 0 ;0
L 0.60031998 -2.06153996 0.60193002 -2.05368996 0 P 0 ;0
L 0.60193002 -2.05368996 0.60416004 -2.04566004 0 P 0 ;0
L 0.60416004 -2.04566004 0.60688996 -2.03786004 0 P 0 ;0
L 0.60688996 -2.03786004 0.6148 -2.01961004 0 P 0 ;0
L 0.6148 -2.01961004 0.62108996 -2.00753002 0 P 0 ;0
L 0.62108996 -2.00753002 0.62811998 -1.99591998 0 P 0 ;0
L 0.62811998 -1.99591998 0.63583996 -1.98478996 0 P 0 ;0
L 0.63583996 -1.98478996 0.64936998 -1.96808002 0 P 0 ;0
L 0.64936998 -1.96808002 0.66418002 -1.95256998 0 P 0 ;0
L 0.66418002 -1.95256998 0.68098002 -1.93756004 0 P 0 ;0
L 0.68098002 -1.93756004 0.69881998 -1.92398002 0 P 0 ;0
L 0.69881998 -1.92398002 0.71841998 -1.91123996 0 P 0 ;0
L 0.71841998 -1.91123996 0.73875 -1.89996998 0 P 0 ;0
L 0.73875 -1.89996998 0.74471004 -1.89696998 0 P 0 ;0
L 0.74471004 -1.89696998 0.74983002 -1.89451004 0 P 0 ;0
L 0.74983002 -1.89451004 0.7511 -1.89391004 0 P 0 ;0
L 0.7511 -1.89391004 0.75076998 -1.89488996 0 P 0 ;0
L 0.75076998 -1.89488996 0.75033996 -1.89658996 0 P 0 ;0
L 0.75033996 -1.89658996 0.75003002 -1.8983 0 P 0 ;0
L 0.75003002 -1.8983 0.74961998 -1.90161998 0 P 0 ;0
L 0.74961998 -1.90161998 0.74936004 -1.90496004 0 P 0 ;0
L 0.74936004 -1.90496004 0.74926998 -1.9085 0 P 0 ;0
L 0.74926998 -1.9085 0.74933002 -1.91201998 0 P 0 ;0
L 0.74933002 -1.91201998 0.74956004 -1.91516998 0 P 0 ;0
L 0.74956004 -1.91516998 0.75 -1.91828996 0 P 0 ;0
L 0.75 -1.91828996 0.75075 -1.92205 0 P 0 ;0
L 0.75075 -1.92205 0.75166004 -1.92573996 0 P 0 ;0
L 0.75166004 -1.92573996 0.7527 -1.92916998 0 P 0 ;0
L 0.7527 -1.92916998 0.75393996 -1.93253002 0 P 0 ;0
L 0.75393996 -1.93253002 0.75536004 -1.93581998 0 P 0 ;0
L 0.75536004 -1.93581998 0.75696004 -1.939 0 P 0 ;0
L 0.75696004 -1.939 0.75885 -1.94231004 0 P 0 ;0
L 0.75885 -1.94231004 0.76083996 -1.94543996 0 P 0 ;0
L 0.76083996 -1.94543996 0.76338996 -1.94933996 0 P 0 ;0
L 0.76338996 -1.94933996 0.76371998 -1.94991998 0 P 0 ;0
L 0.76371998 -1.94991998 0.76401004 -1.9505 0 P 0 ;0
L 0.76401004 -1.9505 0.76423996 -1.95103002 0 P 0 ;0
L 0.76423996 -1.95103002 0.76408996 -1.95111004 0 P 0 ;0
L 0.76408996 -1.95111004 0.76348996 -1.95151004 0 P 0 ;0
L 0.76348996 -1.95151004 0.76021004 -1.95386004 0 P 0 ;0
L 0.76021004 -1.95386004 0.7602 -1.95386998 0 P 0 ;0
L 0.7602 -1.95386998 0.75636998 -1.95666004 0 P 0 ;0
L 0.75636998 -1.95666004 0.75636004 -1.95666998 0 P 0 ;0
L 0.75636004 -1.95666998 0.75635 -1.95666998 0 P 0 ;0
L 0.75635 -1.95666998 0.75208996 -1.95981004 0 P 0 ;0
L 0.75208996 -1.95981004 0.73841004 -1.97066998 0 P 0 ;0
L 0.73841004 -1.97066998 0.72541004 -1.98241004 0 P 0 ;0
L 0.72541004 -1.98241004 0.7143 -1.994 0 P 0 ;0
L 0.7143 -1.994 0.71425 -1.99406004 0 P 0 ;0
L 0.71425 -1.99406004 0.70413996 -2.00648002 0 P 0 ;0
L 0.70413996 -2.00648002 0.69836998 -2.01468996 0 P 0 ;0
L 0.69836998 -2.01468996 0.69313002 -2.02318002 0 P 0 ;0
L 0.69313002 -2.02318002 0.68838996 -2.03196004 0 P 0 ;0
L 0.68838996 -2.03196004 0.68438996 -2.04063996 0 P 0 ;0
L 0.68438996 -2.04063996 0.68098996 -2.04958002 0 P 0 ;0
L 0.68098996 -2.04958002 0.6782 -2.05873002 0 P 0 ;0
L 0.6782 -2.05873002 0.67706004 -2.06366004 0 P 0 ;0
L 0.67706004 -2.06366004 0.67628996 -2.06866998 0 P 0 ;0
L 0.67628996 -2.06866998 0.67538002 -2.08068996 0 P 0 ;0
L 0.67538002 -2.08068996 0.67546004 -2.09268996 0 P 0 ;0
L 0.67546004 -2.09268996 0.67588996 -2.09766998 0 P 0 ;0
L 0.67588996 -2.09766998 0.6767 -2.10258996 0 P 0 ;0
L 0.6767 -2.10258996 0.67881998 -2.11111998 0 P 0 ;0
L 0.67881998 -2.11111998 0.68163996 -2.11936004 0 P 0 ;0
L 0.68163996 -2.11936004 0.68516004 -2.12731998 0 P 0 ;0
L 0.68516004 -2.12731998 0.68935 -2.13493996 0 P 0 ;0
L 0.68935 -2.13493996 0.69418002 -2.14216998 0 P 0 ;0
L 0.69418002 -2.14216998 0.70153002 -2.15135 0 P 0 ;0
L 0.70153002 -2.15135 0.7096 -2.15983002 0 P 0 ;0
L 0.7096 -2.15983002 0.71836004 -2.16758996 0 P 0 ;0
L 0.71836004 -2.16758996 0.71843002 -2.16763996 0 P 0 ;0
L 0.71843002 -2.16763996 0.72773996 -2.17456004 0 P 0 ;0
L 0.72773996 -2.17456004 0.73926998 -2.1818 0 P 0 ;0
L 0.73926998 -2.1818 0.75121004 -2.18818002 0 P 0 ;0
L 0.75121004 -2.18818002 0.75128002 -2.18821004 0 P 0 ;0
L 0.75128002 -2.18821004 0.76358002 -2.19368996 0 P 0 ;0
L 0.76358002 -2.19368996 0.77628002 -2.19831004 0 P 0 ;0
L 0.77628002 -2.19831004 0.79658996 -2.20423996 0 P 0 ;0
L 0.79658996 -2.20423996 0.81701004 -2.20888996 0 P 0 ;0
L 0.81701004 -2.20888996 0.83763996 -2.21233002 0 P 0 ;0
L 0.83763996 -2.21233002 0.85388002 -2.21383002 0 P 0 ;0
L 0.85388002 -2.21383002 0.87733996 -2.21465 0 P 0 ;0
L 0.87733996 -2.21465 0.90118002 -2.21478996 0 P 0 ;0
L 0.90118002 -2.21478996 0.91906004 -2.21398996 0 P 0 ;0
L 0.91906004 -2.21398996 0.94908996 -2.21068002 0 P 0 ;0
L 0.94908996 -2.21068002 0.98176998 -2.2053 0 P 0 ;0
L 0.98176998 -2.2053 1.01575 -2.19815 0 P 0 ;0
L 1.01575 -2.19815 1.04968002 -2.18943002 0 P 0 ;0
L 1.04968002 -2.18943002 1.05633996 -2.18761004 0 P 0 ;0
L 1.05633996 -2.18761004 1.05713996 -2.1874 0 P 0 ;0
L 1.05713996 -2.1874 1.05483002 -2.18875 0 P 0 ;0
L 1.05483002 -2.18875 1.04298996 -2.19526004 0 P 0 ;0
L 1.04298996 -2.19526004 1.03096998 -2.20136998 0 P 0 ;0
L 1.03096998 -2.20136998 0.99835 -2.21595 0 P 0 ;0
L 0.99835 -2.21595 0.96401998 -2.22873996 0 P 0 ;0
L 0.96401998 -2.22873996 0.92993996 -2.23908002 0 P 0 ;0
L 0.92993996 -2.23908002 0.89816004 -2.24626004 0 P 0 ;0
L 0.89816004 -2.24626004 0.87616004 -2.24965 0 P 0 ;0
L 0.87616004 -2.24965 0.85405 -2.25176004 0 P 0 ;0
L 0.85405 -2.25176004 0.83143002 -2.25261998 0 P 0 ;0
L 0.65345 -2.20061998 0.78421004 -2.20061998 0 P 0 ;0
L 0.65221004 -2.19961998 0.78078002 -2.19961998 0 P 0 ;0
L 0.65096004 -2.19861998 0.77735 -2.19861998 0 P 0 ;0
L 0.64971998 -2.19761998 0.77438996 -2.19761998 0 P 0 ;0
L 0.64848002 -2.19661998 0.77163996 -2.19661998 0 P 0 ;0
L 0.64738996 -2.19561998 0.76888996 -2.19561998 0 P 0 ;0
L 0.64633996 -2.19461998 0.76613996 -2.19461998 0 P 0 ;0
L 0.64528002 -2.19361998 0.76343002 -2.19361998 0 P 0 ;0
L 0.64421998 -2.19261998 0.76118996 -2.19261998 0 P 0 ;0
L 0.64316998 -2.19161998 0.75893996 -2.19161998 0 P 0 ;0
L 0.64211004 -2.19061998 0.7567 -2.19061998 0 P 0 ;0
L 0.64106004 -2.18961998 0.75446004 -2.18961998 0 P 0 ;0
L 0.64 -2.18861998 0.75221004 -2.18861998 0 P 0 ;0
L 0.63895 -2.18761998 0.75018002 -2.18761998 0 P 0 ;0
L 0.63801004 -2.18661998 0.74831004 -2.18661998 0 P 0 ;0
L 0.63711004 -2.18561998 0.74643002 -2.18561998 0 P 0 ;0
L 0.63621998 -2.18461998 0.74456004 -2.18461998 0 P 0 ;0
L 0.63533002 -2.18361998 0.74268002 -2.18361998 0 P 0 ;0
L 0.63443996 -2.18261998 0.74081004 -2.18261998 0 P 0 ;0
L 0.63353996 -2.18161998 0.73898996 -2.18161998 0 P 0 ;0
L 0.63265 -2.18061998 0.73738996 -2.18061998 0 P 0 ;0
L 0.63176004 -2.17961998 0.7358 -2.17961998 0 P 0 ;0
L 0.63086998 -2.17861998 0.73421004 -2.17861998 0 P 0 ;0
L 0.62996998 -2.17761998 0.73261998 -2.17761998 0 P 0 ;0
L 0.6292 -2.17661998 0.73103002 -2.17661998 0 P 0 ;0
L 0.62845 -2.17561998 0.72943996 -2.17561998 0 P 0 ;0
L 0.6277 -2.17461998 0.72783996 -2.17461998 0 P 0 ;0
L 0.62693996 -2.17361998 0.72648002 -2.17361998 0 P 0 ;0
L 0.62618996 -2.17261998 0.72513996 -2.17261998 0 P 0 ;0
L 0.62543996 -2.17161998 0.72378996 -2.17161998 0 P 0 ;0
L 0.62468996 -2.17061998 0.72245 -2.17061998 0 P 0 ;0
L 0.62393996 -2.16961998 0.7211 -2.16961998 0 P 0 ;0
L 0.62318002 -2.16861998 0.71976004 -2.16861998 0 P 0 ;0
L 0.62243996 -2.16761998 0.71841004 -2.16761998 0 P 0 ;0
L 0.62171004 -2.16661998 0.71726998 -2.16661998 0 P 0 ;0
L 0.62108002 -2.16561998 0.71613996 -2.16561998 0 P 0 ;0
L 0.62043996 -2.16461998 0.71501004 -2.16461998 0 P 0 ;0
L 0.61981004 -2.16361998 0.71388002 -2.16361998 0 P 0 ;0
L 0.61916998 -2.16261998 0.71276004 -2.16261998 0 P 0 ;0
L 0.61853002 -2.16161998 0.71163002 -2.16161998 0 P 0 ;0
L 0.6179 -2.16061998 0.7105 -2.16061998 0 P 0 ;0
L 0.61726004 -2.15961998 0.7094 -2.15961998 0 P 0 ;0
L 0.61665 -2.15861998 0.70845 -2.15861998 0 P 0 ;0
L 0.61611004 -2.15761998 0.7075 -2.15761998 0 P 0 ;0
L 0.75383996 -2.24561998 0.901 -2.24561998 0 P 0 ;0
L 0.74876998 -2.24461998 0.90541998 -2.24461998 0 P 0 ;0
L 0.74431004 -2.24361998 0.90985 -2.24361998 0 P 0 ;0
L 0.7407 -2.24261998 0.91426998 -2.24261998 0 P 0 ;0
L 0.73708002 -2.24161998 0.9187 -2.24161998 0 P 0 ;0
L 0.73346998 -2.24061998 0.92311998 -2.24061998 0 P 0 ;0
L 0.72986004 -2.23961998 0.92753996 -2.23961998 0 P 0 ;0
L 0.72633996 -2.23861998 0.93145 -2.23861998 0 P 0 ;0
L 0.72348996 -2.23761998 0.93473996 -2.23761998 0 P 0 ;0
L 0.72063996 -2.23661998 0.93803996 -2.23661998 0 P 0 ;0
L 0.7178 -2.23561998 0.94133002 -2.23561998 0 P 0 ;0
L 0.71495 -2.23461998 0.94461998 -2.23461998 0 P 0 ;0
L 0.7121 -2.23361998 0.94791998 -2.23361998 0 P 0 ;0
L 0.70968996 -2.23261998 0.95121004 -2.23261998 0 P 0 ;0
L 0.70731004 -2.23161998 0.95451004 -2.23161998 0 P 0 ;0
L 0.70491998 -2.23061998 0.9578 -2.23061998 0 P 0 ;0
L 0.70253996 -2.22961998 0.9611 -2.22961998 0 P 0 ;0
L 0.70015 -2.22861998 0.96431998 -2.22861998 0 P 0 ;0
L 8.45 3.66615 8.45 3.71615 7 P 0 
L 8.5 3.76615 8.5 3.81615 7 P 0 
L 8.45 3.81615 8.45 3.86615 7 P 0 
L 8.5 3.46615 8.5 3.51615 7 P 0 
L 8.45 3.41615 8.45 3.46615 7 P 0 
L 8.5 3.61615 8.5 3.66615 7 P 0 
L 8.45 3.26615 8.45 3.31615 7 P 0 
L 8.5 3.31615 8.5 3.36615 7 P 0 
L 8.2 3.66615 8.2 3.71615 7 P 0 
L 8.35 3.66615 8.35 3.71615 7 P 0 
L 8.4 3.76615 8.4 3.81615 7 P 0 
L 8.35 3.81615 8.35 3.86615 7 P 0 
L 8.2 3.81615 8.2 3.86615 7 P 0 
L 8.4 3.46615 8.4 3.51615 7 P 0 
L 8.35 3.41615 8.35 3.46615 7 P 0 
L 8.2 3.41615 8.2 3.46615 7 P 0 
L 8.4 3.61615 8.4 3.66615 7 P 0 
L 8.35 3.26615 8.35 3.31615 7 P 0 
L 8.4 3.31615 8.4 3.36615 7 P 0 
L 8.2 3.26615 8.2 3.31615 7 P 0 
L 8.25 2.86615 8.3 2.86615 7 P 0 
L 8.1 3.66615 8.1 3.71615 7 P 0 
L 8.15 3.76615 8.15 3.81615 7 P 0 
L 8.1 3.81615 8.1 3.86615 7 P 0 
L 8.05 3.76615 8.05 3.81615 7 P 0 
L 8.1 3.41615 8.1 3.46615 7 P 0 
L 8.15 3.46615 8.15 3.51615 7 P 0 
L 8 3.46615 8 3.51615 7 P 0 
L 8.05 3.61615 8.05 3.66615 7 P 0 
L 8.15 3.61615 8.15 3.66615 7 P 0 
L 8.1 3.26615 8.1 3.31615 7 P 0 
L 8.15 3.31615 8.15 3.36615 7 P 0 
L 8.05 3.31615 8.05 3.36615 7 P 0 
L 5.42048002 1.91835 5.42048002 1.87835 7 P 0 
L 5.57531004 1.8508 5.57531004 1.8108 7 P 0 
L 2.34606004 3.26615 2.34606004 3.31615 7 P 0 
L 2.39606004 3.31615 2.39606004 3.36615 7 P 0 
L 2.44606004 3.26615 2.44606004 3.31615 7 P 0 
L 2.49606004 3.31615 2.49606004 3.36615 7 P 0 
L 2.49606004 3.46615 2.49606004 3.51615 7 P 0 
L 2.44606004 3.41615 2.44606004 3.46615 7 P 0 
L 2.39606004 3.46615 2.39606004 3.51615 7 P 0 
L 2.34606004 3.41615 2.34606004 3.46615 7 P 0 
L 2.19606004 3.26615 2.19606004 3.31615 7 P 0 
L 2.09606004 3.26615 2.09606004 3.31615 7 P 0 
L 2.14606004 3.31615 2.14606004 3.36615 7 P 0 
L 2.19606004 3.41615 2.19606004 3.46615 7 P 0 
L 2.09606004 3.41615 2.09606004 3.46615 7 P 0 
L 2.04606004 3.31615 2.04606004 3.36615 7 P 0 
L 2.14606004 3.46615 2.14606004 3.51615 7 P 0 
L 1.99606004 3.46615 1.99606004 3.51615 7 P 0 
L 2.04606004 3.61615 2.04606004 3.66615 7 P 0 
L 2.09606004 3.66615 2.09606004 3.71615 7 P 0 
L 2.14606004 3.61615 2.14606004 3.66615 7 P 0 
L 2.19606004 3.66615 2.19606004 3.71615 7 P 0 
L 2.49606004 3.61615 2.49606004 3.66615 7 P 0 
L 2.34606004 3.66615 2.34606004 3.71615 7 P 0 
L 2.39606004 3.61615 2.39606004 3.66615 7 P 0 
L 2.44606004 3.66615 2.44606004 3.71615 7 P 0 
L 2.49606004 3.76615 2.49606004 3.81615 7 P 0 
L 2.44606004 3.81615 2.44606004 3.86615 7 P 0 
L 2.39606004 3.76615 2.39606004 3.81615 7 P 0 
L 2.34606004 3.81615 2.34606004 3.86615 7 P 0 
L 2.14606004 3.76615 2.14606004 3.81615 7 P 0 
L 2.19606004 3.81615 2.19606004 3.86615 7 P 0 
L 2.09606004 3.81615 2.09606004 3.86615 7 P 0 
L 2.04606004 3.76615 2.04606004 3.81615 7 P 0 
L 2.24606004 2.86615 2.29606004 2.86615 7 P 0 
L 5.42048002 1.6433 5.42048002 1.6033 7 P 0 
L 5.57531004 1.7118 5.57531004 1.6718 7 P 0 
L 5.42048002 1.7796 5.42048002 1.7396 7 P 0 
L 5.57531004 1.9869 5.57531004 1.9469 7 P 0 
L 5.42048002 2.0547 5.42048002 2.0147 7 P 0 
L 5.57531004 2.1278 5.57531004 2.0878 7 P 0 
L 5.42048002 2.1954 5.42048002 2.1554 7 P 0 
L 5.57531004 2.2632 5.57531004 2.2232 7 P 0 
L 5.42048002 2.3308 5.42048002 2.2908 7 P 0 
L 5.57531004 2.3986 5.57531004 2.3586 7 P 0 
L 5.42048002 2.4662 5.42048002 2.4262 7 P 0 
L 5.57531004 2.5378 5.57531004 2.4978 7 P 0 
L 5.57531004 2.673 5.57531004 2.633 7 P 0 
L 5.42048002 2.6054 5.42048002 2.5654 7 P 0 
L 10.09 2.73655 10.09 2.69655 7 P 0 
L 9.975 2.66445 9.975 2.62445 7 P 0 
L 9.975 2.5109 9.975 2.4709 7 P 0 
L 10.09 2.57845 10.09 2.53845 7 P 0 
L 10.09 2.44335 10.09 2.40335 7 P 0 
L 9.975 2.3758 9.975 2.3358 7 P 0 
L 10.09 2.30825 10.09 2.26825 7 P 0 
L 9.975 2.23955 9.975 2.19955 7 P 0 
L 10.09 2.17095 10.09 2.13095 7 P 0 
L 10.09 2.05655 10.09 2.01655 7 P 0 
L 10.225 1.96645 10.225 1.92645 7 P 0 
L 10.26025 1.86845 10.26025 1.82845 7 P 0 
L 10.26 1.70445 10.26 1.66445 7 P 0 
L 10.35543996 1.52156004 10.38371998 1.49328002 8 P 0 
L 10.46445 1.395 10.42445 1.395 7 P 0 
L 10.395 1.28555 10.395 1.32555 7 P 0 
L 11.53316004 1.412 11.53316004 1.452 7 P 0 
L 11.73316004 1.492 11.73316004 1.532 7 P 0 
L 11.53316004 1.572 11.53316004 1.612 7 P 0 
L 11.78316004 1.652 11.78316004 1.692 7 P 0 
L 11.53316004 1.732 11.53316004 1.772 7 P 0 
L 11.73316004 1.812 11.73316004 1.852 7 P 0 
L 11.53316004 1.892 11.53316004 1.932 7 P 0 
L 11.53316004 2.052 11.53316004 2.092 7 P 0 
L 11.73316004 1.972 11.73316004 2.012 7 P 0 
L 11.73316004 2.132 11.73316004 2.172 7 P 0 
L 11.83316004 2.212 11.83316004 2.252 7 P 0 
L 11.73316004 2.292 11.73316004 2.332 7 P 0 
L 11.53316004 2.372 11.53316004 2.412 7 P 0 
L 11.53316004 2.532 11.53316004 2.572 7 P 0 
L 11.73316004 2.452 11.73316004 2.492 7 P 0 
L 11.73316004 2.612 11.73316004 2.652 7 P 0 
L 8.98115 2.825 8.98115 2.865 7 P 0 
L 2.97721004 2.825 2.97721004 2.865 7 P 0 
L 11.03661004 2.46615 11.03661004 2.51615 7 P 0 
L 11.08661004 2.21615 11.08661004 2.26615 7 P 0 
L 10.98661004 2.21615 10.98661004 2.26615 7 P 0 
L 11.03661004 2.26615 11.03661004 2.31615 7 P 0 
L 10.93661004 2.26615 10.93661004 2.31615 7 P 0 
L 10.98661004 2.36615 10.98661004 2.41615 7 P 0 
L 10.93661004 2.41615 10.93661004 2.46615 7 P 0 
L 11.08661004 2.36615 11.08661004 2.41615 7 P 0 
L 10.93661004 2.01615 10.93661004 2.06615 7 P 0 
L 10.98661004 2.06615 10.98661004 2.11615 7 P 0 
L 11.03661004 2.01615 11.03661004 2.06615 7 P 0 
L 11.08661004 2.06615 11.08661004 2.11615 7 P 0 
L 10.93661004 1.86615 10.93661004 1.91615 7 P 0 
L 11.03661004 1.86615 11.03661004 1.91615 7 P 0 
L 10.98661004 1.91615 10.98661004 1.96615 7 P 0 
L 11.08661004 1.91615 11.08661004 1.96615 7 P 0 
L 10.73661004 2.46615 10.73661004 2.41615 7 P 0 
L 10.68661004 2.41615 10.68661004 2.36615 7 P 0 
L 10.68661004 2.26615 10.68661004 2.21615 7 P 0 
L 10.73661004 2.31615 10.73661004 2.26615 7 P 0 
L 10.68661004 2.11615 10.68661004 2.06615 7 P 0 
L 10.83661004 2.16615 10.88661004 2.16615 7 P 0 
L 10.73661004 2.01615 10.73661004 2.06615 7 P 0 
L 10.68661004 1.91615 10.68661004 1.96615 7 P 0 
L 10.73661004 1.86615 10.73661004 1.91615 7 P 0 
L 10.63661004 2.46615 10.63661004 2.41615 7 P 0 
L 10.58661004 2.41615 10.58661004 2.36615 7 P 0 
L 10.63661004 2.31615 10.63661004 2.26615 7 P 0 
L 10.58661004 2.26615 10.58661004 2.21615 7 P 0 
L 10.58661004 2.11615 10.58661004 2.06615 7 P 0 
L 10.63661004 2.01615 10.63661004 2.06615 7 P 0 
L 10.58661004 1.91615 10.58661004 1.96615 7 P 0 
L 10.63661004 1.86615 10.63661004 1.91615 7 P 0 
L 0.69348996 1.86611998 0.69348996 1.90611998 7 P 0 
L 5.03268002 2.46615 5.03268002 2.51615 7 P 0 
L 5.08268002 2.36615 5.08268002 2.41615 7 P 0 
L 4.93268002 2.41615 4.93268002 2.46615 7 P 0 
L 4.98268002 2.36615 4.98268002 2.41615 7 P 0 
L 4.93268002 2.26615 4.93268002 2.31615 7 P 0 
L 5.03268002 2.26615 5.03268002 2.31615 7 P 0 
L 4.98268002 2.21615 4.98268002 2.26615 7 P 0 
L 5.08268002 2.21615 5.08268002 2.26615 7 P 0 
L 5.08268002 2.06615 5.08268002 2.11615 7 P 0 
L 5.03268002 2.01615 5.03268002 2.06615 7 P 0 
L 4.98268002 2.06615 4.98268002 2.11615 7 P 0 
L 4.93268002 2.01615 4.93268002 2.06615 7 P 0 
L 5.08268002 1.91615 5.08268002 1.96615 7 P 0 
L 4.98268002 1.91615 4.98268002 1.96615 7 P 0 
L 5.03268002 1.86615 5.03268002 1.91615 7 P 0 
L 4.93268002 1.86615 4.93268002 1.91615 7 P 0 
L 4.73268002 1.86615 4.73268002 1.91615 7 P 0 
L 4.63268002 1.86615 4.63268002 1.91615 7 P 0 
L 4.68268002 1.91615 4.68268002 1.96615 7 P 0 
L 4.58268002 1.91615 4.58268002 1.96615 7 P 0 
L 4.63268002 2.01615 4.63268002 2.06615 7 P 0 
L 4.73268002 2.01615 4.73268002 2.06615 7 P 0 
L 4.83268002 2.16615 4.88268002 2.16615 7 P 0 
L 4.58268002 2.11615 4.58268002 2.06615 7 P 0 
L 4.68268002 2.11615 4.68268002 2.06615 7 P 0 
L 4.73268002 2.31615 4.73268002 2.26615 7 P 0 
L 4.68268002 2.26615 4.68268002 2.21615 7 P 0 
L 4.58268002 2.26615 4.58268002 2.21615 7 P 0 
L 4.63268002 2.31615 4.63268002 2.26615 7 P 0 
L 4.58268002 2.41615 4.58268002 2.36615 7 P 0 
L 4.68268002 2.41615 4.68268002 2.36615 7 P 0 
L 4.63268002 2.46615 4.63268002 2.41615 7 P 0 
L 4.73268002 2.46615 4.73268002 2.41615 7 P 0 
A 12.75476004 4.52361998 12.75476004 4.52361998 12.73621004 4.52361998 4 P 0 N
A 12.8335 4.48425 12.8335 4.48425 12.81495 4.48425 4 P 0 N
L 12.73621004 4.52361998 12.81495 4.48425 10 P 0 
L 12.73621004 4.36613996 12.81495 4.32676998 10 P 0 
A 12.8335 4.32676998 12.8335 4.32676998 12.81495 4.32676998 4 P 0 N
A 12.75476004 4.36613996 12.75476004 4.36613996 12.73621004 4.36613996 4 P 0 N
L 12.73621004 4.20866004 12.81495 4.16928996 10 P 0 
A 12.8335 4.16928996 12.8335 4.16928996 12.81495 4.16928996 4 P 0 N
A 12.75476004 4.20866004 12.75476004 4.20866004 12.73621004 4.20866004 4 P 0 N
L 12.73621004 4.05118002 12.81495 4.01181004 10 P 0 
A 12.8335 4.01181004 12.8335 4.01181004 12.81495 4.01181004 4 P 0 N
A 12.75476004 4.05118002 12.75476004 4.05118002 12.73621004 4.05118002 4 P 0 N
L 12.73621004 3.8937 12.81495 3.85433002 10 P 0 
A 12.8335 3.85433002 12.8335 3.85433002 12.81495 3.85433002 4 P 0 N
A 12.75476004 3.8937 12.75476004 3.8937 12.73621004 3.8937 4 P 0 N
A 12.75476004 3.73621998 12.75476004 3.73621998 12.73621004 3.73621998 4 P 0 N
L 12.73621004 3.73621998 12.81495 3.69685 10 P 0 
A 12.8335 3.69685 12.8335 3.69685 12.81495 3.69685 4 P 0 N
L 12.73621004 3.57873996 12.81495 3.53936998 10 P 0 
A 12.8335 3.53936998 12.8335 3.53936998 12.81495 3.53936998 4 P 0 N
A 12.75476004 3.57873996 12.75476004 3.57873996 12.73621004 3.57873996 4 P 0 N
L 12.73621004 3.42126004 12.81495 3.38188996 10 P 0 
A 12.8335 3.38188996 12.8335 3.38188996 12.81495 3.38188996 4 P 0 N
A 12.75476004 3.42126004 12.75476004 3.42126004 12.73621004 3.42126004 4 P 0 N
A 12.8335 3.22441004 12.8335 3.22441004 12.81495 3.22441004 4 P 0 N
L 12.73621004 3.02756004 12.81495 3.06693002 10 P 0 
A 12.8335 3.06693002 12.8335 3.06693002 12.81495 3.06693002 4 P 0 N
A 12.75476004 3.02756004 12.75476004 3.02756004 12.73621004 3.02756004 4 P 0 N
L 12.73621004 3.18503996 12.81495 3.22441004 10 P 0 
A 12.75476004 3.18503996 12.75476004 3.18503996 12.73621004 3.18503996 4 P 0 N
A 12.8335 2.75196998 12.8335 2.75196998 12.81495 2.75196998 4 P 0 N
L 12.73621004 2.87008002 12.81495 2.90945 10 P 0 
A 12.8335 2.90945 12.8335 2.90945 12.81495 2.90945 4 P 0 N
A 12.75476004 2.87008002 12.75476004 2.87008002 12.73621004 2.87008002 4 P 0 N
A 12.8335 2.51575 12.8335 2.51575 12.81495 2.51575 4 P 0 N
A 12.75476004 2.47638002 12.75476004 2.47638002 12.73621004 2.47638002 4 P 0 N
L 12.73621004 2.7126 12.81495 2.75196998 10 P 0 
A 12.75476004 2.7126 12.75476004 2.7126 12.73621004 2.7126 4 P 0 N
L 12.73621004 2.3189 12.81495 2.35826998 10 P 0 
A 12.8335 2.35826998 12.8335 2.35826998 12.81495 2.35826998 4 P 0 N
A 12.75476004 2.3189 12.75476004 2.3189 12.73621004 2.3189 4 P 0 N
L 12.73621004 2.47638002 12.81495 2.51575 10 P 0 
A 12.75476004 2.00393996 12.75476004 2.00393996 12.73621004 2.00393996 4 P 0 N
L 12.73621004 2.16141998 12.81495 2.20078996 10 P 0 
A 12.8335 2.20078996 12.8335 2.20078996 12.81495 2.20078996 4 P 0 N
A 12.75476004 2.16141998 12.75476004 2.16141998 12.73621004 2.16141998 4 P 0 N
L 12.73621004 2.00393996 12.81495 1.96456998 10 P 0 
A 12.8335 1.96456998 12.8335 1.96456998 12.81495 1.96456998 4 P 0 N
L 12.55905 4.563 12.63778996 4.60236998 10 P 0 
A 12.65633996 4.60236998 12.65633996 4.60236998 12.63778996 4.60236998 4 P 0 N
A 12.5776 4.563 12.5776 4.563 12.55905 4.563 4 P 0 N
L 12.55905 4.24803002 12.63778996 4.2874 10 P 0 
A 12.65633996 4.2874 12.65633996 4.2874 12.63778996 4.2874 4 P 0 N
A 12.5776 4.24803002 12.5776 4.24803002 12.55905 4.24803002 4 P 0 N
L 12.55905 4.40551004 12.63778996 4.44488002 10 P 0 
A 12.65633996 4.44488002 12.65633996 4.44488002 12.63778996 4.44488002 4 P 0 N
A 12.5776 4.40551004 12.5776 4.40551004 12.55905 4.40551004 4 P 0 N
A 12.65633996 3.97243996 12.65633996 3.97243996 12.63778996 3.97243996 4 P 0 N
L 12.55905 4.09055 12.63778996 4.12991998 10 P 0 
A 12.65633996 4.12991998 12.65633996 4.12991998 12.63778996 4.12991998 4 P 0 N
A 12.5776 4.09055 12.5776 4.09055 12.55905 4.09055 4 P 0 N
L 12.55905 3.77558996 12.63778996 3.81496004 10 P 0 
A 12.65633996 3.81496004 12.65633996 3.81496004 12.63778996 3.81496004 4 P 0 N
A 12.5776 3.77558996 12.5776 3.77558996 12.55905 3.77558996 4 P 0 N
L 12.55905 3.93306998 12.63778996 3.97243996 10 P 0 
A 12.5776 3.93306998 12.5776 3.93306998 12.55905 3.93306998 4 P 0 N
A 12.65633996 3.5 12.65633996 3.5 12.63778996 3.5 4 P 0 N
L 12.55905 3.61811004 12.63778996 3.65748002 10 P 0 
A 12.65633996 3.65748002 12.65633996 3.65748002 12.63778996 3.65748002 4 P 0 N
A 12.5776 3.61811004 12.5776 3.61811004 12.55905 3.61811004 4 P 0 N
L 12.55905 3.30315 12.63778996 3.26378002 10 P 0 
A 12.65633996 3.26378002 12.65633996 3.26378002 12.63778996 3.26378002 4 P 0 N
A 12.5776 3.30315 12.5776 3.30315 12.55905 3.30315 4 P 0 N
L 12.55905 3.46063002 12.63778996 3.5 10 P 0 
A 12.5776 3.46063002 12.5776 3.46063002 12.55905 3.46063002 4 P 0 N
L 12.55905 3.14566998 12.63778996 3.1063 10 P 0 
A 12.65633996 3.1063 12.65633996 3.1063 12.63778996 3.1063 4 P 0 N
A 12.5776 3.14566998 12.5776 3.14566998 12.55905 3.14566998 4 P 0 N
A 12.5776 2.98818996 12.5776 2.98818996 12.55905 2.98818996 4 P 0 N
L 12.55905 2.98818996 12.63778996 2.94881998 10 P 0 
A 12.65633996 2.94881998 12.65633996 2.94881998 12.63778996 2.94881998 4 P 0 N
L 12.55905 2.83071004 12.63778996 2.79133996 10 P 0 
A 12.65633996 2.79133996 12.65633996 2.79133996 12.63778996 2.79133996 4 P 0 N
A 12.5776 2.83071004 12.5776 2.83071004 12.55905 2.83071004 4 P 0 N
L 12.55905 2.59448996 12.63778996 2.55511998 10 P 0 
A 12.65633996 2.55511998 12.65633996 2.55511998 12.63778996 2.55511998 4 P 0 N
A 12.5776 2.59448996 12.5776 2.59448996 12.55905 2.59448996 4 P 0 N
L 12.55905 2.43701004 12.63778996 2.39763996 10 P 0 
A 12.65633996 2.39763996 12.65633996 2.39763996 12.63778996 2.39763996 4 P 0 N
A 12.5776 2.43701004 12.5776 2.43701004 12.55905 2.43701004 4 P 0 N
L 12.55905 2.27953002 12.63778996 2.24016004 10 P 0 
A 12.65633996 2.24016004 12.65633996 2.24016004 12.63778996 2.24016004 4 P 0 N
A 12.5776 2.27953002 12.5776 2.27953002 12.55905 2.27953002 4 P 0 N
A 12.5776 2.04331004 12.5776 2.04331004 12.55905 2.04331004 4 P 0 N
A 12.65633996 2.08268002 12.65633996 2.08268002 12.63778996 2.08268002 4 P 0 N
L 12.55905 2.04331004 12.63778996 2.08268002 10 P 0 
L 12.55905 1.96456998 12.63778996 1.9252 10 P 0 
A 12.65633996 1.9252 12.65633996 1.9252 12.63778996 1.9252 4 P 0 N
A 12.5776 1.96456998 12.5776 1.96456998 12.55905 1.96456998 4 P 0 N
A 0.11303996 4.52363002 0.11303996 4.52363002 0.09448996 4.52363002 4 P 0 N
A 0.19178002 4.563 0.19178002 4.563 0.17323002 4.563 4 P 0 N
L 0.09448996 4.52363002 0.17323002 4.563 10 P 0 
A 0.11303996 4.36613996 0.11303996 4.36613996 0.09448996 4.36613996 4 P 0 N
A 0.19178002 4.40551004 0.19178002 4.40551004 0.17323002 4.40551004 4 P 0 N
L 0.09448996 4.36613996 0.17323002 4.40551004 10 P 0 
A 0.11303996 4.20866004 0.11303996 4.20866004 0.09448996 4.20866004 4 P 0 N
A 0.19178002 4.24803002 0.19178002 4.24803002 0.17323002 4.24803002 4 P 0 N
L 0.09448996 4.20866004 0.17323002 4.24803002 10 P 0 
A 0.11303996 4.05118002 0.11303996 4.05118002 0.09448996 4.05118002 4 P 0 N
A 0.19178002 4.09055 0.19178002 4.09055 0.17323002 4.09055 4 P 0 N
L 0.09448996 4.05118002 0.17323002 4.09055 10 P 0 
A 0.11303996 3.8937 0.11303996 3.8937 0.09448996 3.8937 4 P 0 N
A 0.19178002 3.93306998 0.19178002 3.93306998 0.17323002 3.93306998 4 P 0 N
L 0.09448996 3.8937 0.17323002 3.93306998 10 P 0 
A 0.11303996 3.73621998 0.11303996 3.73621998 0.09448996 3.73621998 4 P 0 N
A 0.19178002 3.77558996 0.19178002 3.77558996 0.17323002 3.77558996 4 P 0 N
L 0.09448996 3.73621998 0.17323002 3.77558996 10 P 0 
A 0.11303996 3.57873996 0.11303996 3.57873996 0.09448996 3.57873996 4 P 0 N
A 0.19178002 3.61811004 0.19178002 3.61811004 0.17323002 3.61811004 4 P 0 N
L 0.09448996 3.57873996 0.17323002 3.61811004 10 P 0 
A 0.11303996 3.42126004 0.11303996 3.42126004 0.09448996 3.42126004 4 P 0 N
A 0.19178002 3.46063002 0.19178002 3.46063002 0.17323002 3.46063002 4 P 0 N
L 0.09448996 3.42126004 0.17323002 3.46063002 10 P 0 
A 0.2902 3.14566998 0.2902 3.14566998 0.27165 3.14566998 4 P 0 N
A 0.36893996 3.18503996 0.36893996 3.18503996 0.35038996 3.18503996 4 P 0 N
L 0.27165 3.14566998 0.35038996 3.18503996 10 P 0 
A 0.2902 2.98818996 0.2902 2.98818996 0.27165 2.98818996 4 P 0 N
A 0.36893996 3.02756004 0.36893996 3.02756004 0.35038996 3.02756004 4 P 0 N
L 0.27165 2.98818996 0.35038996 3.02756004 10 P 0 
A 0.2902 2.83071004 0.2902 2.83071004 0.27165 2.83071004 4 P 0 N
A 0.36893996 2.87008002 0.36893996 2.87008002 0.35038996 2.87008002 4 P 0 N
L 0.27165 2.83071004 0.35038996 2.87008002 10 P 0 
A 0.2902 2.67323002 0.2902 2.67323002 0.27165 2.67323002 4 P 0 N
A 0.36893996 2.7126 0.36893996 2.7126 0.35038996 2.7126 4 P 0 N
L 0.27165 2.67323002 0.35038996 2.7126 10 P 0 
A 0.2902 2.43701004 0.2902 2.43701004 0.27165 2.43701004 4 P 0 N
A 0.36893996 2.47638002 0.36893996 2.47638002 0.35038996 2.47638002 4 P 0 N
L 0.27165 2.43701004 0.35038996 2.47638002 10 P 0 
A 0.2902 2.27953002 0.2902 2.27953002 0.27165 2.27953002 4 P 0 N
A 0.36893996 2.3189 0.36893996 2.3189 0.35038996 2.3189 4 P 0 N
L 0.27165 2.27953002 0.35038996 2.3189 10 P 0 
A 0.2902 2.12205 0.2902 2.12205 0.27165 2.12205 4 P 0 N
A 0.36893996 2.16141998 0.36893996 2.16141998 0.35038996 2.16141998 4 P 0 N
L 0.27165 2.12205 0.35038996 2.16141998 10 P 0 
L 0.09448996 2.00393996 0.17323002 2.04331004 10 P 0 
A 0.19178002 2.04331004 0.19178002 2.04331004 0.17323002 2.04331004 4 P 0 N
A 0.11303996 2.00393996 0.11303996 2.00393996 0.09448996 2.00393996 4 P 0 N
A 0.2902 1.96456998 0.2902 1.96456998 0.27165 1.96456998 4 P 0 N
A 0.36893996 1.9252 0.36893996 1.9252 0.35038996 1.9252 4 P 0 N
L 0.27165 1.96456998 0.35038996 1.9252 9 P 0 
A 0.11303996 1.9252 0.11303996 1.9252 0.09448996 1.9252 4 P 0 N
A 0.19178002 1.88583002 0.19178002 1.88583002 0.17323002 1.88583002 4 P 0 N
L 0.09448996 1.9252 0.17323002 1.88583002 10 P 0 
A 0.11303996 2.24016004 0.11303996 2.24016004 0.09448996 2.24016004 4 P 0 N
A 0.19178002 2.20078996 0.19178002 2.20078996 0.17323002 2.20078996 4 P 0 N
L 0.09448996 2.24016004 0.17323002 2.20078996 10 P 0 
A 0.11303996 2.39763996 0.11303996 2.39763996 0.09448996 2.39763996 4 P 0 N
A 0.19178002 2.35826998 0.19178002 2.35826998 0.17323002 2.35826998 4 P 0 N
L 0.09448996 2.39763996 0.17323002 2.35826998 10 P 0 
A 0.11303996 2.55511998 0.11303996 2.55511998 0.09448996 2.55511998 4 P 0 N
A 0.19178002 2.51575 0.19178002 2.51575 0.17323002 2.51575 4 P 0 N
L 0.09448996 2.55511998 0.17323002 2.51575 10 P 0 
A 0.11303996 2.79133996 0.11303996 2.79133996 0.09448996 2.79133996 4 P 0 N
A 0.19178002 2.75196998 0.19178002 2.75196998 0.17323002 2.75196998 4 P 0 N
L 0.09448996 2.79133996 0.17323002 2.75196998 10 P 0 
A 0.11303996 2.94881998 0.11303996 2.94881998 0.09448996 2.94881998 4 P 0 N
A 0.19178002 2.90945 0.19178002 2.90945 0.17323002 2.90945 4 P 0 N
L 0.09448996 2.94881998 0.17323002 2.90945 10 P 0 
A 0.11303996 3.1063 0.11303996 3.1063 0.09448996 3.1063 4 P 0 N
A 0.19178002 3.06693002 0.19178002 3.06693002 0.17323002 3.06693002 4 P 0 N
L 0.09448996 3.1063 0.17323002 3.06693002 10 P 0 
A 0.11303996 3.26378002 0.11303996 3.26378002 0.09448996 3.26378002 4 P 0 N
A 0.19178002 3.22441004 0.19178002 3.22441004 0.17323002 3.22441004 4 P 0 N
L 0.09448996 3.26378002 0.17323002 3.22441004 10 P 0 
A 0.2902 3.38188996 0.2902 3.38188996 0.27165 3.38188996 4 P 0 N
A 0.36893996 3.34251998 0.36893996 3.34251998 0.35038996 3.34251998 4 P 0 N
L 0.27165 3.38188996 0.35038996 3.34251998 10 P 0 
A 0.2902 3.53936998 0.2902 3.53936998 0.27165 3.53936998 4 P 0 N
A 0.36893996 3.5 0.36893996 3.5 0.35038996 3.5 4 P 0 N
L 0.27165 3.53936998 0.35038996 3.5 10 P 0 
A 0.2902 3.69685 0.2902 3.69685 0.27165 3.69685 4 P 0 N
A 0.36893996 3.65748002 0.36893996 3.65748002 0.35038996 3.65748002 4 P 0 N
L 0.27165 3.69685 0.35038996 3.65748002 10 P 0 
A 0.2902 3.85433002 0.2902 3.85433002 0.27165 3.85433002 4 P 0 N
A 0.36893996 3.81496004 0.36893996 3.81496004 0.35038996 3.81496004 4 P 0 N
L 0.27165 3.85433002 0.35038996 3.81496004 10 P 0 
A 0.2902 4.01181004 0.2902 4.01181004 0.27165 4.01181004 4 P 0 N
A 0.36893996 3.97243996 0.36893996 3.97243996 0.35038996 3.97243996 4 P 0 N
L 0.27165 4.01181004 0.35038996 3.97243996 10 P 0 
A 0.2902 4.16928996 0.2902 4.16928996 0.27165 4.16928996 4 P 0 N
A 0.36893996 4.12991998 0.36893996 4.12991998 0.35038996 4.12991998 4 P 0 N
L 0.27165 4.16928996 0.35038996 4.12991998 10 P 0 
A 0.2902 4.32676998 0.2902 4.32676998 0.27165 4.32676998 4 P 0 N
A 0.36893996 4.2874 0.36893996 4.2874 0.35038996 4.2874 4 P 0 N
L 0.27165 4.32676998 0.35038996 4.2874 10 P 0 
L 0.27165 4.48425 0.35038996 4.44488002 10 P 0 
A 0.36893996 4.44488002 0.36893996 4.44488002 0.35038996 4.44488002 4 P 0 N
A 0.2902 4.48425 0.2902 4.48425 0.27165 4.48425 4 P 0 N
L 4.87 0.025 6.565 0.025 15 P 0 
L 4.885 0.085 6.53 0.085 15 P 0 
L 4.895 0.15 6.54 0.15 15 P 0 
L 4.89 0.215 6.555 0.215 15 P 0 
L 4.89 0.3 6.535 0.3 15 P 0 
L 4.895 0.37 6.54 0.37 15 P 0 
A 12.84646004 6.02361998 12.9252 5.94488002 12.84646004 5.94488002 10 P 0 Y
A 12.9252 0.07873996 12.84646004 0 12.84646004 0.07873996 10 P 0 Y
L 12.9252 5.94488002 12.9252 0.07873996 10 P 0 
L 12.84646004 0 6.66536004 0 10 P 0 
A 6.58661998 0.35433002 6.50788002 0.43306998 6.50788002 0.35433002 10 P 0 N
A 6.66536004 0 6.58661998 0.07873996 6.66535994 0.07873996 10 P 0 Y
L 6.58661998 0.07873996 6.58661998 0.35433002 10 P 0 
A 4.93308002 0.43306998 4.85433996 0.35433002 4.93307992 0.35433002 10 P 0 N
L 6.50788002 0.43306998 4.93308002 0.43306998 10 P 0 
L 4.85433996 0.35433002 4.85433996 0.07873996 10 P 0 
A 4.85433996 0.07873996 4.77558996 0 4.7755999 0.07873996 10 P 0 Y
A 0.07873996 0 0 0.07873996 0.07873996 0.07873996 10 P 0 Y
L 4.77558996 0 0.07873996 0 10 P 0 
L 0.07873996 6.02361998 12.84646004 6.02361998 10 P 0 
A 0 5.94488002 0.07873996 6.02361998 0.07873996 5.94488002 10 P 0 Y
L 0 0.07873996 0 5.94488002 10 P 0 
L 0 6.07011998 12.89 6.07011998 15 P 0 
L 0 -0.0465 12.89 -0.0465 15 P 0 
L 0.005 6.16 0.035 6.13 4 P 0 
L 12.91 6.15 12.88 6.12 4 P 0 
L 12.91 -0.13 12.88 -0.1 4 P 0 
L 0.005 -0.135 0.035 -0.105 4 P 0 
L 0 -0.41426004 0 -0.093 10 P 0 
A 0.07873996 -0.493 0 -0.41426004 0.07873996 -0.41426004 10 P 0 Y
L 12.84646004 -0.493 0.07873996 -0.493 10 P 0 
A 12.9252 -0.41426004 12.84646004 -0.493 12.84646004 -0.41426004 10 P 0 Y
L 12.9252 -0.093 12.9252 -0.41426004 10 P 0 
L 0 -0.093 12.9252 -0.093 10 P 0 
L 0 6.11661998 12.9252 6.11661998 10 P 0 
L 0 6.43788002 0 6.11661998 10 P 0 
A 0.07873996 6.51661998 0 6.43788002 0.07873996 6.43788002 10 P 0 N
L 12.84646004 6.51661998 0.07873996 6.51661998 10 P 0 
A 12.9252 6.43788002 12.84646004 6.51661998 12.84646004 6.43788002 10 P 0 N
L 12.9252 6.11661998 12.9252 6.43788002 10 P 0 
L 0.0349 -2.3038 0.0349 -1.0038 3 P 0 ;0
L 0.0349 -1.0038 4.5349 -1.0038 3 P 0 ;0
L 4.5349 -1.0038 4.5349 -2.3038 3 P 0 ;0
L 4.5349 -2.3038 0.0349 -2.3038 3 P 0 ;0
L 0.0349 -1.6038 4.5349 -1.6038 3 P 0 ;0
L 0.0349 -1.8038 4.5349 -1.8038 3 P 0 ;0
L 2.4349 -2.1038 4.0349 -2.1038 3 P 0 ;0
L 2.4349 -2.3038 2.4349 -1.8038 3 P 0 ;0
L 3.2349 -2.1038 3.2349 -1.8038 3 P 0 ;0
L 4.0349 -2.3038 4.0349 -1.8038 3 P 0 ;0
L 0.0723999 -1.6844687 0.07906663 -1.69030079 2 P 0 ;0
L 0.07906663 -1.69030079 0.08656654 -1.6938 2 P 0 ;0
L 0.08656654 -1.6938 0.09323337 -1.6938 2 P 0 ;0
L 0.09323337 -1.6938 0.0999001 -1.69030079 2 P 0 ;0
L 0.0999001 -1.69030079 0.10490059 -1.6844687 2 P 0 ;0
L 0.10490059 -1.6844687 0.1074 -1.67629951 2 P 0 ;0
L 0.1074 -1.67629951 0.10573376 -1.66813455 2 P 0 ;0
L 0.10573376 -1.66813455 0.10156644 -1.66113396 2 P 0 ;0
L 0.10156644 -1.66113396 0.09406654 -1.65646614 2 P 0 ;0
L 0.09406654 -1.65646614 0.08406713 -1.65413327 2 P 0 ;0
L 0.08406713 -1.65413327 0.07823346 -1.64946762 2 P 0 ;0
L 0.07823346 -1.64946762 0.07573248 -1.64130059 2 P 0 ;0
L 0.07573248 -1.64130059 0.0774003 -1.63313356 2 P 0 ;0
L 0.0774003 -1.63313356 0.08156614 -1.62730148 2 P 0 ;0
L 0.08156614 -1.62730148 0.0873997 -1.6238 2 P 0 ;0
L 0.0873997 -1.6238 0.09323337 -1.6238 2 P 8191 ;0
L 0.09323337 -1.6238 0.09906693 -1.62613287 2 P 0 ;0
L 0.09906693 -1.62613287 0.10406742 -1.63196713 2 P 0 ;0
L 0.1383999 -1.6938 0.1383999 -1.6238 2 P 0 ;0
L 0.1734 -1.6238 0.1734 -1.6938 2 P 0 ;0
L 0.1734 -1.65880108 0.1383999 -1.65880108 2 P 0 ;0
L 0.23856683 -1.6938 0.20523307 -1.6938 2 P 0 ;0
L 0.20523307 -1.6938 0.20523307 -1.6238 2 P 0 ;0
L 0.20523307 -1.6238 0.23856683 -1.6238 2 P 0 ;0
L 0.22523337 -1.65763258 0.20523307 -1.65763258 2 P 0 ;0
L 0.30456683 -1.6938 0.27123307 -1.6938 2 P 0 ;0
L 0.27123307 -1.6938 0.27123307 -1.6238 2 P 0 ;0
L 0.27123307 -1.6238 0.30456683 -1.6238 2 P 0 ;0
L 0.29123337 -1.65763258 0.27123307 -1.65763258 2 P 0 ;0
L 0.35389921 -1.6238 0.35389921 -1.6938 2 P 0 ;0
L 0.33473356 -1.6238 0.37306634 -1.6238 2 P 0 ;0
L 0.09489921 -1.7188 0.09489921 -1.7888 2 P 0 ;0
L 0.07573356 -1.7188 0.11406634 -1.7188 2 P 0 ;0
L 0.1508998 -1.7188 0.17089862 -1.7188 2 P 0 ;0
L 0.16089921 -1.7188 0.16089921 -1.7888 2 P 0 ;0
L 0.1508998 -1.7888 0.17089862 -1.7888 2 P 0 ;0
L 0.22689921 -1.7188 0.22689921 -1.7888 2 P 0 ;0
L 0.20773356 -1.7188 0.24606634 -1.7188 2 P 0 ;0
L 0.27623307 -1.7188 0.27623307 -1.7888 2 P 0 ;0
L 0.27623307 -1.7888 0.30956683 -1.7888 2 P 0 ;0
L 0.37556683 -1.7888 0.34223307 -1.7888 2 P 0 ;0
L 0.34223307 -1.7888 0.34223307 -1.7188 2 P 0 ;0
L 0.34223307 -1.7188 0.37556683 -1.7188 2 P 0 ;0
L 0.36223337 -1.75263258 0.34223307 -1.75263258 2 P 0 ;0
L 2.5438999 -1.96813563 2.5519 -1.97480089 2 P 0 ;0
L 2.5519 -1.97480089 2.5608999 -1.9788 2 P 0 ;0
L 2.5608999 -1.9788 2.5689 -1.9788 2 P 0 ;0
L 2.5689 -1.9788 2.5769001 -1.97480089 2 P 0 ;0
L 2.5769001 -1.97480089 2.58290069 -1.96813563 2 P 0 ;0
L 2.58290069 -1.96813563 2.5859 -1.95879941 2 P 0 ;0
L 2.5859 -1.95879941 2.58390049 -1.94946811 2 P 0 ;0
L 2.58390049 -1.94946811 2.5788997 -1.94146732 2 P 0 ;0
L 2.5788997 -1.94146732 2.5698998 -1.93613278 2 P 0 ;0
L 2.5698998 -1.93613278 2.55790049 -1.93346663 2 P 0 ;0
L 2.55790049 -1.93346663 2.5509002 -1.92813445 2 P 0 ;0
L 2.5509002 -1.92813445 2.54789902 -1.91880069 2 P 0 ;0
L 2.54789902 -1.91880069 2.54990039 -1.90946683 2 P 0 ;0
L 2.54990039 -1.90946683 2.55489931 -1.90280167 2 P 0 ;0
L 2.55489931 -1.90280167 2.5618997 -1.8988 2 P 0 ;0
L 2.5618997 -1.8988 2.5689 -1.8988 2 P 0 ;0
L 2.5689 -1.8988 2.57590039 -1.90146614 2 P 0 ;0
L 2.57590039 -1.90146614 2.58190089 -1.90813386 2 P 0 ;0
L 2.6648998 -1.90546772 2.65889931 -1.90146614 2 P 0 ;0
L 2.65889931 -1.90146614 2.65190079 -1.8988 2 P 0 ;0
L 2.65190079 -1.8988 2.64390069 -1.8988 2 P 0 ;0
L 2.64390069 -1.8988 2.63489892 -1.90280167 2 P 0 ;0
L 2.63489892 -1.90280167 2.62790039 -1.90946683 2 P 0 ;0
L 2.62790039 -1.90946683 2.62289961 -1.91746762 2 P 0 ;0
L 2.62289961 -1.91746762 2.61889862 -1.93080049 2 P 0 ;0
L 2.61889862 -1.93080049 2.61789892 -1.94280039 2 P 0 ;0
L 2.61789892 -1.94280039 2.6199003 -1.9548003 2 P 0 ;0
L 2.6199003 -1.9548003 2.62289961 -1.96280098 2 P 0 ;0
L 2.62289961 -1.96280098 2.6289002 -1.97080177 2 P 0 ;0
L 2.6289002 -1.97080177 2.63590049 -1.97613396 2 P 0 ;0
L 2.63590049 -1.97613396 2.64289902 -1.9788 2 P 0 ;0
L 2.64289902 -1.9788 2.64989941 -1.9788 2 P 0 ;0
L 2.64989941 -1.9788 2.6568997 -1.97613396 2 P 0 ;0
L 2.6568997 -1.97613396 2.6629003 -1.97213484 2 P 0 ;0
L 2.6629003 -1.97213484 2.66790098 -1.96680266 2 P 0 ;0
L 2.69589892 -1.9788 2.72089902 -1.8988 2 P 0 ;0
L 2.72089902 -1.8988 2.74590098 -1.9788 2 P 0 ;0
L 2.73689931 -1.95080118 2.70489882 -1.95080118 2 P 0 ;0
L 2.77889961 -1.8988 2.77889961 -1.9788 2 P 0 ;0
L 2.77889961 -1.9788 2.8189003 -1.9788 2 P 0 ;0
L 2.8969003 -1.9788 2.85689961 -1.9788 2 P 0 ;0
L 2.85689961 -1.9788 2.85689961 -1.8988 2 P 0 ;0
L 2.85689961 -1.8988 2.8969003 -1.8988 2 P 0 ;0
L 2.8809 -1.93746575 2.85689961 -1.93746575 2 P 0 ;0
L 3.03289902 -1.9788 3.03289902 -1.8988 2 P 0 ;0
L 3.03289902 -1.8988 3.0208998 -1.91479911 2 P 0 ;0
L 3.0208998 -1.9788 3.04489833 -1.9788 2 P 0 ;0
L 3.11089902 -1.98146604 3.10889951 -1.98013297 2 P 8191 ;0
L 3.10889951 -1.98013297 3.10889951 -1.97746703 2 P 8191 ;0
L 3.10889951 -1.97746703 3.11089902 -1.97613396 2 P 8191 ;0
L 3.11089902 -1.97613396 3.11290039 -1.97746703 2 P 8191 ;0
L 3.11290039 -1.97746703 3.11290039 -1.98013297 2 P 8191 ;0
L 3.11290039 -1.98013297 3.11089902 -1.98146604 2 P 8191 ;0
L 3.11089902 -1.945469 3.10889951 -1.94413346 2 P 8191 ;0
L 3.10889951 -1.94413346 3.10889951 -1.94146732 2 P 8191 ;0
L 3.10889951 -1.94146732 3.11089902 -1.94013435 2 P 8191 ;0
L 3.11089902 -1.94013435 3.11290039 -1.94146732 2 P 8191 ;0
L 3.11290039 -1.94146732 3.11290039 -1.94413346 2 P 8191 ;0
L 3.11290039 -1.94413346 3.11089902 -1.945469 2 P 8191 ;0
L 3.18889902 -1.9788 3.18889902 -1.8988 2 P 0 ;0
L 3.18889902 -1.8988 3.1768998 -1.91479911 2 P 0 ;0
L 3.1768998 -1.9788 3.20089833 -1.9788 2 P 0 ;0
L 2.5138999 -2.23313563 2.5219 -2.23980089 2 P 0 ;0
L 2.5219 -2.23980089 2.5308999 -2.2438 2 P 0 ;0
L 2.5308999 -2.2438 2.5389 -2.2438 2 P 0 ;0
L 2.5389 -2.2438 2.5469001 -2.23980089 2 P 0 ;0
L 2.5469001 -2.23980089 2.55290069 -2.23313563 2 P 0 ;0
L 2.55290069 -2.23313563 2.5559 -2.22379941 2 P 0 ;0
L 2.5559 -2.22379941 2.55390049 -2.21446811 2 P 0 ;0
L 2.55390049 -2.21446811 2.5488997 -2.20646732 2 P 0 ;0
L 2.5488997 -2.20646732 2.5398998 -2.20113278 2 P 0 ;0
L 2.5398998 -2.20113278 2.52790049 -2.19846663 2 P 0 ;0
L 2.52790049 -2.19846663 2.5209002 -2.19313445 2 P 0 ;0
L 2.5209002 -2.19313445 2.51789902 -2.18380069 2 P 0 ;0
L 2.51789902 -2.18380069 2.51990039 -2.17446683 2 P 0 ;0
L 2.51990039 -2.17446683 2.52489931 -2.16780167 2 P 0 ;0
L 2.52489931 -2.16780167 2.5318997 -2.1638 2 P 0 ;0
L 2.5318997 -2.1638 2.5389 -2.1638 2 P 0 ;0
L 2.5389 -2.1638 2.54590039 -2.16646614 2 P 0 ;0
L 2.54590039 -2.16646614 2.55190089 -2.17313386 2 P 0 ;0
L 2.5918999 -2.2438 2.5918999 -2.1638 2 P 0 ;0
L 2.6339 -2.1638 2.6339 -2.2438 2 P 0 ;0
L 2.6339 -2.20380128 2.5918999 -2.20380128 2 P 0 ;0
L 2.7109003 -2.2438 2.67089961 -2.2438 2 P 0 ;0
L 2.67089961 -2.2438 2.67089961 -2.1638 2 P 0 ;0
L 2.67089961 -2.1638 2.7109003 -2.1638 2 P 0 ;0
L 2.6949 -2.20246575 2.67089961 -2.20246575 2 P 0 ;0
L 2.7889003 -2.2438 2.74889961 -2.2438 2 P 0 ;0
L 2.74889961 -2.2438 2.74889961 -2.1638 2 P 0 ;0
L 2.74889961 -2.1638 2.7889003 -2.1638 2 P 0 ;0
L 2.7729 -2.20246575 2.74889961 -2.20246575 2 P 0 ;0
L 2.84689902 -2.1638 2.84689902 -2.2438 2 P 0 ;0
L 2.8239003 -2.1638 2.86989961 -2.1638 2 P 0 ;0
L 3.29489961 -1.9238 3.29489961 -2.0038 2 P 0 ;0
L 3.29489961 -2.0038 3.3349003 -2.0038 2 P 0 ;0
L 3.36789892 -2.0038 3.39289902 -1.9238 2 P 0 ;0
L 3.39289902 -1.9238 3.41790098 -2.0038 2 P 0 ;0
L 3.40889931 -1.97580118 3.37689882 -1.97580118 2 P 0 ;0
L 3.47089902 -2.0038 3.47089902 -1.96780039 2 P 0 ;0
L 3.47089902 -1.96780039 3.45089961 -1.9238 2 P 0 ;0
L 3.4909003 -1.9238 3.47089902 -1.96780039 2 P 0 ;0
L 3.5689003 -2.0038 3.52889961 -2.0038 2 P 0 ;0
L 3.52889961 -2.0038 3.52889961 -1.9238 2 P 0 ;0
L 3.52889961 -1.9238 3.5689003 -1.9238 2 P 0 ;0
L 3.5529 -1.96246575 3.52889961 -1.96246575 2 P 0 ;0
L 3.60689961 -2.0038 3.60689961 -1.9238 2 P 0 ;0
L 3.60689961 -1.9238 3.6318998 -1.9238 2 P 0 ;0
L 3.6318998 -1.9238 3.6398999 -1.92780167 2 P 0 ;0
L 3.6398999 -1.92780167 3.64490069 -1.93313386 2 P 0 ;0
L 3.64490069 -1.93313386 3.6469003 -1.94380069 2 P 0 ;0
L 3.6469003 -1.94380069 3.64490069 -1.95446752 2 P 0 ;0
L 3.64490069 -1.95446752 3.6389001 -1.96113278 2 P 0 ;0
L 3.6389001 -1.96113278 3.6318998 -1.96513435 2 P 0 ;0
L 3.6318998 -1.96513435 3.60689961 -1.96513435 2 P 0 ;0
L 3.6318998 -1.96513435 3.6469003 -2.0038 2 P 0 ;0
L 3.33989902 -2.2538 3.33189892 -2.25246703 2 P 0 ;0
L 3.33189892 -2.25246703 3.32490039 -2.24713484 2 P 0 ;0
L 3.32490039 -2.24713484 3.3188999 -2.23913406 2 P 0 ;0
L 3.3188999 -2.23913406 3.31489892 -2.2298003 2 P 0 ;0
L 3.31489892 -2.2298003 3.31289931 -2.21913346 2 P 0 ;0
L 3.31289931 -2.21913346 3.31289931 -2.20846663 2 P 0 ;0
L 3.31289931 -2.20846663 3.31489892 -2.1977998 2 P 0 ;0
L 3.31489892 -2.1977998 3.3188999 -2.18846604 2 P 0 ;0
L 3.3188999 -2.18846604 3.32490039 -2.18046772 2 P 0 ;0
L 3.32490039 -2.18046772 3.33189892 -2.17513307 2 P 0 ;0
L 3.33189892 -2.17513307 3.33989902 -2.1738 2 P 0 ;0
L 3.33989902 -2.1738 3.34789911 -2.17513307 2 P 0 ;0
L 3.34789911 -2.17513307 3.35489951 -2.18046772 2 P 0 ;0
L 3.35489951 -2.18046772 3.3609 -2.18846604 2 P 0 ;0
L 3.3609 -2.18846604 3.36490098 -2.1977998 2 P 0 ;0
L 3.36490098 -2.1977998 3.36690059 -2.20846663 2 P 0 ;0
L 3.36690059 -2.20846663 3.36690059 -2.21913346 2 P 0 ;0
L 3.36690059 -2.21913346 3.36490098 -2.2298003 2 P 0 ;0
L 3.36490098 -2.2298003 3.3609 -2.23913406 2 P 0 ;0
L 3.3609 -2.23913406 3.35489951 -2.24713484 2 P 0 ;0
L 3.35489951 -2.24713484 3.34789911 -2.25246703 2 P 0 ;0
L 3.34789911 -2.25246703 3.33989902 -2.2538 2 P 0 ;0
L 3.39889941 -2.2538 3.39889941 -2.1738 2 P 0 ;0
L 3.39889941 -2.1738 3.43690049 -2.1738 2 P 0 ;0
L 3.4228998 -2.21246575 3.39889941 -2.21246575 2 P 0 ;0
L 0.16489872 -1.0538 0.16489872 -1.1538 2 P 0 ;0
L 0.13423376 -1.0538 0.19556614 -1.0538 2 P 0 ;0
L 0.2588997 -1.0538 0.29089774 -1.0538 2 P 0 ;0
L 0.27489872 -1.0538 0.27489872 -1.1538 2 P 0 ;0
L 0.2588997 -1.1538 0.29089774 -1.1538 2 P 0 ;0
L 0.38489872 -1.0538 0.38489872 -1.1538 2 P 0 ;0
L 0.35423376 -1.0538 0.41556614 -1.0538 2 P 0 ;0
L 0.46823287 -1.0538 0.46823287 -1.1538 2 P 0 ;0
L 0.46823287 -1.1538 0.52156703 -1.1538 2 P 0 ;0
L 0.63156703 -1.1538 0.57823287 -1.1538 2 P 0 ;0
L 0.57823287 -1.1538 0.57823287 -1.0538 2 P 0 ;0
L 0.57823287 -1.0538 0.63156703 -1.0538 2 P 0 ;0
L 0.61023337 -1.10213219 0.57823287 -1.10213219 2 P 0 ;0
L 4.18989892 -1.9538 4.21489902 -1.8738 2 P 0 ;0
L 4.21489902 -1.8738 4.23990098 -1.9538 2 P 0 ;0
L 4.23089931 -1.92580118 4.19889882 -1.92580118 2 P 0 ;0
L 4.27289961 -1.9538 4.27289961 -1.8738 2 P 0 ;0
L 4.27289961 -1.8738 4.2978998 -1.8738 2 P 0 ;0
L 4.2978998 -1.8738 4.3058999 -1.87780167 2 P 0 ;0
L 4.3058999 -1.87780167 4.31090069 -1.88313386 2 P 0 ;0
L 4.31090069 -1.88313386 4.3129003 -1.89380069 2 P 0 ;0
L 4.3129003 -1.89380069 4.31090069 -1.90446752 2 P 0 ;0
L 4.31090069 -1.90446752 4.3049001 -1.91113278 2 P 0 ;0
L 4.3049001 -1.91113278 4.2978998 -1.91513435 2 P 0 ;0
L 4.2978998 -1.91513435 4.27289961 -1.91513435 2 P 0 ;0
L 4.2978998 -1.91513435 4.3129003 -1.9538 2 P 0 ;0
L 4.37089902 -1.8738 4.37089902 -1.9538 2 P 0 ;0
L 4.3479003 -1.8738 4.39389961 -1.8738 2 P 0 ;0
L 3.61989892 -2.2538 3.61989892 -2.1638 2 P 0 ;0
L 3.61989892 -2.1638 3.6058997 -2.18179892 2 P 0 ;0
L 3.6058997 -2.2538 3.63389803 -2.2538 2 P 0 ;0
L 3.68773268 -2.17879961 3.69473337 -2.16980148 2 P 0 ;0
L 3.69473337 -2.16980148 3.70290039 -2.1652997 2 P 0 ;0
L 3.70290039 -2.1652997 3.71223386 -2.1638 2 P 0 ;0
L 3.71223386 -2.1638 3.7239002 -2.16679941 2 P 0 ;0
L 3.7239002 -2.16679941 3.73206722 -2.17430059 2 P 0 ;0
L 3.73206722 -2.17430059 3.7344001 -2.18329862 2 P 0 ;0
L 3.7344001 -2.18329862 3.73323366 -2.19230217 2 P 0 ;0
L 3.73323366 -2.19230217 3.72856585 -2.19980059 2 P 0 ;0
L 3.72856585 -2.19980059 3.70523317 -2.2148001 2 P 0 ;0
L 3.70523317 -2.2148001 3.69473337 -2.22530069 2 P 0 ;0
L 3.69473337 -2.22530069 3.68773268 -2.24030295 2 P 0 ;0
L 3.68773268 -2.24030295 3.6853998 -2.2538 2 P 0 ;0
L 3.6853998 -2.2538 3.7344001 -2.2538 2 P 0 ;0
L 0.59099833 -1.36499882 0.5990003 -1.35750039 2 P 0 ;0
L 0.5990003 -1.35750039 0.60499902 -1.34500315 2 P 0 ;0
L 0.60499902 -1.34500315 0.60900187 -1.32749764 2 P 0 ;0
L 0.60900187 -1.32749764 0.60499902 -1.31250089 2 P 0 ;0
L 0.60499902 -1.31250089 0.59700079 -1.30250305 2 P 0 ;0
L 0.59700079 -1.30250305 0.5830001 -1.295 2 P 0 ;0
L 0.5830001 -1.295 0.52900059 -1.295 2 P 0 ;0
L 0.52900059 -1.295 0.52900059 -1.445 2 P 0 ;0
L 0.52900059 -1.445 0.59500118 -1.445 2 P 0 ;0
L 0.59500118 -1.445 0.60900187 -1.43500217 2 P 0 ;0
L 0.60900187 -1.43500217 0.6170001 -1.42000079 2 P 0 ;0
L 0.6170001 -1.42000079 0.62099931 -1.4025 2 P 0 ;0
L 0.62099931 -1.4025 0.6170001 -1.38500374 2 P 0 ;0
L 0.6170001 -1.38500374 0.60499902 -1.37000236 2 P 0 ;0
L 0.60499902 -1.37000236 0.59099833 -1.36499882 2 P 0 ;0
L 0.59099833 -1.36499882 0.52900059 -1.36499882 2 P 0 ;0
L 0.77100138 -1.445 0.77100138 -1.34500315 2 P 0 ;0
L 0.77100138 -1.36249941 0.76299951 -1.35250148 2 P 0 ;0
L 0.76299951 -1.35250148 0.75099833 -1.34750256 2 P 0 ;0
L 0.75099833 -1.34750256 0.73700138 -1.34500315 2 P 0 ;0
L 0.73700138 -1.34500315 0.72300069 -1.35000207 2 P 0 ;0
L 0.72300069 -1.35000207 0.71099961 -1.3599999 2 P 0 ;0
L 0.71099961 -1.3599999 0.70299764 -1.37500128 2 P 0 ;0
L 0.70299764 -1.37500128 0.69899852 -1.39500157 2 P 0 ;0
L 0.69899852 -1.39500157 0.70299764 -1.41500187 2 P 0 ;0
L 0.70299764 -1.41500187 0.71099961 -1.43000325 2 P 0 ;0
L 0.71099961 -1.43000325 0.72300069 -1.44000108 2 P 0 ;0
L 0.72300069 -1.44000108 0.73700138 -1.445 2 P 0 ;0
L 0.73700138 -1.445 0.75099833 -1.44250059 2 P 0 ;0
L 0.75099833 -1.44250059 0.76299951 -1.43500217 2 P 0 ;0
L 0.76299951 -1.43500217 0.77100138 -1.42500433 2 P 0 ;0
L 0.86700039 -1.445 0.86700039 -1.34500315 2 P 0 ;0
L 0.86700039 -1.36499882 0.87699833 -1.35500098 2 P 0 ;0
L 0.87699833 -1.35500098 0.8869998 -1.34750256 2 P 0 ;0
L 0.8869998 -1.34750256 0.90100049 -1.34500315 2 P 0 ;0
L 0.90100049 -1.34500315 0.91099833 -1.34750256 2 P 0 ;0
L 0.91099833 -1.34750256 0.92299951 -1.35500098 2 P 0 ;0
L 1.02700039 -1.445 1.02700039 -1.34500315 2 P 0 ;0
L 1.02700039 -1.36499882 1.03699833 -1.35500098 2 P 0 ;0
L 1.03699833 -1.35500098 1.0469998 -1.34750256 2 P 0 ;0
L 1.0469998 -1.34750256 1.06100049 -1.34500315 2 P 0 ;0
L 1.06100049 -1.34500315 1.07099833 -1.34750256 2 P 0 ;0
L 1.07099833 -1.34750256 1.08299951 -1.35500098 2 P 0 ;0
L 1.18500089 -1.37750069 1.24900187 -1.37750069 2 P 0 ;0
L 1.24900187 -1.37750069 1.24299951 -1.3599999 2 P 0 ;0
L 1.24299951 -1.3599999 1.23300157 -1.35000207 2 P 0 ;0
L 1.23300157 -1.35000207 1.21900089 -1.34500315 2 P 0 ;0
L 1.21900089 -1.34500315 1.2050003 -1.34750256 2 P 0 ;0
L 1.2050003 -1.34750256 1.19299911 -1.35500098 2 P 0 ;0
L 1.19299911 -1.35500098 1.18500089 -1.37250177 2 P 0 ;0
L 1.18500089 -1.37250177 1.18099803 -1.38750315 2 P 0 ;0
L 1.18099803 -1.38750315 1.18099803 -1.4025 2 P 0 ;0
L 1.18099803 -1.4025 1.18500089 -1.41750138 2 P 0 ;0
L 1.18500089 -1.41750138 1.19499872 -1.43250276 2 P 0 ;0
L 1.19499872 -1.43250276 1.2069998 -1.44250059 2 P 0 ;0
L 1.2069998 -1.44250059 1.22100049 -1.445 2 P 0 ;0
L 1.22100049 -1.445 1.23500118 -1.44000108 2 P 0 ;0
L 1.23500118 -1.44000108 1.24900187 -1.42500433 2 P 0 ;0
L 1.37499813 -1.445 1.37499813 -1.295 2 P 0 ;0
L 1.50500089 -1.37750069 1.56900187 -1.37750069 2 P 0 ;0
L 1.56900187 -1.37750069 1.56299951 -1.3599999 2 P 0 ;0
L 1.56299951 -1.3599999 1.55300157 -1.35000207 2 P 0 ;0
L 1.55300157 -1.35000207 1.53900089 -1.34500315 2 P 0 ;0
L 1.53900089 -1.34500315 1.5250003 -1.34750256 2 P 0 ;0
L 1.5250003 -1.34750256 1.51299911 -1.35500098 2 P 0 ;0
L 1.51299911 -1.35500098 1.50500089 -1.37250177 2 P 0 ;0
L 1.50500089 -1.37250177 1.50099803 -1.38750315 2 P 0 ;0
L 1.50099803 -1.38750315 1.50099803 -1.4025 2 P 0 ;0
L 1.50099803 -1.4025 1.50500089 -1.41750138 2 P 0 ;0
L 1.50500089 -1.41750138 1.51499872 -1.43250276 2 P 0 ;0
L 1.51499872 -1.43250276 1.5269998 -1.44250059 2 P 0 ;0
L 1.5269998 -1.44250059 1.54100049 -1.445 2 P 0 ;0
L 1.54100049 -1.445 1.55500118 -1.44000108 2 P 0 ;0
L 1.55500118 -1.44000108 1.56900187 -1.42500433 2 P 0 ;0
L 1.6529998 -1.48999951 1.66500089 -1.49499843 2 P 0 ;0
L 1.66500089 -1.49499843 1.68100108 -1.48999951 2 P 0 ;0
L 1.68100108 -1.48999951 1.69099902 -1.48000167 2 P 0 ;0
L 1.69099902 -1.48000167 1.69900089 -1.4674997 2 P 0 ;0
L 1.69900089 -1.4674997 1.71099833 -1.42750374 2 P 0 ;0
L 1.71099833 -1.42750374 1.7370001 -1.34500315 2 P 0 ;0
L 1.67299911 -1.34500315 1.71099833 -1.42750374 2 P 0 ;0
L 1.82500089 -1.37750069 1.88900187 -1.37750069 2 P 0 ;0
L 1.88900187 -1.37750069 1.88299951 -1.3599999 2 P 0 ;0
L 1.88299951 -1.3599999 1.87300157 -1.35000207 2 P 0 ;0
L 1.87300157 -1.35000207 1.85900089 -1.34500315 2 P 0 ;0
L 1.85900089 -1.34500315 1.8450003 -1.34750256 2 P 0 ;0
L 1.8450003 -1.34750256 1.83299911 -1.35500098 2 P 0 ;0
L 1.83299911 -1.35500098 1.82500089 -1.37250177 2 P 0 ;0
L 1.82500089 -1.37250177 1.82099803 -1.38750315 2 P 0 ;0
L 1.82099803 -1.38750315 1.82099803 -1.4025 2 P 0 ;0
L 1.82099803 -1.4025 1.82500089 -1.41750138 2 P 0 ;0
L 1.82500089 -1.41750138 1.83499872 -1.43250276 2 P 0 ;0
L 1.83499872 -1.43250276 1.8469998 -1.44250059 2 P 0 ;0
L 1.8469998 -1.44250059 1.86100049 -1.445 2 P 0 ;0
L 1.86100049 -1.445 1.87500118 -1.44000108 2 P 0 ;0
L 1.87500118 -1.44000108 1.88900187 -1.42500433 2 P 0 ;0
L 2.18699921 -1.37000236 2.22700167 -1.37000236 2 P 0 ;0
L 2.22700167 -1.37000236 2.22700167 -1.41500187 2 P 0 ;0
L 2.22700167 -1.41500187 2.21500059 -1.43000325 2 P 0 ;0
L 2.21500059 -1.43000325 2.2009999 -1.44000108 2 P 0 ;0
L 2.2009999 -1.44000108 2.18100049 -1.445 2 P 0 ;0
L 2.18100049 -1.445 2.16100108 -1.44000108 2 P 0 ;0
L 2.16100108 -1.44000108 2.14700039 -1.43000325 2 P 0 ;0
L 2.14700039 -1.43000325 2.13499931 -1.41500187 2 P 0 ;0
L 2.13499931 -1.41500187 2.12699734 -1.39750108 2 P 0 ;0
L 2.12699734 -1.39750108 2.12299823 -1.37750069 2 P 0 ;0
L 2.12299823 -1.37750069 2.12299823 -1.3599999 2 P 0 ;0
L 2.12299823 -1.3599999 2.12699734 -1.34500315 2 P 0 ;0
L 2.12699734 -1.34500315 2.13499931 -1.32749764 2 P 0 ;0
L 2.13499931 -1.32749764 2.14700039 -1.31250089 2 P 0 ;0
L 2.14700039 -1.31250089 2.15899783 -1.30250305 2 P 0 ;0
L 2.15899783 -1.30250305 2.17499813 -1.295 2 P 0 ;0
L 2.17499813 -1.295 2.18899882 -1.295 2 P 0 ;0
L 2.18899882 -1.295 2.20499902 -1.29999902 2 P 0 ;0
L 2.20499902 -1.29999902 2.2170001 -1.31000138 2 P 0 ;0
L 2.29699892 -1.31999931 2.309 -1.30500246 2 P 0 ;0
L 2.309 -1.30500246 2.32300069 -1.29749951 2 P 0 ;0
L 2.32300069 -1.29749951 2.33900089 -1.295 2 P 0 ;0
L 2.33900089 -1.295 2.3590003 -1.29999902 2 P 0 ;0
L 2.3590003 -1.29999902 2.37300098 -1.31250089 2 P 0 ;0
L 2.37300098 -1.31250089 2.3770001 -1.32749764 2 P 0 ;0
L 2.3770001 -1.32749764 2.37500059 -1.34250364 2 P 0 ;0
L 2.37500059 -1.34250364 2.36699862 -1.35500098 2 P 0 ;0
L 2.36699862 -1.35500098 2.3269998 -1.3800002 2 P 0 ;0
L 2.3269998 -1.3800002 2.309 -1.39750108 2 P 0 ;0
L 2.309 -1.39750108 2.29699892 -1.42250482 2 P 0 ;0
L 2.29699892 -1.42250482 2.2929998 -1.445 2 P 0 ;0
L 2.2929998 -1.445 2.3770001 -1.445 2 P 0 ;0
L 2.6129998 -1.42500433 2.629 -1.43750167 2 P 0 ;0
L 2.629 -1.43750167 2.6469998 -1.445 2 P 0 ;0
L 2.6469998 -1.445 2.6630001 -1.445 2 P 0 ;0
L 2.6630001 -1.445 2.6790003 -1.43750167 2 P 0 ;0
L 2.6790003 -1.43750167 2.69100138 -1.42500433 2 P 0 ;0
L 2.69100138 -1.42500433 2.6970001 -1.40749892 2 P 0 ;0
L 2.6970001 -1.40749892 2.69300098 -1.39000266 2 P 0 ;0
L 2.69300098 -1.39000266 2.68299951 -1.37500128 2 P 0 ;0
L 2.68299951 -1.37500128 2.66499961 -1.36499882 2 P 0 ;0
L 2.66499961 -1.36499882 2.64100108 -1.3599999 2 P 0 ;0
L 2.64100108 -1.3599999 2.62700039 -1.35000207 2 P 0 ;0
L 2.62700039 -1.35000207 2.62099803 -1.33250118 2 P 0 ;0
L 2.62099803 -1.33250118 2.62500089 -1.31500039 2 P 0 ;0
L 2.62500089 -1.31500039 2.63499872 -1.30250305 2 P 0 ;0
L 2.63499872 -1.30250305 2.64899941 -1.295 2 P 0 ;0
L 2.64899941 -1.295 2.6630001 -1.295 2 P 0 ;0
L 2.6630001 -1.295 2.67700079 -1.29999902 2 P 0 ;0
L 2.67700079 -1.29999902 2.68900187 -1.31250089 2 P 0 ;0
L 2.7729998 -1.445 2.8570001 -1.295 2 P 0 ;0
L 2.7729998 -1.295 2.8570001 -1.445 2 P 0 ;0
L 2.92299823 -1.445 2.92299823 -1.295 2 P 0 ;0
L 2.92299823 -1.295 2.97499813 -1.42000079 2 P 0 ;0
L 2.97499813 -1.42000079 3.02700167 -1.295 2 P 0 ;0
L 3.02700167 -1.295 3.02700167 -1.445 2 P 0 ;0
L 3.09699892 -1.31999931 3.109 -1.30500246 2 P 0 ;0
L 3.109 -1.30500246 3.12300069 -1.29749951 2 P 0 ;0
L 3.12300069 -1.29749951 3.13900089 -1.295 2 P 0 ;0
L 3.13900089 -1.295 3.1590003 -1.29999902 2 P 0 ;0
L 3.1590003 -1.29999902 3.17300098 -1.31250089 2 P 0 ;0
L 3.17300098 -1.31250089 3.1770001 -1.32749764 2 P 0 ;0
L 3.1770001 -1.32749764 3.17500059 -1.34250364 2 P 0 ;0
L 3.17500059 -1.34250364 3.16699862 -1.35500098 2 P 0 ;0
L 3.16699862 -1.35500098 3.1269998 -1.3800002 2 P 0 ;0
L 3.1269998 -1.3800002 3.109 -1.39750108 2 P 0 ;0
L 3.109 -1.39750108 3.09699892 -1.42250482 2 P 0 ;0
L 3.09699892 -1.42250482 3.0929998 -1.445 2 P 0 ;0
L 3.0929998 -1.445 3.1770001 -1.445 2 P 0 ;0
L 3.269 -1.39500157 3.3209999 -1.39500157 2 P 0 ;0
L 3.41499931 -1.445 3.41499931 -1.295 2 P 0 ;0
L 3.41499931 -1.295 3.46499961 -1.295 2 P 0 ;0
L 3.46499961 -1.295 3.4809999 -1.30250305 2 P 0 ;0
L 3.4809999 -1.30250305 3.49100138 -1.31250089 2 P 0 ;0
L 3.49100138 -1.31250089 3.49500059 -1.33250118 2 P 0 ;0
L 3.49500059 -1.33250118 3.49100138 -1.35250148 2 P 0 ;0
L 3.49100138 -1.35250148 3.4790003 -1.36499882 2 P 0 ;0
L 3.4790003 -1.36499882 3.46499961 -1.37250177 2 P 0 ;0
L 3.46499961 -1.37250177 3.41499931 -1.37250177 2 P 0 ;0
L 3.46499961 -1.37250177 3.49500059 -1.445 2 P 0 ;0
L 3.61499813 -1.34500315 3.61499813 -1.445 2 P 0 ;0
L 3.61499813 -1.30500246 3.61099902 -1.30250305 2 P 8191 ;0
L 3.61099902 -1.30250305 3.61099902 -1.29749951 2 P 8191 ;0
L 3.61099902 -1.29749951 3.61499813 -1.295 2 P 8191 ;0
L 3.61499813 -1.295 3.61900089 -1.29749951 2 P 8191 ;0
L 3.61900089 -1.29749951 3.61900089 -1.30250305 2 P 8191 ;0
L 3.61900089 -1.30250305 3.61499813 -1.30500246 2 P 8191 ;0
L 3.74500089 -1.42750374 3.75499872 -1.43750167 2 P 0 ;0
L 3.75499872 -1.43750167 3.76899941 -1.445 2 P 0 ;0
L 3.76899941 -1.445 3.78100049 -1.445 2 P 0 ;0
L 3.78100049 -1.445 3.79300157 -1.44000108 2 P 0 ;0
L 3.79300157 -1.44000108 3.8009999 -1.43250276 2 P 0 ;0
L 3.8009999 -1.43250276 3.80499902 -1.42250482 2 P 0 ;0
L 3.80499902 -1.42250482 3.80299951 -1.40749892 2 P 0 ;0
L 3.80299951 -1.40749892 3.79500118 -1.40000049 2 P 0 ;0
L 3.79500118 -1.40000049 3.75899783 -1.38500374 2 P 0 ;0
L 3.75899783 -1.38500374 3.75099961 -1.36749833 2 P 0 ;0
L 3.75099961 -1.36749833 3.75499872 -1.35500098 2 P 0 ;0
L 3.75499872 -1.35500098 3.76300069 -1.34750256 2 P 0 ;0
L 3.76300069 -1.34750256 3.77499813 -1.34500315 2 P 0 ;0
L 3.77499813 -1.34500315 3.78699921 -1.34750256 2 P 0 ;0
L 3.78699921 -1.34750256 3.7990003 -1.35500098 2 P 0 ;0
L 3.90500089 -1.37750069 3.96900187 -1.37750069 2 P 0 ;0
L 3.96900187 -1.37750069 3.96299951 -1.3599999 2 P 0 ;0
L 3.96299951 -1.3599999 3.95300157 -1.35000207 2 P 0 ;0
L 3.95300157 -1.35000207 3.93900089 -1.34500315 2 P 0 ;0
L 3.93900089 -1.34500315 3.9250003 -1.34750256 2 P 0 ;0
L 3.9250003 -1.34750256 3.91299911 -1.35500098 2 P 0 ;0
L 3.91299911 -1.35500098 3.90500089 -1.37250177 2 P 0 ;0
L 3.90500089 -1.37250177 3.90099803 -1.38750315 2 P 0 ;0
L 3.90099803 -1.38750315 3.90099803 -1.4025 2 P 0 ;0
L 3.90099803 -1.4025 3.90500089 -1.41750138 2 P 0 ;0
L 3.90500089 -1.41750138 3.91499872 -1.43250276 2 P 0 ;0
L 3.91499872 -1.43250276 3.9269998 -1.44250059 2 P 0 ;0
L 3.9269998 -1.44250059 3.94100049 -1.445 2 P 0 ;0
L 3.94100049 -1.445 3.95500118 -1.44000108 2 P 0 ;0
L 3.95500118 -1.44000108 3.96900187 -1.42500433 2 P 0 ;0
L 4.06700039 -1.445 4.06700039 -1.34500315 2 P 0 ;0
L 4.06700039 -1.36499882 4.07699833 -1.35500098 2 P 0 ;0
L 4.07699833 -1.35500098 4.0869998 -1.34750256 2 P 0 ;0
L 4.0869998 -1.34750256 4.10100049 -1.34500315 2 P 0 ;0
L 4.10100049 -1.34500315 4.11099833 -1.34750256 2 P 0 ;0
L 4.11099833 -1.34750256 4.12299951 -1.35500098 2 P 0 ;0
L 4.16964783 -2.2038 4.21839813 -2.0478 2 P 0 ;0
L 4.21839813 -2.0478 4.26715207 -2.2038 2 P 0 ;0
L 4.24959862 -2.14920217 4.18719774 -2.14920217 2 P 0 ;0
L 4.37939813 -2.2038 4.37939813 -2.0478 2 P 0 ;0
L 4.37939813 -2.0478 4.35599961 -2.07899813 2 P 0 ;0
L 4.35599961 -2.2038 4.40279675 -2.2038 2 P 0 ;0
L 2.0009002 -0.9538 2.0009002 -0.8038 2 P 0 ;0
L 2.0009002 -0.8038 2.04089902 -0.8038 2 P 0 ;0
L 2.04089902 -0.8038 2.05689921 -0.81130305 2 P 0 ;0
L 2.05689921 -0.81130305 2.0689003 -0.82130089 2 P 0 ;0
L 2.0689003 -0.82130089 2.07890187 -0.83629764 2 P 0 ;0
L 2.07890187 -0.83629764 2.0869001 -0.85380315 2 P 0 ;0
L 2.0869001 -0.85380315 2.0888997 -0.87880236 2 P 0 ;0
L 2.0888997 -0.87880236 2.0869001 -0.90380157 2 P 0 ;0
L 2.0869001 -0.90380157 2.07890187 -0.92130246 2 P 0 ;0
L 2.07890187 -0.92130246 2.0689003 -0.93630374 2 P 0 ;0
L 2.0689003 -0.93630374 2.05689921 -0.94630167 2 P 0 ;0
L 2.05689921 -0.94630167 2.04089902 -0.9538 2 P 0 ;0
L 2.04089902 -0.9538 2.0009002 -0.9538 2 P 0 ;0
L 2.15489783 -0.9538 2.20489813 -0.8038 2 P 0 ;0
L 2.20489813 -0.8038 2.25490207 -0.9538 2 P 0 ;0
L 2.23689862 -0.90130207 2.17289764 -0.90130207 2 P 0 ;0
L 2.36489813 -0.8038 2.36489813 -0.9538 2 P 0 ;0
L 2.31890059 -0.8038 2.41089931 -0.8038 2 P 0 ;0
L 2.56490059 -0.9538 2.48489931 -0.9538 2 P 0 ;0
L 2.48489931 -0.9538 2.48489931 -0.8038 2 P 0 ;0
L 2.48489931 -0.8038 2.56490059 -0.8038 2 P 0 ;0
L 2.5329001 -0.87629833 2.48489931 -0.87629833 2 P 0 ;0
L 2.84489813 -0.9538 2.82889783 -0.95130059 2 P 0 ;0
L 2.82889783 -0.95130059 2.81490089 -0.94130276 2 P 0 ;0
L 2.81490089 -0.94130276 2.8028998 -0.92630138 2 P 0 ;0
L 2.8028998 -0.92630138 2.79489783 -0.90880049 2 P 0 ;0
L 2.79489783 -0.90880049 2.79089862 -0.8888002 2 P 0 ;0
L 2.79089862 -0.8888002 2.79089862 -0.8687999 2 P 0 ;0
L 2.79089862 -0.8687999 2.79489783 -0.84879961 2 P 0 ;0
L 2.79489783 -0.84879961 2.8028998 -0.83129872 2 P 0 ;0
L 2.8028998 -0.83129872 2.81490089 -0.81630197 2 P 0 ;0
L 2.81490089 -0.81630197 2.82889783 -0.80629951 2 P 0 ;0
L 2.82889783 -0.80629951 2.84489813 -0.8038 2 P 0 ;0
L 2.84489813 -0.8038 2.86089833 -0.80629951 2 P 0 ;0
L 2.86089833 -0.80629951 2.87489902 -0.81630197 2 P 0 ;0
L 2.87489902 -0.81630197 2.8869001 -0.83129872 2 P 0 ;0
L 2.8869001 -0.83129872 2.89490207 -0.84879961 2 P 0 ;0
L 2.89490207 -0.84879961 2.89890128 -0.8687999 2 P 0 ;0
L 2.89890128 -0.8687999 2.89890128 -0.8888002 2 P 0 ;0
L 2.89890128 -0.8888002 2.89490207 -0.90880049 2 P 0 ;0
L 2.89490207 -0.90880049 2.8869001 -0.92630138 2 P 0 ;0
L 2.8869001 -0.92630138 2.87489902 -0.94130276 2 P 0 ;0
L 2.87489902 -0.94130276 2.86089833 -0.95130059 2 P 0 ;0
L 2.86089833 -0.95130059 2.84489813 -0.9538 2 P 0 ;0
L 3.0488997 -0.81630197 3.03689862 -0.80879902 2 P 0 ;0
L 3.03689862 -0.80879902 3.02290157 -0.8038 2 P 0 ;0
L 3.02290157 -0.8038 3.00690138 -0.8038 2 P 0 ;0
L 3.00690138 -0.8038 2.98889783 -0.81130305 2 P 0 ;0
L 2.98889783 -0.81130305 2.97490089 -0.82380039 2 P 0 ;0
L 2.97490089 -0.82380039 2.96489931 -0.83880177 2 P 0 ;0
L 2.96489931 -0.83880177 2.95689734 -0.86380098 2 P 0 ;0
L 2.95689734 -0.86380098 2.95489783 -0.88630069 2 P 0 ;0
L 2.95489783 -0.88630069 2.95890059 -0.90880049 2 P 0 ;0
L 2.95890059 -0.90880049 2.96489931 -0.92380187 2 P 0 ;0
L 2.96489931 -0.92380187 2.97690039 -0.93880325 2 P 0 ;0
L 2.97690039 -0.93880325 2.99090108 -0.94880108 2 P 0 ;0
L 2.99090108 -0.94880108 3.00489813 -0.9538 2 P 0 ;0
L 3.00489813 -0.9538 3.01889882 -0.9538 2 P 0 ;0
L 3.01889882 -0.9538 3.03289951 -0.94880108 2 P 0 ;0
L 3.03289951 -0.94880108 3.04490059 -0.94130276 2 P 0 ;0
L 3.04490059 -0.94130276 3.05490207 -0.93130482 2 P 0 ;0
L 3.16489813 -0.8038 3.16489813 -0.9538 2 P 0 ;0
L 3.11890059 -0.8038 3.21089931 -0.8038 2 P 0 ;0
L 3.28889852 -0.95879892 3.36090138 -0.8038 2 P 0 ;0
L 3.44689892 -0.82879931 3.4589 -0.81380246 2 P 0 ;0
L 3.4589 -0.81380246 3.47290069 -0.80629951 2 P 0 ;0
L 3.47290069 -0.80629951 3.48890089 -0.8038 2 P 0 ;0
L 3.48890089 -0.8038 3.5089003 -0.80879902 2 P 0 ;0
L 3.5089003 -0.80879902 3.52290098 -0.82130089 2 P 0 ;0
L 3.52290098 -0.82130089 3.5269001 -0.83629764 2 P 0 ;0
L 3.5269001 -0.83629764 3.52490059 -0.85130364 2 P 0 ;0
L 3.52490059 -0.85130364 3.51689862 -0.86380098 2 P 0 ;0
L 3.51689862 -0.86380098 3.4768998 -0.8888002 2 P 0 ;0
L 3.4768998 -0.8888002 3.4589 -0.90630108 2 P 0 ;0
L 3.4589 -0.90630108 3.44689892 -0.93130482 2 P 0 ;0
L 3.44689892 -0.93130482 3.4428998 -0.9538 2 P 0 ;0
L 3.4428998 -0.9538 3.5269001 -0.9538 2 P 0 ;0
L 3.64089902 -0.9538 3.64489813 -0.92130246 2 P 0 ;0
L 3.64489813 -0.92130246 3.65090049 -0.89380374 2 P 0 ;0
L 3.65090049 -0.89380374 3.65889882 -0.8687999 2 P 0 ;0
L 3.65889882 -0.8687999 3.6689003 -0.84130118 2 P 0 ;0
L 3.6689003 -0.84130118 3.68490059 -0.8038 2 P 0 ;0
L 3.68490059 -0.8038 3.60489931 -0.8038 2 P 0 ;0
L 3.76889852 -0.95879892 3.84090138 -0.8038 2 P 0 ;0
L 3.92689892 -0.82879931 3.9389 -0.81380246 2 P 0 ;0
L 3.9389 -0.81380246 3.95290069 -0.80629951 2 P 0 ;0
L 3.95290069 -0.80629951 3.96890089 -0.8038 2 P 0 ;0
L 3.96890089 -0.8038 3.9889003 -0.80879902 2 P 0 ;0
L 3.9889003 -0.80879902 4.00290098 -0.82130089 2 P 0 ;0
L 4.00290098 -0.82130089 4.0069001 -0.83629764 2 P 0 ;0
L 4.0069001 -0.83629764 4.00490059 -0.85130364 2 P 0 ;0
L 4.00490059 -0.85130364 3.99689862 -0.86380098 2 P 0 ;0
L 3.99689862 -0.86380098 3.9568998 -0.8888002 2 P 0 ;0
L 3.9568998 -0.8888002 3.9389 -0.90630108 2 P 0 ;0
L 3.9389 -0.90630108 3.92689892 -0.93130482 2 P 0 ;0
L 3.92689892 -0.93130482 3.9228998 -0.9538 2 P 0 ;0
L 3.9228998 -0.9538 4.0069001 -0.9538 2 P 0 ;0
L 4.12489813 -0.8038 4.10889783 -0.80879902 2 P 0 ;0
L 4.10889783 -0.80879902 4.09690039 -0.82130089 2 P 0 ;0
L 4.09690039 -0.82130089 4.08889852 -0.83629764 2 P 0 ;0
L 4.08889852 -0.83629764 4.0828998 -0.85630256 2 P 0 ;0
L 4.0828998 -0.85630256 4.0809002 -0.87880236 2 P 0 ;0
L 4.0809002 -0.87880236 4.0828998 -0.90130207 2 P 0 ;0
L 4.0828998 -0.90130207 4.08889852 -0.92130246 2 P 0 ;0
L 4.08889852 -0.92130246 4.09690039 -0.93630374 2 P 0 ;0
L 4.09690039 -0.93630374 4.10889783 -0.94880108 2 P 0 ;0
L 4.10889783 -0.94880108 4.12489813 -0.9538 2 P 0 ;0
L 4.12489813 -0.9538 4.14089833 -0.94880108 2 P 0 ;0
L 4.14089833 -0.94880108 4.15289951 -0.93630374 2 P 0 ;0
L 4.15289951 -0.93630374 4.16090138 -0.92130246 2 P 0 ;0
L 4.16090138 -0.92130246 4.1669001 -0.90130207 2 P 0 ;0
L 4.1669001 -0.90130207 4.1688997 -0.87880236 2 P 0 ;0
L 4.1688997 -0.87880236 4.1669001 -0.85630256 2 P 0 ;0
L 4.1669001 -0.85630256 4.16090138 -0.83629764 2 P 0 ;0
L 4.16090138 -0.83629764 4.15289951 -0.82130089 2 P 0 ;0
L 4.15289951 -0.82130089 4.14089833 -0.80879902 2 P 0 ;0
L 4.14089833 -0.80879902 4.12489813 -0.8038 2 P 0 ;0
L 4.28489813 -0.9538 4.28489813 -0.8038 2 P 0 ;0
L 4.28489813 -0.8038 4.26089961 -0.83379823 2 P 0 ;0
L 4.26089961 -0.9538 4.30889665 -0.9538 2 P 0 ;0
L 4.44089902 -0.9538 4.44489813 -0.92130246 2 P 0 ;0
L 4.44489813 -0.92130246 4.45090049 -0.89380374 2 P 0 ;0
L 4.45090049 -0.89380374 4.45889882 -0.8687999 2 P 0 ;0
L 4.45889882 -0.8687999 4.4689003 -0.84130118 2 P 0 ;0
L 4.4689003 -0.84130118 4.48490059 -0.8038 2 P 0 ;0
L 4.48490059 -0.8038 4.40489931 -0.8038 2 P 0 ;0
L 1.9639003 -1.6638 1.93590197 -1.6638 2 P 0 ;0
L 1.94990108 -1.6638 1.94990108 -1.7538 2 P 0 ;0
L 1.9639003 -1.7538 1.93590197 -1.7538 2 P 0 ;0
L 1.88673297 -1.7538 1.88673297 -1.6638 2 P 0 ;0
L 1.88673297 -1.6638 1.83306713 -1.7538 2 P 0 ;0
L 1.83306713 -1.7538 1.83306713 -1.6638 2 P 0 ;0
L 1.76990108 -1.6638 1.76990108 -1.7538 2 P 0 ;0
L 1.79673297 -1.6638 1.74306713 -1.6638 2 P 0 ;0
L 1.65656634 -1.7538 1.70323376 -1.7538 2 P 0 ;0
L 1.70323376 -1.7538 1.70323376 -1.6638 2 P 0 ;0
L 1.70323376 -1.6638 1.65656634 -1.6638 2 P 0 ;0
L 1.67523327 -1.70729902 1.70323376 -1.70729902 2 P 0 ;0
L 1.61323376 -1.7538 1.61323376 -1.6638 2 P 0 ;0
L 1.61323376 -1.6638 1.58406693 -1.6638 2 P 0 ;0
L 1.58406693 -1.6638 1.57473346 -1.66830187 2 P 0 ;0
L 1.57473346 -1.66830187 1.56889921 -1.67430059 2 P 0 ;0
L 1.56889921 -1.67430059 1.56656634 -1.68630069 2 P 0 ;0
L 1.56656634 -1.68630069 1.56889921 -1.69830089 2 P 0 ;0
L 1.56889921 -1.69830089 1.5758998 -1.70579931 2 P 0 ;0
L 1.5758998 -1.70579931 1.58406693 -1.71030108 2 P 0 ;0
L 1.58406693 -1.71030108 1.61323376 -1.71030108 2 P 0 ;0
L 1.58406693 -1.71030108 1.56656634 -1.7538 2 P 0 ;0
L 1.52673297 -1.7538 1.52673297 -1.6638 2 P 0 ;0
L 1.52673297 -1.6638 1.47306713 -1.7538 2 P 0 ;0
L 1.47306713 -1.7538 1.47306713 -1.6638 2 P 0 ;0
L 1.43906791 -1.7538 1.40990108 -1.6638 2 P 0 ;0
L 1.40990108 -1.6638 1.38073219 -1.7538 2 P 0 ;0
L 1.39123415 -1.72230128 1.42856811 -1.72230128 2 P 0 ;0
L 1.34323376 -1.6638 1.34323376 -1.7538 2 P 0 ;0
L 1.34323376 -1.7538 1.29656634 -1.7538 2 P 0 ;0
L 1.16323376 -1.6638 1.16323376 -1.7538 2 P 0 ;0
L 1.16323376 -1.7538 1.11656634 -1.7538 2 P 0 ;0
L 1.07906791 -1.7538 1.04990108 -1.6638 2 P 0 ;0
L 1.04990108 -1.6638 1.02073219 -1.7538 2 P 0 ;0
L 1.03123415 -1.72230128 1.06856811 -1.72230128 2 P 0 ;0
L 0.95990108 -1.7538 0.95990108 -1.71330049 2 P 0 ;0
L 0.95990108 -1.71330049 0.98323376 -1.6638 2 P 0 ;0
L 0.93656634 -1.6638 0.95990108 -1.71330049 2 P 0 ;0
L 0.84656634 -1.7538 0.89323376 -1.7538 2 P 0 ;0
L 0.89323376 -1.7538 0.89323376 -1.6638 2 P 0 ;0
L 0.89323376 -1.6638 0.84656634 -1.6638 2 P 0 ;0
L 0.86523327 -1.70729902 0.89323376 -1.70729902 2 P 0 ;0
L 0.80323376 -1.7538 0.80323376 -1.6638 2 P 0 ;0
L 0.80323376 -1.6638 0.77406693 -1.6638 2 P 0 ;0
L 0.77406693 -1.6638 0.76473346 -1.66830187 2 P 0 ;0
L 0.76473346 -1.66830187 0.75889921 -1.67430059 2 P 0 ;0
L 0.75889921 -1.67430059 0.75656634 -1.68630069 2 P 0 ;0
L 0.75656634 -1.68630069 0.75889921 -1.69830089 2 P 0 ;0
L 0.75889921 -1.69830089 0.7658998 -1.70579931 2 P 0 ;0
L 0.7658998 -1.70579931 0.77406693 -1.71030108 2 P 0 ;0
L 0.77406693 -1.71030108 0.80323376 -1.71030108 2 P 0 ;0
L 0.77406693 -1.71030108 0.75656634 -1.7538 2 P 0 ;0
L 0.59990108 -1.7538 0.59990108 -1.6638 2 P 0 ;0
L 0.59990108 -1.6638 0.6139003 -1.68179892 2 P 0 ;0
L 0.6139003 -1.7538 0.58590197 -1.7538 2 P 0 ;0
L 0.50990108 -1.7538 0.50990108 -1.6638 2 P 0 ;0
L 0.50990108 -1.6638 0.5239003 -1.68179892 2 P 0 ;0
L 0.5239003 -1.7538 0.49590197 -1.7538 2 P 0 ;0
L 3.76989892 -2.0038 3.76989892 -1.9138 2 P 0 ;0
L 3.76989892 -1.9138 3.7558997 -1.93179892 2 P 0 ;0
L 3.7558997 -2.0038 3.78389803 -2.0038 2 P 0 ;0
L 3.85989892 -2.0038 3.85989892 -1.9138 2 P 0 ;0
L 3.85989892 -1.9138 3.8458997 -1.93179892 2 P 0 ;0
L 3.8458997 -2.0038 3.87389803 -2.0038 2 P 0 ;0
L 3.01989892 -2.2538 3.01989892 -2.1638 2 P 0 ;0
L 3.01989892 -2.1638 3.0058997 -2.18179892 2 P 0 ;0
L 3.0058997 -2.2538 3.03389803 -2.2538 2 P 0 ;0
L 3.10989892 -2.2538 3.10989892 -2.1638 2 P 0 ;0
L 3.10989892 -2.1638 3.0958997 -2.18179892 2 P 0 ;0
L 3.0958997 -2.2538 3.12389803 -2.2538 2 P 0 ;0

### steps/drc/layers/l2/features
#
#Feature symbol names
#
$0 r2
$1 r5
$2 r6
$3 r10
$4 r15
$5 r20
$6 r28
$7 r30
$8 r32
$9 r33
$10 r40
$11 r50
$12 r57.09
$13 r78.74
$14 r86.61
$15 r90.55
$16 r100
$17 r131.89
$18 r137.8
$19 r161.42
$20 r168.31
$21 r173.23
$22 r181.1
$23 r204.72
$24 r224.41
$25 r440.94
$26 null
$27 oval236.22x177.17
$28 thr61.02x49.21x45x4x15.75
$29 thr96.46x76.77x45x4x19.69

#
#Feature attribute names
#
@0 .nomenclature
@1 .geometry

#
#Feature attribute text strings
#
&0 TPB30V20D10AT28BPM
&1 C1_11P0_7
&2 C1_11P0_7TP
&3 V17D8AT30SM11
&4 V20D10AT28SM14
&5 C2_5N
&6 S1_11P0_7TP
&7 S1_11P0_7
&8 V20D10AT28PG
&9 C1_17P0_76TPM
&10 C1_9P1_4
&11 S1_9P1_4
&12 SP-8C5_2P0_254
&13 SP-9C5_7P0_254
&14 C3_175N-A
&15 C10N
&16 C3_3N
&17 C4_5N-B
&18 C4N-B
&19 C3_5N
&20 O5X3_5N
&21 C3N
&22 C1_3N
&23 C2_35N
&24 C1N

#
#Layer features
#
P 7.785 4.45 6 P 0 0;1=0
P 7.835 4.45 6 P 0 0;1=0
P 1.8 4.485 6 P 0 0;1=0
P 1.86 4.485 6 P 0 0;1=0
P 0.27165 1.72835 12 P 0 0;1=1
P 0.17323002 2.12205 12 P 0 0;1=1
P 12.73621004 1.76771998 12 P 0 0;1=1
P 12.81495 2.59448996 12 P 0 0;1=1
P 12.63778996 2.16141998 12 P 0 0;1=1
P 0.725 -0.25 12 P 0 0;1=2
P 0.875 -0.25 12 P 0 0;1=2
P 1.065 6.26 12 P 0 0;1=2
P 1.065 6.36 12 P 0 0;1=2
P 1.29 6.26 12 P 0 0;1=2
P 1.29 6.36 12 P 0 0;1=2
P 1.515 6.26 12 P 0 0;1=2
P 1.515 6.36 12 P 0 0;1=2
P 0.84 6.26 12 P 0 0;1=2
P 0.84 6.36 12 P 0 0;1=2
P 1.74 6.26 12 P 0 0;1=2
P 1.74 6.36 12 P 0 0;1=2
P 2.09606004 3.56615 7 P 0 0;1=3
P 8.1 3.56615 7 P 0 0;1=3
P 12.55905 3.38188996 12 P 0 0;1=1
P 12.81495 4.64173996 12 P 0 0;1=1
P 12.81495 1.88583002 12 P 0 0;1=1
P 0.35038996 4.60236998 12 P 0 0;1=1
P 0.35038996 2.55511998 12 P 0 0;1=1
P 0.35038996 1.84646004 12 P 0 0;1=1
P 0.09448996 3.34251998 12 P 0 0;1=1
P 6.385 5.03 6 P 0 0;1=4
P 12.68701998 0.97243996 18 P 0 0;1=5
P 0.22245 0.93306998 18 P 0 0;1=5
P 12.68701004 4.91338002 18 P 0 0;1=5
P 3.94 4.545 6 P 0 0;1=0
P 4.91 5.375 6 P 0 0;1=4
P 1.08 5.85 6 P 0 0;1=0
P 3.6817 5.74 6 P 0 0;1=4
P 10.07 2.928 6 P 0 0;1=4
P 4.105 4.985 6 P 0 0;1=0
P 4.125 2.725 6 P 0 0;1=4
P 4.02 4.355 6 P 0 0;1=0
P 1.16 5.85 6 P 0 0;1=0
P 3.815 5.815 6 P 0 0;1=4
P 1.19 6.36 28 P 0 3;1=6
P 1.19 6.26 28 P 0 3;1=6
P 1.415 6.36 28 P 0 3;1=6
P 1.415 6.26 28 P 0 3;1=6
P 1.64 6.36 28 P 0 3;1=6
P 1.64 6.26 28 P 0 3;1=6
P 0.965 6.26 28 P 0 3;1=6
P 0.965 6.36 28 P 0 3;1=6
P 0.74 6.26 28 P 0 3;1=6
P 0.74 6.36 28 P 0 3;1=6
P 12.63778996 1.37401998 12 P 0 0;1=7
P 0.17323002 1.33465 12 P 0 0;1=7
P 6.501 5.017 6 P 0 0;1=0
P 7.425 3.43 6 P 0 0;1=0
P 7.445 1.705 6 P 0 0;1=4
P 11.03661004 3.81615 7 P 0 0;1=3
P 11.135 2.845 6 P 0 0;1=4
P 11.03661004 2.16615 7 P 0 0;1=3
P 3.8899 4.765 6 P 0 0;1=0
P 4.93268002 2.41615 7 P 0 0;1=3
P 4.93268002 2.46615 7 P 0 0;1=3
P 7.2926 5.04351004 6 P 0 0;1=0
P 7.2426 5.04351004 6 P 0 0;1=0
P 3.45646004 5.3 6 P 0 0;1=0
P 1.28906004 5.04351004 6 P 0 0;1=0
P 1.23906004 5.04351004 6 P 0 0;1=0
P 9.46 5.3 6 P 0 0;1=0
P 4.68268002 2.36615 7 P 0 0;1=3
P 0.27165 4.01181004 12 P 0 0;1=1
P 4.58268002 2.36615 7 P 0 0;1=3
P 0.27165 4.16928996 12 P 0 0;1=1
P 4.63268002 2.41615 7 P 0 0;1=3
P 0.27165 4.32676998 12 P 0 0;1=1
P 4.73268002 2.26615 7 P 0 0;1=3
P 0.27165 3.38188996 12 P 0 0;1=1
P 4.73268002 2.41615 7 P 0 0;1=3
P 0.27165 4.48425 12 P 0 0;1=1
P 4.68268002 2.21615 7 P 0 0;1=3
P 0.27165 3.53936998 12 P 0 0;1=1
P 4.63268002 2.26615 7 P 0 0;1=3
P 0.27165 3.85433002 12 P 0 0;1=1
P 4.58268002 2.06615 7 P 0 0;1=3
P 0.35038996 3.02756004 12 P 0 0;1=1
P 4.58268002 2.11615 7 P 0 0;1=3
P 0.27165 2.98818996 12 P 0 0;1=1
P 4.63268002 1.86615 7 P 0 0;1=3
P 0.35038996 2.3189 12 P 0 0;1=1
P 4.58268002 1.96615 7 P 0 0;1=3
P 0.27165 2.43701004 12 P 0 0;1=1
P 4.68268002 2.06615 7 P 0 0;1=3
P 0.35038996 3.18503996 12 P 0 0;1=1
P 4.58268002 1.91615 7 P 0 0;1=3
P 0.35038996 2.47638002 12 P 0 0;1=1
P 0.27165 2.27953002 12 P 0 0;1=1
P 4.63268002 1.91615 7 P 0 0;1=3
P 5.42048002 1.7396 7 P 0 0;1=3
P 0.09448996 2.55511998 12 P 0 0;1=1
P 4.68268002 2.11615 7 P 0 0;1=3
P 0.27165 3.14566998 12 P 0 0;1=1
P 5.42048002 1.7796 7 P 0 0;1=3
P 0.17323002 2.51575 12 P 0 0;1=1
P 4.68268002 1.91615 7 P 0 0;1=3
P 0.35038996 2.16141998 12 P 0 0;1=1
P 4.68268002 1.96615 7 P 0 0;1=3
P 0.27165 2.12205 12 P 0 0;1=1
P 5.57531004 2.0878 7 P 0 0;1=3
P 0.09448996 3.1063 12 P 0 0;1=1
P 5.57531004 2.1278 7 P 0 0;1=3
P 0.17323002 3.06693002 12 P 0 0;1=1
P 5.57531004 2.2232 7 P 0 0;1=3
P 0.17323002 3.46063002 12 P 0 0;1=1
P 5.57531004 2.2632 7 P 0 0;1=3
P 0.09448996 3.42126004 12 P 0 0;1=1
P 5.42048002 2.4662 7 P 0 0;1=3
P 0.09448996 4.05118002 12 P 0 0;1=1
P 5.57531004 2.3986 7 P 0 0;1=3
P 0.09448996 3.8937 12 P 0 0;1=1
P 5.57531004 2.673 7 P 0 0;1=3
P 0.09448996 4.36613996 12 P 0 0;1=1
P 5.57531004 1.9869 7 P 0 0;1=3
P 0.17323002 2.75196998 12 P 0 0;1=1
P 5.57531004 2.4978 7 P 0 0;1=3
P 0.17323002 4.24803002 12 P 0 0;1=1
P 5.57531004 1.6718 7 P 0 0;1=3
P 0.17323002 2.20078996 12 P 0 0;1=1
P 5.57531004 2.633 7 P 0 0;1=3
P 0.17323002 4.40551004 12 P 0 0;1=1
P 5.57531004 1.7118 7 P 0 0;1=3
P 0.09448996 2.24016004 12 P 0 0;1=1
P 5.57531004 2.5378 7 P 0 0;1=3
P 0.09448996 4.20866004 12 P 0 0;1=1
P 5.42048002 1.6433 7 P 0 0;1=3
P 0.09448996 2.39763996 12 P 0 0;1=1
P 5.42048002 2.6054 7 P 0 0;1=3
P 0.09448996 4.52361998 12 P 0 0;1=1
P 5.42048002 1.87835 7 P 0 0;1=3
P 0.09448996 2.94881998 12 P 0 0;1=1
P 5.57531004 2.3586 7 P 0 0;1=3
P 0.17323002 3.93306998 12 P 0 0;1=1
P 5.42048002 1.6033 7 P 0 0;1=3
P 0.17323002 2.35826998 12 P 0 0;1=1
P 5.42048002 2.4262 7 P 0 0;1=3
P 0.17323002 4.09055 12 P 0 0;1=1
P 5.42048002 1.91835 7 P 0 0;1=3
P 0.17323002 2.90945 12 P 0 0;1=1
P 5.42048002 2.0547 7 P 0 0;1=3
P 0.17323002 3.22441004 12 P 0 0;1=1
P 5.57531004 1.9469 7 P 0 0;1=3
P 0.09448996 2.79133996 12 P 0 0;1=1
P 5.42048002 2.0147 7 P 0 0;1=3
P 0.09448996 3.26378002 12 P 0 0;1=1
P 5.57531004 1.8508 7 P 0 0;1=3
P 0.09448996 2.00393996 12 P 0 0;1=1
P 5.57531004 1.8108 7 P 0 0;1=3
P 0.17323002 2.04331004 12 P 0 0;1=1
P 0.35038996 3.97243996 12 P 0 0;1=1
P 4.68268002 2.41615 7 P 0 0;1=3
P 4.73268002 2.46615 7 P 0 0;1=3
P 0.35038996 4.44488002 12 P 0 0;1=1
P 4.63268002 2.46615 7 P 0 0;1=3
P 0.35038996 4.2874 12 P 0 0;1=1
P 0.35038996 4.12991998 12 P 0 0;1=1
P 4.58268002 2.41615 7 P 0 0;1=3
P 4.68268002 2.26615 7 P 0 0;1=3
P 0.35038996 3.5 12 P 0 0;1=1
P 5.42048002 2.1554 7 P 0 0;1=3
P 0.17323002 3.77558996 12 P 0 0;1=1
P 4.73268002 2.31615 7 P 0 0;1=3
P 0.35038996 3.34251998 12 P 0 0;1=1
P 4.63268002 2.31615 7 P 0 0;1=3
P 0.35038996 3.81496004 12 P 0 0;1=1
P 4.58268002 2.26615 7 P 0 0;1=3
P 0.35038996 3.65748002 12 P 0 0;1=1
P 5.42048002 2.5654 7 P 0 0;1=3
P 0.17323002 4.563 12 P 0 0;1=1
P 5.42048002 2.1954 7 P 0 0;1=3
P 0.09448996 3.73621998 12 P 0 0;1=1
P 0.09448996 3.57873996 12 P 0 0;1=1
P 5.42048002 2.3308 7 P 0 0;1=3
P 0.17323002 3.61811004 12 P 0 0;1=1
P 5.42048002 2.2908 7 P 0 0;1=3
P 0.35038996 1.9252 12 P 0 0;1=1
P 4.73268002 1.91615 7 P 0 0;1=3
P 4.73268002 1.86615 7 P 0 0;1=3
P 0.27165 1.96456998 12 P 0 0;1=1
P 4.58268002 2.21615 7 P 0 0;1=3
P 0.27165 3.69685 12 P 0 0;1=1
P 4.73268002 2.06615 7 P 0 0;1=3
P 0.27165 2.67323002 12 P 0 0;1=1
P 4.73268002 2.01615 7 P 0 0;1=3
P 0.35038996 2.7126 12 P 0 0;1=1
P 4.63268002 2.01615 7 P 0 0;1=3
P 0.35038996 2.87008002 12 P 0 0;1=1
P 4.63268002 2.06615 7 P 0 0;1=3
P 0.27165 2.83071004 12 P 0 0;1=1
P 6.785 4.725 6 P 0 0;1=4
P 6.785 4.685 6 P 0 0;1=4
P 6.74018996 4.765 6 P 0 0;1=4
P 6.74 4.805 6 P 0 0;1=0
P 6.785 4.845 6 P 0 0;1=4
P 6.785 4.805 6 P 0 0;1=4
P 6.785 4.765 6 P 0 0;1=4
P 6.74 4.845 6 P 0 0;1=4
P 6.65 5.055 6 P 0 0;1=0
P 6.49205 5.09705 6 P 0 0;1=0
P 6.495 4.9328 6 P 0 0;1=0
P 6.55118996 5.04705 6 P 0 0;1=0
P 6.78 4.94705 6 P 0 0;1=0
P 6.755 4.89705 6 P 0 0;1=0
P 6.74 4.987 6 P 0 0;1=0
P 12.73621004 2.08268002 12 P 0 0;1=1
P 12.73621004 2.63386004 12 P 0 0;1=1
P 12.81495 3.30315 12 P 0 0;1=1
P 12.73621004 4.60236998 12 P 0 0;1=1
P 12.55905 1.96456998 12 P 0 0;1=1
P 12.63778996 1.9252 12 P 0 0;1=1
P 0.09448996 1.9252 12 P 0 0;1=1
P 0.17323002 1.88583002 12 P 0 0;1=1
P 0.27165 2.04331004 12 P 0 0;1=1
P 0.27165 4.563 12 P 0 0;1=1
P 0.35038996 3.26378002 12 P 0 0;1=1
P 0.27165 2.59448996 12 P 0 0;1=1
P 0.17323002 1.72835 12 P 0 0;1=1
P 5.03268002 1.91615 7 P 0 0;1=3
P 1.025 -0.25 12 P 0 0;1=2
P 1.175 -0.25 12 P 0 0;1=2
P 1.325 -0.25 12 P 0 0;1=2
P 5.03268002 2.06615 7 P 0 0;1=3
P 12.63778996 4.12991998 12 P 0 0;1=1
P 11.53316004 2.372 7 P 0 0;1=3
P 5.08268002 2.26615 7 P 0 0;1=3
P 11.53316004 1.892 7 P 0 0;1=3
P 12.55905 3.30315 12 P 0 0;1=1
P 12.81495 2.51575 12 P 0 0;1=1
P 10.58661004 1.91615 7 P 0 0;1=3
P 10.26 1.66445 7 P 0 0;1=3
P 11.03998996 4.8431 6 P 0 0;1=4
P 11.08498996 4.8431 6 P 0 0;1=4
P 11.13498996 4.8431 6 P 0 0;1=4
P 11.17998996 4.8431 6 P 0 0;1=4
P 11.17998996 4.8031 6 P 0 0;1=4
P 11.17998996 4.7581 6 P 0 0;1=4
P 11.17998996 4.7131 6 P 0 0;1=4
P 11.17998996 4.6731 6 P 0 0;1=4
P 11.03998996 4.6731 6 P 0 0;1=4
P 11.08498996 4.6731 6 P 0 0;1=4
P 11.13498996 4.6731 6 P 0 0;1=4
P 11.03998996 4.7131 6 P 0 0;1=4
P 11.03998996 4.8031 6 P 0 0;1=4
P 11.03998996 4.7581 6 P 0 0;1=4
P 10.81998996 4.6631 6 P 0 0;1=4
P 10.85998996 4.6631 6 P 0 0;1=4
P 10.65998996 4.6631 6 P 0 0;1=4
P 10.69998996 4.6631 6 P 0 0;1=4
P 10.81998996 4.7031 6 P 0 0;1=4
P 10.81998996 4.8381 6 P 0 0;1=4
P 10.81998996 4.7931 6 P 0 0;1=4
P 10.81998996 4.7481 6 P 0 0;1=4
P 10.85998996 4.7031 6 P 0 0;1=4
P 10.85998996 4.8381 6 P 0 0;1=4
P 10.85998996 4.7931 6 P 0 0;1=4
P 10.85998996 4.7481 6 P 0 0;1=4
P 10.65998996 4.7031 6 P 0 0;1=4
P 10.65998996 4.8381 6 P 0 0;1=4
P 10.65998996 4.7931 6 P 0 0;1=4
P 10.65998996 4.7481 6 P 0 0;1=4
P 10.69998996 4.7031 6 P 0 0;1=4
P 10.69998996 4.8381 6 P 0 0;1=4
P 10.69998996 4.7931 6 P 0 0;1=4
P 10.69998996 4.7481 6 P 0 0;1=4
P 10.77998996 4.6431 6 P 0 0;1=4
P 10.73498996 4.6431 6 P 0 0;1=4
P 10.73998996 4.8381 6 P 0 0;1=4
P 10.77998996 4.8381 6 P 0 0;1=4
P 10.30998996 4.6631 6 P 0 0;1=4
P 10.26998996 4.6631 6 P 0 0;1=4
P 10.34498996 4.6431 6 P 0 0;1=4
P 10.38998996 4.6431 6 P 0 0;1=4
P 10.42998996 4.6631 6 P 0 0;1=4
P 10.46998996 4.6631 6 P 0 0;1=4
P 10.30998996 4.7481 6 P 0 0;1=4
P 10.30998996 4.7931 6 P 0 0;1=4
P 10.30998996 4.7031 6 P 0 0;1=4
P 10.26998996 4.7481 6 P 0 0;1=4
P 10.26998996 4.7931 6 P 0 0;1=4
P 10.26998996 4.7031 6 P 0 0;1=4
P 10.26998996 4.8381 6 P 0 0;1=4
P 10.30998996 4.8381 6 P 0 0;1=4
P 10.38998996 4.8381 6 P 0 0;1=4
P 10.34998996 4.8381 6 P 0 0;1=4
P 10.46998996 4.8381 6 P 0 0;1=4
P 10.42998996 4.8381 6 P 0 0;1=4
P 10.42998996 4.7031 6 P 0 0;1=4
P 10.42998996 4.7931 6 P 0 0;1=4
P 10.42998996 4.7481 6 P 0 0;1=4
P 10.46998996 4.7031 6 P 0 0;1=4
P 10.46998996 4.7931 6 P 0 0;1=4
P 10.46998996 4.7481 6 P 0 0;1=4
P 10.58661004 3.16615 7 P 0 0;1=3
P 10.63661004 3.01615 7 P 0 0;1=3
P 10.58661004 3.11615 7 P 0 0;1=3
P 10.58661004 3.01615 7 P 0 0;1=3
P 10.63661004 3.11615 7 P 0 0;1=3
P 10.63661004 2.96615 7 P 0 0;1=3
P 10.58661004 2.96615 7 P 0 0;1=3
P 10.58661004 3.41615 7 P 0 0;1=3
P 10.63661004 3.16615 7 P 0 0;1=3
P 10.63661004 3.26615 7 P 0 0;1=3
P 10.58661004 3.31615 7 P 0 0;1=3
P 10.58661004 3.26615 7 P 0 0;1=3
P 10.63661004 3.31615 7 P 0 0;1=3
P 10.63661004 3.56615 7 P 0 0;1=3
P 10.63661004 3.61615 7 P 0 0;1=3
P 10.58661004 3.56615 7 P 0 0;1=3
P 10.58661004 3.61615 7 P 0 0;1=3
P 10.63661004 3.46615 7 P 0 0;1=3
P 10.63661004 3.41615 7 P 0 0;1=3
P 10.58661004 3.46615 7 P 0 0;1=3
P 10.63661004 3.86615 7 P 0 0;1=3
P 10.63661004 3.76615 7 P 0 0;1=3
P 10.58661004 3.86615 7 P 0 0;1=3
P 10.58661004 3.76615 7 P 0 0;1=3
P 10.63661004 3.71615 7 P 0 0;1=3
P 10.58661004 3.71615 7 P 0 0;1=3
P 10.88661004 2.96615 7 P 0 0;1=3
P 10.83661004 2.96615 7 P 0 0;1=3
P 10.88661004 3.01615 7 P 0 0;1=3
P 10.83661004 3.01615 7 P 0 0;1=3
P 10.88661004 3.11615 7 P 0 0;1=3
P 10.83661004 3.11615 7 P 0 0;1=3
P 10.83661004 3.16615 7 P 0 0;1=3
P 10.78661004 3.16615 7 P 0 0;1=3
P 10.68661004 3.16615 7 P 0 0;1=3
P 10.73661004 3.16615 7 P 0 0;1=3
P 10.78661004 3.01615 7 P 0 0;1=3
P 10.78661004 3.11615 7 P 0 0;1=3
P 10.73661004 3.01615 7 P 0 0;1=3
P 10.73661004 3.11615 7 P 0 0;1=3
P 10.68661004 3.01615 7 P 0 0;1=3
P 10.68661004 3.11615 7 P 0 0;1=3
P 10.78661004 2.96615 7 P 0 0;1=3
P 10.73661004 2.96615 7 P 0 0;1=3
P 10.68661004 2.96615 7 P 0 0;1=3
P 10.88661004 3.16615 7 P 0 0;1=3
P 10.88661004 3.26615 7 P 0 0;1=3
P 10.83661004 3.26615 7 P 0 0;1=3
P 10.83661004 3.31615 7 P 0 0;1=3
P 10.88661004 3.31615 7 P 0 0;1=3
P 10.83661004 3.41615 7 P 0 0;1=3
P 10.78661004 3.41615 7 P 0 0;1=3
P 10.68661004 3.41615 7 P 0 0;1=3
P 10.73661004 3.41615 7 P 0 0;1=3
P 10.78661004 3.31615 7 P 0 0;1=3
P 10.78661004 3.26615 7 P 0 0;1=3
P 10.68661004 3.31615 7 P 0 0;1=3
P 10.68661004 3.26615 7 P 0 0;1=3
P 10.73661004 3.26615 7 P 0 0;1=3
P 10.73661004 3.31615 7 P 0 0;1=3
P 10.88661004 3.41615 7 P 0 0;1=3
P 10.83661004 3.46615 7 P 0 0;1=3
P 10.88661004 3.46615 7 P 0 0;1=3
P 10.83661004 3.56615 7 P 0 0;1=3
P 10.88661004 3.56615 7 P 0 0;1=3
P 10.83661004 3.61615 7 P 0 0;1=3
P 10.88661004 3.61615 7 P 0 0;1=3
P 10.78661004 3.56615 7 P 0 0;1=3
P 10.78661004 3.61615 7 P 0 0;1=3
P 10.68661004 3.61615 7 P 0 0;1=3
P 10.68661004 3.56615 7 P 0 0;1=3
P 10.73661004 3.61615 7 P 0 0;1=3
P 10.73661004 3.56615 7 P 0 0;1=3
P 10.78661004 3.46615 7 P 0 0;1=3
P 10.73661004 3.46615 7 P 0 0;1=3
P 10.68661004 3.46615 7 P 0 0;1=3
P 10.83661004 3.71615 7 P 0 0;1=3
P 10.88661004 3.71615 7 P 0 0;1=3
P 10.83661004 3.76615 7 P 0 0;1=3
P 10.88661004 3.76615 7 P 0 0;1=3
P 10.83661004 3.86615 7 P 0 0;1=3
P 10.88661004 3.86615 7 P 0 0;1=3
P 10.78661004 3.86615 7 P 0 0;1=3
P 10.78661004 3.76615 7 P 0 0;1=3
P 10.68661004 3.86615 7 P 0 0;1=3
P 10.68661004 3.76615 7 P 0 0;1=3
P 10.73661004 3.86615 7 P 0 0;1=3
P 10.73661004 3.76615 7 P 0 0;1=3
P 10.78661004 3.71615 7 P 0 0;1=3
P 10.68661004 3.71615 7 P 0 0;1=3
P 10.73661004 3.71615 7 P 0 0;1=3
P 11.03661004 2.96615 7 P 0 0;1=3
P 10.93661004 2.96615 7 P 0 0;1=3
P 10.98661004 2.96615 7 P 0 0;1=3
P 11.03661004 3.01615 7 P 0 0;1=3
P 10.93661004 3.01615 7 P 0 0;1=3
P 10.98661004 3.01615 7 P 0 0;1=3
P 11.03661004 3.11615 7 P 0 0;1=3
P 10.93661004 3.11615 7 P 0 0;1=3
P 10.98661004 3.11615 7 P 0 0;1=3
P 11.03661004 3.16615 7 P 0 0;1=3
P 10.93661004 3.16615 7 P 0 0;1=3
P 10.98661004 3.16615 7 P 0 0;1=3
P 11.03661004 3.26615 7 P 0 0;1=3
P 10.93661004 3.26615 7 P 0 0;1=3
P 10.98661004 3.26615 7 P 0 0;1=3
P 10.98661004 3.31615 7 P 0 0;1=3
P 10.93661004 3.31615 7 P 0 0;1=3
P 11.03661004 3.31615 7 P 0 0;1=3
P 10.98661004 3.41615 7 P 0 0;1=3
P 10.93661004 3.41615 7 P 0 0;1=3
P 11.03661004 3.41615 7 P 0 0;1=3
P 10.98661004 3.46615 7 P 0 0;1=3
P 10.93661004 3.46615 7 P 0 0;1=3
P 11.03661004 3.46615 7 P 0 0;1=3
P 10.98661004 3.56615 7 P 0 0;1=3
P 10.93661004 3.56615 7 P 0 0;1=3
P 11.03661004 3.56615 7 P 0 0;1=3
P 10.98661004 3.61615 7 P 0 0;1=3
P 10.93661004 3.61615 7 P 0 0;1=3
P 11.03661004 3.61615 7 P 0 0;1=3
P 10.98661004 3.71615 7 P 0 0;1=3
P 10.93661004 3.71615 7 P 0 0;1=3
P 11.03661004 3.71615 7 P 0 0;1=3
P 10.98661004 3.76615 7 P 0 0;1=3
P 10.93661004 3.76615 7 P 0 0;1=3
P 11.03661004 3.76615 7 P 0 0;1=3
P 10.98661004 3.86615 7 P 0 0;1=3
P 10.93661004 3.86615 7 P 0 0;1=3
P 11.03661004 3.86615 7 P 0 0;1=3
P 5.08268002 2.06615 7 P 0 0;1=3
P 10.58661004 2.36615 7 P 0 0;1=3
P 9.975 2.4709 7 P 0 0;1=3
P 12.73621004 4.20866004 12 P 0 0;1=1
P 11.08661004 2.36615 7 P 0 0;1=3
P 5.08268002 2.11615 7 P 0 0;1=3
P 11.08661004 2.41615 7 P 0 0;1=3
P 12.73621004 2.47638002 12 P 0 0;1=1
P 10.58661004 1.96615 7 P 0 0;1=3
P 10.26 1.70445 7 P 0 0;1=3
P 10.98661004 2.41615 7 P 0 0;1=3
P 8.5 3.76615 7 P 0 0;1=3
P 9.35271004 5.1035 7 P 0 0;1=3
P 4.98268002 2.06615 7 P 0 0;1=3
P 8.5 3.81615 7 P 0 0;1=3
P 9.31271004 5.1035 7 P 0 0;1=3
P 12.55905 2.59448996 12 P 0 0;1=1
P 11.53316004 1.572 7 P 0 0;1=3
P 4.98268002 2.11615 7 P 0 0;1=3
P 10.98661004 2.36615 7 P 0 0;1=3
P 8.5 3.61615 7 P 0 0;1=3
P 9.56531004 5.14 7 P 0 0;1=3
P 4.93268002 2.01615 7 P 0 0;1=3
P 11.53316004 1.412 7 P 0 0;1=3
P 12.63778996 2.39763996 12 P 0 0;1=1
P 8.5 3.66615 7 P 0 0;1=3
P 9.52531004 5.14 7 P 0 0;1=3
P 12.73621004 2.87008002 12 P 0 0;1=1
P 10.63661004 2.06615 7 P 0 0;1=3
P 10.225 1.96645 7 P 0 0;1=3
P 11.53316004 1.452 7 P 0 0;1=3
P 12.55905 2.43701004 12 P 0 0;1=1
P 8.35 3.66615 7 P 0 0;1=3
P 9.56531004 4.71973002 7 P 0 0;1=3
P 4.93268002 2.06615 7 P 0 0;1=3
P 8.35 3.71615 7 P 0 0;1=3
P 9.52531004 4.71973002 7 P 0 0;1=3
P 11.83316004 2.212 7 P 0 0;1=3
P 12.63778996 3.65748002 12 P 0 0;1=1
P 12.73621004 3.02756004 12 P 0 0;1=1
P 10.58661004 2.11615 7 P 0 0;1=3
P 10.09 2.05655 7 P 0 0;1=3
P 11.53316004 1.932 7 P 0 0;1=3
P 12.63778996 3.26378002 12 P 0 0;1=1
P 8.74578996 5.14 7 P 0 0;1=3
P 8.05 3.61615 7 P 0 0;1=3
P 12.81495 4.01181004 12 P 0 0;1=1
P 10.09 2.57845 7 P 0 0;1=3
P 10.68661004 2.41615 7 P 0 0;1=3
P 11.73316004 1.492 7 P 0 0;1=3
P 12.63778996 2.24016004 12 P 0 0;1=1
P 8.78578996 5.14 7 P 0 0;1=3
P 8.05 3.66615 7 P 0 0;1=3
P 12.73621004 2.7126 12 P 0 0;1=1
P 10.73661004 2.06615 7 P 0 0;1=3
P 10.26025 1.86845 7 P 0 0;1=3
P 11.03661004 2.46615 7 P 0 0;1=3
P 8.15 3.61615 7 P 0 0;1=3
P 8.88441004 5.17001998 7 P 0 0;1=3
P 12.55905 4.09055 12 P 0 0;1=1
P 11.53316004 2.412 7 P 0 0;1=3
P 11.03661004 2.51615 7 P 0 0;1=3
P 8.15 3.66615 7 P 0 0;1=3
P 8.92441004 5.17001998 7 P 0 0;1=3
P 1.057 5.027 6 P 0 0;1=0
P 12.73621004 3.18503996 12 P 0 0;1=1
P 10.68661004 2.11615 7 P 0 0;1=3
P 10.09 2.17095 7 P 0 0;1=3
P 11.78316004 1.692 7 P 0 0;1=3
P 12.55905 2.04331004 12 P 0 0;1=1
P 12.81495 2.90945 12 P 0 0;1=1
P 10.63661004 2.01615 7 P 0 0;1=3
P 10.225 1.92645 7 P 0 0;1=3
P 11.78316004 1.652 7 P 0 0;1=3
P 12.63778996 2.08268002 12 P 0 0;1=1
P 1.122 5.417 6 P 0 0;1=4
P 5.855 0.925 6 P 0 0;1=4
P 3.88 4.545 6 P 0 0;1=0
P 0.96555 5.78055 6 P 0 0;1=0
P 4.07 4.625 6 P 0 0;1=4
P 10.58661004 2.71615 7 P 0 0;1=3
P 9.91 4.433 6 P 0 0;1=0
P 9.995 2.936 6 P 0 0;1=4
P 11.83316004 2.252 7 P 0 0;1=3
P 12.55905 3.61811004 12 P 0 0;1=1
P 12.81495 3.06693002 12 P 0 0;1=1
P 10.58661004 2.06615 7 P 0 0;1=3
P 10.09 2.01655 7 P 0 0;1=3
P 8.1 3.81615 7 P 0 0;1=3
P 9.10011004 5.0535 7 P 0 0;1=3
P 8.1 3.86615 7 P 0 0;1=3
P 9.14011004 5.0535 7 P 0 0;1=3
P 3.9599 5.395 6 P 0 0;1=0
P 0.88681004 5.78181004 6 P 0 0;1=4
P 12.73621004 2.3189 12 P 0 0;1=1
P 10.63661004 1.91615 7 P 0 0;1=3
P 10.38371998 1.49328002 7 P 0 0;1=3
P 8.35 3.81615 7 P 0 0;1=3
P 9.28185 5.22001998 7 P 0 0;1=3
P 0.72933002 5.463 6 P 0 0;1=0
P 11.53316004 2.572 7 P 0 0;1=3
P 12.55905 4.56298996 12 P 0 0;1=1
P 8.35 3.86615 7 P 0 0;1=3
P 9.24185 5.22001998 7 P 0 0;1=3
P 4.125 2.682 6 P 0 0;1=4
P 3.94 4.42 6 P 0 0;1=0
P 5.03 5.4 6 P 0 0;1=4
P 4.58268002 2.71615 7 P 0 0;1=3
P 8.45 3.81615 7 P 0 0;1=3
P 9.21098002 4.78291998 7 P 0 0;1=3
P 8.45 3.86615 7 P 0 0;1=3
P 9.17098002 4.78291998 7 P 0 0;1=3
P 3.75998996 0.24001004 6 P 0 0;1=0
P 9.55795 0.26133996 6 P 0 0;1=0
P 3.71203002 0.77535 6 P 0 0;1=4
P 3.70998996 0.7 6 P 0 0;1=4
P 9.50795 0.72133002 6 P 0 0;1=4
P 9.46795 0.82631998 6 P 0 0;1=4
P 4.02893002 2.59336998 6 P 0 0;1=4
P 11.395 2.725 6 P 0 0;1=0
P 11.395 2.8 6 P 0 0;1=4
P 11.58613002 2.905 6 P 0 0;1=4
P 11.58613002 2.785 6 P 0 0;1=4
P 1.33906004 4.60351004 6 P 0 0;1=0
P 3.67 4.45 6 P 0 0;1=4
P 3.72 4.545 6 P 0 0;1=4
P 5.37968996 2.8 6 P 0 0;1=4
P 5.387 2.725 6 P 0 0;1=0
P 5.5822 2.785 6 P 0 0;1=4
P 5.5822 2.905 6 P 0 0;1=4
P 7.2426 4.69351004 6 P 0 0;1=4
P 7.2926 4.60351004 6 P 0 0;1=4
P 9.98 4.51 6 P 0 0;1=4
P 10.07286004 2.82336998 6 P 0 0;1=4
P 10.03 4.61 6 P 0 0;1=4
P 1.23906004 4.69351004 6 P 0 0;1=4
P 3.89 4.655 6 P 0 0;1=4
P 3.9899 4.765 6 P 0 0;1=4
P 4.1049 4.86 6 P 0 0;1=4
P 4.0599 5.395 6 P 0 0;1=4
P 3.91 5.51 6 P 0 0;1=4
P 5.125 5.4 6 P 0 0;1=4
P 1.37925 5.78 6 P 0 0;1=4
P 1.45798996 5.78 6 P 0 0;1=4
P 1.42 5.78 6 P 0 0;1=4
P 1.335 5.78 6 P 0 0;1=4
P 12.63778996 2.55511998 12 P 0 0;1=1
P 11.53316004 1.612 7 P 0 0;1=3
P 8.4 3.76615 7 P 0 0;1=3
P 9.28185 4.642 7 P 0 0;1=3
P 12.73621004 4.36613996 12 P 0 0;1=1
P 10.63661004 2.41615 7 P 0 0;1=3
P 9.975 2.66445 7 P 0 0;1=3
P 8.4 3.81615 7 P 0 0;1=3
P 9.24185 4.642 7 P 0 0;1=3
P 11.53316004 2.532 7 P 0 0;1=3
P 12.63778996 4.60236998 12 P 0 0;1=1
P 8.45 3.66615 7 P 0 0;1=3
P 9.42358002 4.78291998 7 P 0 0;1=3
P 0.95951004 5.4595 6 P 0 0;1=0
P 8.45 3.71615 7 P 0 0;1=3
P 9.38358002 4.78291998 7 P 0 0;1=3
P 8.4 3.61615 7 P 0 0;1=3
P 9.49445 4.587 7 P 0 0;1=3
P 8.4 3.66615 7 P 0 0;1=3
P 9.45445 4.587 7 P 0 0;1=3
P 9.07353996 4.42 6 P 0 0;1=4
P 7.1926 5.15351004 6 P 0 0;1=0
P 8.1 3.66615 7 P 0 0;1=3
P 8.74578996 4.667 7 P 0 0;1=3
P 8.1 3.71615 7 P 0 0;1=3
P 8.78578996 4.667 7 P 0 0;1=3
P 8.2 3.66615 7 P 0 0;1=3
P 8.81665 4.78291998 7 P 0 0;1=3
P 8.2 3.71615 7 P 0 0;1=3
P 8.85665 4.78291998 7 P 0 0;1=3
P 8.05 3.76615 7 P 0 0;1=3
P 8.89061998 4.667 7 P 0 0;1=3
P 8.05 3.81615 7 P 0 0;1=3
P 8.93061998 4.667 7 P 0 0;1=3
P 9.02925 4.667 7 P 0 0;1=3
P 8.2 3.81615 7 P 0 0;1=3
P 9.06925 4.667 7 P 0 0;1=3
P 8.2 3.86615 7 P 0 0;1=3
P 4.68268002 2.71615 7 P 0 0;1=3
P 4.98268002 2.71615 7 P 0 0;1=3
P 2.14606004 2.51615 7 P 0 0;1=3
P 8.45 3.41615 7 P 0 0;1=3
P 8.18811004 5.0535 7 P 0 0;1=3
P 5.03268002 3.81615 7 P 0 0;1=3
P 4.07408002 4.01978996 6 P 0 0;1=0
P 8.45 3.46615 7 P 0 0;1=3
P 8.14811004 5.0535 7 P 0 0;1=3
P 5.03268002 2.16615 7 P 0 0;1=3
P 3.9099 5.395 6 P 0 0;1=0
P 8.45 3.26615 7 P 0 0;1=3
P 8.40071004 5.115 7 P 0 0;1=3
P 8.45 3.31615 7 P 0 0;1=3
P 8.36071004 5.115 7 P 0 0;1=3
P 8.35 3.26615 7 P 0 0;1=3
P 8.40071004 4.742 7 P 0 0;1=3
P 8.35 3.31615 7 P 0 0;1=3
P 8.36071004 4.742 7 P 0 0;1=3
P 8.3 3.56615 7 P 0 0;1=3
P 8.05 3.31615 7 P 0 0;1=3
P 7.58118996 5.169 7 P 0 0;1=3
P 8.25 3.56615 7 P 0 0;1=3
P 8.05 3.36615 7 P 0 0;1=3
P 7.62118996 5.169 7 P 0 0;1=3
P 2.24606004 2.86615 7 P 0 0;1=3
P 8.05 2.61615 26 P 0 0;1=3
P 8.05 2.66615 26 P 0 0;1=3
P 8.1 2.46615 26 P 0 0;1=3
P 8.1 2.41615 26 P 0 0;1=3
P 8.2 2.46615 26 P 0 0;1=3
P 8.2 2.41615 26 P 0 0;1=3
P 8.15 2.41615 26 P 0 0;1=3
P 8.15 2.36615 26 P 0 0;1=3
P 8.05 2.41615 26 P 0 0;1=3
P 8.05 2.36615 26 P 0 0;1=3
P 8.2 2.31615 26 P 0 0;1=3
P 8.2 2.26615 26 P 0 0;1=3
P 8.15 2.26615 26 P 0 0;1=3
P 8.15 2.21615 26 P 0 0;1=3
P 8.1 2.31615 26 P 0 0;1=3
P 8.1 2.26615 26 P 0 0;1=3
P 8.05 2.26615 26 P 0 0;1=3
P 8.05 2.21615 26 P 0 0;1=3
P 8.1 2.11615 26 P 0 0;1=3
P 8.1 2.06615 26 P 0 0;1=3
P 8.2 2.11615 26 P 0 0;1=3
P 8.2 2.06615 26 P 0 0;1=3
P 8.15 2.06615 26 P 0 0;1=3
P 8.15 2.01615 26 P 0 0;1=3
P 8.05 2.06615 26 P 0 0;1=3
P 8.05 2.01615 26 P 0 0;1=3
P 8.2 1.96615 26 P 0 0;1=3
P 8.2 1.91615 26 P 0 0;1=3
P 8.15 1.91615 26 P 0 0;1=3
P 8.15 1.86615 26 P 0 0;1=3
P 8.1 1.96615 26 P 0 0;1=3
P 8.1 1.91615 26 P 0 0;1=3
P 8.05 1.91615 26 P 0 0;1=3
P 8.05 1.86615 26 P 0 0;1=3
P 8.1 3.16615 26 P 0 0;1=3
P 8.1 3.11615 26 P 0 0;1=3
P 8.2 3.16615 26 P 0 0;1=3
P 8.2 3.11615 26 P 0 0;1=3
P 8.15 3.11615 26 P 0 0;1=3
P 8.15 3.06615 26 P 0 0;1=3
P 8.05 3.11615 26 P 0 0;1=3
P 8.05 3.06615 26 P 0 0;1=3
P 8.2 3.01615 26 P 0 0;1=3
P 8.2 2.96615 26 P 0 0;1=3
P 8.15 2.96615 26 P 0 0;1=3
P 8.15 2.91615 26 P 0 0;1=3
P 8.1 3.01615 26 P 0 0;1=3
P 8.1 2.96615 26 P 0 0;1=3
P 8.05 2.96615 26 P 0 0;1=3
P 8.05 2.91615 26 P 0 0;1=3
P 8 2.81615 26 P 0 0;1=3
P 8 2.76615 26 P 0 0;1=3
P 8.15 2.81615 26 P 0 0;1=3
P 8.15 2.76615 26 P 0 0;1=3
P 8.2 2.76615 26 P 0 0;1=3
P 8.2 2.71615 26 P 0 0;1=3
P 8.1 2.76615 26 P 0 0;1=3
P 8.1 2.71615 26 P 0 0;1=3
P 8.15 2.66615 26 P 0 0;1=3
P 8.15 2.61615 26 P 0 0;1=3
P 8.2 2.61615 26 P 0 0;1=3
P 8.2 2.56615 26 P 0 0;1=3
P 8.1 2.61615 26 P 0 0;1=3
P 8.1 2.56615 26 P 0 0;1=3
P 8.35 2.56615 26 P 0 0;1=3
P 8.35 2.61615 26 P 0 0;1=3
P 8.35 2.46615 26 P 0 0;1=3
P 8.35 2.41615 26 P 0 0;1=3
P 8.45 2.46615 26 P 0 0;1=3
P 8.45 2.41615 26 P 0 0;1=3
P 8.5 2.41615 26 P 0 0;1=3
P 8.5 2.36615 26 P 0 0;1=3
P 8.4 2.41615 26 P 0 0;1=3
P 8.4 2.36615 26 P 0 0;1=3
P 8.45 2.31615 26 P 0 0;1=3
P 8.45 2.26615 26 P 0 0;1=3
P 8.5 2.26615 26 P 0 0;1=3
P 8.5 2.21615 26 P 0 0;1=3
P 8.4 2.26615 26 P 0 0;1=3
P 8.4 2.21615 26 P 0 0;1=3
P 8.35 2.31615 26 P 0 0;1=3
P 8.35 2.26615 26 P 0 0;1=3
P 8.35 2.11615 26 P 0 0;1=3
P 8.35 2.06615 26 P 0 0;1=3
P 8.45 2.11615 26 P 0 0;1=3
P 8.45 2.06615 26 P 0 0;1=3
P 8.5 2.06615 26 P 0 0;1=3
P 8.5 2.01615 26 P 0 0;1=3
P 8.4 2.06615 26 P 0 0;1=3
P 8.4 2.01615 26 P 0 0;1=3
P 8.45 1.96615 26 P 0 0;1=3
P 8.45 1.91615 26 P 0 0;1=3
P 8.5 1.91615 26 P 0 0;1=3
P 8.5 1.86615 26 P 0 0;1=3
P 8.4 1.91615 26 P 0 0;1=3
P 8.4 1.86615 26 P 0 0;1=3
P 8.35 1.96615 26 P 0 0;1=3
P 8.35 1.91615 26 P 0 0;1=3
P 8.35 3.16615 26 P 0 0;1=3
P 8.35 3.11615 26 P 0 0;1=3
P 8.45 3.16615 26 P 0 0;1=3
P 8.45 3.11615 26 P 0 0;1=3
P 8.5 3.11615 26 P 0 0;1=3
P 8.5 3.06615 26 P 0 0;1=3
P 8.4 3.11615 26 P 0 0;1=3
P 8.4 3.06615 26 P 0 0;1=3
P 8.45 3.01615 26 P 0 0;1=3
P 8.45 2.96615 26 P 0 0;1=3
P 8.5 2.96615 26 P 0 0;1=3
P 8.5 2.91615 26 P 0 0;1=3
P 8.4 2.96615 26 P 0 0;1=3
P 8.4 2.91615 26 P 0 0;1=3
P 8.35 3.01615 26 P 0 0;1=3
P 8.35 2.96615 26 P 0 0;1=3
P 8.4 2.81615 26 P 0 0;1=3
P 8.4 2.76615 26 P 0 0;1=3
P 8.5 2.81615 26 P 0 0;1=3
P 8.5 2.76615 26 P 0 0;1=3
P 8.45 2.76615 26 P 0 0;1=3
P 8.45 2.71615 26 P 0 0;1=3
P 8.35 2.76615 26 P 0 0;1=3
P 8.35 2.71615 26 P 0 0;1=3
P 8.5 2.66615 26 P 0 0;1=3
P 8.5 2.61615 26 P 0 0;1=3
P 8.45 2.61615 26 P 0 0;1=3
P 8.45 2.56615 26 P 0 0;1=3
P 8.4 2.66615 26 P 0 0;1=3
P 8.4 2.61615 26 P 0 0;1=3
P 2.04606024 2.61615 26 P 0 0;1=3
P 2.04606024 2.66615 26 P 0 0;1=3
P 2.09606024 2.46615 26 P 0 0;1=3
P 2.09606024 2.41615 26 P 0 0;1=3
P 2.19606024 2.46615 26 P 0 0;1=3
P 2.19606024 2.41615 26 P 0 0;1=3
P 2.14606024 2.41615 26 P 0 0;1=3
P 2.14606024 2.36615 26 P 0 0;1=3
P 2.04606024 2.41615 26 P 0 0;1=3
P 2.04606024 2.36615 26 P 0 0;1=3
P 2.19606024 2.31615 26 P 0 0;1=3
P 2.19606024 2.26615 26 P 0 0;1=3
P 2.14606024 2.26615 26 P 0 0;1=3
P 2.14606024 2.21615 26 P 0 0;1=3
P 2.09606024 2.31615 26 P 0 0;1=3
P 2.09606024 2.26615 26 P 0 0;1=3
P 2.04606024 2.26615 26 P 0 0;1=3
P 2.04606024 2.21615 26 P 0 0;1=3
P 2.09606024 2.11615 26 P 0 0;1=3
P 2.09606024 2.06615 26 P 0 0;1=3
P 2.19606024 2.11615 26 P 0 0;1=3
P 2.19606024 2.06615 26 P 0 0;1=3
P 2.14606024 2.06615 26 P 0 0;1=3
P 2.14606024 2.01615 26 P 0 0;1=3
P 2.04606024 2.06615 26 P 0 0;1=3
P 2.04606024 2.01615 26 P 0 0;1=3
P 2.19606024 1.96615 26 P 0 0;1=3
P 2.19606024 1.91615 26 P 0 0;1=3
P 2.14606024 1.91615 26 P 0 0;1=3
P 2.14606024 1.86615 26 P 0 0;1=3
P 2.09606024 1.96615 26 P 0 0;1=3
P 2.09606024 1.91615 26 P 0 0;1=3
P 2.04606024 1.91615 26 P 0 0;1=3
P 2.04606024 1.86615 26 P 0 0;1=3
P 2.09606024 3.16615 26 P 0 0;1=3
P 2.09606024 3.11615 26 P 0 0;1=3
P 2.19606024 3.16615 26 P 0 0;1=3
P 2.19606024 3.11615 26 P 0 0;1=3
P 2.14606024 3.11615 26 P 0 0;1=3
P 2.14606024 3.06615 26 P 0 0;1=3
P 2.04606024 3.11615 26 P 0 0;1=3
P 2.04606024 3.06615 26 P 0 0;1=3
P 2.19606024 3.01615 26 P 0 0;1=3
P 2.19606024 2.96615 26 P 0 0;1=3
P 2.14606024 2.96615 26 P 0 0;1=3
P 2.14606024 2.91615 26 P 0 0;1=3
P 2.09606024 3.01615 26 P 0 0;1=3
P 2.09606024 2.96615 26 P 0 0;1=3
P 2.04606024 2.96615 26 P 0 0;1=3
P 2.04606024 2.91615 26 P 0 0;1=3
P 1.99605974 2.81615 26 P 0 0;1=3
P 1.99605974 2.76615 26 P 0 0;1=3
P 2.14606024 2.81615 26 P 0 0;1=3
P 2.14606024 2.76615 26 P 0 0;1=3
P 2.19606024 2.76615 26 P 0 0;1=3
P 2.19606024 2.71615 26 P 0 0;1=3
P 2.09606024 2.76615 26 P 0 0;1=3
P 2.09606024 2.71615 26 P 0 0;1=3
P 2.14606024 2.66615 26 P 0 0;1=3
P 2.14606024 2.61615 26 P 0 0;1=3
P 2.19606024 2.61615 26 P 0 0;1=3
P 2.19606024 2.56615 26 P 0 0;1=3
P 2.09606024 2.61615 26 P 0 0;1=3
P 2.09606024 2.56615 26 P 0 0;1=3
P 2.34606024 2.56615 26 P 0 0;1=3
P 2.34606024 2.61615 26 P 0 0;1=3
P 2.34606024 2.46615 26 P 0 0;1=3
P 2.34606024 2.41615 26 P 0 0;1=3
P 2.44606024 2.46615 26 P 0 0;1=3
P 2.44606024 2.41615 26 P 0 0;1=3
P 2.49606024 2.41615 26 P 0 0;1=3
P 2.49606024 2.36615 26 P 0 0;1=3
P 2.39606024 2.41615 26 P 0 0;1=3
P 2.39606024 2.36615 26 P 0 0;1=3
P 2.44606024 2.31615 26 P 0 0;1=3
P 2.44606024 2.26615 26 P 0 0;1=3
P 2.49606024 2.26615 26 P 0 0;1=3
P 2.49606024 2.21615 26 P 0 0;1=3
P 2.39606024 2.26615 26 P 0 0;1=3
P 2.39606024 2.21615 26 P 0 0;1=3
P 2.34606024 2.31615 26 P 0 0;1=3
P 2.34606024 2.26615 26 P 0 0;1=3
P 2.34606024 2.11615 26 P 0 0;1=3
P 2.34606024 2.06615 26 P 0 0;1=3
P 2.44606024 2.11615 26 P 0 0;1=3
P 2.44606024 2.06615 26 P 0 0;1=3
P 2.49606024 2.06615 26 P 0 0;1=3
P 2.49606024 2.01615 26 P 0 0;1=3
P 2.39606024 2.06615 26 P 0 0;1=3
P 2.39606024 2.01615 26 P 0 0;1=3
P 2.44606024 1.96615 26 P 0 0;1=3
P 2.44606024 1.91615 26 P 0 0;1=3
P 2.49606024 1.91615 26 P 0 0;1=3
P 2.49606024 1.86615 26 P 0 0;1=3
P 2.39606024 1.91615 26 P 0 0;1=3
P 2.39606024 1.86615 26 P 0 0;1=3
P 2.34606024 1.96615 26 P 0 0;1=3
P 2.34606024 1.91615 26 P 0 0;1=3
P 2.34606024 3.16615 26 P 0 0;1=3
P 2.34606024 3.11615 26 P 0 0;1=3
P 2.44606024 3.16615 26 P 0 0;1=3
P 2.44606024 3.11615 26 P 0 0;1=3
P 2.49606024 3.11615 26 P 0 0;1=3
P 2.49606024 3.06615 26 P 0 0;1=3
P 2.39606024 3.11615 26 P 0 0;1=3
P 2.39606024 3.06615 26 P 0 0;1=3
P 2.44606024 3.01615 26 P 0 0;1=3
P 2.44606024 2.96615 26 P 0 0;1=3
P 2.49606024 2.96615 26 P 0 0;1=3
P 2.49606024 2.91615 26 P 0 0;1=3
P 2.39606024 2.96615 26 P 0 0;1=3
P 2.39606024 2.91615 26 P 0 0;1=3
P 2.34606024 3.01615 26 P 0 0;1=3
P 2.34606024 2.96615 26 P 0 0;1=3
P 2.39606024 2.81615 26 P 0 0;1=3
P 2.39606024 2.76615 26 P 0 0;1=3
P 2.49606024 2.81615 26 P 0 0;1=3
P 2.49606024 2.76615 26 P 0 0;1=3
P 2.44606024 2.76615 26 P 0 0;1=3
P 2.44606024 2.71615 26 P 0 0;1=3
P 2.34606024 2.76615 26 P 0 0;1=3
P 2.34606024 2.71615 26 P 0 0;1=3
P 2.49606024 2.66615 26 P 0 0;1=3
P 2.49606024 2.61615 26 P 0 0;1=3
P 2.44606024 2.61615 26 P 0 0;1=3
P 2.44606024 2.56615 26 P 0 0;1=3
P 2.39606024 2.66615 26 P 0 0;1=3
P 2.39606024 2.61615 26 P 0 0;1=3
P 8.94061998 4.70574026 26 P 0 0;1=4
P 9.01925 4.70574026 26 P 0 0;1=4
P 9.07925 4.70574026 26 P 0 0;1=4
P 8.73579006 4.70573996 26 P 0 0;1=4
P 8.79579006 4.70573996 26 P 0 0;1=4
P 8.86665 4.74417972 26 P 0 0;1=4
P 8.80665 4.74417972 26 P 0 0;1=4
P 9.43358002 4.74417972 26 P 0 0;1=4
P 9.51531004 4.68098996 26 P 0 0;1=4
P 9.57531004 4.68098996 26 P 0 0;1=4
P 9.44445 4.62574026 26 P 0 0;1=4
P 9.50445 4.62574026 26 P 0 0;1=4
P 9.23185 4.68074026 26 P 0 0;1=4
P 9.29185 4.68074026 26 P 0 0;1=4
P 9.16098002 4.74417972 26 P 0 0;1=4
P 9.37358002 4.74417972 26 P 0 0;1=4
P 9.22098002 4.74417972 26 P 0 0;1=4
P 9.51531004 5.17873996 26 P 0 0;1=4
P 9.57531004 5.17873996 26 P 0 0;1=4
P 9.43358002 5.18127972 26 P 0 0;1=4
P 9.23185 5.18127972 26 P 0 0;1=4
P 9.29185 5.18127972 26 P 0 0;1=4
P 9.37358002 5.18127972 26 P 0 0;1=4
P 9.36271004 5.14223996 26 P 0 0;1=4
P 9.30271004 5.14223996 26 P 0 0;1=4
P 9.15011004 5.09223996 26 P 0 0;1=4
P 9.09011004 5.09223996 26 P 0 0;1=4
P 9.07925 5.20374026 26 P 0 0;1=4
P 9.01925 5.20374026 26 P 0 0;1=4
P 8.93440994 5.20876004 26 P 0 0;1=4
P 8.73579006 5.17873996 26 P 0 0;1=4
P 8.79579006 5.17873996 26 P 0 0;1=4
P 8.87440994 5.20876004 26 P 0 0;1=4
P 7.64205 4.74417972 26 P 0 0;1=4
P 7.70205 4.74417972 26 P 0 0;1=4
P 7.63118996 4.66826004 26 P 0 0;1=4
P 7.57118996 4.66826004 26 P 0 0;1=4
P 7.91465 4.61825974 26 P 0 0;1=4
P 7.78378996 4.74418002 26 P 0 0;1=4
P 7.84378996 4.74418002 26 P 0 0;1=4
P 7.85465 4.61825974 26 P 0 0;1=4
P 8.06725 4.74417972 26 P 0 0;1=4
P 8.12725 4.74417972 26 P 0 0;1=4
P 8.02207028 4.62815 26 P 0 0;1=4
P 8.08207028 4.62815 26 P 0 0;1=4
P 8.41070994 4.70326004 26 P 0 0;1=4
P 8.35070994 4.70326004 26 P 0 0;1=4
P 8.20898002 4.74417972 26 P 0 0;1=4
P 8.26898002 4.74417972 26 P 0 0;1=4
P 8.21208996 4.62826004 26 P 0 0;1=4
P 8.27208996 4.62826004 26 P 0 0;1=4
P 8.19811004 5.09223996 26 P 0 0;1=4
P 8.12725 5.13025974 26 P 0 0;1=4
P 8.06725 5.13025974 26 P 0 0;1=4
P 7.91465 5.13025974 26 P 0 0;1=4
P 7.92551004 5.09223996 26 P 0 0;1=4
P 7.98551004 5.09223996 26 P 0 0;1=4
P 7.85465 5.13025974 26 P 0 0;1=4
P 7.64204006 5.09223996 26 P 0 0;1=4
P 7.70204006 5.09223996 26 P 0 0;1=4
P 7.57118996 5.13026004 26 P 0 0;1=4
P 7.63118996 5.13026004 26 P 0 0;1=4
P 2.73225 4.70574026 26 P 0 0;1=4
P 2.79225 4.70574026 26 P 0 0;1=4
P 3.22830994 5.18128002 26 P 0 0;1=4
P 3.28830994 5.18128002 26 P 0 0;1=4
P 3.01571004 5.20373996 26 P 0 0;1=4
P 3.07571004 5.20373996 26 P 0 0;1=4
P 2.73225 5.17874026 26 P 0 0;1=4
P 2.79225 5.17874026 26 P 0 0;1=4
P 1.56765 4.66825974 26 P 0 0;1=4
P 1.62765 4.66825974 26 P 0 0;1=4
P 1.56765 5.13025974 26 P 0 0;1=4
P 1.62765 5.13025974 26 P 0 0;1=4
P 1.91110994 5.13026004 26 P 0 0;1=4
P 1.85110994 5.13026004 26 P 0 0;1=4
P 5.08267972 2.76615 26 P 0 0;1=3
P 5.03267972 2.76615 26 P 0 0;1=3
P 5.03267972 2.71615 26 P 0 0;1=3
P 4.93267972 2.76615 26 P 0 0;1=3
P 4.98267972 2.76615 26 P 0 0;1=3
P 4.93267972 2.71615 26 P 0 0;1=3
P 5.08267972 2.66615 26 P 0 0;1=3
P 4.98267972 2.66615 26 P 0 0;1=3
P 5.03267972 2.56615 26 P 0 0;1=3
P 4.93267972 2.56615 26 P 0 0;1=3
P 4.98267972 2.46615 26 P 0 0;1=3
P 4.98267972 2.51615 26 P 0 0;1=3
P 4.93267972 2.51615 26 P 0 0;1=3
P 5.08267972 2.51615 26 P 0 0;1=3
P 5.08267972 2.46615 26 P 0 0;1=3
P 5.03267972 2.21615 26 P 0 0;1=3
P 4.93267972 2.21615 26 P 0 0;1=3
P 4.98267972 2.31615 26 P 0 0;1=3
P 4.93267972 2.36615 26 P 0 0;1=3
P 5.08267972 2.31615 26 P 0 0;1=3
P 5.08267972 2.16615 26 P 0 0;1=3
P 4.93267972 2.16615 26 P 0 0;1=3
P 4.98267972 2.16615 26 P 0 0;1=3
P 4.93267972 1.96615 26 P 0 0;1=3
P 5.03267972 1.96615 26 P 0 0;1=3
P 5.03267972 2.11615 26 P 0 0;1=3
P 4.93267972 2.11615 26 P 0 0;1=3
P 4.98267972 2.01615 26 P 0 0;1=3
P 5.08267972 2.01615 26 P 0 0;1=3
P 4.98267972 1.86615 26 P 0 0;1=3
P 5.08267972 1.86615 26 P 0 0;1=3
P 4.78267972 3.81615 26 P 0 0;1=3
P 4.78267972 3.66615 26 P 0 0;1=3
P 4.73267972 3.81615 26 P 0 0;1=3
P 4.73267972 3.66615 26 P 0 0;1=3
P 4.68267972 3.81615 26 P 0 0;1=3
P 4.68267972 3.66615 26 P 0 0;1=3
P 4.78267972 3.51615 26 P 0 0;1=3
P 4.73267972 3.51615 26 P 0 0;1=3
P 4.68267972 3.51615 26 P 0 0;1=3
P 4.78267972 3.36615 26 P 0 0;1=3
P 4.73267972 3.36615 26 P 0 0;1=3
P 4.78267972 3.21615 26 P 0 0;1=3
P 4.73267972 3.21615 26 P 0 0;1=3
P 4.68267972 3.36615 26 P 0 0;1=3
P 4.68267972 3.21615 26 P 0 0;1=3
P 4.78267972 3.06615 26 P 0 0;1=3
P 4.73267972 3.06615 26 P 0 0;1=3
P 4.68267972 3.06615 26 P 0 0;1=3
P 4.78267972 2.91615 26 P 0 0;1=3
P 4.73267972 2.91615 26 P 0 0;1=3
P 4.68267972 2.91615 26 P 0 0;1=3
P 4.88267972 2.76615 26 P 0 0;1=3
P 4.88267972 2.66615 26 P 0 0;1=3
P 4.78267972 2.46615 26 P 0 0;1=3
P 4.88267972 2.56615 26 P 0 0;1=3
P 4.88267972 2.61615 26 P 0 0;1=3
P 4.68267972 2.46615 26 P 0 0;1=3
P 4.88267972 2.46615 26 P 0 0;1=3
P 4.88267972 2.51615 26 P 0 0;1=3
P 4.78267972 2.41615 26 P 0 0;1=3
P 4.88267972 2.41615 26 P 0 0;1=3
P 4.78267972 2.36615 26 P 0 0;1=3
P 4.78267972 2.31615 26 P 0 0;1=3
P 4.78267972 2.26615 26 P 0 0;1=3
P 4.78267972 2.21615 26 P 0 0;1=3
P 4.73267972 2.36615 26 P 0 0;1=3
P 4.68267972 2.31615 26 P 0 0;1=3
P 4.73267972 2.21615 26 P 0 0;1=3
P 4.88267972 2.21615 26 P 0 0;1=3
P 4.88267972 2.26615 26 P 0 0;1=3
P 4.88267972 2.31615 26 P 0 0;1=3
P 4.88267972 2.36615 26 P 0 0;1=3
P 4.73267972 2.16615 26 P 0 0;1=3
P 4.68267972 2.16615 26 P 0 0;1=3
P 4.78267972 1.96615 26 P 0 0;1=3
P 4.78267972 2.06615 26 P 0 0;1=3
P 4.78267972 2.01615 26 P 0 0;1=3
P 4.88267972 1.96615 26 P 0 0;1=3
P 4.88267972 2.06615 26 P 0 0;1=3
P 4.88267972 2.01615 26 P 0 0;1=3
P 4.78267972 2.11615 26 P 0 0;1=3
P 4.88267972 2.11615 26 P 0 0;1=3
P 4.73267972 2.11615 26 P 0 0;1=3
P 4.68267972 2.01615 26 P 0 0;1=3
P 4.73267972 1.96615 26 P 0 0;1=3
P 4.78267972 1.86615 26 P 0 0;1=3
P 4.88267972 1.86615 26 P 0 0;1=3
P 4.68267972 1.86615 26 P 0 0;1=3
P 4.63267972 3.81615 26 P 0 0;1=3
P 4.63267972 3.66615 26 P 0 0;1=3
P 4.58267972 3.81615 26 P 0 0;1=3
P 4.58267972 3.66615 26 P 0 0;1=3
P 4.63267972 3.51615 26 P 0 0;1=3
P 4.58267972 3.51615 26 P 0 0;1=3
P 4.63267972 3.36615 26 P 0 0;1=3
P 4.58267972 3.36615 26 P 0 0;1=3
P 4.63267972 3.21615 26 P 0 0;1=3
P 4.58267972 3.21615 26 P 0 0;1=3
P 4.63267972 3.06615 26 P 0 0;1=3
P 4.58267972 3.06615 26 P 0 0;1=3
P 4.63267972 2.91615 26 P 0 0;1=3
P 4.58267972 2.91615 26 P 0 0;1=3
P 4.58267972 2.46615 26 P 0 0;1=3
P 4.63267972 2.21615 26 P 0 0;1=3
P 4.58267972 2.31615 26 P 0 0;1=3
P 4.63267972 2.36615 26 P 0 0;1=3
P 4.58267972 2.01615 26 P 0 0;1=3
P 4.63267972 2.11615 26 P 0 0;1=3
P 4.63267972 1.96615 26 P 0 0;1=3
P 4.58267972 1.86615 26 P 0 0;1=3
P 2.04606024 3.41615 26 P 0 0;1=3
P 2.09606024 3.51615 26 P 0 0;1=3
P 3.37003996 5.18128002 26 P 0 0;1=4
P 3.43003996 5.18128002 26 P 0 0;1=4
P 3.29916998 5.14224026 26 P 0 0;1=4
P 3.35916998 5.14224026 26 P 0 0;1=4
P 2.93708002 4.70573996 26 P 0 0;1=4
P 3.07571004 4.70573996 26 P 0 0;1=4
P 3.01571004 4.70573996 26 P 0 0;1=4
P 2.87708002 4.70573996 26 P 0 0;1=4
P 2.93086998 5.20876024 26 P 0 0;1=4
P 2.87086998 5.20876024 26 P 0 0;1=4
P 2.80310994 4.74418002 26 P 0 0;1=4
P 2.86310994 4.74418002 26 P 0 0;1=4
P 3.08656998 5.09224026 26 P 0 0;1=4
P 3.14656998 5.09224026 26 P 0 0;1=4
P 2.26855 4.62825974 26 P 0 0;1=4
P 2.20855 4.62825974 26 P 0 0;1=4
P 2.26543996 4.74418002 26 P 0 0;1=4
P 2.20543996 4.74418002 26 P 0 0;1=4
P 2.34716998 4.70326004 26 P 0 0;1=4
P 2.07853002 4.62815 26 P 0 0;1=4
P 2.01853002 4.62815 26 P 0 0;1=4
P 2.12370994 4.74418002 26 P 0 0;1=4
P 2.06370994 4.74418002 26 P 0 0;1=4
P 2.19456998 5.09224026 26 P 0 0;1=4
P 2.13456998 5.09224026 26 P 0 0;1=4
P 2.12370994 5.13026004 26 P 0 0;1=4
P 2.06370994 5.13026004 26 P 0 0;1=4
P 1.6985 5.09224026 26 P 0 0;1=4
P 1.6385 5.09224026 26 P 0 0;1=4
P 1.85110994 4.61826004 26 P 0 0;1=4
P 1.63850994 4.74418002 26 P 0 0;1=4
P 1.69850994 4.74418002 26 P 0 0;1=4
P 1.98196998 5.09224026 26 P 0 0;1=4
P 1.92196998 5.09224026 26 P 0 0;1=4
P 1.84025 4.74417972 26 P 0 0;1=4
P 1.78025 4.74417972 26 P 0 0;1=4
P 11.03660974 2.71615 26 P 0 0;1=3
P 10.93660974 2.71615 26 P 0 0;1=3
P 11.03660974 2.76615 26 P 0 0;1=3
P 10.98660974 2.76615 26 P 0 0;1=3
P 10.93660974 2.76615 26 P 0 0;1=3
P 11.08660974 2.76615 26 P 0 0;1=3
P 11.03660974 2.56615 26 P 0 0;1=3
P 10.93660974 2.56615 26 P 0 0;1=3
P 10.98660974 2.66615 26 P 0 0;1=3
P 10.98660974 2.51615 26 P 0 0;1=3
P 10.93660974 2.51615 26 P 0 0;1=3
P 11.08660974 2.66615 26 P 0 0;1=3
P 11.08660974 2.51615 26 P 0 0;1=3
P 11.08660974 2.46615 26 P 0 0;1=3
P 10.98660974 2.46615 26 P 0 0;1=3
P 11.08660974 2.31615 26 P 0 0;1=3
P 10.93660974 2.36615 26 P 0 0;1=3
P 10.98660974 2.31615 26 P 0 0;1=3
P 10.93660974 2.21615 26 P 0 0;1=3
P 11.03660974 2.21615 26 P 0 0;1=3
P 11.03660974 2.11615 26 P 0 0;1=3
P 10.93660974 2.11615 26 P 0 0;1=3
P 10.98660974 2.01615 26 P 0 0;1=3
P 10.93660974 1.96615 26 P 0 0;1=3
P 11.03660974 1.96615 26 P 0 0;1=3
P 11.08660974 2.01615 26 P 0 0;1=3
P 10.98660974 2.16615 26 P 0 0;1=3
P 10.93660974 2.16615 26 P 0 0;1=3
P 11.08660974 2.16615 26 P 0 0;1=3
P 10.98660974 1.86615 26 P 0 0;1=3
P 11.08660974 1.86615 26 P 0 0;1=3
P 10.73660974 2.71615 26 P 0 0;1=3
P 10.73660974 2.76615 26 P 0 0;1=3
P 10.88660974 2.76615 26 P 0 0;1=3
P 10.78660974 2.76615 26 P 0 0;1=3
P 10.73660974 2.56615 26 P 0 0;1=3
P 10.68660974 2.66615 26 P 0 0;1=3
P 10.73660974 2.51615 26 P 0 0;1=3
P 10.68660974 2.51615 26 P 0 0;1=3
P 10.88660974 2.61615 26 P 0 0;1=3
P 10.88660974 2.56615 26 P 0 0;1=3
P 10.88660974 2.51615 26 P 0 0;1=3
P 10.78660974 2.56615 26 P 0 0;1=3
P 10.78660974 2.61615 26 P 0 0;1=3
P 10.78660974 2.66615 26 P 0 0;1=3
P 10.78660974 2.51615 26 P 0 0;1=3
P 10.78660974 2.46615 26 P 0 0;1=3
P 10.68660974 2.46615 26 P 0 0;1=3
P 10.88660974 2.46615 26 P 0 0;1=3
P 10.78660974 2.21615 26 P 0 0;1=3
P 10.78660974 2.26615 26 P 0 0;1=3
P 10.78660974 2.31615 26 P 0 0;1=3
P 10.78660974 2.36615 26 P 0 0;1=3
P 10.68660974 2.31615 26 P 0 0;1=3
P 10.73660974 2.36615 26 P 0 0;1=3
P 10.73660974 2.21615 26 P 0 0;1=3
P 10.78660974 2.41615 26 P 0 0;1=3
P 10.88660974 2.36615 26 P 0 0;1=3
P 10.88660974 2.31615 26 P 0 0;1=3
P 10.88660974 2.26615 26 P 0 0;1=3
P 10.88660974 2.21615 26 P 0 0;1=3
P 10.73660974 1.96615 26 P 0 0;1=3
P 10.68660974 2.01615 26 P 0 0;1=3
P 10.73660974 2.11615 26 P 0 0;1=3
P 10.78660974 2.11615 26 P 0 0;1=3
P 10.78660974 2.01615 26 P 0 0;1=3
P 10.78660974 1.96615 26 P 0 0;1=3
P 10.78660974 2.06615 26 P 0 0;1=3
P 10.68660974 2.16615 26 P 0 0;1=3
P 10.73660974 2.16615 26 P 0 0;1=3
P 10.88660974 2.01615 26 P 0 0;1=3
P 10.88660974 2.06615 26 P 0 0;1=3
P 10.88660974 2.11615 26 P 0 0;1=3
P 10.88660974 1.96615 26 P 0 0;1=3
P 10.78660974 1.91615 26 P 0 0;1=3
P 10.68660974 1.86615 26 P 0 0;1=3
P 10.78660974 1.86615 26 P 0 0;1=3
P 10.88660974 1.86615 26 P 0 0;1=3
P 10.63660974 2.71615 26 P 0 0;1=3
P 10.63660974 2.76615 26 P 0 0;1=3
P 10.63660974 2.56615 26 P 0 0;1=3
P 10.58660974 2.66615 26 P 0 0;1=3
P 10.63660974 2.51615 26 P 0 0;1=3
P 10.58660974 2.51615 26 P 0 0;1=3
P 10.58660974 2.46615 26 P 0 0;1=3
P 10.63660974 2.36615 26 P 0 0;1=3
P 10.58660974 2.31615 26 P 0 0;1=3
P 10.58660974 2.01615 26 P 0 0;1=3
P 10.63660974 1.96615 26 P 0 0;1=3
P 10.63660974 2.11615 26 P 0 0;1=3
P 10.58660974 1.86615 26 P 0 0;1=3
P 1.92345974 5.377 26 P 0 0;1=4
P 2.14345974 5.377 26 P 0 0;1=4
P 7.927 5.377 26 P 0 0;1=4
P 8.147 5.377 26 P 0 0;1=4
P 3.43003996 4.74418002 26 P 0 0;1=4
P 3.51177008 4.68098996 26 P 0 0;1=4
P 3.57177008 4.68098996 26 P 0 0;1=4
P 3.21743996 4.74418002 26 P 0 0;1=4
P 3.37003996 4.74418002 26 P 0 0;1=4
P 3.41 5.332 26 P 0 0;1=4
P 5.38047972 1.5957 26 P 0 0;1=4
P 5.38047972 1.7891 26 P 0 0;1=4
P 5.38047972 1.732 26 P 0 0;1=4
P 5.38047972 1.6528 26 P 0 0;1=4
P 5.53530974 1.8603 26 P 0 0;1=4
P 5.53530974 1.8032 26 P 0 0;1=4
P 5.53530974 2.2727 26 P 0 0;1=4
P 5.53530974 2.1373 26 P 0 0;1=4
P 5.53530974 1.9964 26 P 0 0;1=4
P 5.38047972 2.3403 26 P 0 0;1=4
P 5.38047972 2.2832 26 P 0 0;1=4
P 5.38047972 2.2049 26 P 0 0;1=4
P 5.38047972 2.1478 26 P 0 0;1=4
P 5.38047972 2.0642 26 P 0 0;1=4
P 5.38047972 2.0071 26 P 0 0;1=4
P 5.38047972 1.9288 26 P 0 0;1=4
P 5.38047972 1.8717 26 P 0 0;1=4
P 5.53530974 2.351 26 P 0 0;1=4
P 5.38047972 2.4757 26 P 0 0;1=4
P 5.38047972 2.4186 26 P 0 0;1=4
P 5.53530974 2.4902 26 P 0 0;1=4
P 5.53530974 2.6825 26 P 0 0;1=4
P 5.53530974 2.6254 26 P 0 0;1=4
P 5.38047972 2.5578 26 P 0 0;1=4
P 5.38047972 2.6149 26 P 0 0;1=4
P 10.43 1.3341 26 P 0 0;1=4
P 10.43 1.277 26 P 0 0;1=4
P 10.4159 1.43 26 P 0 0;1=4
P 10.473 1.43 26 P 0 0;1=4
P 10.37313996 1.55333474 26 P 0 0;1=4
P 10.41451004 1.51195472 26 P 0 0;1=4
P 10.295 1.713 26 P 0 0;1=4
P 10.295 1.6559 26 P 0 0;1=4
P 10.26 1.9179 26 P 0 0;1=4
P 10.29525 1.877 26 P 0 0;1=4
P 10.29525 1.8199 26 P 0 0;1=4
P 10.26 1.975 26 P 0 0;1=4
P 10.125 2.0651 26 P 0 0;1=4
P 10.125 2.1224 26 P 0 0;1=4
P 10.125 2.1795 26 P 0 0;1=4
P 10.01 2.2481 26 P 0 0;1=4
P 10.01 2.191 26 P 0 0;1=4
P 10.01 2.38435 26 P 0 0;1=4
P 10.01 2.32725 26 P 0 0;1=4
P 10.125 2.3168 26 P 0 0;1=4
P 10.125 2.2597 26 P 0 0;1=4
P 10.125 2.4519 26 P 0 0;1=4
P 10.125 2.3948 26 P 0 0;1=4
P 10.01 2.51945 26 P 0 0;1=4
P 10.01 2.46235 26 P 0 0;1=4
P 10.125 2.587 26 P 0 0;1=4
P 10.125 2.5299 26 P 0 0;1=4
P 10.01 2.673 26 P 0 0;1=4
P 10.01 2.6159 26 P 0 0;1=4
P 11.74315974 1.7035 26 P 0 0;1=4
P 11.74315974 1.6405 26 P 0 0;1=4
P 11.69315974 1.4805 26 P 0 0;1=4
P 11.69315974 1.5435 26 P 0 0;1=4
P 11.49315974 1.5605 26 P 0 0;1=4
P 11.49315974 1.6235 26 P 0 0;1=4
P 11.49315974 1.4635 26 P 0 0;1=4
P 11.49365974 1.401 26 P 0 0;1=4
P 11.69315974 2.6005 26 P 0 0;1=4
P 11.69315974 2.5035 26 P 0 0;1=4
P 11.69315974 2.4405 26 P 0 0;1=4
P 11.69315974 2.3435 26 P 0 0;1=4
P 11.69315974 2.2805 26 P 0 0;1=4
P 11.69315974 2.1835 26 P 0 0;1=4
P 11.69315974 1.9605 26 P 0 0;1=4
P 11.69315974 2.0235 26 P 0 0;1=4
P 11.69315974 2.1205 26 P 0 0;1=4
P 11.69315974 1.8005 26 P 0 0;1=4
P 11.69315974 1.8635 26 P 0 0;1=4
P 11.49315974 2.5205 26 P 0 0;1=4
P 11.49315974 2.5835 26 P 0 0;1=4
P 11.49315974 2.4235 26 P 0 0;1=4
P 11.49315974 2.3605 26 P 0 0;1=4
P 11.79315974 2.2635 26 P 0 0;1=4
P 11.79315974 2.2005 26 P 0 0;1=4
P 11.49315974 1.9435 26 P 0 0;1=4
P 11.49315974 2.1035 26 P 0 0;1=4
P 11.49315974 2.0405 26 P 0 0;1=4
P 11.49315974 1.8805 26 P 0 0;1=4
P 11.49365974 1.721 26 P 0 0;1=4
P 11.49315974 1.7835 26 P 0 0;1=4
P 10.125 2.7451 26 P 0 0;1=4
P 10.125 2.688 26 P 0 0;1=4
P 12.34 2.19 26 P 0 0;1=4
P 9.415 5.332 26 P 0 0;1=4
P 9.265 5.332 26 P 0 0;1=4
P 9.07 5.332 26 P 0 0;1=4
P 4.7 5.54929026 26 P 0 0;1=4
P 4.81 5.375 26 P 0 0;1=4
P 4.96 5.375 26 P 0 0;1=4
P 5.16 5.645 26 P 0 0;1=4
P 5.04440974 5.605 26 P 0 0;1=4
P 4.92 5.7 26 P 0 0;1=4
P 9.91 4.7 26 P 0 0;1=4
P 3.57 4.45 26 P 0 0;1=4
P 10.465 5.195 26 P 0 0;1=4
P 10.515 5.32 26 P 0 0;1=4
P 10.465 5.275 26 P 0 0;1=4
P 12.025 4.915 26 P 0 0;1=4
P 12.12 4.965 26 P 0 0;1=4
P 12.185 4.915 26 P 0 0;1=4
P 3.72 4.45 26 P 0 0;1=4
P 3.66 4.63 26 P 0 0;1=4
P 3.77 4.86 26 P 0 0;1=4
P 9.96 4.69 26 P 0 0;1=4
P 10.03 4.51 26 P 0 0;1=4
P 3.835 4.6 26 P 0 0;1=4
P 3.9865 4.635 26 P 0 0;1=4
P 4.14 4.655 26 P 0 0;1=4
P 4.1049 4.7649 26 P 0 0;1=4
P 1.28050974 5.78 26 P 0 0;1=4
P 3.87 5.125 26 P 0 0;1=4
P 0.4826 5.8976 26 P 0 0;1=4
P 0.84952972 5.17 26 P 0 0;1=4
P 0.955 5.325 26 P 0 0;1=4
P 1.31 5.355 26 P 0 0;1=4
P 1.20176998 5.78 26 P 0 0;1=4
P 6.31295 4.99705 26 P 0 0;1=4
P 6.87 5 26 P 0 0;1=4
P 9.64795974 0.79643002 26 P 0 0;1=4
P 9.40795 0.26133002 26 P 0 0;1=4
P 3.60998976 0.24 26 P 0 0;1=4
P 3.65998976 0.345 26 P 0 0;1=4
P 3.86 0.7751 26 P 0 0;1=0
P 6.905 4.94705 26 P 0 0;1=4
P 6.905 4.88705 26 P 0 0;1=4
P 6.955 4.8 26 P 0 0;1=4
P 6.955 4.84 26 P 0 0;1=4
P 6.955 4.72 26 P 0 0;1=4
P 6.955 4.76 26 P 0 0;1=4
P 6.59708976 5.0502 26 P 0 0;1=4
P 6.65218976 4.77 26 P 0 0;1=4
P 6.62119006 4.95641998 26 P 0 0;1=8
P 6.6015 4.93674026 26 P 0 0;1=8
P 6.64088002 4.93673996 26 P 0 0;1=8
P 6.62118976 4.91705 26 P 0 0;1=8
P 6.62118976 4.87768002 26 P 0 0;1=8
P 6.6015 4.89736024 26 P 0 0;1=8
P 6.64087992 4.89736004 26 P 0 0;1=8
P 6.62 4.69 26 P 0 0;1=4
P 6.62 4.725 26 P 0 0;1=4
P 6.385 5.07 26 P 0 0;1=4
P 5.53594026 4.55505 26 P 0 0;1=4
P 6.05708976 4.5102 26 P 0 0;1=4
P 6.01708976 4.5102 26 P 0 0;1=4
P 5.97708976 4.5102 26 P 0 0;1=4
P 5.93708976 4.5102 26 P 0 0;1=4
P 5.89708976 4.5102 26 P 0 0;1=4
P 6.09708976 4.5102 26 P 0 0;1=4
P 5.61708976 4.5102 26 P 0 0;1=4
P 5.65708976 4.5102 26 P 0 0;1=4
P 5.85708976 4.5102 26 P 0 0;1=4
P 5.81708976 4.5102 26 P 0 0;1=4
P 5.77708976 4.5102 26 P 0 0;1=4
P 5.73708976 4.5102 26 P 0 0;1=4
P 5.69708976 4.5102 26 P 0 0;1=4
P 5.57708976 4.5102 26 P 0 0;1=4
P 0.036 0.10868002 26 P 0 0;1=4
P 0.036 0.15868002 26 P 0 0;1=4
P 0.036 0.20868002 26 P 0 0;1=4
P 0.22873976 0.036 26 P 0 0;1=4
P 0.17873976 0.036 26 P 0 0;1=4
P 0.12873976 0.036 26 P 0 0;1=4
P 0.07873976 0.036 26 P 0 0;1=4
P 0.47873976 0.036 26 P 0 0;1=4
P 0.42873976 0.036 26 P 0 0;1=4
P 0.37873976 0.036 26 P 0 0;1=4
P 0.32873976 0.036 26 P 0 0;1=4
P 0.27873976 0.036 26 P 0 0;1=4
P 0.77873976 0.036 26 P 0 0;1=4
P 0.72873976 0.036 26 P 0 0;1=4
P 0.67873976 0.036 26 P 0 0;1=4
P 0.62873976 0.036 26 P 0 0;1=4
P 0.57873976 0.036 26 P 0 0;1=4
P 0.52873976 0.036 26 P 0 0;1=4
P 1.02873976 0.036 26 P 0 0;1=4
P 0.97873976 0.036 26 P 0 0;1=4
P 0.92873976 0.036 26 P 0 0;1=4
P 0.87873976 0.036 26 P 0 0;1=4
P 0.82873976 0.036 26 P 0 0;1=4
P 1.27873976 0.036 26 P 0 0;1=4
P 1.22873976 0.036 26 P 0 0;1=4
P 1.17873976 0.036 26 P 0 0;1=4
P 1.12873976 0.036 26 P 0 0;1=4
P 1.07873976 0.036 26 P 0 0;1=4
P 1.52873976 0.036 26 P 0 0;1=4
P 1.47873976 0.036 26 P 0 0;1=4
P 1.42873976 0.036 26 P 0 0;1=4
P 1.37873976 0.036 26 P 0 0;1=4
P 1.32873976 0.036 26 P 0 0;1=4
P 1.82873976 0.036 26 P 0 0;1=4
P 1.77873976 0.036 26 P 0 0;1=4
P 1.72873976 0.036 26 P 0 0;1=4
P 1.67873976 0.036 26 P 0 0;1=4
P 1.62873976 0.036 26 P 0 0;1=4
P 1.57873976 0.036 26 P 0 0;1=4
P 2.07873976 0.036 26 P 0 0;1=4
P 2.02873976 0.036 26 P 0 0;1=4
P 1.97873976 0.036 26 P 0 0;1=4
P 1.92873976 0.036 26 P 0 0;1=4
P 1.87873976 0.036 26 P 0 0;1=4
P 2.32873976 0.036 26 P 0 0;1=4
P 2.27873976 0.036 26 P 0 0;1=4
P 2.22873976 0.036 26 P 0 0;1=4
P 2.17873976 0.036 26 P 0 0;1=4
P 2.12873976 0.036 26 P 0 0;1=4
P 2.62873976 0.036 26 P 0 0;1=4
P 2.57873976 0.036 26 P 0 0;1=4
P 2.52873976 0.036 26 P 0 0;1=4
P 2.47873976 0.036 26 P 0 0;1=4
P 2.42873976 0.036 26 P 0 0;1=4
P 2.37873976 0.036 26 P 0 0;1=4
P 2.87873976 0.036 26 P 0 0;1=4
P 2.82873976 0.036 26 P 0 0;1=4
P 2.77873976 0.036 26 P 0 0;1=4
P 2.72873976 0.036 26 P 0 0;1=4
P 2.67873976 0.036 26 P 0 0;1=4
P 3.12873976 0.036 26 P 0 0;1=4
P 3.07873976 0.036 26 P 0 0;1=4
P 3.02873976 0.036 26 P 0 0;1=4
P 2.97873976 0.036 26 P 0 0;1=4
P 2.92873976 0.036 26 P 0 0;1=4
P 3.37873976 0.036 26 P 0 0;1=4
P 3.32873976 0.036 26 P 0 0;1=4
P 3.27873976 0.036 26 P 0 0;1=4
P 3.22873976 0.036 26 P 0 0;1=4
P 3.17873976 0.036 26 P 0 0;1=4
P 3.67873976 0.036 26 P 0 0;1=4
P 3.62873976 0.036 26 P 0 0;1=4
P 3.57873976 0.036 26 P 0 0;1=4
P 3.52873976 0.036 26 P 0 0;1=4
P 3.47873976 0.036 26 P 0 0;1=4
P 3.42873976 0.036 26 P 0 0;1=4
P 3.92873976 0.036 26 P 0 0;1=4
P 3.87873976 0.036 26 P 0 0;1=4
P 3.82873976 0.036 26 P 0 0;1=4
P 3.77873976 0.036 26 P 0 0;1=4
P 3.72873976 0.036 26 P 0 0;1=4
P 4.17873976 0.036 26 P 0 0;1=4
P 4.12873976 0.036 26 P 0 0;1=4
P 4.07873976 0.036 26 P 0 0;1=4
P 4.02873976 0.036 26 P 0 0;1=4
P 3.97873976 0.036 26 P 0 0;1=4
P 4.42873976 0.036 26 P 0 0;1=4
P 4.37873976 0.036 26 P 0 0;1=4
P 4.32873976 0.036 26 P 0 0;1=4
P 4.27873976 0.036 26 P 0 0;1=4
P 4.22873976 0.036 26 P 0 0;1=4
P 4.72873976 0.036 26 P 0 0;1=4
P 4.67873976 0.036 26 P 0 0;1=4
P 4.62873976 0.036 26 P 0 0;1=4
P 4.57873976 0.036 26 P 0 0;1=4
P 4.52873976 0.036 26 P 0 0;1=4
P 4.47873976 0.036 26 P 0 0;1=4
P 4.81833976 0.21825 26 P 0 0;1=4
P 4.81833976 0.16825 26 P 0 0;1=4
P 4.81833976 0.11825 26 P 0 0;1=4
P 4.81703888 0.06825906 26 P 0 0;1=4
P 4.77873809 0.03612175 26 P 0 0;1=4
P 6.80730974 0.036 26 P 0 0;1=4
P 6.75730974 0.036 26 P 0 0;1=4
P 6.70730974 0.036 26 P 0 0;1=4
P 6.65730955 0.03676043 26 P 0 0;1=4
P 6.62298947 0.07311939 26 P 0 0;1=4
P 6.62261998 0.12311998 26 P 0 0;1=4
P 6.62261998 0.17311998 26 P 0 0;1=4
P 6.62261998 0.22311998 26 P 0 0;1=4
P 7.00730974 0.036 26 P 0 0;1=4
P 6.95730974 0.036 26 P 0 0;1=4
P 6.90730974 0.036 26 P 0 0;1=4
P 6.85730974 0.036 26 P 0 0;1=4
P 0.036 0.25868002 26 P 0 0;1=4
P 0.036 0.30868002 26 P 0 0;1=4
P 0.036 0.35868002 26 P 0 0;1=4
P 0.036 0.40868002 26 P 0 0;1=4
P 0.036 0.45868002 26 P 0 0;1=4
P 4.96804006 0.46906998 26 P 0 0;1=4
P 4.91804941 0.46808051 26 P 0 0;1=4
P 4.87108927 0.45089055 26 P 0 0;1=4
P 4.83591132 0.41536132 26 P 0 0;1=4
P 4.81919035 0.36823996 26 P 0 0;1=4
P 4.81833976 0.31825 26 P 0 0;1=4
P 4.81833976 0.26825 26 P 0 0;1=4
P 5.21804006 0.46906998 26 P 0 0;1=4
P 5.16804006 0.46906998 26 P 0 0;1=4
P 5.11804006 0.46906998 26 P 0 0;1=4
P 5.06804006 0.46906998 26 P 0 0;1=4
P 5.01804006 0.46906998 26 P 0 0;1=4
P 5.51804006 0.46906998 26 P 0 0;1=4
P 5.46804006 0.46906998 26 P 0 0;1=4
P 5.41804006 0.46906998 26 P 0 0;1=4
P 5.36804006 0.46906998 26 P 0 0;1=4
P 5.31804006 0.46906998 26 P 0 0;1=4
P 5.26804006 0.46906998 26 P 0 0;1=4
P 5.76804006 0.46906998 26 P 0 0;1=4
P 5.71804006 0.46906998 26 P 0 0;1=4
P 5.66804006 0.46906998 26 P 0 0;1=4
P 5.61804006 0.46906998 26 P 0 0;1=4
P 5.56804006 0.46906998 26 P 0 0;1=4
P 6.01804006 0.46906998 26 P 0 0;1=4
P 5.96804006 0.46906998 26 P 0 0;1=4
P 5.91804006 0.46906998 26 P 0 0;1=4
P 5.86804006 0.46906998 26 P 0 0;1=4
P 5.81804006 0.46906998 26 P 0 0;1=4
P 6.31804006 0.46906998 26 P 0 0;1=4
P 6.26804006 0.46906998 26 P 0 0;1=4
P 6.21804006 0.46906998 26 P 0 0;1=4
P 6.16804006 0.46906998 26 P 0 0;1=4
P 6.11804006 0.46906998 26 P 0 0;1=4
P 6.06804006 0.46906998 26 P 0 0;1=4
P 6.56567894 0.45345098 26 P 0 0;1=4
P 6.5180314 0.46861841 26 P 0 0;1=4
P 6.46804006 0.46906998 26 P 0 0;1=4
P 6.41804006 0.46906998 26 P 0 0;1=4
P 6.36804006 0.46906998 26 P 0 0;1=4
P 6.62261998 0.27311998 26 P 0 0;1=4
P 6.62261998 0.32311998 26 P 0 0;1=4
P 6.62106949 0.37309951 26 P 0 0;1=4
P 6.60234085 0.41946063 26 P 0 0;1=4
P 0.036 0.50868002 26 P 0 0;1=4
P 0.036 0.55868002 26 P 0 0;1=4
P 11.845 2.85 26 P 0 0;1=4
P 8.98115 2.7861 26 P 0 0;1=4
P 8.98115 2.8989 26 P 0 0;1=4
P 11.58612972 2.855 26 P 0 0;1=4
P 11.50361998 2.8 26 P 0 0;1=4
P 11.50361998 2.73 26 P 0 0;1=4
P 5.5722 3 26 P 0 0;1=4
P 5.75779006 3.02558996 26 P 0 0;1=4
P 5.9192 2.943 26 P 0 0;1=4
P 4.07385974 2.55 26 P 0 0;1=4
P 3.86826998 2.64559026 26 P 0 0;1=4
P 9.995 2.87559026 26 P 0 0;1=4
P 10.11778976 2.78 26 P 0 0;1=4
P 7.2426 4.60351024 26 P 0 0;1=4
P 7.3401 4.85601024 26 P 0 0;1=4
P 7.1926 5.04351024 26 P 0 0;1=4
P 0.66 2.045 26 P 0 0;1=0
P 1.792 2.4781 26 P 0 0;1=4
P 2.97720974 2.8989 26 P 0 0;1=4
P 2.97720974 2.7861 26 P 0 0;1=4
P 2.9422 2.925 26 P 0 0;1=4
P 8.94278976 2.925 26 P 0 0;1=4
P 5.5822 2.855 26 P 0 0;1=4
P 5.84969026 2.85 26 P 0 0;1=4
P 0.65348996 1.85608996 26 P 0 0;1=4
P 0.65348996 1.91628996 26 P 0 0;1=4
P 0.09448996 4.60236998 28 P 0 3;1=1
P 0.35038996 4.20865994 28 P 0 3;1=1
P 0.09448996 4.2874 28 P 0 3;1=1
P 0.09448996 4.12991998 28 P 0 3;1=1
P 0.17322992 4.16928996 28 P 0 3;1=1
P 0.27165 4.09055 28 P 0 3;1=1
P 0.27165 3.93306998 28 P 0 3;1=1
P 0.35038996 4.05117992 28 P 0 3;1=1
P 0.35038996 3.8937 28 P 0 3;1=1
P 0.09448996 3.97243996 28 P 0 3;1=1
P 0.09448996 3.81495994 28 P 0 3;1=1
P 0.17322992 4.01180994 28 P 0 3;1=1
P 0.17322992 3.85432992 28 P 0 3;1=1
P 0.27165 3.77558996 28 P 0 3;1=1
P 0.27165 3.61810994 28 P 0 3;1=1
P 0.35038996 3.73621998 28 P 0 3;1=1
P 0.35038996 3.57873996 28 P 0 3;1=1
P 0.09448996 3.65747992 28 P 0 3;1=1
P 0.09448996 3.5 28 P 0 3;1=1
P 0.17322992 3.69685 28 P 0 3;1=1
P 0.17322992 3.53936998 28 P 0 3;1=1
P 0.27165 3.46062992 28 P 0 3;1=1
P 0.35038996 3.42125994 28 P 0 3;1=1
P 0.27165 3.30315 28 P 0 3;1=1
P 0.27165 3.22440994 28 P 0 3;1=1
P 0.17322992 3.38188996 28 P 0 3;1=1
P 0.17322992 3.30315 28 P 0 3;1=1
P 0.35038996 3.1063 28 P 0 3;1=1
P 0.35038996 2.94881998 28 P 0 3;1=1
P 0.27165 3.06692992 28 P 0 3;1=1
P 0.27165 2.90945 28 P 0 3;1=1
P 0.17322992 3.14566998 28 P 0 3;1=1
P 0.17322992 2.98818996 28 P 0 3;1=1
P 0.09448996 3.18503996 28 P 0 3;1=1
P 0.09448996 3.02755994 28 P 0 3;1=1
P 0.35038996 2.79133996 28 P 0 3;1=1
P 0.27165 2.75196998 28 P 0 3;1=1
P 0.35038996 2.63385994 28 P 0 3;1=1
P 0.17322992 2.83070994 28 P 0 3;1=1
P 0.09448996 2.87007992 28 P 0 3;1=1
P 0.09448996 2.7126 28 P 0 3;1=1
P 0.35038996 2.39763996 28 P 0 3;1=1
P 0.27165 2.51575 28 P 0 3;1=1
P 0.27165 2.35826998 28 P 0 3;1=1
P 0.17322992 2.59448996 28 P 0 3;1=1
P 0.17322992 2.43700994 28 P 0 3;1=1
P 0.09448996 2.47637992 28 P 0 3;1=1
P 0.09448996 2.3189 28 P 0 3;1=1
P 0.35038996 2.24015994 28 P 0 3;1=1
P 0.35038996 2.08267992 28 P 0 3;1=1
P 0.35038996 2.00393996 28 P 0 3;1=1
P 0.27165 2.20078996 28 P 0 3;1=1
P 0.17322992 2.27952992 28 P 0 3;1=1
P 0.09448996 2.16141998 28 P 0 3;1=1
P 0.09448996 2.08267992 28 P 0 3;1=1
P 0.17322992 1.96456998 28 P 0 3;1=1
P 0.09448996 1.84645994 28 P 0 3;1=1
P 0.09448996 4.44487992 28 P 0 3;1=1
P 12.63778996 2.00393996 28 P 0 3;1=1
P 12.55905 2.12205 28 P 0 3;1=1
P 12.55905 1.88582992 28 P 0 3;1=1
P 12.81495 2.12205 28 P 0 3;1=1
P 12.81495 2.04330994 28 P 0 3;1=1
P 12.73620994 2.39763996 28 P 0 3;1=1
P 12.73620994 2.24015994 28 P 0 3;1=1
P 12.63778996 2.3189 28 P 0 3;1=1
P 12.55905 2.35826998 28 P 0 3;1=1
P 12.55905 2.20078996 28 P 0 3;1=1
P 12.81495 2.43700994 28 P 0 3;1=1
P 12.81495 2.27952992 28 P 0 3;1=1
P 12.73620994 2.55511998 28 P 0 3;1=1
P 12.63778996 2.63385994 28 P 0 3;1=1
P 12.63778996 2.47637992 28 P 0 3;1=1
P 12.55905 2.51575 28 P 0 3;1=1
P 12.81495 2.67322992 28 P 0 3;1=1
P 12.73620994 2.94881998 28 P 0 3;1=1
P 12.73620994 2.79133996 28 P 0 3;1=1
P 12.63778996 3.02755994 28 P 0 3;1=1
P 12.63778996 2.87007992 28 P 0 3;1=1
P 12.55905 2.90945 28 P 0 3;1=1
P 12.55905 2.75196998 28 P 0 3;1=1
P 12.81495 2.98818996 28 P 0 3;1=1
P 12.81495 2.83070994 28 P 0 3;1=1
P 12.73620994 3.26377992 28 P 0 3;1=1
P 12.73620994 3.1063 28 P 0 3;1=1
P 12.63778996 3.18503996 28 P 0 3;1=1
P 12.55905 3.22440994 28 P 0 3;1=1
P 12.55905 3.06692992 28 P 0 3;1=1
P 12.81495 3.14566998 28 P 0 3;1=1
P 12.55905 3.53936998 28 P 0 3;1=1
P 12.63778996 3.57873996 28 P 0 3;1=1
P 12.63778996 3.42125994 28 P 0 3;1=1
P 12.73620994 3.5 28 P 0 3;1=1
P 12.73620994 3.34251998 28 P 0 3;1=1
P 12.63778996 3.34251998 28 P 0 3;1=1
P 12.81495 3.61810994 28 P 0 3;1=1
P 12.81495 3.46062992 28 P 0 3;1=1
P 12.55905 3.85432992 28 P 0 3;1=1
P 12.55905 3.69685 28 P 0 3;1=1
P 12.63778996 3.8937 28 P 0 3;1=1
P 12.63778996 3.73621998 28 P 0 3;1=1
P 12.73620994 3.81495994 28 P 0 3;1=1
P 12.73620994 3.65747992 28 P 0 3;1=1
P 12.81495 3.93306998 28 P 0 3;1=1
P 12.81495 3.77558996 28 P 0 3;1=1
P 12.55905 4.16928996 28 P 0 3;1=1
P 12.55905 4.01180994 28 P 0 3;1=1
P 12.63778996 4.20865994 28 P 0 3;1=1
P 12.63778996 4.05117992 28 P 0 3;1=1
P 12.73620994 4.12991998 28 P 0 3;1=1
P 12.73620994 3.97243996 28 P 0 3;1=1
P 12.81495 4.09055 28 P 0 3;1=1
P 12.55905 4.48425 28 P 0 3;1=1
P 12.55905 4.32676998 28 P 0 3;1=1
P 12.63778996 4.52361998 28 P 0 3;1=1
P 12.63778996 4.36613996 28 P 0 3;1=1
P 12.73620994 4.44487992 28 P 0 3;1=1
P 12.73620994 4.2874 28 P 0 3;1=1
P 12.81495 4.40550994 28 P 0 3;1=1
P 12.81495 4.24802992 28 P 0 3;1=1
P 12.55905 4.64173996 28 P 0 3;1=1
P 12.81495 4.56298996 28 P 0 3;1=1
P 0.27165 4.40550994 28 P 0 3;1=1
P 0.35038996 4.52361998 28 P 0 3;1=1
P 0.17322992 4.48425 28 P 0 3;1=1
P 0.27165 4.24802992 28 P 0 3;1=1
P 0.35038996 4.36613996 28 P 0 3;1=1
P 0.17322992 4.32676998 28 P 0 3;1=1
P 5.49220974 2.73 26 P 0 0;1=4
P 5.44885974 2.9414 26 P 0 0;1=4
P 5.44885974 3.0214 26 P 0 0;1=4
P 5.44885974 3.0564 26 P 0 0;1=4
P 5.44885974 3.1014 26 P 0 0;1=4
P 5.44885974 3.1364 26 P 0 0;1=4
P 5.44885974 3.2164 26 P 0 0;1=4
P 5.44885974 3.1814 26 P 0 0;1=4
P 5.44885974 2.9764 26 P 0 0;1=4
P 5.44885974 3.2614 26 P 0 0;1=4
P 5.44885974 3.2964 26 P 0 0;1=4
P 10.33998976 4.9231 26 P 0 0;1=4
P 10.38498976 4.9231 26 P 0 0;1=0
P 10.77498976 4.9231 26 P 0 0;1=4
P 10.72998976 4.9231 26 P 0 0;1=4
P 10.30498976 4.9431 26 P 0 0;1=4
P 10.26498976 4.9431 26 P 0 0;1=4
P 10.30498976 5.0281 26 P 0 0;1=4
P 10.30498976 5.0731 26 P 0 0;1=4
P 10.30498976 4.9831 26 P 0 0;1=4
P 10.26498976 5.0281 26 P 0 0;1=4
P 10.26498976 5.0731 26 P 0 0;1=4
P 10.26498976 4.9831 26 P 0 0;1=4
P 10.26498976 5.1181 26 P 0 0;1=4
P 10.30498976 5.1181 26 P 0 0;1=4
P 10.34498976 5.1181 26 P 0 0;1=4
P 10.42498976 4.9431 26 P 0 0;1=4
P 10.46498976 4.9431 26 P 0 0;1=4
P 10.38498976 5.1181 26 P 0 0;1=4
P 10.46498976 5.1181 26 P 0 0;1=4
P 10.42498976 5.1181 26 P 0 0;1=4
P 10.42498976 4.9831 26 P 0 0;1=4
P 10.42498976 5.0731 26 P 0 0;1=4
P 10.42498976 5.0281 26 P 0 0;1=4
P 10.46498976 4.9831 26 P 0 0;1=4
P 10.46498976 5.0731 26 P 0 0;1=4
P 10.46498976 5.0281 26 P 0 0;1=4
P 10.85498976 4.9431 26 P 0 0;1=4
P 10.81498976 4.9431 26 P 0 0;1=4
P 10.65498976 4.9431 26 P 0 0;1=4
P 10.69498976 4.9431 26 P 0 0;1=4
P 10.85498976 5.0281 26 P 0 0;1=4
P 10.85498976 5.0731 26 P 0 0;1=4
P 10.85498976 4.9831 26 P 0 0;1=4
P 10.81498976 5.0281 26 P 0 0;1=4
P 10.81498976 5.0731 26 P 0 0;1=4
P 10.81498976 4.9831 26 P 0 0;1=4
P 10.81498976 5.1181 26 P 0 0;1=4
P 10.85498976 5.1181 26 P 0 0;1=4
P 10.73498976 5.1181 26 P 0 0;1=4
P 10.69498976 5.1181 26 P 0 0;1=4
P 10.65498976 5.1181 26 P 0 0;1=4
P 10.77498976 5.1181 26 P 0 0;1=4
P 10.65498976 4.9831 26 P 0 0;1=4
P 10.65498976 5.0731 26 P 0 0;1=4
P 10.65498976 5.0281 26 P 0 0;1=4
P 10.69498976 4.9831 26 P 0 0;1=4
P 10.69498976 5.0731 26 P 0 0;1=4
P 10.69498976 5.0281 26 P 0 0;1=4
P 1.23905994 4.60351004 26 P 0 0;1=4
P 1.18905994 5.04351004 26 P 0 0;1=4
P 1.33655994 4.85601004 26 P 0 0;1=4
P 10.16606998 2.81 26 P 0 0;1=4
P 4.15220974 2.9281 26 P 0 0;1=4
P 11.45278976 2.9414 26 P 0 0;1=4
P 11.45278976 3.0214 26 P 0 0;1=4
P 11.45278976 3.0564 26 P 0 0;1=4
P 11.45278976 3.1014 26 P 0 0;1=4
P 11.45278976 3.1364 26 P 0 0;1=4
P 11.45278976 3.2164 26 P 0 0;1=4
P 11.45278976 3.1814 26 P 0 0;1=4
P 11.45278976 2.9764 26 P 0 0;1=4
P 11.45278976 3.2614 26 P 0 0;1=4
P 11.45278976 3.2964 26 P 0 0;1=4
P 0.09448996 1.45275994 28 P 0 3;1=1
P 0.27165 1.57086998 28 P 0 3;1=1
P 0.35038996 1.45275994 28 P 0 3;1=1
P 12.81495 1.49212992 28 P 0 3;1=1
P 12.73620994 1.61023996 28 P 0 3;1=1
P 12.55905 1.49212992 28 P 0 3;1=1
P 0.27165 1.88582992 28 P 0 3;1=1
P 12.73620994 1.9252 28 P 0 3;1=1
P 7.35730974 0.036 26 P 0 0;1=4
P 7.60730974 0.036 26 P 0 0;1=4
P 7.55730974 0.036 26 P 0 0;1=4
P 7.50730974 0.036 26 P 0 0;1=4
P 7.45730974 0.036 26 P 0 0;1=4
P 7.40730974 0.036 26 P 0 0;1=4
P 7.85730974 0.036 26 P 0 0;1=4
P 7.80730974 0.036 26 P 0 0;1=4
P 7.75730974 0.036 26 P 0 0;1=4
P 7.70730974 0.036 26 P 0 0;1=4
P 7.65730974 0.036 26 P 0 0;1=4
P 8.15730974 0.036 26 P 0 0;1=4
P 8.10730974 0.036 26 P 0 0;1=4
P 8.05730974 0.036 26 P 0 0;1=4
P 8.00730974 0.036 26 P 0 0;1=4
P 7.95730974 0.036 26 P 0 0;1=4
P 7.90730974 0.036 26 P 0 0;1=4
P 8.40730974 0.036 26 P 0 0;1=4
P 8.35730974 0.036 26 P 0 0;1=4
P 8.30730974 0.036 26 P 0 0;1=4
P 8.25730974 0.036 26 P 0 0;1=4
P 8.20730974 0.036 26 P 0 0;1=4
P 8.65730974 0.036 26 P 0 0;1=4
P 8.60730974 0.036 26 P 0 0;1=4
P 8.55730974 0.036 26 P 0 0;1=4
P 8.50730974 0.036 26 P 0 0;1=4
P 8.45730974 0.036 26 P 0 0;1=4
P 8.90730974 0.036 26 P 0 0;1=4
P 8.85730974 0.036 26 P 0 0;1=4
P 8.80730974 0.036 26 P 0 0;1=4
P 8.75730974 0.036 26 P 0 0;1=4
P 8.70730974 0.036 26 P 0 0;1=4
P 9.20730974 0.036 26 P 0 0;1=4
P 9.15730974 0.036 26 P 0 0;1=4
P 9.10730974 0.036 26 P 0 0;1=4
P 9.05730974 0.036 26 P 0 0;1=4
P 9.00730974 0.036 26 P 0 0;1=4
P 8.95730974 0.036 26 P 0 0;1=4
P 9.45730974 0.036 26 P 0 0;1=4
P 9.40730974 0.036 26 P 0 0;1=4
P 9.35730974 0.036 26 P 0 0;1=4
P 9.30730974 0.036 26 P 0 0;1=4
P 9.25730974 0.036 26 P 0 0;1=4
P 9.70730974 0.036 26 P 0 0;1=4
P 9.65730974 0.036 26 P 0 0;1=4
P 9.60730974 0.036 26 P 0 0;1=4
P 9.55730974 0.036 26 P 0 0;1=4
P 9.50730974 0.036 26 P 0 0;1=4
P 10.00730974 0.036 26 P 0 0;1=4
P 9.95730974 0.036 26 P 0 0;1=4
P 9.90730974 0.036 26 P 0 0;1=4
P 9.85730974 0.036 26 P 0 0;1=4
P 9.80730974 0.036 26 P 0 0;1=4
P 9.75730974 0.036 26 P 0 0;1=4
P 10.25730974 0.036 26 P 0 0;1=4
P 10.20730974 0.036 26 P 0 0;1=4
P 10.15730974 0.036 26 P 0 0;1=4
P 10.10730974 0.036 26 P 0 0;1=4
P 10.05730974 0.036 26 P 0 0;1=4
P 10.50730974 0.036 26 P 0 0;1=4
P 10.45730974 0.036 26 P 0 0;1=4
P 10.40730974 0.036 26 P 0 0;1=4
P 10.35730974 0.036 26 P 0 0;1=4
P 10.30730974 0.036 26 P 0 0;1=4
P 10.75730974 0.036 26 P 0 0;1=4
P 10.70730974 0.036 26 P 0 0;1=4
P 10.65730974 0.036 26 P 0 0;1=4
P 10.60730974 0.036 26 P 0 0;1=4
P 10.55730974 0.036 26 P 0 0;1=4
P 11.05730974 0.036 26 P 0 0;1=4
P 11.00730974 0.036 26 P 0 0;1=4
P 10.95730974 0.036 26 P 0 0;1=4
P 10.90730974 0.036 26 P 0 0;1=4
P 10.85730974 0.036 26 P 0 0;1=4
P 10.80730974 0.036 26 P 0 0;1=4
P 11.30730974 0.036 26 P 0 0;1=4
P 11.25730974 0.036 26 P 0 0;1=4
P 11.20730974 0.036 26 P 0 0;1=4
P 11.15730974 0.036 26 P 0 0;1=4
P 11.10730974 0.036 26 P 0 0;1=4
P 11.55730974 0.036 26 P 0 0;1=4
P 11.50730974 0.036 26 P 0 0;1=4
P 11.45730974 0.036 26 P 0 0;1=4
P 11.40730974 0.036 26 P 0 0;1=4
P 11.35730974 0.036 26 P 0 0;1=4
P 11.80730974 0.036 26 P 0 0;1=4
P 11.75730974 0.036 26 P 0 0;1=4
P 11.70730974 0.036 26 P 0 0;1=4
P 11.65730974 0.036 26 P 0 0;1=4
P 11.60730974 0.036 26 P 0 0;1=4
P 12.10730974 0.036 26 P 0 0;1=4
P 12.05730974 0.036 26 P 0 0;1=4
P 12.00730974 0.036 26 P 0 0;1=4
P 11.95730974 0.036 26 P 0 0;1=4
P 11.90730974 0.036 26 P 0 0;1=4
P 11.85730974 0.036 26 P 0 0;1=4
P 12.35730974 0.036 26 P 0 0;1=4
P 12.30730974 0.036 26 P 0 0;1=4
P 12.25730974 0.036 26 P 0 0;1=4
P 12.20730974 0.036 26 P 0 0;1=4
P 12.15730974 0.036 26 P 0 0;1=4
P 12.60730974 0.036 26 P 0 0;1=4
P 12.55730974 0.036 26 P 0 0;1=4
P 12.50730974 0.036 26 P 0 0;1=4
P 12.45730974 0.036 26 P 0 0;1=4
P 12.40730974 0.036 26 P 0 0;1=4
P 12.8892 0.22595974 26 P 0 0;1=4
P 12.8892 0.17595974 26 P 0 0;1=4
P 12.8892 0.12595974 26 P 0 0;1=4
P 12.88911073 0.07596083 26 P 0 0;1=4
P 12.85728868 0.03739114 26 P 0 0;1=4
P 12.80730974 0.036 26 P 0 0;1=4
P 12.75730974 0.036 26 P 0 0;1=4
P 12.70730974 0.036 26 P 0 0;1=4
P 12.65730974 0.036 26 P 0 0;1=4
P 12.8892 0.47595974 26 P 0 0;1=4
P 12.8892 0.42595974 26 P 0 0;1=4
P 12.8892 0.37595974 26 P 0 0;1=4
P 12.8892 0.32595974 26 P 0 0;1=4
P 12.8892 0.27595974 26 P 0 0;1=4
P 12.8892 0.62595974 26 P 0 0;1=4
P 12.8892 0.57595974 26 P 0 0;1=4
P 12.8892 0.52595974 26 P 0 0;1=4
P 0.036 1.00868002 26 P 0 0;1=4
P 0.036 1.05868002 26 P 0 0;1=4
P 0.036 1.10868002 26 P 0 0;1=4
P 0.036 1.15868002 26 P 0 0;1=4
P 0.036 1.20868002 26 P 0 0;1=4
P 0.036 1.25868002 26 P 0 0;1=4
P 0.036 1.30868002 26 P 0 0;1=4
P 0.036 1.35868002 26 P 0 0;1=4
P 0.036 1.40868002 26 P 0 0;1=4
P 0.036 1.45868002 26 P 0 0;1=4
P 0.036 1.50868002 26 P 0 0;1=4
P 0.036 1.55868002 26 P 0 0;1=4
P 0.036 1.60868002 26 P 0 0;1=4
P 0.036 1.65868002 26 P 0 0;1=4
P 0.036 1.70868002 26 P 0 0;1=4
P 0.036 1.75868002 26 P 0 0;1=4
P 0.036 1.80868002 26 P 0 0;1=4
P 0.036 1.85868002 26 P 0 0;1=4
P 0.036 1.90868002 26 P 0 0;1=4
P 0.036 1.95868002 26 P 0 0;1=4
P 0.036 2.00868002 26 P 0 0;1=4
P 0.036 2.05868002 26 P 0 0;1=4
P 0.036 2.10868002 26 P 0 0;1=4
P 0.036 2.15868002 26 P 0 0;1=4
P 0.036 2.20868002 26 P 0 0;1=4
P 0.036 2.25868002 26 P 0 0;1=4
P 0.036 2.30868002 26 P 0 0;1=4
P 0.036 2.35868002 26 P 0 0;1=4
P 0.036 2.40868002 26 P 0 0;1=4
P 0.036 2.45868002 26 P 0 0;1=4
P 0.036 2.50868002 26 P 0 0;1=4
P 0.036 2.55868002 26 P 0 0;1=4
P 0.036 2.60868002 26 P 0 0;1=4
P 0.036 2.65868002 26 P 0 0;1=4
P 0.036 2.70868002 26 P 0 0;1=4
P 0.036 2.75868002 26 P 0 0;1=4
P 0.036 2.80868002 26 P 0 0;1=4
P 0.036 2.85868002 26 P 0 0;1=4
P 0.036 2.90868002 26 P 0 0;1=4
P 0.036 2.95868002 26 P 0 0;1=4
P 0.036 3.00868002 26 P 0 0;1=4
P 0.036 3.05868002 26 P 0 0;1=4
P 0.036 3.10868002 26 P 0 0;1=4
P 0.036 3.15868002 26 P 0 0;1=4
P 0.036 3.20868002 26 P 0 0;1=4
P 0.036 3.25868002 26 P 0 0;1=4
P 0.036 3.30868002 26 P 0 0;1=4
P 0.036 3.35868002 26 P 0 0;1=4
P 0.036 3.40868002 26 P 0 0;1=4
P 0.036 3.45868002 26 P 0 0;1=4
P 0.036 3.50868002 26 P 0 0;1=4
P 0.036 3.55868002 26 P 0 0;1=4
P 0.036 3.60868002 26 P 0 0;1=4
P 0.036 3.65868002 26 P 0 0;1=4
P 0.036 3.70868002 26 P 0 0;1=4
P 0.036 3.75868002 26 P 0 0;1=4
P 0.036 3.80868002 26 P 0 0;1=4
P 0.036 3.85868002 26 P 0 0;1=4
P 0.036 3.90868002 26 P 0 0;1=4
P 0.036 3.95868002 26 P 0 0;1=4
P 0.036 4.00868002 26 P 0 0;1=4
P 0.036 4.05868002 26 P 0 0;1=4
P 0.036 4.10868002 26 P 0 0;1=4
P 0.036 4.15868002 26 P 0 0;1=4
P 0.036 4.20868002 26 P 0 0;1=4
P 0.036 4.25868002 26 P 0 0;1=4
P 0.036 4.30868002 26 P 0 0;1=4
P 0.036 4.35868002 26 P 0 0;1=4
P 0.036 4.40868002 26 P 0 0;1=4
P 0.036 4.45868002 26 P 0 0;1=4
P 0.036 4.50868002 26 P 0 0;1=4
P 0.036 4.55868002 26 P 0 0;1=4
P 0.036 4.60868002 26 P 0 0;1=4
P 0.036 4.65868002 26 P 0 0;1=4
P 0.036 4.70868002 26 P 0 0;1=4
P 0.036 4.75868002 26 P 0 0;1=4
P 12.8892 1.02595974 26 P 0 0;1=4
P 12.8892 1.27595974 26 P 0 0;1=4
P 12.8892 1.22595974 26 P 0 0;1=4
P 12.8892 1.17595974 26 P 0 0;1=4
P 12.8892 1.12595974 26 P 0 0;1=4
P 12.8892 1.07595974 26 P 0 0;1=4
P 12.8892 1.52595974 26 P 0 0;1=4
P 12.8892 1.47595974 26 P 0 0;1=4
P 12.8892 1.42595974 26 P 0 0;1=4
P 12.8892 1.37595974 26 P 0 0;1=4
P 12.8892 1.32595974 26 P 0 0;1=4
P 12.8892 1.77595974 26 P 0 0;1=4
P 12.8892 1.72595974 26 P 0 0;1=4
P 12.8892 1.67595974 26 P 0 0;1=4
P 12.8892 1.62595974 26 P 0 0;1=4
P 12.8892 1.57595974 26 P 0 0;1=4
P 12.8892 2.07595974 26 P 0 0;1=4
P 12.8892 2.02595974 26 P 0 0;1=4
P 12.8892 1.97595974 26 P 0 0;1=4
P 12.8892 1.92595974 26 P 0 0;1=4
P 12.8892 1.87595974 26 P 0 0;1=4
P 12.8892 1.82595974 26 P 0 0;1=4
P 12.8892 2.32595974 26 P 0 0;1=4
P 12.8892 2.27595974 26 P 0 0;1=4
P 12.8892 2.22595974 26 P 0 0;1=4
P 12.8892 2.17595974 26 P 0 0;1=4
P 12.8892 2.57595974 26 P 0 0;1=4
P 12.8892 2.52595974 26 P 0 0;1=4
P 12.8892 2.47595974 26 P 0 0;1=4
P 12.8892 2.42595974 26 P 0 0;1=4
P 12.8892 2.37595974 26 P 0 0;1=4
P 12.8892 2.82595974 26 P 0 0;1=4
P 12.8892 2.77595974 26 P 0 0;1=4
P 12.8892 2.72595974 26 P 0 0;1=4
P 12.8892 2.67595974 26 P 0 0;1=4
P 12.8892 2.62595974 26 P 0 0;1=4
P 12.8892 3.12595974 26 P 0 0;1=4
P 12.8892 3.07595974 26 P 0 0;1=4
P 12.8892 3.02595974 26 P 0 0;1=4
P 12.8892 2.97595974 26 P 0 0;1=4
P 12.8892 2.92595974 26 P 0 0;1=4
P 12.8892 2.87595974 26 P 0 0;1=4
P 12.8892 3.37595974 26 P 0 0;1=4
P 12.8892 3.32595974 26 P 0 0;1=4
P 12.8892 3.27595974 26 P 0 0;1=4
P 12.8892 3.22595974 26 P 0 0;1=4
P 12.8892 3.17595974 26 P 0 0;1=4
P 12.8892 3.62595974 26 P 0 0;1=4
P 12.8892 3.57595974 26 P 0 0;1=4
P 12.8892 3.52595974 26 P 0 0;1=4
P 12.8892 3.47595974 26 P 0 0;1=4
P 12.8892 3.42595974 26 P 0 0;1=4
P 12.8892 3.92595974 26 P 0 0;1=4
P 12.8892 3.87595974 26 P 0 0;1=4
P 12.8892 3.82595974 26 P 0 0;1=4
P 12.8892 3.77595974 26 P 0 0;1=4
P 12.8892 3.72595974 26 P 0 0;1=4
P 12.8892 3.67595974 26 P 0 0;1=4
P 12.8892 4.17595974 26 P 0 0;1=4
P 12.8892 4.12595974 26 P 0 0;1=4
P 12.8892 4.07595974 26 P 0 0;1=4
P 12.8892 4.02595974 26 P 0 0;1=4
P 12.8892 3.97595974 26 P 0 0;1=4
P 12.8892 4.42595974 26 P 0 0;1=4
P 12.8892 4.37595974 26 P 0 0;1=4
P 12.8892 4.32595974 26 P 0 0;1=4
P 12.8892 4.27595974 26 P 0 0;1=4
P 12.8892 4.22595974 26 P 0 0;1=4
P 12.8892 4.67595974 26 P 0 0;1=4
P 12.8892 4.62595974 26 P 0 0;1=4
P 12.8892 4.57595974 26 P 0 0;1=4
P 12.8892 4.52595974 26 P 0 0;1=4
P 12.8892 4.47595974 26 P 0 0;1=4
P 12.8892 4.82595974 26 P 0 0;1=4
P 12.8892 4.77595974 26 P 0 0;1=4
P 12.8892 4.72595974 26 P 0 0;1=4
P 0.036 5.25868002 26 P 0 0;1=4
P 0.036 5.30868002 26 P 0 0;1=4
P 0.036 5.35868002 26 P 0 0;1=4
P 0.036 5.40868002 26 P 0 0;1=4
P 0.036 5.45868002 26 P 0 0;1=4
P 0.036 5.50868002 26 P 0 0;1=4
P 0.036 5.55868002 26 P 0 0;1=4
P 0.036 5.60868002 26 P 0 0;1=4
P 0.036 5.65868002 26 P 0 0;1=4
P 0.036 5.70868002 26 P 0 0;1=4
P 0.036 5.75868002 26 P 0 0;1=4
P 0.036 5.80868002 26 P 0 0;1=4
P 0.036 5.85868002 26 P 0 0;1=4
P 0.036 5.90868002 26 P 0 0;1=4
P 0.03826998 5.95863002 26 P 0 0;1=4
P 0.07901024 5.98761998 26 P 0 0;1=4
P 0.12901024 5.98761998 26 P 0 0;1=4
P 0.17901024 5.98761998 26 P 0 0;1=4
P 0.22901024 5.98761998 26 P 0 0;1=4
P 0.27901024 5.98761998 26 P 0 0;1=4
P 0.32901024 5.98761998 26 P 0 0;1=4
P 0.37901024 5.98761998 26 P 0 0;1=4
P 0.42901024 5.98761998 26 P 0 0;1=4
P 0.47901024 5.98761998 26 P 0 0;1=4
P 0.52901024 5.98761998 26 P 0 0;1=4
P 0.57901024 5.98761998 26 P 0 0;1=4
P 0.62901024 5.98761998 26 P 0 0;1=4
P 0.67901024 5.98761998 26 P 0 0;1=4
P 0.72901024 5.98761998 26 P 0 0;1=4
P 0.77901024 5.98761998 26 P 0 0;1=4
P 0.82901024 5.98761998 26 P 0 0;1=4
P 0.87901024 5.98761998 26 P 0 0;1=4
P 0.92901024 5.98761998 26 P 0 0;1=4
P 0.97901024 5.98761998 26 P 0 0;1=4
P 1.02901024 5.98761998 26 P 0 0;1=4
P 1.07901024 5.98761998 26 P 0 0;1=4
P 1.12901024 5.98761998 26 P 0 0;1=4
P 1.17901024 5.98761998 26 P 0 0;1=4
P 1.22901024 5.98761998 26 P 0 0;1=4
P 1.27901024 5.98761998 26 P 0 0;1=4
P 1.32901024 5.98761998 26 P 0 0;1=4
P 1.37901024 5.98761998 26 P 0 0;1=4
P 1.42901024 5.98761998 26 P 0 0;1=4
P 1.47901024 5.98761998 26 P 0 0;1=4
P 1.52901024 5.98761998 26 P 0 0;1=4
P 1.57901024 5.98761998 26 P 0 0;1=4
P 1.62901024 5.98761998 26 P 0 0;1=4
P 1.67901024 5.98761998 26 P 0 0;1=4
P 1.72901024 5.98761998 26 P 0 0;1=4
P 1.77901024 5.98761998 26 P 0 0;1=4
P 1.82901024 5.98761998 26 P 0 0;1=4
P 1.87901024 5.98761998 26 P 0 0;1=4
P 1.92901024 5.98761998 26 P 0 0;1=4
P 1.97901024 5.98761998 26 P 0 0;1=4
P 2.02901024 5.98761998 26 P 0 0;1=4
P 2.07901024 5.98761998 26 P 0 0;1=4
P 2.12901024 5.98761998 26 P 0 0;1=4
P 2.17901024 5.98761998 26 P 0 0;1=4
P 2.22901024 5.98761998 26 P 0 0;1=4
P 2.27901024 5.98761998 26 P 0 0;1=4
P 2.32901024 5.98761998 26 P 0 0;1=4
P 2.37901024 5.98761998 26 P 0 0;1=4
P 2.42901024 5.98761998 26 P 0 0;1=4
P 2.47901024 5.98761998 26 P 0 0;1=4
P 2.52901024 5.98761998 26 P 0 0;1=4
P 2.57901024 5.98761998 26 P 0 0;1=4
P 2.62901024 5.98761998 26 P 0 0;1=4
P 2.67901024 5.98761998 26 P 0 0;1=4
P 2.72901024 5.98761998 26 P 0 0;1=4
P 2.77901024 5.98761998 26 P 0 0;1=4
P 2.82901024 5.98761998 26 P 0 0;1=4
P 2.87901024 5.98761998 26 P 0 0;1=4
P 2.92901024 5.98761998 26 P 0 0;1=4
P 2.97901024 5.98761998 26 P 0 0;1=4
P 3.02901024 5.98761998 26 P 0 0;1=4
P 3.07901024 5.98761998 26 P 0 0;1=4
P 3.12901024 5.98761998 26 P 0 0;1=4
P 3.17901024 5.98761998 26 P 0 0;1=4
P 3.22901024 5.98761998 26 P 0 0;1=4
P 3.27901024 5.98761998 26 P 0 0;1=4
P 3.32901024 5.98761998 26 P 0 0;1=4
P 3.37901024 5.98761998 26 P 0 0;1=4
P 3.42901024 5.98761998 26 P 0 0;1=4
P 3.47901024 5.98761998 26 P 0 0;1=4
P 3.52901024 5.98761998 26 P 0 0;1=4
P 3.57901024 5.98761998 26 P 0 0;1=4
P 3.62901024 5.98761998 26 P 0 0;1=4
P 3.67901024 5.98761998 26 P 0 0;1=4
P 3.72901024 5.98761998 26 P 0 0;1=4
P 3.77901024 5.98761998 26 P 0 0;1=4
P 3.82901024 5.98761998 26 P 0 0;1=4
P 3.87901024 5.98761998 26 P 0 0;1=4
P 3.92901024 5.98761998 26 P 0 0;1=4
P 3.97901024 5.98761998 26 P 0 0;1=4
P 4.02901024 5.98761998 26 P 0 0;1=4
P 4.07901024 5.98761998 26 P 0 0;1=4
P 4.12901024 5.98761998 26 P 0 0;1=4
P 4.17901024 5.98761998 26 P 0 0;1=4
P 4.22901024 5.98761998 26 P 0 0;1=4
P 4.27901024 5.98761998 26 P 0 0;1=4
P 4.32901024 5.98761998 26 P 0 0;1=4
P 4.37901024 5.98761998 26 P 0 0;1=4
P 4.42901024 5.98761998 26 P 0 0;1=4
P 4.47901024 5.98761998 26 P 0 0;1=4
P 4.52901024 5.98761998 26 P 0 0;1=4
P 4.57901024 5.98761998 26 P 0 0;1=4
P 4.62901024 5.98761998 26 P 0 0;1=4
P 4.67901024 5.98761998 26 P 0 0;1=4
P 4.72901024 5.98761998 26 P 0 0;1=4
P 4.77901024 5.98761998 26 P 0 0;1=4
P 4.82901024 5.98761998 26 P 0 0;1=4
P 4.87901024 5.98761998 26 P 0 0;1=4
P 4.92901024 5.98761998 26 P 0 0;1=4
P 4.97901024 5.98761998 26 P 0 0;1=4
P 5.02901024 5.98761998 26 P 0 0;1=4
P 5.07901024 5.98761998 26 P 0 0;1=4
P 5.12901024 5.98761998 26 P 0 0;1=4
P 5.17901024 5.98761998 26 P 0 0;1=4
P 5.22901024 5.98761998 26 P 0 0;1=4
P 5.27901024 5.98761998 26 P 0 0;1=4
P 5.32901024 5.98761998 26 P 0 0;1=4
P 5.37901024 5.98761998 26 P 0 0;1=4
P 5.42901024 5.98761998 26 P 0 0;1=4
P 5.47901024 5.98761998 26 P 0 0;1=4
P 5.52901024 5.98761998 26 P 0 0;1=4
P 5.57901024 5.98761998 26 P 0 0;1=4
P 5.62901024 5.98761998 26 P 0 0;1=4
P 5.67901024 5.98761998 26 P 0 0;1=4
P 5.72901024 5.98761998 26 P 0 0;1=4
P 5.77901024 5.98761998 26 P 0 0;1=4
P 5.82901024 5.98761998 26 P 0 0;1=4
P 5.87901024 5.98761998 26 P 0 0;1=4
P 5.92901024 5.98761998 26 P 0 0;1=4
P 5.97901024 5.98761998 26 P 0 0;1=4
P 6.02901024 5.98761998 26 P 0 0;1=4
P 6.07901024 5.98761998 26 P 0 0;1=4
P 6.12901024 5.98761998 26 P 0 0;1=4
P 6.17901024 5.98761998 26 P 0 0;1=4
P 6.22901024 5.98761998 26 P 0 0;1=4
P 6.27901024 5.98761998 26 P 0 0;1=4
P 6.32901024 5.98761998 26 P 0 0;1=4
P 6.37901024 5.98761998 26 P 0 0;1=4
P 6.42901024 5.98761998 26 P 0 0;1=4
P 6.47901024 5.98761998 26 P 0 0;1=4
P 6.52901024 5.98761998 26 P 0 0;1=4
P 6.57901024 5.98761998 26 P 0 0;1=4
P 6.62901024 5.98761998 26 P 0 0;1=4
P 6.67901024 5.98761998 26 P 0 0;1=4
P 6.72901024 5.98761998 26 P 0 0;1=4
P 6.77901024 5.98761998 26 P 0 0;1=4
P 6.82901024 5.98761998 26 P 0 0;1=4
P 6.87901024 5.98761998 26 P 0 0;1=4
P 6.92901024 5.98761998 26 P 0 0;1=4
P 6.97901024 5.98761998 26 P 0 0;1=4
P 12.8892 5.47595974 26 P 0 0;1=4
P 12.8892 5.42595974 26 P 0 0;1=4
P 12.8892 5.37595974 26 P 0 0;1=4
P 12.8892 5.32595974 26 P 0 0;1=4
P 12.8892 5.27595974 26 P 0 0;1=4
P 12.8892 5.72595974 26 P 0 0;1=4
P 12.8892 5.67595974 26 P 0 0;1=4
P 12.8892 5.62595974 26 P 0 0;1=4
P 12.8892 5.57595974 26 P 0 0;1=4
P 12.8892 5.52595974 26 P 0 0;1=4
P 7.37901024 5.98761998 26 P 0 0;1=4
P 7.42901024 5.98761998 26 P 0 0;1=4
P 7.47901024 5.98761998 26 P 0 0;1=4
P 7.52901024 5.98761998 26 P 0 0;1=4
P 7.57901024 5.98761998 26 P 0 0;1=4
P 7.62901024 5.98761998 26 P 0 0;1=4
P 7.67901024 5.98761998 26 P 0 0;1=4
P 7.72901024 5.98761998 26 P 0 0;1=4
P 7.77901024 5.98761998 26 P 0 0;1=4
P 7.82901024 5.98761998 26 P 0 0;1=4
P 7.87901024 5.98761998 26 P 0 0;1=4
P 7.92901024 5.98761998 26 P 0 0;1=4
P 7.97901024 5.98761998 26 P 0 0;1=4
P 8.02901024 5.98761998 26 P 0 0;1=4
P 8.07901024 5.98761998 26 P 0 0;1=4
P 8.12901024 5.98761998 26 P 0 0;1=4
P 8.17901024 5.98761998 26 P 0 0;1=4
P 8.22901024 5.98761998 26 P 0 0;1=4
P 8.27901024 5.98761998 26 P 0 0;1=4
P 8.32901024 5.98761998 26 P 0 0;1=4
P 8.37901024 5.98761998 26 P 0 0;1=4
P 8.42901024 5.98761998 26 P 0 0;1=4
P 8.47901024 5.98761998 26 P 0 0;1=4
P 8.52901024 5.98761998 26 P 0 0;1=4
P 8.57901024 5.98761998 26 P 0 0;1=4
P 8.62901024 5.98761998 26 P 0 0;1=4
P 8.67901024 5.98761998 26 P 0 0;1=4
P 8.72901024 5.98761998 26 P 0 0;1=4
P 8.77901024 5.98761998 26 P 0 0;1=4
P 8.82901024 5.98761998 26 P 0 0;1=4
P 8.87901024 5.98761998 26 P 0 0;1=4
P 8.92901024 5.98761998 26 P 0 0;1=4
P 8.97901024 5.98761998 26 P 0 0;1=4
P 9.02901024 5.98761998 26 P 0 0;1=4
P 9.07901024 5.98761998 26 P 0 0;1=4
P 9.12901024 5.98761998 26 P 0 0;1=4
P 9.17901024 5.98761998 26 P 0 0;1=4
P 9.22901024 5.98761998 26 P 0 0;1=4
P 9.27901024 5.98761998 26 P 0 0;1=4
P 9.32901024 5.98761998 26 P 0 0;1=4
P 9.37901024 5.98761998 26 P 0 0;1=4
P 9.42901024 5.98761998 26 P 0 0;1=4
P 9.47901024 5.98761998 26 P 0 0;1=4
P 9.52901024 5.98761998 26 P 0 0;1=4
P 9.57901024 5.98761998 26 P 0 0;1=4
P 9.62901024 5.98761998 26 P 0 0;1=4
P 9.67901024 5.98761998 26 P 0 0;1=4
P 9.72901024 5.98761998 26 P 0 0;1=4
P 9.77901024 5.98761998 26 P 0 0;1=4
P 9.82901024 5.98761998 26 P 0 0;1=4
P 9.87901024 5.98761998 26 P 0 0;1=4
P 9.92901024 5.98761998 26 P 0 0;1=4
P 9.97901024 5.98761998 26 P 0 0;1=4
P 10.02901024 5.98761998 26 P 0 0;1=4
P 10.07901024 5.98761998 26 P 0 0;1=4
P 10.12901024 5.98761998 26 P 0 0;1=4
P 10.17901024 5.98761998 26 P 0 0;1=4
P 10.22901024 5.98761998 26 P 0 0;1=4
P 10.27901024 5.98761998 26 P 0 0;1=4
P 10.32901024 5.98761998 26 P 0 0;1=4
P 10.37901024 5.98761998 26 P 0 0;1=4
P 10.42901024 5.98761998 26 P 0 0;1=4
P 10.47901024 5.98761998 26 P 0 0;1=4
P 10.52901024 5.98761998 26 P 0 0;1=4
P 10.57901024 5.98761998 26 P 0 0;1=4
P 10.62901024 5.98761998 26 P 0 0;1=4
P 10.67901024 5.98761998 26 P 0 0;1=4
P 10.72901024 5.98761998 26 P 0 0;1=4
P 10.77901024 5.98761998 26 P 0 0;1=4
P 10.82901024 5.98761998 26 P 0 0;1=4
P 10.87901024 5.98761998 26 P 0 0;1=4
P 10.92901024 5.98761998 26 P 0 0;1=4
P 10.97901024 5.98761998 26 P 0 0;1=4
P 11.02901024 5.98761998 26 P 0 0;1=4
P 11.07901024 5.98761998 26 P 0 0;1=4
P 11.12901024 5.98761998 26 P 0 0;1=4
P 11.17901024 5.98761998 26 P 0 0;1=4
P 11.22901024 5.98761998 26 P 0 0;1=4
P 11.27901024 5.98761998 26 P 0 0;1=4
P 11.32901024 5.98761998 26 P 0 0;1=4
P 11.37901024 5.98761998 26 P 0 0;1=4
P 11.42901024 5.98761998 26 P 0 0;1=4
P 11.47901024 5.98761998 26 P 0 0;1=4
P 11.52901024 5.98761998 26 P 0 0;1=4
P 11.57901024 5.98761998 26 P 0 0;1=4
P 11.62901024 5.98761998 26 P 0 0;1=4
P 11.67901024 5.98761998 26 P 0 0;1=4
P 11.72901024 5.98761998 26 P 0 0;1=4
P 11.77901024 5.98761998 26 P 0 0;1=4
P 11.82901024 5.98761998 26 P 0 0;1=4
P 11.87901024 5.98761998 26 P 0 0;1=4
P 11.92901024 5.98761998 26 P 0 0;1=4
P 11.97901024 5.98761998 26 P 0 0;1=4
P 12.02901024 5.98761998 26 P 0 0;1=4
P 12.07901024 5.98761998 26 P 0 0;1=4
P 12.12901024 5.98761998 26 P 0 0;1=4
P 12.17901024 5.98761998 26 P 0 0;1=4
P 12.22901024 5.98761998 26 P 0 0;1=4
P 12.27901024 5.98761998 26 P 0 0;1=4
P 12.32901024 5.98761998 26 P 0 0;1=4
P 12.37901024 5.98761998 26 P 0 0;1=4
P 12.42901024 5.98761998 26 P 0 0;1=4
P 12.47901024 5.98761998 26 P 0 0;1=4
P 12.52901024 5.98761998 26 P 0 0;1=4
P 12.57901024 5.98761998 26 P 0 0;1=4
P 12.62901024 5.98761998 26 P 0 0;1=4
P 12.67901024 5.98761998 26 P 0 0;1=4
P 12.72901024 5.98761998 26 P 0 0;1=4
P 12.77901024 5.98761998 26 P 0 0;1=4
P 12.82901024 5.98761998 26 P 0 0;1=4
P 12.87725994 5.97451004 26 P 0 0;1=4
P 12.8892 5.92595974 26 P 0 0;1=4
P 12.8892 5.87595974 26 P 0 0;1=4
P 12.8892 5.82595974 26 P 0 0;1=4
P 12.8892 5.77595974 26 P 0 0;1=4
P 4.33605 4.9231 26 P 0 0;1=4
P 4.38105 4.9231 26 P 0 0;1=4
P 4.30105 4.9431 26 P 0 0;1=4
P 4.42105 4.9431 26 P 0 0;1=4
P 4.46105 4.9431 26 P 0 0;1=4
P 4.26105 4.9431 26 P 0 0;1=4
P 4.72605 4.9231 26 P 0 0;1=4
P 4.65105 4.9431 26 P 0 0;1=4
P 4.69105 4.9431 26 P 0 0;1=4
P 4.85105 4.9431 26 P 0 0;1=4
P 4.81105 4.9431 26 P 0 0;1=4
P 4.77105 4.9231 26 P 0 0;1=4
P 4.30105 5.0281 26 P 0 0;1=4
P 4.30105 5.0731 26 P 0 0;1=4
P 4.30105 4.9831 26 P 0 0;1=4
P 4.34105 5.1181 26 P 0 0;1=4
P 4.38105 5.1181 26 P 0 0;1=4
P 4.46105 5.1181 26 P 0 0;1=4
P 4.42105 5.1181 26 P 0 0;1=4
P 4.42105 4.9831 26 P 0 0;1=4
P 4.42105 5.0731 26 P 0 0;1=4
P 4.42105 5.0281 26 P 0 0;1=4
P 4.46105 4.9831 26 P 0 0;1=4
P 4.46105 5.0731 26 P 0 0;1=4
P 4.46105 5.0281 26 P 0 0;1=4
P 4.26105 5.0281 26 P 0 0;1=4
P 4.26105 5.0731 26 P 0 0;1=4
P 4.26105 4.9831 26 P 0 0;1=4
P 4.73105 5.1181 26 P 0 0;1=4
P 4.69105 5.1181 26 P 0 0;1=4
P 4.65105 5.1181 26 P 0 0;1=4
P 4.65105 4.9831 26 P 0 0;1=4
P 4.65105 5.0731 26 P 0 0;1=4
P 4.65105 5.0281 26 P 0 0;1=4
P 4.69105 4.9831 26 P 0 0;1=4
P 4.69105 5.0731 26 P 0 0;1=4
P 4.69105 5.0281 26 P 0 0;1=4
P 4.85105 5.0281 26 P 0 0;1=4
P 4.85105 5.0731 26 P 0 0;1=4
P 4.85105 4.9831 26 P 0 0;1=4
P 4.81105 5.0281 26 P 0 0;1=4
P 4.81105 5.0731 26 P 0 0;1=4
P 4.81105 4.9831 26 P 0 0;1=4
P 4.81105 5.1181 26 P 0 0;1=4
P 4.85105 5.1181 26 P 0 0;1=4
P 4.77105 5.1181 26 P 0 0;1=4
P 4.30105 5.1181 26 P 0 0;1=4
P 4.26105 5.1181 26 P 0 0;1=4
P 9.45795 0.36633002 26 P 0 0;1=4
P 6.62 4.645 26 P 0 0;1=4
P 6.62 4.61 26 P 0 0;1=4
P 6.605 4.77 26 P 0 0;1=4
P 6.315 4.9 26 P 0 0;1=4
P 6.315 4.865 26 P 0 0;1=4
P 6.315 4.82 26 P 0 0;1=4
P 6.315 4.785 26 P 0 0;1=4
P 6.315 4.705 26 P 0 0;1=4
P 6.315 4.74 26 P 0 0;1=4
P 6.315 4.66 26 P 0 0;1=4
P 6.315 4.625 26 P 0 0;1=4
P 1.51672972 5.78 26 P 0 0;1=4
P 1.12303002 5.46015974 26 P 0 0;1=4
P 1.20176998 5.46016004 26 P 0 0;1=4
P 1.51673002 5.46015974 26 P 0 0;1=4
P 1.36 5.355 26 P 0 0;1=4
P 1.41 5.355 26 P 0 0;1=4
P 1.46 5.355 26 P 0 0;1=4
P 1.305 5.885 26 P 0 0;1=4
P 1.355 5.885 26 P 0 0;1=4
P 1.405 5.885 26 P 0 0;1=4
P 1.455 5.885 26 P 0 0;1=4
P 0.705 5.355 26 P 0 0;1=4
P 0.7 5.267 26 P 0 0;1=0
P 0.73 5.175 26 P 0 0;1=4
P 1.03 5.065 26 P 0 0;1=4
P 1.28050994 5.46016004 26 P 0 0;1=4
P 12.215 4.915 26 P 0 0;1=4
P 12.055 4.915 26 P 0 0;1=4
P 10.465 5.245 26 P 0 0;1=4
P 10.465 5.165 26 P 0 0;1=4
P 11.7719 4.80998976 26 P 0 0;1=4
P 11.7719 4.85498976 26 P 0 0;1=4
P 11.7719 4.90498976 26 P 0 0;1=4
P 11.7719 4.94998976 26 P 0 0;1=4
P 11.9719 4.94998976 26 P 0 0;1=4
P 11.9719 4.80998976 26 P 0 0;1=4
P 11.9719 4.85498976 26 P 0 0;1=4
P 11.9719 4.90498976 26 P 0 0;1=4
P 11.9219 4.94998976 26 P 0 0;1=4
P 11.9219 4.80998976 26 P 0 0;1=4
P 11.8719 4.94998976 26 P 0 0;1=4
P 11.8719 4.80998976 26 P 0 0;1=4
P 11.8219 4.80998976 26 P 0 0;1=4
P 11.8219 4.94998976 26 P 0 0;1=4
P 11.69315974 2.6635 26 P 0 0;1=4
P 10.125 2.008 26 P 0 0;1=4
P 5.53530974 1.6642 26 P 0 0;1=4
P 5.53530974 1.7213 26 P 0 0;1=4
P 5.53530974 2.0802 26 P 0 0;1=4
P 5.53530974 1.9393 26 P 0 0;1=4
P 5.53530974 2.2156 26 P 0 0;1=4
P 5.53530974 2.4081 26 P 0 0;1=4
P 5.53530974 2.5473 26 P 0 0;1=4
P 2.86855 4.92 26 P 0 0;1=4
P 2.79767972 4.92 26 P 0 0;1=4
P 3.08113976 4.92 26 P 0 0;1=4
P 3.36460974 4.926 26 P 0 0;1=4
P 3.22287972 4.92 26 P 0 0;1=4
P 3.50633976 4.92 26 P 0 0;1=4
P 3.43546998 4.928 26 P 0 0;1=4
P 3.15398002 4.81401998 26 P 0 0;1=4
P 3.22288002 4.81401998 26 P 0 0;1=4
P 3.36461024 4.81401998 26 P 0 0;1=4
P 3.43547028 4.81401998 26 P 0 0;1=4
P 3.50634026 4.81401998 26 P 0 0;1=4
P 3.22287972 5.023 26 P 0 0;1=4
P 3.50633976 5.023 26 P 0 0;1=4
P 3.43546998 5.023 26 P 0 0;1=4
P 3.14 4.92 26 P 0 0;1=4
P 3.275 4.92 26 P 0 0;1=4
P 3.26 5.332 26 P 0 0;1=4
P 3.06792028 5.332 26 P 0 0;1=4
P 3.51176998 5.17874026 26 P 0 0;1=4
P 3.57176998 5.17874026 26 P 0 0;1=4
P 3.15743996 4.74418002 26 P 0 0;1=4
P 1.63307972 4.92 26 P 0 0;1=4
P 1.84567972 4.92 26 P 0 0;1=4
P 1.77480974 4.92 26 P 0 0;1=4
P 1.70395 4.92 26 P 0 0;1=4
P 2.12913976 4.92 26 P 0 0;1=4
P 2.05827972 4.92 26 P 0 0;1=4
P 1.98740974 4.92 26 P 0 0;1=4
P 1.91653976 4.92 26 P 0 0;1=4
P 2.34173976 4.92 26 P 0 0;1=4
P 2.27086998 4.92 26 P 0 0;1=4
P 2.20000974 4.926 26 P 0 0;1=4
P 2.34173976 4.81 26 P 0 0;1=4
P 2.27086998 4.81 26 P 0 0;1=4
P 2.20000974 4.81 26 P 0 0;1=4
P 1.63173002 4.81526998 26 P 0 0;1=4
P 1.7 4.812 26 P 0 0;1=4
P 1.84567972 4.81 26 P 0 0;1=4
P 1.776 4.812 26 P 0 0;1=4
P 2.12913976 4.81 26 P 0 0;1=4
P 1.99 4.81 26 P 0 0;1=4
P 1.92 4.81 26 P 0 0;1=4
P 2.40716998 5.15374026 26 P 0 0;1=4
P 2.34716998 5.15374026 26 P 0 0;1=4
P 10.58660974 2.16615 26 P 0 0;1=3
P 10.63660974 2.16615 26 P 0 0;1=3
P 10.63660974 2.21615 26 P 0 0;1=3
P 10.88660974 1.91615 26 P 0 0;1=3
P 10.88660974 2.41615 26 P 0 0;1=3
P 10.88660974 2.66615 26 P 0 0;1=3
P 11.03660974 2.41615 26 P 0 0;1=3
P 11.03660974 2.36615 26 P 0 0;1=3
P 1.91110994 4.61826004 26 P 0 0;1=4
P 2.40716998 4.70326004 26 P 0 0;1=4
P 2.945 4.92 26 P 0 0;1=4
P 3.01027972 4.92 26 P 0 0;1=4
P 7.78 2.4781 26 P 0 0;1=0
P 2.24606024 3.86615 26 P 0 0;1=3
P 2.49606024 3.86615 26 P 0 0;1=3
P 2.24606024 3.81615 26 P 0 0;1=3
P 2.19606024 3.76615 26 P 0 0;1=3
P 2.24606024 3.76615 26 P 0 0;1=3
P 2.29606024 3.76615 26 P 0 0;1=3
P 2.49606024 3.71615 26 P 0 0;1=3
P 2.49606024 3.56615 26 P 0 0;1=3
P 2.44606024 3.56615 26 P 0 0;1=3
P 2.39606024 3.56615 26 P 0 0;1=3
P 2.29606024 3.61615 26 P 0 0;1=3
P 2.24606024 3.71615 26 P 0 0;1=3
P 2.24606024 3.66615 26 P 0 0;1=3
P 2.24606024 3.61615 26 P 0 0;1=3
P 2.19606024 3.61615 26 P 0 0;1=3
P 2.19606024 3.56615 26 P 0 0;1=3
P 2.14606024 3.56615 26 P 0 0;1=3
P 2.04606024 3.56615 26 P 0 0;1=3
P 1.99605974 3.56615 26 P 0 0;1=3
P 2.04606024 3.51615 26 P 0 0;1=3
P 2.04605974 3.46615 26 P 0 0;1=3
P 2.19606024 3.51615 26 P 0 0;1=3
P 2.24606024 3.51615 26 P 0 0;1=3
P 2.29606024 3.51615 26 P 0 0;1=3
P 2.49606024 3.41615 26 P 0 0;1=3
P 2.44606024 3.36615 26 P 0 0;1=3
P 2.24606024 3.46615 26 P 0 0;1=3
P 2.24606024 3.41615 26 P 0 0;1=3
P 2.29606024 3.36615 26 P 0 0;1=3
P 2.24606024 3.36615 26 P 0 0;1=3
P 2.19606024 3.36615 26 P 0 0;1=3
P 1.99605974 3.41615 26 P 0 0;1=3
P 2.09606024 3.36615 26 P 0 0;1=3
P 2.24606024 3.31615 26 P 0 0;1=3
P 2.24606024 3.26615 26 P 0 0;1=3
P 2.29606024 3.21615 26 P 0 0;1=3
P 2.24606024 3.21615 26 P 0 0;1=3
P 2.19606024 3.21615 26 P 0 0;1=3
P 2.09606024 3.21615 26 P 0 0;1=3
P 2.14606024 3.16615 26 P 0 0;1=3
P 2.04606024 3.16615 26 P 0 0;1=3
P 2.24606024 3.16615 26 P 0 0;1=3
P 2.29606024 3.16615 26 P 0 0;1=3
P 2.34606024 3.21615 26 P 0 0;1=3
P 2.44606024 3.21615 26 P 0 0;1=3
P 2.49606024 3.21615 26 P 0 0;1=3
P 2.49606024 3.26615 26 P 0 0;1=3
P 2.49606024 3.16615 26 P 0 0;1=3
P 2.39606024 3.16615 26 P 0 0;1=3
P 2.29606024 3.06615 26 P 0 0;1=3
P 2.29606024 3.11615 26 P 0 0;1=3
P 2.29606024 2.96615 26 P 0 0;1=3
P 2.29606024 3.01615 26 P 0 0;1=3
P 2.24606024 3.06615 26 P 0 0;1=3
P 2.24606024 3.11615 26 P 0 0;1=3
P 2.24606024 2.96615 26 P 0 0;1=3
P 2.24606024 3.01615 26 P 0 0;1=3
P 2.34606024 2.86615 26 P 0 0;1=3
P 2.34606024 2.91615 26 P 0 0;1=3
P 2.29606024 2.76615 26 P 0 0;1=3
P 2.29606024 2.81615 26 P 0 0;1=3
P 2.24606024 2.76615 26 P 0 0;1=3
P 2.24606024 2.81615 26 P 0 0;1=3
P 2.19606024 2.81615 26 P 0 0;1=3
P 2.09606024 2.81615 26 P 0 0;1=3
P 2.09606024 2.86615 26 P 0 0;1=3
P 2.19606024 3.06615 26 P 0 0;1=3
P 2.14606024 3.01615 26 P 0 0;1=3
P 2.09606024 3.06615 26 P 0 0;1=3
P 2.04606024 3.01615 26 P 0 0;1=3
P 2.09606024 2.91615 26 P 0 0;1=3
P 2.14606024 2.86615 26 P 0 0;1=3
P 2.04606024 2.86615 26 P 0 0;1=3
P 2.19606024 2.91615 26 P 0 0;1=3
P 2.24606024 2.91615 26 P 0 0;1=3
P 2.29606024 2.91615 26 P 0 0;1=3
P 2.39606024 3.01615 26 P 0 0;1=3
P 2.34606024 3.06615 26 P 0 0;1=3
P 2.44606024 3.06615 26 P 0 0;1=3
P 2.49606024 3.01615 26 P 0 0;1=3
P 2.44606024 2.91615 26 P 0 0;1=3
P 2.44606024 2.86615 26 P 0 0;1=3
P 2.39606024 2.86615 26 P 0 0;1=3
P 2.34606024 2.81615 26 P 0 0;1=3
P 2.44606024 2.81615 26 P 0 0;1=3
P 2.49606024 2.86615 26 P 0 0;1=3
P 2.49606024 2.71615 26 P 0 0;1=3
P 2.44606024 2.66615 26 P 0 0;1=3
P 2.39606024 2.71615 26 P 0 0;1=3
P 2.34606024 2.66615 26 P 0 0;1=3
P 2.29606024 2.71615 26 P 0 0;1=3
P 2.29606024 2.66615 26 P 0 0;1=3
P 2.24606024 2.71615 26 P 0 0;1=3
P 2.24606024 2.66615 26 P 0 0;1=3
P 2.19606024 2.66615 26 P 0 0;1=3
P 2.14606024 2.71615 26 P 0 0;1=3
P 2.09606024 2.66615 26 P 0 0;1=3
P 2.04606024 2.71615 26 P 0 0;1=3
P 2.04606024 2.56615 26 P 0 0;1=3
P 2.04606024 2.51615 26 P 0 0;1=3
P 2.04606024 2.46615 26 P 0 0;1=3
P 2.09606024 2.51615 26 P 0 0;1=3
P 2.14606024 2.56615 26 P 0 0;1=3
P 2.24606024 2.61615 26 P 0 0;1=3
P 2.24606024 2.56615 26 P 0 0;1=3
P 2.29606024 2.61615 26 P 0 0;1=3
P 2.29606024 2.56615 26 P 0 0;1=3
P 2.34606024 2.51615 26 P 0 0;1=3
P 2.29606024 2.51615 26 P 0 0;1=3
P 2.24606024 2.51615 26 P 0 0;1=3
P 2.19606024 2.51615 26 P 0 0;1=3
P 2.14606024 2.46615 26 P 0 0;1=3
P 2.24606024 2.46615 26 P 0 0;1=3
P 2.29606024 2.46615 26 P 0 0;1=3
P 2.29606024 2.41615 26 P 0 0;1=3
P 2.24606024 2.41615 26 P 0 0;1=3
P 2.24606024 2.36615 26 P 0 0;1=3
P 2.19606024 2.36615 26 P 0 0;1=3
P 2.29606024 2.36615 26 P 0 0;1=3
P 2.39606024 2.46615 26 P 0 0;1=3
P 2.39606024 2.51615 26 P 0 0;1=3
P 2.39606024 2.56615 26 P 0 0;1=3
P 2.44606024 2.51615 26 P 0 0;1=3
P 2.49606024 2.56615 26 P 0 0;1=3
P 2.49606024 2.51615 26 P 0 0;1=3
P 2.49606024 2.46615 26 P 0 0;1=3
P 2.44606024 2.36615 26 P 0 0;1=3
P 2.49606024 2.31615 26 P 0 0;1=3
P 2.39606024 2.31615 26 P 0 0;1=3
P 2.34606024 2.36615 26 P 0 0;1=3
P 2.29606024 2.31615 26 P 0 0;1=3
P 2.24606024 2.31615 26 P 0 0;1=3
P 2.04606024 2.31615 26 P 0 0;1=3
P 2.04606024 2.16615 26 P 0 0;1=3
P 2.04606024 2.11615 26 P 0 0;1=3
P 2.04606024 1.96615 26 P 0 0;1=3
P 2.09606024 2.01615 26 P 0 0;1=3
P 2.14606024 1.96615 26 P 0 0;1=3
P 2.09606024 1.86615 26 P 0 0;1=3
P 2.19606024 1.86615 26 P 0 0;1=3
P 2.24606024 1.86615 26 P 0 0;1=3
P 2.29606024 1.86615 26 P 0 0;1=3
P 2.34606024 1.86615 26 P 0 0;1=3
P 2.24606024 1.91615 26 P 0 0;1=3
P 2.29606024 1.91615 26 P 0 0;1=3
P 2.24606024 1.96615 26 P 0 0;1=3
P 2.29606024 1.96615 26 P 0 0;1=3
P 2.19606024 2.01615 26 P 0 0;1=3
P 2.24606024 2.01615 26 P 0 0;1=3
P 2.29606024 2.01615 26 P 0 0;1=3
P 2.34606024 2.01615 26 P 0 0;1=3
P 2.39606024 1.96615 26 P 0 0;1=3
P 2.44606024 2.01615 26 P 0 0;1=3
P 2.49606024 1.96615 26 P 0 0;1=3
P 2.44606024 1.86615 26 P 0 0;1=3
P 2.49606024 2.11615 26 P 0 0;1=3
P 2.44606024 2.16615 26 P 0 0;1=3
P 2.49606024 2.16615 26 P 0 0;1=3
P 2.44606024 2.21615 26 P 0 0;1=3
P 2.39606024 2.16615 26 P 0 0;1=3
P 2.39606024 2.11615 26 P 0 0;1=3
P 2.34606024 2.16615 26 P 0 0;1=3
P 2.34606024 2.21615 26 P 0 0;1=3
P 2.29606024 2.21615 26 P 0 0;1=3
P 2.29606024 2.16615 26 P 0 0;1=3
P 2.29606024 2.06615 26 P 0 0;1=3
P 2.29606024 2.11615 26 P 0 0;1=3
P 2.24606024 2.11615 26 P 0 0;1=3
P 2.24606024 2.16615 26 P 0 0;1=3
P 2.24606024 2.06615 26 P 0 0;1=3
P 2.24606024 2.21615 26 P 0 0;1=3
P 2.29606024 2.26615 26 P 0 0;1=3
P 2.24606024 2.26615 26 P 0 0;1=3
P 2.19606024 2.21615 26 P 0 0;1=3
P 2.19606024 2.16615 26 P 0 0;1=3
P 2.14606024 2.11615 26 P 0 0;1=3
P 2.14606024 2.16615 26 P 0 0;1=3
P 2.09606024 2.21615 26 P 0 0;1=3
P 2.09606024 2.16615 26 P 0 0;1=3
P 2.09606024 2.36615 26 P 0 0;1=3
P 2.14606024 2.31615 26 P 0 0;1=3
P 1.99605974 2.71615 26 P 0 0;1=3
P 1.99605974 2.86615 26 P 0 0;1=3
P 2.04605974 2.81615 26 P 0 0;1=3
P 2.04605974 2.76615 26 P 0 0;1=3
P 3.29373976 5.023 26 P 0 0;1=4
P 2.14606024 3.26615 26 P 0 0;1=3
P 2.04606024 3.26615 26 P 0 0;1=3
P 2.04606024 3.21615 26 P 0 0;1=3
P 2.14606024 3.21615 26 P 0 0;1=3
P 2.39606024 3.21615 26 P 0 0;1=3
P 2.39606024 3.26615 26 P 0 0;1=3
P 2.29606024 3.26615 26 P 0 0;1=3
P 2.29606024 3.31615 26 P 0 0;1=3
P 2.34606024 3.36615 26 P 0 0;1=3
P 2.14606024 3.41615 26 P 0 0;1=3
P 2.09606024 3.61615 26 P 0 0;1=3
P 2.29606024 3.46615 26 P 0 0;1=3
P 2.29606024 3.41615 26 P 0 0;1=3
P 2.39606024 3.41615 26 P 0 0;1=3
P 2.34606024 3.51615 26 P 0 0;1=3
P 2.34606024 3.61615 26 P 0 0;1=3
P 2.34606024 3.56615 26 P 0 0;1=3
P 2.44606024 3.51615 26 P 0 0;1=3
P 2.44606024 3.61615 26 P 0 0;1=3
P 2.14606024 3.71615 26 P 0 0;1=3
P 2.04606024 3.71615 26 P 0 0;1=3
P 2.09606024 3.76615 26 P 0 0;1=3
P 2.14606024 3.86615 26 P 0 0;1=3
P 2.04606024 3.86615 26 P 0 0;1=3
P 2.29606024 3.71615 26 P 0 0;1=3
P 2.29606024 3.66615 26 P 0 0;1=3
P 2.39606024 3.71615 26 P 0 0;1=3
P 2.34606024 3.76615 26 P 0 0;1=3
P 2.29606024 3.81615 26 P 0 0;1=3
P 2.39606024 3.86615 26 P 0 0;1=3
P 2.29606024 3.86615 26 P 0 0;1=3
P 2.44606024 3.76615 26 P 0 0;1=3
P 2.19606024 2.86615 26 P 0 0;1=3
P 3.36460974 5.023 26 P 0 0;1=4
P 3.29374026 4.81401998 26 P 0 0;1=4
P 3.01028002 4.81401998 26 P 0 0;1=4
P 2.94141024 4.81401998 26 P 0 0;1=4
P 2.86555 4.81401998 26 P 0 0;1=4
P 2.79768002 4.81401998 26 P 0 0;1=4
P 3.15200974 5.023 26 P 0 0;1=4
P 3.08113976 5.023 26 P 0 0;1=4
P 3.01027972 5.023 26 P 0 0;1=4
P 2.93940974 5.023 26 P 0 0;1=4
P 2.86855 5.023 26 P 0 0;1=4
P 2.79767972 5.023 26 P 0 0;1=4
P 1.70395 5.023 26 P 0 0;1=4
P 1.63307972 5.023 26 P 0 0;1=4
P 1.77480974 5.023 26 P 0 0;1=4
P 1.91653976 5.023 26 P 0 0;1=4
P 1.84567972 5.023 26 P 0 0;1=4
P 1.98740974 5.023 26 P 0 0;1=4
P 2.05827972 5.023 26 P 0 0;1=4
P 2.12913976 5.023 26 P 0 0;1=4
P 2.20000974 5.023 26 P 0 0;1=4
P 2.27086998 5.023 26 P 0 0;1=4
P 2.34173976 5.023 26 P 0 0;1=4
P 1.56220974 5.023 26 P 0 0;1=4
P 1.56221024 4.81401998 26 P 0 0;1=4
P 2.06086998 4.81 26 P 0 0;1=4
P 2.41260974 5.023 26 P 0 0;1=4
P 2.41261024 4.81401998 26 P 0 0;1=4
P 2.72680974 5.023 26 P 0 0;1=4
P 2.72681024 4.81401998 26 P 0 0;1=4
P 3.57721024 4.81401998 26 P 0 0;1=4
P 3.57720974 5.023 26 P 0 0;1=4
P 4.88267972 1.91615 26 P 0 0;1=3
P 4.78267972 1.91615 26 P 0 0;1=3
P 5.03267972 2.36615 26 P 0 0;1=3
P 5.03267972 2.41615 26 P 0 0;1=3
P 4.88267972 3.66615 26 P 0 0;1=3
P 4.83267972 3.66615 26 P 0 0;1=3
P 5.03267972 3.66615 26 P 0 0;1=3
P 4.93267972 3.66615 26 P 0 0;1=3
P 4.98267972 3.66615 26 P 0 0;1=3
P 4.88267972 3.51615 26 P 0 0;1=3
P 4.83267972 3.51615 26 P 0 0;1=3
P 5.03267972 3.51615 26 P 0 0;1=3
P 4.93267972 3.51615 26 P 0 0;1=3
P 4.98267972 3.51615 26 P 0 0;1=3
P 4.88267972 3.81615 26 P 0 0;1=3
P 4.83267972 3.81615 26 P 0 0;1=3
P 4.93267972 3.81615 26 P 0 0;1=3
P 4.98267972 3.81615 26 P 0 0;1=3
P 4.88267972 3.36615 26 P 0 0;1=3
P 4.83267972 3.36615 26 P 0 0;1=3
P 5.03267972 3.36615 26 P 0 0;1=3
P 4.93267972 3.36615 26 P 0 0;1=3
P 4.98267972 3.36615 26 P 0 0;1=3
P 4.83267972 3.21615 26 P 0 0;1=3
P 4.88267972 3.21615 26 P 0 0;1=3
P 4.98267972 3.21615 26 P 0 0;1=3
P 4.93267972 3.21615 26 P 0 0;1=3
P 5.03267972 3.21615 26 P 0 0;1=3
P 4.83267972 3.06615 26 P 0 0;1=3
P 4.88267972 3.06615 26 P 0 0;1=3
P 4.98267972 3.06615 26 P 0 0;1=3
P 4.93267972 3.06615 26 P 0 0;1=3
P 5.03267972 3.06615 26 P 0 0;1=3
P 4.83267972 2.91615 26 P 0 0;1=3
P 4.88267972 2.91615 26 P 0 0;1=3
P 4.98267972 2.91615 26 P 0 0;1=3
P 4.93267972 2.91615 26 P 0 0;1=3
P 5.03267972 2.91615 26 P 0 0;1=3
P 4.78268002 2.51615 26 P 0 0;1=3
P 4.73268002 2.51615 26 P 0 0;1=3
P 4.68268002 2.51615 26 P 0 0;1=3
P 4.63268002 2.51615 26 P 0 0;1=3
P 4.58268002 2.51615 26 P 0 0;1=3
P 4.63268002 2.56615 26 P 0 0;1=3
P 4.73268002 2.56615 26 P 0 0;1=3
P 4.78268002 2.56615 26 P 0 0;1=3
P 4.78268002 2.61615 26 P 0 0;1=3
P 4.78268002 2.66615 26 P 0 0;1=3
P 4.68268002 2.66615 26 P 0 0;1=3
P 4.58268002 2.66615 26 P 0 0;1=3
P 4.73268002 2.71615 26 P 0 0;1=3
P 4.63268002 2.71615 26 P 0 0;1=3
P 4.63268002 2.76615 26 P 0 0;1=3
P 4.73268002 2.76615 26 P 0 0;1=3
P 4.78268002 2.76615 26 P 0 0;1=3
P 4.63267972 2.16615 26 P 0 0;1=3
P 4.78267972 2.16615 26 P 0 0;1=3
P 10.63660974 2.91615 26 P 0 0;1=3
P 10.58660974 2.91615 26 P 0 0;1=3
P 10.63660974 3.06615 26 P 0 0;1=3
P 10.58660974 3.06615 26 P 0 0;1=3
P 10.63660974 3.36615 26 P 0 0;1=3
P 10.58660974 3.36615 26 P 0 0;1=3
P 10.63660974 3.21615 26 P 0 0;1=3
P 10.58660974 3.21615 26 P 0 0;1=3
P 10.58660974 3.66615 26 P 0 0;1=3
P 10.63660974 3.51615 26 P 0 0;1=3
P 10.58660974 3.51615 26 P 0 0;1=3
P 10.63660974 3.81615 26 P 0 0;1=3
P 10.63660974 3.66615 26 P 0 0;1=3
P 10.58660974 3.81615 26 P 0 0;1=3
P 10.83660974 2.91615 26 P 0 0;1=3
P 10.78660974 2.91615 26 P 0 0;1=3
P 10.73660974 2.91615 26 P 0 0;1=3
P 10.68660974 2.91615 26 P 0 0;1=3
P 10.88660974 2.91615 26 P 0 0;1=3
P 10.88660974 3.06615 26 P 0 0;1=3
P 10.83660974 3.06615 26 P 0 0;1=3
P 10.78660974 3.06615 26 P 0 0;1=3
P 10.73660974 3.06615 26 P 0 0;1=3
P 10.68660974 3.06615 26 P 0 0;1=3
P 10.88660974 3.21615 26 P 0 0;1=3
P 10.83660974 3.21615 26 P 0 0;1=3
P 10.83660974 3.36615 26 P 0 0;1=3
P 10.88660974 3.36615 26 P 0 0;1=3
P 10.78660974 3.36615 26 P 0 0;1=3
P 10.73660974 3.36615 26 P 0 0;1=3
P 10.78660974 3.21615 26 P 0 0;1=3
P 10.73660974 3.21615 26 P 0 0;1=3
P 10.68660974 3.36615 26 P 0 0;1=3
P 10.68660974 3.21615 26 P 0 0;1=3
P 10.83660974 3.51615 26 P 0 0;1=3
P 10.88660974 3.51615 26 P 0 0;1=3
P 10.83660974 3.66615 26 P 0 0;1=3
P 10.78660974 3.66615 26 P 0 0;1=3
P 10.73660974 3.66615 26 P 0 0;1=3
P 10.68660974 3.66615 26 P 0 0;1=3
P 10.78660974 3.51615 26 P 0 0;1=3
P 10.73660974 3.51615 26 P 0 0;1=3
P 10.68660974 3.51615 26 P 0 0;1=3
P 10.83660974 3.81615 26 P 0 0;1=3
P 10.88660974 3.81615 26 P 0 0;1=3
P 10.88660974 3.66615 26 P 0 0;1=3
P 10.78660974 3.81615 26 P 0 0;1=3
P 10.73660974 3.81615 26 P 0 0;1=3
P 10.68660974 3.81615 26 P 0 0;1=3
P 11.03660974 2.91615 26 P 0 0;1=3
P 10.93660974 2.91615 26 P 0 0;1=3
P 10.98660974 2.91615 26 P 0 0;1=3
P 11.03660974 3.06615 26 P 0 0;1=3
P 10.93660974 3.06615 26 P 0 0;1=3
P 10.98660974 3.06615 26 P 0 0;1=3
P 11.03660974 3.21615 26 P 0 0;1=3
P 10.93660974 3.21615 26 P 0 0;1=3
P 10.98660974 3.21615 26 P 0 0;1=3
P 10.98660974 3.36615 26 P 0 0;1=3
P 10.93660974 3.36615 26 P 0 0;1=3
P 11.03660974 3.36615 26 P 0 0;1=3
P 10.98660974 3.51615 26 P 0 0;1=3
P 10.93660974 3.51615 26 P 0 0;1=3
P 11.03660974 3.51615 26 P 0 0;1=3
P 10.98660974 3.66615 26 P 0 0;1=3
P 10.93660974 3.66615 26 P 0 0;1=3
P 11.03660974 3.66615 26 P 0 0;1=3
P 10.98660974 3.81615 26 P 0 0;1=3
P 10.93660974 3.81615 26 P 0 0;1=3
P 3.07691024 4.81401998 26 P 0 0;1=4
P 8.1 1.86615 26 P 0 0;1=3
P 8.15 2.16615 26 P 0 0;1=3
P 8.15 2.11615 26 P 0 0;1=3
P 8.15 1.96615 26 P 0 0;1=3
P 8.1 2.01615 26 P 0 0;1=3
P 8.05 1.96615 26 P 0 0;1=3
P 8.05 2.11615 26 P 0 0;1=3
P 8.05 2.16615 26 P 0 0;1=3
P 8.15 2.31615 26 P 0 0;1=3
P 8.1 2.36615 26 P 0 0;1=3
P 8.1 2.16615 26 P 0 0;1=3
P 8.1 2.21615 26 P 0 0;1=3
P 8.05 2.31615 26 P 0 0;1=3
P 8.15 2.46615 26 P 0 0;1=3
P 8.15 2.56615 26 P 0 0;1=3
P 8.1 2.51615 26 P 0 0;1=3
P 8.05 2.46615 26 P 0 0;1=3
P 8.05 2.51615 26 P 0 0;1=3
P 8.05 2.56615 26 P 0 0;1=3
P 8.1 2.66615 26 P 0 0;1=3
P 8.05 2.76615 26 P 0 0;1=3
P 8.05 2.81615 26 P 0 0;1=3
P 8 2.86615 26 P 0 0;1=3
P 8 2.71615 26 P 0 0;1=3
P 8.05 2.71615 26 P 0 0;1=3
P 8.15 2.71615 26 P 0 0;1=3
P 8.05 2.86615 26 P 0 0;1=3
P 8.15 2.86615 26 P 0 0;1=3
P 8.1 2.91615 26 P 0 0;1=3
P 8.1 2.86615 26 P 0 0;1=3
P 8.1 2.81615 26 P 0 0;1=3
P 8.05 3.01615 26 P 0 0;1=3
P 8.1 3.06615 26 P 0 0;1=3
P 8.15 3.01615 26 P 0 0;1=3
P 8.15 3.16615 26 P 0 0;1=3
P 8.05 3.16615 26 P 0 0;1=3
P 8 3.41615 26 P 0 0;1=3
P 8.05 3.41615 26 P 0 0;1=3
P 8.1 3.36615 26 P 0 0;1=3
P 8.1 3.21615 26 P 0 0;1=3
P 8.15 3.56615 26 P 0 0;1=3
P 8.05 3.56615 26 P 0 0;1=3
P 8 3.56615 26 P 0 0;1=3
P 8.05 3.51615 26 P 0 0;1=3
P 8.05 3.46615 26 P 0 0;1=3
P 8.1 3.51615 26 P 0 0;1=3
P 8.35 1.86615 26 P 0 0;1=3
P 8.3 1.86615 26 P 0 0;1=3
P 8.25 1.86615 26 P 0 0;1=3
P 8.2 1.86615 26 P 0 0;1=3
P 8.25 2.06615 26 P 0 0;1=3
P 8.25 2.16615 26 P 0 0;1=3
P 8.25 2.11615 26 P 0 0;1=3
P 8.3 2.11615 26 P 0 0;1=3
P 8.3 2.06615 26 P 0 0;1=3
P 8.4 2.11615 26 P 0 0;1=3
P 8.4 2.16615 26 P 0 0;1=3
P 8.4 1.96615 26 P 0 0;1=3
P 8.35 2.01615 26 P 0 0;1=3
P 8.3 2.01615 26 P 0 0;1=3
P 8.25 2.01615 26 P 0 0;1=3
P 8.2 2.01615 26 P 0 0;1=3
P 8.3 1.96615 26 P 0 0;1=3
P 8.25 1.96615 26 P 0 0;1=3
P 8.3 1.91615 26 P 0 0;1=3
P 8.25 1.91615 26 P 0 0;1=3
P 8.2 2.16615 26 P 0 0;1=3
P 8.2 2.21615 26 P 0 0;1=3
P 8.25 2.26615 26 P 0 0;1=3
P 8.3 2.26615 26 P 0 0;1=3
P 8.25 2.21615 26 P 0 0;1=3
P 8.3 2.16615 26 P 0 0;1=3
P 8.3 2.21615 26 P 0 0;1=3
P 8.35 2.21615 26 P 0 0;1=3
P 8.35 2.16615 26 P 0 0;1=3
P 8.25 2.31615 26 P 0 0;1=3
P 8.3 2.31615 26 P 0 0;1=3
P 8.35 2.36615 26 P 0 0;1=3
P 8.4 2.31615 26 P 0 0;1=3
P 8.3 2.36615 26 P 0 0;1=3
P 8.2 2.36615 26 P 0 0;1=3
P 8.25 2.36615 26 P 0 0;1=3
P 8.25 2.41615 26 P 0 0;1=3
P 8.3 2.41615 26 P 0 0;1=3
P 8.4 2.56615 26 P 0 0;1=3
P 8.4 2.51615 26 P 0 0;1=3
P 8.4 2.46615 26 P 0 0;1=3
P 8.3 2.46615 26 P 0 0;1=3
P 8.25 2.46615 26 P 0 0;1=3
P 8.2 2.51615 26 P 0 0;1=3
P 8.25 2.51615 26 P 0 0;1=3
P 8.3 2.51615 26 P 0 0;1=3
P 8.35 2.51615 26 P 0 0;1=3
P 8.3 2.56615 26 P 0 0;1=3
P 8.3 2.61615 26 P 0 0;1=3
P 8.25 2.56615 26 P 0 0;1=3
P 8.25 2.61615 26 P 0 0;1=3
P 8.2 2.66615 26 P 0 0;1=3
P 8.25 2.66615 26 P 0 0;1=3
P 8.3 2.66615 26 P 0 0;1=3
P 8.35 2.66615 26 P 0 0;1=3
P 8.25 2.71615 26 P 0 0;1=3
P 8.3 2.71615 26 P 0 0;1=3
P 8.4 2.71615 26 P 0 0;1=3
P 8.35 2.81615 26 P 0 0;1=3
P 8.4 2.86615 26 P 0 0;1=3
P 8.3 2.91615 26 P 0 0;1=3
P 8.25 2.91615 26 P 0 0;1=3
P 8.2 2.91615 26 P 0 0;1=3
P 8.2 2.81615 26 P 0 0;1=3
P 8.25 2.81615 26 P 0 0;1=3
P 8.25 2.76615 26 P 0 0;1=3
P 8.3 2.81615 26 P 0 0;1=3
P 8.3 2.76615 26 P 0 0;1=3
P 8.35 2.91615 26 P 0 0;1=3
P 8.35 2.86615 26 P 0 0;1=3
P 8.35 3.06615 26 P 0 0;1=3
P 8.4 3.01615 26 P 0 0;1=3
P 8.2 3.06615 26 P 0 0;1=3
P 8.25 3.01615 26 P 0 0;1=3
P 8.25 2.96615 26 P 0 0;1=3
P 8.25 3.11615 26 P 0 0;1=3
P 8.25 3.06615 26 P 0 0;1=3
P 8.3 3.01615 26 P 0 0;1=3
P 8.3 2.96615 26 P 0 0;1=3
P 8.3 3.11615 26 P 0 0;1=3
P 8.3 3.06615 26 P 0 0;1=3
P 8.25 3.16615 26 P 0 0;1=3
P 8.3 3.16615 26 P 0 0;1=3
P 8.4 3.16615 26 P 0 0;1=3
P 8.25 3.41615 26 P 0 0;1=3
P 8.3 3.36615 26 P 0 0;1=3
P 8.25 3.36615 26 P 0 0;1=3
P 8.2 3.36615 26 P 0 0;1=3
P 8.25 3.31615 26 P 0 0;1=3
P 8.25 3.26615 26 P 0 0;1=3
P 8.3 3.21615 26 P 0 0;1=3
P 8.25 3.21615 26 P 0 0;1=3
P 8.2 3.21615 26 P 0 0;1=3
P 8.35 3.21615 26 P 0 0;1=3
P 8.4 3.56615 26 P 0 0;1=3
P 8.3 3.61615 26 P 0 0;1=3
P 8.25 3.66615 26 P 0 0;1=3
P 8.25 3.61615 26 P 0 0;1=3
P 8.2 3.61615 26 P 0 0;1=3
P 8.2 3.56615 26 P 0 0;1=3
P 8.2 3.51615 26 P 0 0;1=3
P 8.25 3.51615 26 P 0 0;1=3
P 8.3 3.51615 26 P 0 0;1=3
P 8.25 3.46615 26 P 0 0;1=3
P 8.25 3.86615 26 P 0 0;1=3
P 8.25 3.81615 26 P 0 0;1=3
P 8.2 3.76615 26 P 0 0;1=3
P 8.25 3.76615 26 P 0 0;1=3
P 8.3 3.76615 26 P 0 0;1=3
P 8.25 3.71615 26 P 0 0;1=3
P 8.45 1.86615 26 P 0 0;1=3
P 8.5 2.16615 26 P 0 0;1=3
P 8.5 2.11615 26 P 0 0;1=3
P 8.5 1.96615 26 P 0 0;1=3
P 8.45 2.01615 26 P 0 0;1=3
P 8.45 2.21615 26 P 0 0;1=3
P 8.45 2.16615 26 P 0 0;1=3
P 8.5 2.31615 26 P 0 0;1=3
P 8.45 2.36615 26 P 0 0;1=3
P 8.5 2.46615 26 P 0 0;1=3
P 8.5 2.51615 26 P 0 0;1=3
P 8.5 2.56615 26 P 0 0;1=3
P 8.45 2.51615 26 P 0 0;1=3
P 8.45 2.66615 26 P 0 0;1=3
P 8.5 2.71615 26 P 0 0;1=3
P 8.5 2.86615 26 P 0 0;1=3
P 8.45 2.81615 26 P 0 0;1=3
P 8.45 2.86615 26 P 0 0;1=3
P 8.45 2.91615 26 P 0 0;1=3
P 8.5 3.01615 26 P 0 0;1=3
P 8.45 3.06615 26 P 0 0;1=3
P 8.5 3.16615 26 P 0 0;1=3
P 8.5 3.41615 26 P 0 0;1=3
P 8.45 3.36615 26 P 0 0;1=3
P 8.45 3.21615 26 P 0 0;1=3
P 8.5 3.21615 26 P 0 0;1=3
P 8.5 3.26615 26 P 0 0;1=3
P 8.5 3.56615 26 P 0 0;1=3
P 8.45 3.56615 26 P 0 0;1=3
P 8.5 3.86615 26 P 0 0;1=3
P 8.5 3.71615 26 P 0 0;1=3
P 8.2 2.86615 26 P 0 0;1=3
P 8.05 3.26615 26 P 0 0;1=3
P 8.05 3.21615 26 P 0 0;1=3
P 8.3 3.26615 26 P 0 0;1=3
P 8.3 3.31615 26 P 0 0;1=3
P 8.35 3.36615 26 P 0 0;1=3
P 8.15 3.26615 26 P 0 0;1=3
P 8.15 3.21615 26 P 0 0;1=3
P 8.4 3.21615 26 P 0 0;1=3
P 8.4 3.26615 26 P 0 0;1=3
P 8.1 3.61615 26 P 0 0;1=3
P 8.3 3.46615 26 P 0 0;1=3
P 8.3 3.41615 26 P 0 0;1=3
P 8.35 3.51615 26 P 0 0;1=3
P 8.35 3.61615 26 P 0 0;1=3
P 8.35 3.56615 26 P 0 0;1=3
P 8.15 3.41615 26 P 0 0;1=3
P 8.45 3.51615 26 P 0 0;1=3
P 8.45 3.61615 26 P 0 0;1=3
P 8.4 3.41615 26 P 0 0;1=3
P 8.05 3.71615 26 P 0 0;1=3
P 8.1 3.76615 26 P 0 0;1=3
P 8.05 3.86615 26 P 0 0;1=3
P 8.3 3.71615 26 P 0 0;1=3
P 8.3 3.66615 26 P 0 0;1=3
P 8.35 3.76615 26 P 0 0;1=3
P 8.3 3.81615 26 P 0 0;1=3
P 8.3 3.86615 26 P 0 0;1=3
P 8.15 3.71615 26 P 0 0;1=3
P 8.15 3.86615 26 P 0 0;1=3
P 8.45 3.76615 26 P 0 0;1=3
P 8.4 3.71615 26 P 0 0;1=3
P 8.4 3.86615 26 P 0 0;1=3
P 3.28831004 4.68073996 26 P 0 0;1=4
P 3.22831004 4.68073996 26 P 0 0;1=4
P 3.50091004 4.62573996 26 P 0 0;1=4
P 3.44091004 4.62573996 26 P 0 0;1=4
P 7.56575 5.023 26 P 0 0;1=4
P 7.63661998 5.023 26 P 0 0;1=4
P 7.84921998 5.023 26 P 0 0;1=4
P 7.77835 5.023 26 P 0 0;1=4
P 7.70748976 5.023 26 P 0 0;1=4
P 7.92007972 5.023 26 P 0 0;1=4
P 8.06181998 5.023 26 P 0 0;1=4
P 8.13267972 5.023 26 P 0 0;1=4
P 7.99095 5.023 26 P 0 0;1=4
P 8.34527972 5.023 26 P 0 0;1=4
P 8.27440974 5.023 26 P 0 0;1=4
P 8.20355 5.023 26 P 0 0;1=4
P 8.41615 5.023 26 P 0 0;1=4
P 7.63661998 4.92 26 P 0 0;1=4
P 7.84921998 4.9207 26 P 0 0;1=4
P 7.70748976 4.9207 26 P 0 0;1=4
P 7.77835 4.9207 26 P 0 0;1=4
P 7.99095 4.9207 26 P 0 0;1=4
P 7.92007972 4.9207 26 P 0 0;1=4
P 8.06181998 4.9207 26 P 0 0;1=4
P 8.13267972 4.9207 26 P 0 0;1=4
P 8.27440974 4.9207 26 P 0 0;1=4
P 8.20355 4.9267 26 P 0 0;1=4
P 8.34527972 4.9207 26 P 0 0;1=4
P 7.63526998 4.81527028 26 P 0 0;1=4
P 7.84921998 4.81 26 P 0 0;1=4
P 7.77953976 4.812 26 P 0 0;1=4
P 7.70353976 4.812 26 P 0 0;1=4
P 8.13267972 4.81 26 P 0 0;1=4
P 8.06440974 4.81 26 P 0 0;1=4
P 7.99353976 4.81 26 P 0 0;1=4
P 7.92353976 4.81 26 P 0 0;1=4
P 8.27440974 4.81 26 P 0 0;1=4
P 8.34527972 4.81 26 P 0 0;1=4
P 8.20355 4.81 26 P 0 0;1=4
P 8.41615 4.81401998 26 P 0 0;1=4
P 8.86909026 4.81401998 26 P 0 0;1=4
P 8.73035 4.81401998 26 P 0 0;1=4
P 8.80122028 4.81401998 26 P 0 0;1=4
P 8.94495 4.81401998 26 P 0 0;1=4
P 9.08045 4.81401998 26 P 0 0;1=4
P 9.01382028 4.81401998 26 P 0 0;1=4
P 9.36815 4.81401998 26 P 0 0;1=4
P 9.29728002 4.81401998 26 P 0 0;1=4
P 9.22642028 4.81401998 26 P 0 0;1=4
P 9.15752028 4.81401998 26 P 0 0;1=4
P 9.43901024 4.81401998 26 P 0 0;1=4
P 9.50988002 4.81401998 26 P 0 0;1=4
P 9.58075 4.81401998 26 P 0 0;1=4
P 8.80121998 5.023 26 P 0 0;1=4
P 8.73035 5.023 26 P 0 0;1=4
P 8.87208976 5.023 26 P 0 0;1=4
P 9.08467972 5.023 26 P 0 0;1=4
P 9.01381998 5.023 26 P 0 0;1=4
P 8.94295 5.023 26 P 0 0;1=4
P 8.87208976 4.92 26 P 0 0;1=4
P 8.80121998 4.92 26 P 0 0;1=4
P 9.01381998 4.92 26 P 0 0;1=4
P 9.08467972 4.92 26 P 0 0;1=4
P 9.22641998 4.92 26 P 0 0;1=4
P 9.36815 4.926 26 P 0 0;1=4
P 9.50987972 4.92 26 P 0 0;1=4
P 9.43900974 4.928 26 P 0 0;1=4
P 9.36815 5.023 26 P 0 0;1=4
P 9.29727972 5.023 26 P 0 0;1=4
P 9.22641998 5.023 26 P 0 0;1=4
P 9.15555 5.023 26 P 0 0;1=4
P 9.50987972 5.023 26 P 0 0;1=4
P 9.43900974 5.023 26 P 0 0;1=4
P 9.58075 5.023 26 P 0 0;1=4
P 8.94853976 4.92 26 P 0 0;1=4
P 9.27853976 4.92 26 P 0 0;1=4
P 9.14353976 4.92 26 P 0 0;1=4
P 8.13811004 5.09223996 26 P 0 0;1=4
P 8.35071004 5.15373996 26 P 0 0;1=4
P 8.41071004 5.15373996 26 P 0 0;1=4
P 7.56575 4.81401998 26 P 0 0;1=4
P 8.88061998 4.70574026 26 P 0 0;1=4
P 2.45985 4.77875 28 P 0 0;1=9
P 1.51496998 4.77875 28 P 0 0;1=9
P 2.44016998 5.05826998 28 P 0 0;1=9
P 1.53465 5.05826998 28 P 0 0;1=9
P 3.60476998 4.77875 28 P 0 0;1=9
P 2.67956998 4.77875 28 P 0 0;1=9
P 3.60476998 5.05826998 28 P 0 0;1=9
P 2.69925 5.05826998 28 P 0 0;1=9
P 8.46338996 4.77875 28 P 0 0;1=9
P 7.51850994 4.77875 28 P 0 0;1=9
P 8.44370994 5.05826998 28 P 0 0;1=9
P 7.53818996 5.05826998 28 P 0 0;1=9
P 9.60830994 4.77875 28 P 0 0;1=9
P 8.68310994 4.77875 28 P 0 0;1=9
P 9.60830994 5.05826998 28 P 0 0;1=9
P 8.70278996 5.05826998 28 P 0 0;1=9
P 10.82676998 5.49685 29 P 0 2;1=10
P 10.99213002 5.49685 29 P 0 2;1=10
P 11.15748002 5.49685 29 P 0 2;1=10
P 11.32283996 5.49685 29 P 0 2;1=10
P 11.48818996 5.49685 29 P 0 2;1=10
P 11.65353996 5.49685 29 P 0 2;1=10
P 11.8189 5.49685 29 P 0 2;1=10
P 11.98425 5.49685 29 P 0 2;1=10
P 12.14961004 5.49685 29 P 0 2;1=11
P 10.83662028 1.37795 26 P 0 2;1=12
P 10.83661998 1.6378 26 P 0 2;1=12
P 8.25 1.6378 26 P 0 2;1=12
P 8.25 1.37795 26 P 0 2;1=12
P 6.96457008 1.39763996 26 P 0 2;1=12
P 6.96456998 1.65748002 26 P 0 2;1=12
P 6.96457028 4.0748 26 P 0 2;1=12
P 6.96456998 4.33465 26 P 0 2;1=12
P 8.25 4.09448976 26 P 0 2;1=12
P 8.25 4.35433002 26 P 0 2;1=12
P 10.83662008 4.09448996 26 P 0 2;1=12
P 10.83661998 4.35433002 26 P 0 2;1=12
P 12.12205 4.0748 26 P 0 2;1=12
P 12.12205 4.33465 26 P 0 2;1=12
P 12.12205 1.65748002 26 P 0 2;1=12
P 12.12205 1.39763976 26 P 0 2;1=12
P 11.99212972 4.20473002 26 P 0 2;1=4
P 12.03020522 4.11286004 26 P 0 2;1=4
P 12.03018002 4.2965747 26 P 0 2;1=4
P 12.21391998 4.11288524 26 P 0 2;1=4
P 12.25196998 4.20473002 26 P 0 2;1=4
P 12.21389469 4.2966 26 P 0 2;1=4
P 10.7067 4.22441024 26 P 0 2;1=4
P 10.7447752 4.13253996 26 P 0 2;1=4
P 10.74475 4.31625472 26 P 0 2;1=4
P 10.92848996 4.13256516 26 P 0 2;1=4
P 10.96653996 4.22441004 26 P 0 2;1=4
P 10.92846467 4.31628002 26 P 0 2;1=4
P 8.12007992 4.22441004 26 P 0 2;1=4
P 8.15815522 4.13253996 26 P 0 2;1=4
P 8.15813002 4.31625472 26 P 0 2;1=4
P 8.34186998 4.13256516 26 P 0 2;1=4
P 8.37991998 4.22441004 26 P 0 2;1=4
P 8.34184469 4.31628002 26 P 0 2;1=4
P 6.83465 4.20473002 26 P 0 2;1=4
P 6.8727252 4.11286004 26 P 0 2;1=4
P 6.8727 4.2965747 26 P 0 2;1=4
P 7.05643996 4.11288524 26 P 0 2;1=4
P 7.09448996 4.20473002 26 P 0 2;1=4
P 7.05641467 4.2966 26 P 0 2;1=4
P 6.83465 1.52756024 26 P 0 2;1=4
P 6.8727252 1.43568996 26 P 0 2;1=4
P 6.8727 1.61940472 26 P 0 2;1=4
P 7.05643996 1.43571516 26 P 0 2;1=4
P 7.09448996 1.52756004 26 P 0 2;1=4
P 7.05641467 1.61943002 26 P 0 2;1=4
P 8.15815522 1.416 26 P 0 2;1=4
P 8.12008002 1.50786998 26 P 0 2;1=4
P 8.15813002 1.5997247 26 P 0 2;1=4
P 8.34186998 1.4160252 26 P 0 2;1=4
P 8.34184469 1.59975 26 P 0 2;1=4
P 8.37992028 1.50786998 26 P 0 2;1=4
P 10.74475 1.5997247 26 P 0 2;1=4
P 10.92846467 1.59975 26 P 0 2;1=4
P 10.96654026 1.50786998 26 P 0 2;1=4
P 10.92848996 1.4160252 26 P 0 2;1=4
P 10.7447752 1.416 26 P 0 2;1=4
P 10.7067 1.50787028 26 P 0 2;1=4
P 12.2126 1.43700974 26 P 0 2;1=4
P 12.25196998 1.52756004 26 P 0 2;1=4
P 12.2126 1.61810974 26 P 0 2;1=4
P 12.0315 1.61810974 26 P 0 2;1=4
P 11.99213002 1.52755974 26 P 0 2;1=4
P 12.0315 1.43700974 26 P 0 2;1=4
P 4.83268002 1.37795 26 P 0 2;1=12
P 4.83267972 1.6378 26 P 0 2;1=12
P 2.24605974 1.6378 26 P 0 2;1=12
P 2.24606024 1.37795 26 P 0 2;1=12
P 0.96063002 1.39763976 26 P 0 2;1=12
P 0.96062972 1.65748002 26 P 0 2;1=12
P 0.96063002 4.0748 26 P 0 2;1=12
P 0.96062972 4.33465 26 P 0 2;1=12
P 2.24606004 4.09448996 26 P 0 2;1=12
P 2.24605974 4.35433002 26 P 0 2;1=12
P 4.83268002 4.09448976 26 P 0 2;1=12
P 4.83267972 4.35433002 26 P 0 2;1=12
P 6.11811024 4.0748 26 P 0 2;1=12
P 6.11810974 4.33465 26 P 0 2;1=12
P 6.11810974 1.65748002 26 P 0 2;1=12
P 6.11811004 1.39763996 26 P 0 2;1=12
P 5.98818976 4.20473002 26 P 0 2;1=4
P 6.02626516 4.11286004 26 P 0 2;1=4
P 6.02623996 4.2965747 26 P 0 2;1=4
P 6.20998002 4.11288524 26 P 0 2;1=4
P 6.24803002 4.20472972 26 P 0 2;1=4
P 6.20995472 4.2966 26 P 0 2;1=4
P 4.70275994 4.22441004 26 P 0 2;1=4
P 4.74083524 4.13253996 26 P 0 2;1=4
P 4.74081004 4.31625472 26 P 0 2;1=4
P 4.92455 4.13256516 26 P 0 2;1=4
P 4.9626 4.22440974 26 P 0 2;1=4
P 4.9245247 4.31628002 26 P 0 2;1=4
P 2.11613996 4.22441004 26 P 0 2;1=4
P 2.15421516 4.13253996 26 P 0 2;1=4
P 2.15418996 4.31625472 26 P 0 2;1=4
P 2.33793002 4.13256516 26 P 0 2;1=4
P 2.37598002 4.22440974 26 P 0 2;1=4
P 2.33790472 4.31628002 26 P 0 2;1=4
P 0.83070974 4.20473002 26 P 0 2;1=4
P 0.86878524 4.11286004 26 P 0 2;1=4
P 0.86876004 4.2965747 26 P 0 2;1=4
P 1.0525 4.11288524 26 P 0 2;1=4
P 1.09055 4.20472972 26 P 0 2;1=4
P 1.0524747 4.2966 26 P 0 2;1=4
P 0.83070994 1.52756004 26 P 0 2;1=4
P 0.86878524 1.43568996 26 P 0 2;1=4
P 0.86876004 1.61940472 26 P 0 2;1=4
P 1.0525 1.43571516 26 P 0 2;1=4
P 1.09055 1.52755974 26 P 0 2;1=4
P 1.0524747 1.61943002 26 P 0 2;1=4
P 2.15421516 1.416 26 P 0 2;1=4
P 2.11614006 1.50786998 26 P 0 2;1=4
P 2.15418996 1.5997247 26 P 0 2;1=4
P 2.33793002 1.4160252 26 P 0 2;1=4
P 2.33790472 1.59975 26 P 0 2;1=4
P 2.37598002 1.50786998 26 P 0 2;1=4
P 4.74081004 1.5997247 26 P 0 2;1=4
P 4.9245247 1.59975 26 P 0 2;1=4
P 4.9626 1.50786998 26 P 0 2;1=4
P 4.92455 1.4160252 26 P 0 2;1=4
P 4.74083524 1.416 26 P 0 2;1=4
P 4.70276004 1.50786998 26 P 0 2;1=4
P 6.20865994 1.43701004 26 P 0 2;1=4
P 6.24803002 1.52755974 26 P 0 2;1=4
P 6.20865994 1.61811004 26 P 0 2;1=4
P 6.02755994 1.61811004 26 P 0 2;1=4
P 5.98818996 1.52756004 26 P 0 2;1=4
P 6.02755994 1.43701004 26 P 0 2;1=4
P 12.59646998 0.8189 26 P 0 0;1=4
P 12.5571 0.72835 26 P 0 0;1=4
P 12.59646998 0.6378 26 P 0 0;1=4
P 12.68701998 0.59843002 26 P 0 0;1=12
P 12.77756998 0.6378 26 P 0 0;1=4
P 12.81693976 0.72835 26 P 0 0;1=4
P 12.77756998 0.8189 26 P 0 0;1=4
P 12.68701998 0.85827028 26 P 0 0;1=12
P 12.59646998 5.24803002 26 P 0 0;1=4
P 12.5571 5.15748002 26 P 0 0;1=4
P 12.59646998 5.06693002 26 P 0 0;1=4
P 12.68701998 5.02756004 26 P 0 0;1=12
P 12.77756998 5.06693002 26 P 0 0;1=4
P 12.81693976 5.15748002 26 P 0 0;1=4
P 12.77756998 5.24803002 26 P 0 0;1=4
P 12.68701998 5.2874 26 P 0 0;1=12
P 0.1319 5.20866024 26 P 0 0;1=4
P 0.09252992 5.11811004 26 P 0 0;1=4
P 0.1319 5.02756024 26 P 0 0;1=4
P 0.22245 4.98818976 26 P 0 0;1=12
P 0.313 5.02756024 26 P 0 0;1=4
P 0.35236998 5.11811024 26 P 0 0;1=4
P 0.313 5.20866024 26 P 0 0;1=4
P 0.22245 5.24803002 26 P 0 0;1=12
P 0.1319 0.77953002 26 P 0 0;1=4
P 0.09252972 0.68898002 26 P 0 0;1=4
P 0.1319 0.59843002 26 P 0 0;1=4
P 0.22245 0.55905974 26 P 0 0;1=12
P 0.313 0.59843002 26 P 0 0;1=4
P 0.35236998 0.68898002 26 P 0 0;1=4
P 0.313 0.77953002 26 P 0 0;1=4
P 0.22245 0.8189 26 P 0 0;1=12
P 10.80498996 5.56656004 26 P 0 0;1=4
P 10.84498996 5.56656004 26 P 0 0;1=4
P 10.80498996 5.42656004 26 P 0 0;1=4
P 10.84498996 5.42656004 26 P 0 0;1=4
P 11.01035 5.42656024 26 P 0 0;1=4
P 10.97035 5.42656024 26 P 0 0;1=4
P 11.01035 5.56656024 26 P 0 0;1=4
P 10.97035 5.56656024 26 P 0 0;1=4
P 11.17570994 5.42656004 26 P 0 0;1=4
P 11.13570994 5.42656004 26 P 0 0;1=4
P 11.17570994 5.56656004 26 P 0 0;1=4
P 11.13570994 5.56656004 26 P 0 0;1=4
P 11.34106998 5.42656024 26 P 0 0;1=4
P 11.30106998 5.42656024 26 P 0 0;1=4
P 11.34106998 5.56656024 26 P 0 0;1=4
P 11.30106998 5.56656024 26 P 0 0;1=4
P 11.50642992 5.42656004 26 P 0 0;1=4
P 11.46642992 5.42656004 26 P 0 0;1=4
P 11.50642992 5.56656004 26 P 0 0;1=4
P 11.46642992 5.56656004 26 P 0 0;1=4
P 11.67178996 5.42656004 26 P 0 0;1=4
P 11.63178996 5.42656004 26 P 0 0;1=4
P 11.67178996 5.56656004 26 P 0 0;1=4
P 11.63178996 5.56656004 26 P 0 0;1=4
P 11.83715 5.42656024 26 P 0 0;1=4
P 11.79715 5.42656024 26 P 0 0;1=4
P 11.83715 5.56656024 26 P 0 0;1=4
P 11.79715 5.56656024 26 P 0 0;1=4
P 12.00250994 5.42656004 26 P 0 0;1=4
P 11.96250994 5.42656004 26 P 0 0;1=4
P 12.00250994 5.56656004 26 P 0 0;1=4
P 11.96250994 5.56656004 26 P 0 0;1=4
P 12.16786998 5.42656024 26 P 0 0;1=4
P 12.12786998 5.42656024 26 P 0 0;1=4
P 12.16786998 5.56656024 26 P 0 0;1=4
P 12.12786998 5.56656024 26 P 0 0;1=4
P 7.32284006 0.23621998 26 P 0 0;1=4
P 7.28019518 0.33921998 26 P 0 0;1=4
P 7.17716998 0.38189026 26 P 0 0;1=13
P 7.28016998 0.13319469 26 P 0 0;1=4
P 7.17717028 0.09055 26 P 0 0;1=13
P 7.07414469 0.13321998 26 P 0 0;1=4
P 7.0315 0.23621998 26 P 0 0;1=4
P 7.07416998 0.33924518 26 P 0 0;1=4
P 7.32283976 5.7874 26 P 0 0;1=4
P 7.28019518 5.8904 26 P 0 0;1=4
P 7.17716998 5.93307028 26 P 0 0;1=13
P 7.28016998 5.6843747 26 P 0 0;1=4
P 7.17716998 5.64173002 26 P 0 0;1=13
P 7.07414469 5.6844 26 P 0 0;1=4
P 7.0315 5.7874 26 P 0 0;1=4
P 7.07416998 5.8904252 26 P 0 0;1=4
P 2.24606004 3.56615 7 P 0 0;1=3
P 8.2 3.26615 7 P 0 0;1=3
P 7.65203996 5.0535 7 P 0 0;1=3
P 2.29606004 2.86615 7 P 0 0;1=3
P 2.29606004 3.56615 7 P 0 0;1=3
P 7.69203996 5.0535 7 P 0 0;1=3
P 8.2 3.31615 7 P 0 0;1=3
P 1.33906004 4.69351004 6 P 0 0;1=0
P 0.80806998 5.46193996 6 P 0 0;1=0
P 3.733 5.075 6 P 0 0;1=4
P 1.28906004 4.69351004 6 P 0 0;1=0
P 8.2 3.41615 7 P 0 0;1=3
P 7.86465 5.169 7 P 0 0;1=3
P 3.94 4.765 6 P 0 0;1=0
P 2.34606004 3.26615 7 P 0 0;1=3
P 2.39716998 4.742 7 P 0 0;1=3
P 8.2 3.46615 7 P 0 0;1=3
P 7.90465 5.169 7 P 0 0;1=3
P 2.06646004 5.29 6 P 0 0;1=0
P 2.34606004 3.31615 7 P 0 0;1=3
P 2.35716998 4.742 7 P 0 0;1=3
P 1.33906004 5.15351004 6 P 0 0;1=0
P 3.105 4.47 6 P 0 0;1=4
P 8 3.46615 7 P 0 0;1=3
P 7.93551004 5.0535 7 P 0 0;1=3
P 2.00146004 5.29 6 P 0 0;1=0
P 2.25855 4.667 7 P 0 0;1=3
P 2.39606004 3.31615 7 P 0 0;1=3
P 1.18906004 5.15351004 6 P 0 0;1=0
P 3.07 4.42 6 P 0 0;1=4
P 8 3.51615 7 P 0 0;1=3
P 7.97551004 5.0535 7 P 0 0;1=3
P 2.21855 4.667 7 P 0 0;1=3
P 2.39606004 3.36615 7 P 0 0;1=3
P 8.11725 5.169 7 P 0 0;1=3
P 8.4 3.46615 7 P 0 0;1=3
P 3.635 0.715 6 P 0 0;1=0
P 4.63268002 2.81615 7 P 0 0;1=3
P 2.44606004 3.26615 7 P 0 0;1=3
P 2.39716998 5.115 7 P 0 0;1=3
P 8.07725 5.169 7 P 0 0;1=3
P 8.4 3.51615 7 P 0 0;1=3
P 2.44606004 3.31615 7 P 0 0;1=3
P 2.35716998 5.115 7 P 0 0;1=3
P 8.5 3.46615 7 P 0 0;1=3
P 8.07206998 4.66688996 7 P 0 0;1=3
P 2.25543996 4.78291998 7 P 0 0;1=3
P 2.49606004 3.31615 7 P 0 0;1=3
P 8.5 3.51615 7 P 0 0;1=3
P 8.03206998 4.66688996 7 P 0 0;1=3
P 4.02 4.42 6 P 0 0;1=0
P 4.58268002 2.76615 7 P 0 0;1=3
P 2.21543996 4.78291998 7 P 0 0;1=3
P 2.49606004 3.36615 7 P 0 0;1=3
P 8.35 3.41615 7 P 0 0;1=3
P 8.11725 4.78291998 7 P 0 0;1=3
P 4.78268002 2.71615 7 P 0 0;1=3
P 2.11371004 4.78291998 7 P 0 0;1=3
P 2.34606004 3.41615 7 P 0 0;1=3
P 8.35 3.46615 7 P 0 0;1=3
P 8.07725 4.78291998 7 P 0 0;1=3
P 5.08268002 2.71615 7 P 0 0;1=3
P 4.06 4.86 6 P 0 0;1=0
P 2.07371004 4.78291998 7 P 0 0;1=3
P 2.34606004 3.46615 7 P 0 0;1=3
P 2.18456998 5.0535 7 P 0 0;1=3
P 2.44606004 3.41615 7 P 0 0;1=3
P 10.93661004 2.41615 7 P 0 0;1=3
P 2.14456998 5.0535 7 P 0 0;1=3
P 2.44606004 3.46615 7 P 0 0;1=3
P 10.93661004 2.46615 7 P 0 0;1=3
P 8.5 3.31615 7 P 0 0;1=3
P 8.25898002 4.78291998 7 P 0 0;1=3
P 4.88268002 2.71615 7 P 0 0;1=3
P 2.06853002 4.66688996 7 P 0 0;1=3
P 2.49606004 3.46615 7 P 0 0;1=3
P 8.5 3.36615 7 P 0 0;1=3
P 8.21898002 4.78291998 7 P 0 0;1=3
P 2.02853002 4.66688996 7 P 0 0;1=3
P 2.49606004 3.51615 7 P 0 0;1=3
P 8.4 3.31615 7 P 0 0;1=3
P 8.26208996 4.667 7 P 0 0;1=3
P 2.11371004 5.169 7 P 0 0;1=3
P 2.39606004 3.46615 7 P 0 0;1=3
P 8.4 3.36615 7 P 0 0;1=3
P 8.22208996 4.667 7 P 0 0;1=3
P 3.84 0.69 6 P 0 0;1=0
P 4.68268002 2.76615 7 P 0 0;1=3
P 2.07371004 5.169 7 P 0 0;1=3
P 2.39606004 3.51615 7 P 0 0;1=3
P 3.56 0.49 6 P 0 0;1=0
P 4.73268002 2.81615 7 P 0 0;1=3
P 1.57765 5.169 7 P 0 0;1=3
P 2.04606004 3.31615 7 P 0 0;1=3
P 9.10853996 4.47 6 P 0 0;1=4
P 7.3426 5.15351004 6 P 0 0;1=0
P 3.785 0.69 6 P 0 0;1=0
P 4.78268002 2.81615 7 P 0 0;1=3
P 1.61765 5.169 7 P 0 0;1=3
P 2.04606004 3.36615 7 P 0 0;1=3
P 8.1 3.26615 7 P 0 0;1=3
P 7.58118996 4.707 7 P 0 0;1=3
P 2.09606004 3.26615 7 P 0 0;1=3
P 1.57765 4.707 7 P 0 0;1=3
P 5.08268002 1.96615 7 P 0 0;1=3
P 8.1 3.31615 7 P 0 0;1=3
P 7.62118996 4.707 7 P 0 0;1=3
P 3.75998996 0.345 6 P 0 0;1=0
P 4.68268002 2.81615 7 P 0 0;1=3
P 2.09606004 3.31615 7 P 0 0;1=3
P 1.61765 4.707 7 P 0 0;1=3
P 0.58 5.591 6 P 0 0;1=0
P 11.67761998 2.85 6 P 0 0;1=4
P 11.865 4.455 6 P 0 0;1=0
P 5.67368996 2.85 6 P 0 0;1=4
P 5.855 3.07 6 P 0 0;1=4
P 5.8522 2.97 6 P 0 0;1=4
P 7.2926 5.15351004 6 P 0 0;1=4
P 7.2426 5.15351004 6 P 0 0;1=4
P 7.1926 4.95351004 6 P 0 0;1=4
P 7.42603996 5.15895 6 P 0 0;1=0
P 3.94 4.655 6 P 0 0;1=4
P 3.77 4.765 6 P 0 0;1=4
P 4.14 4.745 6 P 0 0;1=4
P 4.76 5.375 6 P 0 0;1=4
P 4.96 5.5 6 P 0 0;1=4
P 5.16 5.555 6 P 0 0;1=4
P 4.892 5.767 6 P 0 0;1=4
P 5.088 5.767 6 P 0 0;1=4
P 0.91 5.075 6 P 0 0;1=4
P 1.03 4.96 6 P 0 0;1=4
P 1.03 5.155 6 P 0 0;1=4
P 1.38906004 5.15351004 6 P 0 0;1=0
P 1.23906004 5.15351004 6 P 0 0;1=4
P 1.28906004 5.15351004 6 P 0 0;1=4
P 1.18906004 4.95351004 6 P 0 0;1=4
P 0.83 5.355 6 P 0 0;1=4
P 0.9 5.355 6 P 0 0;1=4
P 0.755 5.355 6 P 0 0;1=4
P 0.73 5.205 6 P 0 0;1=4
P 0.81016004 5.17 6 P 0 0;1=4
P 1.094 5.356 6 P 0 0;1=0
P 1.044 5.448 6 P 0 0;1=4
P 1.4 5.46 6 P 0 0;1=4
P 1.32 5.46 6 P 0 0;1=4
P 1.43798996 5.46016004 6 P 0 0;1=4
P 1.35925 5.46016004 6 P 0 0;1=4
P 0.89 5.885 6 P 0 0;1=4
P 0.81 5.885 6 P 0 0;1=4
P 0.73 5.885 6 P 0 0;1=4
P 0.97 5.885 6 P 0 0;1=4
P 1.04 5.885 6 P 0 0;1=4
P 1.12 5.885 6 P 0 0;1=4
P 8.15 3.31615 7 P 0 0;1=3
P 7.65205 4.78291998 7 P 0 0;1=3
P 11.235 3.3 6 P 0 0;1=4
P 5.815 0.925 6 P 0 0;1=0
P 3.635 0.49 6 P 0 0;1=0
P 4.58268002 2.81615 7 P 0 0;1=3
P 2.19606004 3.26615 7 P 0 0;1=3
P 1.6485 5.0535 7 P 0 0;1=3
P 8.15 3.36615 7 P 0 0;1=3
P 7.69205 4.78291998 7 P 0 0;1=3
P 2.19606004 3.31615 7 P 0 0;1=3
P 1.6885 5.0535 7 P 0 0;1=3
P 8.1 3.41615 7 P 0 0;1=3
P 7.79378996 4.78291998 7 P 0 0;1=3
P 2.14606004 3.31615 7 P 0 0;1=3
P 1.64851004 4.78291998 7 P 0 0;1=3
P 8.1 3.46615 7 P 0 0;1=3
P 7.83378996 4.78291998 7 P 0 0;1=3
P 2.14606004 3.36615 7 P 0 0;1=3
P 1.68851004 4.78291998 7 P 0 0;1=3
P 0.73 4.96 6 P 0 0;1=0
P 3.795 4.6 6 P 0 0;1=4
P 4.86 5.375 6 P 0 0;1=4
P 8.15 3.46615 7 P 0 0;1=3
P 7.86465 4.657 7 P 0 0;1=3
P 2.09606004 3.41615 7 P 0 0;1=3
P 1.79025 4.78291998 7 P 0 0;1=3
P 8.15 3.51615 7 P 0 0;1=3
P 7.90465 4.657 7 P 0 0;1=3
P 2.09606004 3.46615 7 P 0 0;1=3
P 1.83025 4.78291998 7 P 0 0;1=3
P 2.19606004 3.41615 7 P 0 0;1=3
P 1.86111004 5.169 7 P 0 0;1=3
P 2.19606004 3.46615 7 P 0 0;1=3
P 1.90111004 5.169 7 P 0 0;1=3
P 6.72708996 4.5652 6 P 0 0;1=4
P 6.76208996 4.5652 6 P 0 0;1=4
P 6.79708996 4.5652 6 P 0 0;1=4
P 6.83708996 4.5652 6 P 0 0;1=0
P 6.90208996 4.5652 6 P 0 0;1=4
P 6.87208996 4.5652 6 P 0 0;1=4
P 10.99998996 4.9531 6 P 0 0;1=4
P 11.03998996 4.9531 6 P 0 0;1=4
P 10.99998996 4.9131 6 P 0 0;1=4
P 11.03998996 4.9131 6 P 0 0;1=4
P 11.21998996 4.9531 6 P 0 0;1=4
P 11.17998996 4.9531 6 P 0 0;1=4
P 11.13498996 4.9531 6 P 0 0;1=4
P 11.08498996 4.9531 6 P 0 0;1=4
P 11.21998996 4.9131 6 P 0 0;1=4
P 11.17998996 4.9131 6 P 0 0;1=4
P 11.08498996 4.9131 6 P 0 0;1=4
P 11.13498996 4.9131 6 P 0 0;1=4
P 10.99998996 5.1631 6 P 0 0;1=4
P 11.03998996 5.1631 6 P 0 0;1=4
P 10.99998996 5.1231 6 P 0 0;1=4
P 10.99998996 5.0381 6 P 0 0;1=4
P 10.99998996 5.0831 6 P 0 0;1=4
P 10.99998996 4.9931 6 P 0 0;1=4
P 11.03998996 4.9931 6 P 0 0;1=4
P 11.03998996 5.0831 6 P 0 0;1=4
P 11.03998996 5.0381 6 P 0 0;1=4
P 11.03998996 5.1231 6 P 0 0;1=4
P 11.21998996 5.1631 6 P 0 0;1=4
P 11.17998996 5.1631 6 P 0 0;1=4
P 11.08498996 5.1631 6 P 0 0;1=4
P 11.13498996 5.1631 6 P 0 0;1=4
P 11.21998996 5.1231 6 P 0 0;1=4
P 11.21998996 5.0381 6 P 0 0;1=4
P 11.21998996 5.0831 6 P 0 0;1=4
P 11.21998996 4.9931 6 P 0 0;1=4
P 11.17998996 4.9931 6 P 0 0;1=4
P 11.17998996 5.1231 6 P 0 0;1=4
P 11.17998996 5.0831 6 P 0 0;1=4
P 11.17998996 5.0381 6 P 0 0;1=4
P 11.13498996 5.1231 6 P 0 0;1=4
P 11.08498996 5.1231 6 P 0 0;1=4
P 11.6269 4.90498996 6 P 0 0;1=4
P 11.6269 4.85498996 6 P 0 0;1=4
P 11.4269 4.80998996 6 P 0 0;1=4
P 11.4269 4.85498996 6 P 0 0;1=4
P 11.4269 4.90498996 6 P 0 0;1=4
P 11.4269 4.94998996 6 P 0 0;1=4
P 11.4769 4.94998996 6 P 0 0;1=4
P 11.4769 4.80998996 6 P 0 0;1=4
P 11.5269 4.94998996 6 P 0 0;1=4
P 11.5269 4.80998996 6 P 0 0;1=4
P 11.5769 4.94998996 6 P 0 0;1=4
P 11.6269 4.94998996 6 P 0 0;1=4
P 11.6269 4.80998996 6 P 0 0;1=4
P 11.5769 4.80998996 6 P 0 0;1=4
P 10.82676998 5.71338996 14 P 0 0;1=10
P 10.99213002 5.71338996 14 P 0 0;1=10
P 11.15748002 5.71338996 14 P 0 0;1=10
P 11.32283996 5.71338996 14 P 0 0;1=10
P 11.48818996 5.71338996 14 P 0 0;1=10
P 11.65353996 5.71338996 14 P 0 0;1=10
P 11.8189 5.71338996 14 P 0 0;1=10
P 11.98425 5.71338996 14 P 0 0;1=10
P 12.14961004 5.71338996 14 P 0 0;1=10
P 10.80498996 5.7831 6 P 0 0;1=4
P 10.84498996 5.7831 6 P 0 0;1=4
P 10.80498996 5.6431 6 P 0 0;1=4
P 10.84498996 5.6431 6 P 0 0;1=4
P 11.01035 5.6431 6 P 0 0;1=4
P 10.97035 5.6431 6 P 0 0;1=4
P 11.01035 5.7831 6 P 0 0;1=4
P 10.97035 5.7831 6 P 0 0;1=4
P 11.17571004 5.6431 6 P 0 0;1=4
P 11.13571004 5.6431 6 P 0 0;1=4
P 11.17571004 5.7831 6 P 0 0;1=4
P 11.13571004 5.7831 6 P 0 0;1=4
P 11.34106998 5.6431 6 P 0 0;1=4
P 11.30106998 5.6431 6 P 0 0;1=4
P 11.34106998 5.7831 6 P 0 0;1=4
P 11.30106998 5.7831 6 P 0 0;1=4
P 11.50643002 5.6431 6 P 0 0;1=4
P 11.46643002 5.6431 6 P 0 0;1=4
P 11.50643002 5.7831 6 P 0 0;1=4
P 11.46643002 5.7831 6 P 0 0;1=4
P 11.67178996 5.6431 6 P 0 0;1=4
P 11.63178996 5.6431 6 P 0 0;1=4
P 11.67178996 5.7831 6 P 0 0;1=4
P 11.63178996 5.7831 6 P 0 0;1=4
P 11.83715 5.6431 6 P 0 0;1=4
P 11.79715 5.6431 6 P 0 0;1=4
P 11.83715 5.7831 6 P 0 0;1=4
P 11.79715 5.7831 6 P 0 0;1=4
P 12.00251004 5.6431 6 P 0 0;1=4
P 11.96251004 5.6431 6 P 0 0;1=4
P 12.00251004 5.7831 6 P 0 0;1=4
P 11.96251004 5.7831 6 P 0 0;1=4
P 12.16786998 5.6431 6 P 0 0;1=4
P 12.12786998 5.6431 6 P 0 0;1=4
P 12.16786998 5.7831 6 P 0 0;1=4
P 12.12786998 5.7831 6 P 0 0;1=4
P 5.03605 5.1631 6 P 0 0;1=4
P 5.03605 4.9931 6 P 0 0;1=4
P 5.03605 5.0831 6 P 0 0;1=4
P 5.03605 5.0381 6 P 0 0;1=4
P 5.03605 5.1231 6 P 0 0;1=4
P 5.21605 5.1631 6 P 0 0;1=4
P 5.17605 5.1631 6 P 0 0;1=4
P 5.08105 5.1631 6 P 0 0;1=4
P 5.13105 5.1631 6 P 0 0;1=4
P 5.21605 5.1231 6 P 0 0;1=4
P 5.21605 5.0381 6 P 0 0;1=4
P 5.21605 5.0831 6 P 0 0;1=4
P 5.21605 4.9931 6 P 0 0;1=4
P 5.17605 4.9931 6 P 0 0;1=4
P 5.17605 5.1231 6 P 0 0;1=4
P 5.17605 5.0831 6 P 0 0;1=4
P 5.17605 5.0381 6 P 0 0;1=4
P 5.13105 5.1231 6 P 0 0;1=4
P 5.08105 5.1231 6 P 0 0;1=4
P 4.99605 5.1631 6 P 0 0;1=4
P 4.99605 5.1231 6 P 0 0;1=4
P 4.99605 5.0381 6 P 0 0;1=4
P 4.99605 5.0831 6 P 0 0;1=4
P 4.99605 4.9931 6 P 0 0;1=4
P 5.03605 4.9531 6 P 0 0;1=4
P 5.03605 4.9131 6 P 0 0;1=4
P 5.21605 4.9531 6 P 0 0;1=4
P 5.17605 4.9531 6 P 0 0;1=4
P 5.13105 4.9531 6 P 0 0;1=4
P 5.08105 4.9531 6 P 0 0;1=4
P 5.21605 4.9131 6 P 0 0;1=4
P 5.17605 4.9131 6 P 0 0;1=4
P 5.08105 4.9131 6 P 0 0;1=4
P 5.13105 4.9131 6 P 0 0;1=4
P 4.99605 4.9531 6 P 0 0;1=4
P 4.99605 4.9131 6 P 0 0;1=4
P 6.34948996 5.03 6 P 0 0;1=4
P 2.74225 5.14 7 P 0 0;1=3
P 2.04606004 3.61615 7 P 0 0;1=3
P 2.14606004 3.46615 7 P 0 0;1=3
P 1.86111004 4.657 7 P 0 0;1=3
P 2.78225 5.14 7 P 0 0;1=3
P 2.04606004 3.66615 7 P 0 0;1=3
P 2.14606004 3.51615 7 P 0 0;1=3
P 1.90111004 4.657 7 P 0 0;1=3
P 1.93196998 5.0535 7 P 0 0;1=3
P 1.99606004 3.46615 7 P 0 0;1=3
P 4.58268002 2.56615 7 P 0 0;1=3
P 1.97196998 5.0535 7 P 0 0;1=3
P 1.99606004 3.51615 7 P 0 0;1=3
P 2.88086998 5.17001998 7 P 0 0;1=3
P 2.14606004 3.61615 7 P 0 0;1=3
P 2.34606004 3.66615 7 P 0 0;1=3
P 3.56176998 4.71973002 7 P 0 0;1=3
P 2.92086998 5.17001998 7 P 0 0;1=3
P 2.14606004 3.66615 7 P 0 0;1=3
P 2.34606004 3.71615 7 P 0 0;1=3
P 3.52176998 4.71973002 7 P 0 0;1=3
P 2.39606004 3.61615 7 P 0 0;1=3
P 3.49091004 4.587 7 P 0 0;1=3
P 2.39606004 3.66615 7 P 0 0;1=3
P 3.45091004 4.587 7 P 0 0;1=3
P 2.49606004 3.61615 7 P 0 0;1=3
P 3.56176998 5.14 7 P 0 0;1=3
P 2.49606004 3.66615 7 P 0 0;1=3
P 3.52176998 5.14 7 P 0 0;1=3
P 2.44606004 3.66615 7 P 0 0;1=3
P 3.42003996 4.78291998 7 P 0 0;1=3
P 4.30605 4.6631 6 P 0 0;1=4
P 4.34105 4.6431 6 P 0 0;1=4
P 4.38605 4.6431 6 P 0 0;1=4
P 4.42605 4.6631 6 P 0 0;1=4
P 4.46605 4.6631 6 P 0 0;1=4
P 4.30605 4.7031 6 P 0 0;1=4
P 4.42605 4.7031 6 P 0 0;1=4
P 4.46605 4.7031 6 P 0 0;1=4
P 4.26605 4.6631 6 P 0 0;1=4
P 4.26605 4.7031 6 P 0 0;1=4
P 4.65605 4.6631 6 P 0 0;1=4
P 4.69605 4.6631 6 P 0 0;1=4
P 4.65605 4.7031 6 P 0 0;1=4
P 4.69605 4.7031 6 P 0 0;1=4
P 4.73105 4.6431 6 P 0 0;1=4
P 4.81605 4.6631 6 P 0 0;1=4
P 4.85605 4.6631 6 P 0 0;1=4
P 4.81605 4.7031 6 P 0 0;1=4
P 4.85605 4.7031 6 P 0 0;1=4
P 4.77605 4.6431 6 P 0 0;1=4
P 5.17605 4.7131 6 P 0 0;1=4
P 5.17605 4.6731 6 P 0 0;1=4
P 5.08105 4.6731 6 P 0 0;1=4
P 5.13105 4.6731 6 P 0 0;1=4
P 5.03605 4.6731 6 P 0 0;1=4
P 5.03605 4.7131 6 P 0 0;1=4
P 4.30605 4.7481 6 P 0 0;1=4
P 4.30605 4.7931 6 P 0 0;1=4
P 4.30605 4.8381 6 P 0 0;1=4
P 4.38605 4.8381 6 P 0 0;1=4
P 4.34605 4.8381 6 P 0 0;1=4
P 4.46605 4.8381 6 P 0 0;1=4
P 4.42605 4.8381 6 P 0 0;1=4
P 4.42605 4.7931 6 P 0 0;1=4
P 4.42605 4.7481 6 P 0 0;1=4
P 4.46605 4.7931 6 P 0 0;1=4
P 4.46605 4.7481 6 P 0 0;1=4
P 4.26605 4.7481 6 P 0 0;1=4
P 4.26605 4.7931 6 P 0 0;1=4
P 4.26605 4.8381 6 P 0 0;1=4
P 4.65605 4.8381 6 P 0 0;1=4
P 4.65605 4.7931 6 P 0 0;1=4
P 4.65605 4.7481 6 P 0 0;1=4
P 4.69605 4.8381 6 P 0 0;1=4
P 4.69605 4.7931 6 P 0 0;1=4
P 4.69605 4.7481 6 P 0 0;1=4
P 4.73605 4.8381 6 P 0 0;1=4
P 4.81605 4.8381 6 P 0 0;1=4
P 4.81605 4.7931 6 P 0 0;1=4
P 4.81605 4.7481 6 P 0 0;1=4
P 4.85605 4.8381 6 P 0 0;1=4
P 4.85605 4.7931 6 P 0 0;1=4
P 4.85605 4.7481 6 P 0 0;1=4
P 4.77605 4.8381 6 P 0 0;1=4
P 5.08105 4.8431 6 P 0 0;1=4
P 5.13105 4.8431 6 P 0 0;1=4
P 5.17605 4.8431 6 P 0 0;1=4
P 5.17605 4.8031 6 P 0 0;1=4
P 5.17605 4.7581 6 P 0 0;1=4
P 5.03605 4.8431 6 P 0 0;1=4
P 5.03605 4.8031 6 P 0 0;1=4
P 5.03605 4.7581 6 P 0 0;1=4
P 4.58268002 2.96615 7 P 0 0;1=3
P 4.63268002 2.96615 7 P 0 0;1=3
P 4.63268002 3.11615 7 P 0 0;1=3
P 4.58268002 3.01615 7 P 0 0;1=3
P 4.58268002 3.11615 7 P 0 0;1=3
P 4.63268002 3.01615 7 P 0 0;1=3
P 4.63268002 3.31615 7 P 0 0;1=3
P 4.58268002 3.26615 7 P 0 0;1=3
P 4.58268002 3.31615 7 P 0 0;1=3
P 4.63268002 3.26615 7 P 0 0;1=3
P 4.63268002 3.16615 7 P 0 0;1=3
P 4.58268002 3.16615 7 P 0 0;1=3
P 4.58268002 3.46615 7 P 0 0;1=3
P 4.63268002 3.41615 7 P 0 0;1=3
P 4.63268002 3.46615 7 P 0 0;1=3
P 4.58268002 3.41615 7 P 0 0;1=3
P 4.58268002 3.61615 7 P 0 0;1=3
P 4.58268002 3.56615 7 P 0 0;1=3
P 4.63268002 3.61615 7 P 0 0;1=3
P 4.63268002 3.56615 7 P 0 0;1=3
P 4.58268002 3.71615 7 P 0 0;1=3
P 4.63268002 3.71615 7 P 0 0;1=3
P 4.58268002 3.76615 7 P 0 0;1=3
P 4.58268002 3.86615 7 P 0 0;1=3
P 4.63268002 3.76615 7 P 0 0;1=3
P 4.63268002 3.86615 7 P 0 0;1=3
P 4.68268002 2.96615 7 P 0 0;1=3
P 4.73268002 2.96615 7 P 0 0;1=3
P 4.78268002 2.96615 7 P 0 0;1=3
P 4.68268002 3.11615 7 P 0 0;1=3
P 4.68268002 3.01615 7 P 0 0;1=3
P 4.73268002 3.11615 7 P 0 0;1=3
P 4.73268002 3.01615 7 P 0 0;1=3
P 4.78268002 3.11615 7 P 0 0;1=3
P 4.78268002 3.01615 7 P 0 0;1=3
P 4.73268002 3.31615 7 P 0 0;1=3
P 4.73268002 3.26615 7 P 0 0;1=3
P 4.68268002 3.26615 7 P 0 0;1=3
P 4.68268002 3.31615 7 P 0 0;1=3
P 4.78268002 3.26615 7 P 0 0;1=3
P 4.78268002 3.31615 7 P 0 0;1=3
P 4.73268002 3.16615 7 P 0 0;1=3
P 4.68268002 3.16615 7 P 0 0;1=3
P 4.78268002 3.16615 7 P 0 0;1=3
P 4.73268002 3.41615 7 P 0 0;1=3
P 4.68268002 3.41615 7 P 0 0;1=3
P 4.68268002 3.46615 7 P 0 0;1=3
P 4.73268002 3.46615 7 P 0 0;1=3
P 4.78268002 3.46615 7 P 0 0;1=3
P 4.78268002 3.41615 7 P 0 0;1=3
P 4.73268002 3.56615 7 P 0 0;1=3
P 4.73268002 3.61615 7 P 0 0;1=3
P 4.68268002 3.56615 7 P 0 0;1=3
P 4.68268002 3.61615 7 P 0 0;1=3
P 4.78268002 3.61615 7 P 0 0;1=3
P 4.78268002 3.56615 7 P 0 0;1=3
P 4.73268002 3.71615 7 P 0 0;1=3
P 4.68268002 3.71615 7 P 0 0;1=3
P 4.78268002 3.71615 7 P 0 0;1=3
P 4.73268002 3.76615 7 P 0 0;1=3
P 4.73268002 3.86615 7 P 0 0;1=3
P 4.68268002 3.76615 7 P 0 0;1=3
P 4.68268002 3.86615 7 P 0 0;1=3
P 4.78268002 3.76615 7 P 0 0;1=3
P 4.78268002 3.86615 7 P 0 0;1=3
P 4.88268002 3.86615 7 P 0 0;1=3
P 4.83268002 3.86615 7 P 0 0;1=3
P 5.03268002 3.86615 7 P 0 0;1=3
P 4.93268002 3.86615 7 P 0 0;1=3
P 4.98268002 3.86615 7 P 0 0;1=3
P 4.88268002 3.76615 7 P 0 0;1=3
P 4.83268002 3.76615 7 P 0 0;1=3
P 5.03268002 3.76615 7 P 0 0;1=3
P 4.93268002 3.76615 7 P 0 0;1=3
P 4.98268002 3.76615 7 P 0 0;1=3
P 4.88268002 3.71615 7 P 0 0;1=3
P 4.83268002 3.71615 7 P 0 0;1=3
P 5.03268002 3.71615 7 P 0 0;1=3
P 4.93268002 3.71615 7 P 0 0;1=3
P 4.98268002 3.71615 7 P 0 0;1=3
P 4.88268002 3.61615 7 P 0 0;1=3
P 4.83268002 3.61615 7 P 0 0;1=3
P 5.03268002 3.61615 7 P 0 0;1=3
P 4.93268002 3.61615 7 P 0 0;1=3
P 4.98268002 3.61615 7 P 0 0;1=3
P 4.88268002 3.56615 7 P 0 0;1=3
P 4.83268002 3.56615 7 P 0 0;1=3
P 5.03268002 3.56615 7 P 0 0;1=3
P 4.93268002 3.56615 7 P 0 0;1=3
P 4.98268002 3.56615 7 P 0 0;1=3
P 4.88268002 3.46615 7 P 0 0;1=3
P 4.83268002 3.46615 7 P 0 0;1=3
P 5.03268002 3.46615 7 P 0 0;1=3
P 4.93268002 3.46615 7 P 0 0;1=3
P 4.98268002 3.46615 7 P 0 0;1=3
P 4.88268002 3.41615 7 P 0 0;1=3
P 4.83268002 3.41615 7 P 0 0;1=3
P 5.03268002 3.41615 7 P 0 0;1=3
P 4.93268002 3.41615 7 P 0 0;1=3
P 4.98268002 3.41615 7 P 0 0;1=3
P 4.88268002 3.31615 7 P 0 0;1=3
P 4.83268002 3.31615 7 P 0 0;1=3
P 5.03268002 3.31615 7 P 0 0;1=3
P 4.93268002 3.31615 7 P 0 0;1=3
P 4.98268002 3.31615 7 P 0 0;1=3
P 4.83268002 3.26615 7 P 0 0;1=3
P 4.88268002 3.26615 7 P 0 0;1=3
P 4.98268002 3.26615 7 P 0 0;1=3
P 4.93268002 3.26615 7 P 0 0;1=3
P 5.03268002 3.26615 7 P 0 0;1=3
P 4.83268002 3.16615 7 P 0 0;1=3
P 4.88268002 3.16615 7 P 0 0;1=3
P 4.98268002 3.16615 7 P 0 0;1=3
P 4.93268002 3.16615 7 P 0 0;1=3
P 5.03268002 3.16615 7 P 0 0;1=3
P 4.83268002 3.11615 7 P 0 0;1=3
P 4.88268002 3.11615 7 P 0 0;1=3
P 4.98268002 3.11615 7 P 0 0;1=3
P 4.93268002 3.11615 7 P 0 0;1=3
P 5.03268002 3.11615 7 P 0 0;1=3
P 4.83268002 3.01615 7 P 0 0;1=3
P 4.88268002 3.01615 7 P 0 0;1=3
P 4.98268002 3.01615 7 P 0 0;1=3
P 4.93268002 3.01615 7 P 0 0;1=3
P 5.03268002 3.01615 7 P 0 0;1=3
P 4.83268002 2.96615 7 P 0 0;1=3
P 4.88268002 2.96615 7 P 0 0;1=3
P 4.98268002 2.96615 7 P 0 0;1=3
P 4.93268002 2.96615 7 P 0 0;1=3
P 5.03268002 2.96615 7 P 0 0;1=3
P 2.44606004 3.71615 7 P 0 0;1=3
P 3.38003996 4.78291998 7 P 0 0;1=3
P 2.19606004 3.81615 7 P 0 0;1=3
P 3.02571004 4.667 7 P 0 0;1=3
P 2.19606004 3.86615 7 P 0 0;1=3
P 3.06571004 4.667 7 P 0 0;1=3
P 3.27831004 4.642 7 P 0 0;1=3
P 2.39606004 3.76615 7 P 0 0;1=3
P 4.73268002 2.66615 7 P 0 0;1=3
P 10.73661004 2.66615 7 P 0 0;1=3
P 3.23831004 4.642 7 P 0 0;1=3
P 2.39606004 3.81615 7 P 0 0;1=3
P 5.03268002 2.61615 7 P 0 0;1=3
P 3.34916998 5.1035 7 P 0 0;1=3
P 2.49606004 3.76615 7 P 0 0;1=3
P 3.30916998 5.1035 7 P 0 0;1=3
P 2.49606004 3.81615 7 P 0 0;1=3
P 11.03661004 2.61615 7 P 0 0;1=3
P 2.74225 4.667 7 P 0 0;1=3
P 2.09606004 3.66615 7 P 0 0;1=3
P 2.44606004 3.81615 7 P 0 0;1=3
P 3.20743996 4.78291998 7 P 0 0;1=3
P 2.78225 4.667 7 P 0 0;1=3
P 2.09606004 3.71615 7 P 0 0;1=3
P 2.44606004 3.86615 7 P 0 0;1=3
P 3.16743996 4.78291998 7 P 0 0;1=3
P 2.34606004 3.81615 7 P 0 0;1=3
P 3.27831004 5.22001998 7 P 0 0;1=3
P 2.34606004 3.86615 7 P 0 0;1=3
P 3.23831004 5.22001998 7 P 0 0;1=3
P 4.63268002 2.61615 7 P 0 0;1=3
P 10.98661004 2.61615 7 P 0 0;1=3
P 2.19606004 3.66615 7 P 0 0;1=3
P 2.81311004 4.78291998 7 P 0 0;1=3
P 10.98661004 2.56615 7 P 0 0;1=3
P 2.19606004 3.71615 7 P 0 0;1=3
P 2.85311004 4.78291998 7 P 0 0;1=3
P 0.64808996 1.655 6 P 0 0;1=4
P 5.76 2.66 6 P 0 0;1=0
P 10.63661004 2.61615 7 P 0 0;1=3
P 2.09606004 3.81615 7 P 0 0;1=3
P 3.09656998 5.0535 7 P 0 0;1=3
P 2.09606004 3.86615 7 P 0 0;1=3
P 3.13656998 5.0535 7 P 0 0;1=3
P 2.88708002 4.667 7 P 0 0;1=3
P 2.04606004 3.76615 7 P 0 0;1=3
P 10.73661004 2.61615 7 P 0 0;1=3
P 2.92708002 4.667 7 P 0 0;1=3
P 2.04606004 3.81615 7 P 0 0;1=3
P 10.68661004 2.61615 7 P 0 0;1=3
P 5.03268002 2.46615 7 P 0 0;1=3
P 5.03268002 2.51615 7 P 0 0;1=3
P 11.08661004 2.56615 7 P 0 0;1=3
P 10.68661004 2.56615 7 P 0 0;1=3
P 9.175 5.255 6 P 0 0;1=0
P 4.73268002 2.61615 7 P 0 0;1=3
P 9.11853996 5.255 6 P 0 0;1=0
P 5.08268002 2.41615 7 P 0 0;1=3
P 10.93661004 2.66615 7 P 0 0;1=3
P 10.58661004 2.61615 7 P 0 0;1=3
P 8.15 3.76615 7 P 0 0;1=3
P 9.02925 5.165 7 P 0 0;1=3
P 4.98268002 2.21615 7 P 0 0;1=3
P 10.58661004 2.56615 7 P 0 0;1=3
P 8.15 3.81615 7 P 0 0;1=3
P 9.06925 5.165 7 P 0 0;1=3
P 11.03661004 2.66615 7 P 0 0;1=3
P 4.98268002 2.26615 7 P 0 0;1=3
P 10.93661004 2.61615 7 P 0 0;1=3
P 5.03268002 2.26615 7 P 0 0;1=3
P 11.08661004 2.61615 7 P 0 0;1=3
P 5.03268002 2.31615 7 P 0 0;1=3
P 10.63661004 2.66615 7 P 0 0;1=3
P 3.775 5.295 6 P 0 0;1=0
P 0.73 5.78 6 P 0 0;1=4
P 8.07 5.29 6 P 0 0;1=0
P 3.8399 4.765 6 P 0 0;1=0
P 0.81 5.78 6 P 0 0;1=4
P 8.005 5.29 6 P 0 0;1=0
P 11.08661004 1.91615 7 P 0 0;1=3
P 4.98268002 1.91615 7 P 0 0;1=3
P 4.98268002 1.96615 7 P 0 0;1=3
P 4.93268002 1.86615 7 P 0 0;1=3
P 4.93268002 1.91615 7 P 0 0;1=3
P 5.03268002 1.86615 7 P 0 0;1=3
P 5.08268002 1.91615 7 P 0 0;1=3
P 5.08268002 2.56615 7 P 0 0;1=3
P 8.15 2.51615 7 P 0 0;1=3
P 4.98268002 2.61615 7 P 0 0;1=3
P 10.68661004 2.71615 7 P 0 0;1=3
P 10.98661004 2.71615 7 P 0 0;1=3
P 10.78661004 2.71615 7 P 0 0;1=3
P 4.93268002 2.66615 7 P 0 0;1=3
P 10.88661004 2.71615 7 P 0 0;1=3
P 10.68661004 2.76615 7 P 0 0;1=3
P 9.64 0.71 6 P 0 0;1=0
P 10.58661004 2.81615 7 P 0 0;1=3
P 9.43296004 0.49133002 6 P 0 0;1=0
P 9.43296004 0.73633002 6 P 0 0;1=0
P 10.63661004 2.81615 7 P 0 0;1=3
P 4.68268002 2.56615 7 P 0 0;1=3
P 10.68661004 2.81615 7 P 0 0;1=3
P 9.55795 0.36633002 6 P 0 0;1=0
P 10.73661004 2.81615 7 P 0 0;1=3
P 9.35796004 0.49133002 6 P 0 0;1=0
P 5.03268002 2.66615 7 P 0 0;1=3
P 10.78661004 2.81615 7 P 0 0;1=3
P 9.58296004 0.71133002 6 P 0 0;1=0
P 5.08268002 2.61615 7 P 0 0;1=3
P 11.08661004 1.96615 7 P 0 0;1=3
P 11.03661004 1.86615 7 P 0 0;1=3
P 11.03661004 1.91615 7 P 0 0;1=3
P 10.93661004 1.86615 7 P 0 0;1=3
P 10.93661004 1.91615 7 P 0 0;1=3
P 10.98661004 1.91615 7 P 0 0;1=3
P 10.98661004 1.96615 7 P 0 0;1=3
P 4.93268002 2.61615 7 P 0 0;1=3
P 11.03661004 2.01615 7 P 0 0;1=3
P 11.03661004 2.06615 7 P 0 0;1=3
P 10.93661004 2.01615 7 P 0 0;1=3
P 10.93661004 2.06615 7 P 0 0;1=3
P 10.98661004 2.06615 7 P 0 0;1=3
P 10.98661004 2.11615 7 P 0 0;1=3
P 11.08661004 2.06615 7 P 0 0;1=3
P 11.08661004 2.11615 7 P 0 0;1=3
P 3.115 5.255 6 P 0 0;1=0
P 4.63268002 2.66615 7 P 0 0;1=3
P 11.08661004 2.21615 7 P 0 0;1=3
P 4.98268002 2.56615 7 P 0 0;1=3
P 11.08661004 2.26615 7 P 0 0;1=3
P 11.03661004 2.26615 7 P 0 0;1=3
P 2.14606004 3.76615 7 P 0 0;1=3
P 3.02571004 5.165 7 P 0 0;1=3
P 11.03661004 2.31615 7 P 0 0;1=3
P 10.98661004 2.21615 7 P 0 0;1=3
P 10.98661004 2.26615 7 P 0 0;1=3
P 3.17146004 5.255 6 P 0 0;1=0
P 4.68268002 2.61615 7 P 0 0;1=3
P 10.93661004 2.26615 7 P 0 0;1=3
P 10.58661004 2.76615 7 P 0 0;1=3
P 4 5.29 6 P 0 0;1=0
P 10.93661004 2.31615 7 P 0 0;1=3
P 10.88661004 2.16615 7 P 0 0;1=3
P 10.73661004 1.91615 7 P 0 0;1=3
P 10.395 1.28555 7 P 0 0;1=3
P 12.81495 1.96456998 12 P 0 0;1=1
P 9.42358002 5.22001998 7 P 0 0;1=3
P 8.98115 2.825 7 P 0 0;1=3
P 4.58268002 2.61615 7 P 0 0;1=3
P 9.38358002 5.22001998 7 P 0 0;1=3
P 8.98115 2.865 7 P 0 0;1=3
P 2.14606004 3.81615 7 P 0 0;1=3
P 3.06571004 5.165 7 P 0 0;1=3
P 11.08661004 2.71615 7 P 0 0;1=3
P 3.985 4.88998996 6 P 0 0;1=0
P 11.73316004 2.652 7 P 0 0;1=3
P 12.55905 4.40551004 12 P 0 0;1=1
P 11.73316004 2.612 7 P 0 0;1=3
P 12.63778996 4.44488002 12 P 0 0;1=1
P 8.3 2.86615 7 P 0 0;1=3
P 4.83268002 2.16615 7 P 0 0;1=3
P 0.69348996 1.90611998 7 P 0 0;1=3
P 11.73316004 2.492 7 P 0 0;1=3
P 12.55905 4.24803002 12 P 0 0;1=1
P 4.88268002 2.16615 7 P 0 0;1=3
P 0.69348996 1.86611998 7 P 0 0;1=3
P 11.73316004 2.452 7 P 0 0;1=3
P 12.63778996 4.2874 12 P 0 0;1=1
P 8.25 2.86615 7 P 0 0;1=3
P 12.55905 3.93306998 12 P 0 0;1=1
P 11.73316004 2.332 7 P 0 0;1=3
P 12.63778996 3.97243996 12 P 0 0;1=1
P 11.73316004 2.292 7 P 0 0;1=3
P 10.83661004 2.16615 7 P 0 0;1=3
P 11.53316004 2.092 7 P 0 0;1=3
P 12.55905 3.77558996 12 P 0 0;1=1
P 11.53316004 2.052 7 P 0 0;1=3
P 12.63778996 3.81496004 12 P 0 0;1=1
P 12.81495 3.53936998 12 P 0 0;1=1
P 10.68661004 2.26615 7 P 0 0;1=3
P 9.975 2.3758 7 P 0 0;1=3
P 12.81495 3.38188996 12 P 0 0;1=1
P 10.73661004 2.31615 7 P 0 0;1=3
P 9.975 2.23955 7 P 0 0;1=3
P 12.81495 2.20078996 12 P 0 0;1=1
P 10.68661004 1.91615 7 P 0 0;1=3
P 10.42445 1.395 7 P 0 0;1=3
P 12.81495 2.75196998 12 P 0 0;1=1
P 10.73661004 2.01615 7 P 0 0;1=3
P 10.26025 1.82845 7 P 0 0;1=3
P 12.73621004 3.73621998 12 P 0 0;1=1
P 10.58661004 2.21615 7 P 0 0;1=3
P 10.09 2.26825 7 P 0 0;1=3
P 10.73661004 2.41615 7 P 0 0;1=3
P 10.09 2.69655 7 P 0 0;1=3
P 12.73621004 4.52361998 12 P 0 0;1=1
P 7.3426 4.69351004 6 P 0 0;1=0
P 11.73316004 1.532 7 P 0 0;1=3
P 12.55905 2.27953002 12 P 0 0;1=1
P 7.2926 4.69351004 6 P 0 0;1=0
P 12.73621004 3.57873996 12 P 0 0;1=1
P 10.68661004 2.21615 7 P 0 0;1=3
P 9.975 2.3358 7 P 0 0;1=3
P 12.73621004 3.42126004 12 P 0 0;1=1
P 10.73661004 2.26615 7 P 0 0;1=3
P 9.975 2.19955 7 P 0 0;1=3
P 11.73316004 2.172 7 P 0 0;1=3
P 12.55905 3.46063002 12 P 0 0;1=1
P 4.98268002 2.36615 7 P 0 0;1=3
P 10.73661004 1.86615 7 P 0 0;1=3
P 10.395 1.32555 7 P 0 0;1=3
P 12.73621004 2.00393996 12 P 0 0;1=1
P 11.73316004 2.132 7 P 0 0;1=3
P 12.63778996 3.5 12 P 0 0;1=1
P 3.38003996 5.22001998 7 P 0 0;1=3
P 2.97721004 2.865 7 P 0 0;1=3
P 4.98268002 2.41615 7 P 0 0;1=3
P 12.63778996 1.76771998 12 P 0 0;1=1
P 3.42003996 5.22001998 7 P 0 0;1=3
P 2.97721004 2.825 7 P 0 0;1=3
P 4.88268002 2.81615 7 P 0 0;1=3
P 4.93268002 2.81615 7 P 0 0;1=3
P 4.98268002 2.81615 7 P 0 0;1=3
P 5.03268002 2.81615 7 P 0 0;1=3
P 5.08268002 2.81615 7 P 0 0;1=3
P 11.03661004 2.81615 7 P 0 0;1=3
P 11.08661004 2.81615 7 P 0 0;1=3
P 10.98661004 2.81615 7 P 0 0;1=3
P 10.93661004 2.81615 7 P 0 0;1=3
P 10.88661004 2.81615 7 P 0 0;1=3
P 5.27886004 3.0214 6 P 0 0;1=4
P 5.27886004 3.0564 6 P 0 0;1=4
P 5.27886004 3.1014 6 P 0 0;1=4
P 5.27886004 3.1364 6 P 0 0;1=4
P 5.27886004 2.9764 6 P 0 0;1=4
P 5.27886004 2.9414 6 P 0 0;1=4
P 5.27886004 3.2614 6 P 0 0;1=4
P 5.27886004 3.2964 6 P 0 0;1=4
P 5.27886004 3.2164 6 P 0 0;1=4
P 5.27886004 3.1814 6 P 0 0;1=4
P 11.28278996 3.1814 6 P 0 0;1=4
P 11.28278996 3.2164 6 P 0 0;1=4
P 11.28278996 3.2964 6 P 0 0;1=4
P 11.28278996 3.2614 6 P 0 0;1=4
P 11.28278996 2.9414 6 P 0 0;1=4
P 11.28278996 2.9764 6 P 0 0;1=4
P 11.28278996 3.1364 6 P 0 0;1=4
P 11.28278996 3.1014 6 P 0 0;1=4
P 11.28278996 3.0564 6 P 0 0;1=4
P 11.28278996 3.0214 6 P 0 0;1=4
P 5.59708996 4.7302 6 P 0 0;1=4
P 5.57708996 4.6802 6 P 0 0;1=4
P 5.75708996 4.7302 6 P 0 0;1=4
P 5.83708996 4.7302 6 P 0 0;1=4
P 5.69708996 4.6802 6 P 0 0;1=4
P 5.73708996 4.6802 6 P 0 0;1=4
P 5.77708996 4.6802 6 P 0 0;1=4
P 5.81708996 4.6802 6 P 0 0;1=4
P 5.85708996 4.6802 6 P 0 0;1=4
P 5.67708996 4.7302 6 P 0 0;1=4
P 5.65708996 4.6802 6 P 0 0;1=4
P 5.61708996 4.6802 6 P 0 0;1=4
P 6.13708996 4.7602 6 P 0 0;1=4
P 6.09708996 4.6802 6 P 0 0;1=4
P 6.13708996 4.6402 6 P 0 0;1=4
P 6.13708996 4.6802 6 P 0 0;1=4
P 6.13708996 4.7202 6 P 0 0;1=4
P 5.91708996 4.7302 6 P 0 0;1=4
P 5.99708996 4.7302 6 P 0 0;1=4
P 6.07708996 4.7302 6 P 0 0;1=4
P 5.89708996 4.6802 6 P 0 0;1=4
P 5.93708996 4.6802 6 P 0 0;1=4
P 5.97708996 4.6802 6 P 0 0;1=4
P 6.01708996 4.6802 6 P 0 0;1=4
P 6.05708996 4.6802 6 P 0 0;1=4
P 5.59708996 4.7702 6 P 0 0;1=4
P 5.59708996 4.8102 6 P 0 0;1=4
P 5.75708996 4.8102 6 P 0 0;1=4
P 5.83708996 4.8102 6 P 0 0;1=4
P 5.75708996 4.7702 6 P 0 0;1=4
P 5.83708996 4.7702 6 P 0 0;1=4
P 5.67708996 4.8102 6 P 0 0;1=4
P 5.67708996 4.7702 6 P 0 0;1=4
P 6.13708996 4.9252 6 P 0 0;1=4
P 6.13708996 4.8402 6 P 0 0;1=4
P 6.13708996 4.8002 6 P 0 0;1=4
P 6.13708996 4.8852 6 P 0 0;1=4
P 5.91708996 4.8102 6 P 0 0;1=4
P 5.99708996 4.8102 6 P 0 0;1=4
P 5.91708996 4.7702 6 P 0 0;1=4
P 5.99708996 4.7702 6 P 0 0;1=4
P 6.07708996 4.8102 6 P 0 0;1=4
P 6.07708996 4.7702 6 P 0 0;1=4
P 4.93268002 2.26615 7 P 0 0;1=3
P 4.93268002 2.31615 7 P 0 0;1=3
P 5.08268002 2.36615 7 P 0 0;1=3
P 12.81495 3.22441004 12 P 0 0;1=1
P 10.68661004 2.06615 7 P 0 0;1=3
P 10.09 2.13095 7 P 0 0;1=3
P 10.63661004 2.31615 7 P 0 0;1=3
P 10.09 2.40335 7 P 0 0;1=3
P 12.81495 3.85433002 12 P 0 0;1=1
P 11.73316004 2.012 7 P 0 0;1=3
P 12.63778996 3.1063 12 P 0 0;1=1
P 11.73316004 1.972 7 P 0 0;1=3
P 12.55905 3.14566998 12 P 0 0;1=1
P 11.53316004 1.732 7 P 0 0;1=3
P 12.55905 2.98818996 12 P 0 0;1=1
P 12.81495 3.69685 12 P 0 0;1=1
P 10.58661004 2.26615 7 P 0 0;1=3
P 10.09 2.30825 7 P 0 0;1=3
P 11.53316004 1.772 7 P 0 0;1=3
P 12.63778996 2.94881998 12 P 0 0;1=1
P 12.81495 4.32676998 12 P 0 0;1=1
P 10.63661004 2.46615 7 P 0 0;1=3
P 9.975 2.62445 7 P 0 0;1=3
P 12.63778996 2.79133996 12 P 0 0;1=1
P 11.73316004 1.852 7 P 0 0;1=3
P 12.55905 2.83071004 12 P 0 0;1=1
P 11.73316004 1.812 7 P 0 0;1=3
P 10.73661004 2.46615 7 P 0 0;1=3
P 10.09 2.73655 7 P 0 0;1=3
P 12.81495 4.48425 12 P 0 0;1=1
P 10.63661004 2.26615 7 P 0 0;1=3
P 10.09 2.44335 7 P 0 0;1=3
P 12.73621004 3.8937 12 P 0 0;1=1
P 10.58661004 2.41615 7 P 0 0;1=3
P 9.975 2.5109 7 P 0 0;1=3
P 12.81495 4.16928996 12 P 0 0;1=1
P 1.025 -0.35 28 P 0 3;1=6
P 1.325 -0.35 28 P 0 3;1=6
P 1.175 -0.35 28 P 0 3;1=6
P 0.725 -0.35 28 P 0 3;1=6
P 0.875 -0.35 28 P 0 3;1=6
P 12.73621004 4.05118002 12 P 0 0;1=1
P 10.68661004 2.36615 7 P 0 0;1=3
P 10.09 2.53845 7 P 0 0;1=3
P 12.81495 2.35826998 12 P 0 0;1=1
P 10.63661004 1.86615 7 P 0 0;1=3
P 10.35543002 1.52156998 7 P 0 0;1=3
P 5.03268002 2.01615 7 P 0 0;1=3
P 5.08268002 2.21615 7 P 0 0;1=3
P 12.73621004 2.16141998 12 P 0 0;1=1
P 10.68661004 1.96615 7 P 0 0;1=3
P 10.46445 1.395 7 P 0 0;1=3
P 0.2 -0.293 20 P 0 0;1=14
P 12.27 0.29 20 P 0 0;1=14
P 0.66 0.29 20 P 0 0;1=14
P 0.2 5.82361998 20 P 0 0;1=14
P 12.81495 1.57086998 12 P 0 0;1=1
P 12.73621004 1.5315 12 P 0 0;1=1
P 12.63778996 2.7126 12 P 0 0;1=1
P 12.55905 2.67323002 12 P 0 0;1=1
P 12.55905 1.64961004 12 P 0 0;1=1
P 12.63778996 1.61023996 12 P 0 0;1=1
P 12.55905 1.57086998 12 P 0 0;1=1
P 12.63778996 1.5315 12 P 0 0;1=1
P 12.73621004 1.68898002 12 P 0 0;1=1
P 12.81495 1.64961004 12 P 0 0;1=1
P 12.63778996 1.68898002 12 P 0 0;1=1
P 12.55905 1.72835 12 P 0 0;1=1
P 12.81495 1.72835 12 P 0 0;1=1
P 12.73621004 1.45276004 12 P 0 0;1=1
P 12.81495 1.41338996 12 P 0 0;1=1
P 12.73621004 1.37401998 12 P 0 0;1=7
P 12.63778996 1.45276004 12 P 0 0;1=1
P 12.55905 1.41338996 12 P 0 0;1=1
P 0.35038996 1.5315 12 P 0 0;1=1
P 0.27165 1.49213002 12 P 0 0;1=1
P 0.17323002 2.67323002 12 P 0 0;1=1
P 0.09448996 2.63386004 12 P 0 0;1=1
P 0.09448996 1.61023996 12 P 0 0;1=1
P 0.17323002 1.57086998 12 P 0 0;1=1
P 0.09448996 1.5315 12 P 0 0;1=1
P 0.17323002 1.49213002 12 P 0 0;1=1
P 0.27165 1.64961004 12 P 0 0;1=1
P 0.35038996 1.61023996 12 P 0 0;1=1
P 0.17323002 1.64961004 12 P 0 0;1=1
P 0.09448996 1.68898002 12 P 0 0;1=1
P 0.35038996 1.68898002 12 P 0 0;1=1
P 0.27165 1.41338996 12 P 0 0;1=1
P 0.35038996 1.37401998 12 P 0 0;1=1
P 0.27165 1.33465 12 P 0 0;1=7
P 0.17323002 1.41338996 12 P 0 0;1=1
P 0.09448996 1.37401998 12 P 0 0;1=1
P 10.20866004 5.4441 25 P 0 0;1=15
P 5.78346004 5.4441 25 P 0 0;1=15
P 12.7252 6.31661998 20 P 0 0;1=14
P 0.2 6.31661998 20 P 0 0;1=14
P 12.7252 -0.293 20 P 0 0;1=14
P 0.22245 4.87401004 18 P 0 0;1=5
P 12.68701004 0.46063002 21 P 0 0;1=16
P 12.68701998 5.4252 21 P 0 0;1=16
P 0.22245 0.42126004 21 P 0 0;1=16
P 0.22255 5.38583002 21 P 0 0;1=16
P 7.17716998 5.7874 24 P 0 0;1=17
P 7.17716998 0.23621998 24 P 0 0;1=17
P 0.22245 0.68898002 23 P 0 0;1=18
P 0.22245 5.11811004 23 P 0 0;1=18
P 12.68701998 5.15748002 23 P 0 0;1=18
P 12.68701998 0.72835 23 P 0 0;1=18
P 6.11811004 1.52756004 23 P 0 0;1=18
P 6.11811004 4.20473002 23 P 0 0;1=18
P 4.83268002 4.22441004 23 P 0 0;1=18
P 2.24606004 4.22441004 23 P 0 0;1=18
P 0.96063002 4.20473002 23 P 0 0;1=18
P 0.96063002 1.52756004 23 P 0 0;1=18
P 2.24606004 1.50786998 23 P 0 0;1=18
P 4.83268002 1.50786998 23 P 0 0;1=18
P 6.04921004 2.58268002 22 P 0 0;1=19
P 1.05905 2.58268002 27 P 0 0;1=20
P 12.12205 1.52756004 23 P 0 0;1=18
P 12.12205 4.20473002 23 P 0 0;1=18
P 10.83661998 4.22441004 23 P 0 0;1=18
P 8.25 4.22441004 23 P 0 0;1=18
P 6.96456998 4.20473002 23 P 0 0;1=18
P 6.96456998 1.52756004 23 P 0 0;1=18
P 8.25 1.50786998 23 P 0 0;1=18
P 10.83661998 1.50786998 23 P 0 0;1=18
P 12.05315 2.58268002 22 P 0 0;1=19
P 7.06298996 2.58268002 27 P 0 0;1=20
P 12.33465 5.69528002 19 P 0 0;1=21
P 3.58311004 4.91851004 15 P 0 0;1=22
P 2.72091004 4.91851004 15 P 0 0;1=22
P 9.58665 4.91851004 15 P 0 0;1=22
P 8.72445 4.91851004 15 P 0 0;1=22
P 2.41851004 4.91851004 15 P 0 0;1=22
P 1.55631004 4.91851004 15 P 0 0;1=22
P 8.42205 4.91851004 15 P 0 0;1=22
P 7.55985 4.91851004 15 P 0 0;1=22
P 0.22243996 1.79331004 17 P 0 0;1=23
P 0.22243996 4.67323002 17 P 0 0;1=23
P 12.687 1.83268002 17 P 0 0;1=23
P 12.687 4.7126 17 P 0 0;1=23
P 0.7687 5.62008002 13 P 0 0;1=24
P 1.47736004 5.62008002 13 P 0 0;1=24
L 1.88908002 -1.91246004 1.89293002 -1.91246004 0 P 0 ;0
L 1.89126998 -1.91146004 1.89656998 -1.91146004 0 P 0 ;0
L 1.89393996 -1.91046004 1.9155 -1.91046004 0 P 0 ;0
L 1.91593996 -1.91246004 1.92048996 -1.91246004 0 P 0 ;0
L 1.9126 -1.91146004 1.9184 -1.91146004 0 P 0 ;0
L 1.89763002 -1.90946004 1.91016998 -1.90946004 0 P 0 ;0
L 1.89053002 -1.96001004 1.8974 -1.96001004 0 P 0 ;0
L 1.89053002 -1.95901004 1.8974 -1.95901004 0 P 0 ;0
L 1.89053002 -1.95801004 1.8974 -1.95801004 0 P 0 ;0
L 1.89053002 -1.95701004 1.8974 -1.95701004 0 P 0 ;0
L 1.89053002 -1.95601004 1.8974 -1.95601004 0 P 0 ;0
L 1.89053002 -1.95501004 1.8974 -1.95501004 0 P 0 ;0
L 1.89053002 -1.95401004 1.8974 -1.95401004 0 P 0 ;0
L 1.89053002 -1.95301004 1.89741004 -1.95301004 0 P 0 ;0
L 1.89053002 -1.95201004 1.89741998 -1.95201004 0 P 0 ;0
L 1.89053002 -1.95101004 1.89743996 -1.95101004 0 P 0 ;0
L 1.89053002 -1.95001004 1.89745 -1.95001004 0 P 0 ;0
L 1.89053002 -1.94901004 1.89746004 -1.94901004 0 P 0 ;0
L 1.89053002 -1.94801004 1.89753002 -1.94801004 0 P 0 ;0
L 1.89053002 -1.94701004 1.8977 -1.94701004 0 P 0 ;0
L 1.89053002 -1.94601004 1.89798002 -1.94601004 0 P 0 ;0
L 1.89053002 -1.94501004 1.89861004 -1.94501004 0 P 0 ;0
L 1.89053002 -1.94401004 1.90005 -1.94401004 0 P 0 ;0
L 1.89053002 -1.94301004 1.9113 -1.94301004 0 P 0 ;0
L 1.89053002 -1.94201004 1.91168002 -1.94201004 0 P 0 ;0
L 1.89053002 -1.94101004 1.91246998 -1.94101004 0 P 0 ;0
L 1.89053002 -1.94001004 1.90093996 -1.94001004 0 P 0 ;0
L 1.89053002 -1.93901004 1.89856004 -1.93901004 0 P 0 ;0
L 1.89053002 -1.93801004 1.89786998 -1.93801004 0 P 0 ;0
L 1.89053002 -1.93701004 1.89753996 -1.93701004 0 P 0 ;0
L 1.89053002 -1.93601004 1.89746998 -1.93601004 0 P 0 ;0
L 1.89053002 -1.93501004 1.89743996 -1.93501004 0 P 0 ;0
L 1.89053002 -1.93401004 1.89741998 -1.93401004 0 P 0 ;0
L 1.89053002 -1.93301004 1.8974 -1.93301004 0 P 0 ;0
L 1.89053002 -1.93201004 1.8974 -1.93201004 0 P 0 ;0
L 1.89053002 -1.93101004 1.8974 -1.93101004 0 P 0 ;0
L 1.89053002 -1.93001004 1.8974 -1.93001004 0 P 0 ;0
L 1.89053002 -1.92901004 1.8974 -1.92901004 0 P 0 ;0
L 1.89053002 -1.92801004 1.89753002 -1.92801004 0 P 0 ;0
L 1.89053002 -1.92701004 1.89793996 -1.92701004 0 P 0 ;0
L 1.89053002 -1.92601004 1.91713002 -1.92601004 0 P 0 ;0
L 1.89053002 -1.92501004 1.91628996 -1.92501004 0 P 0 ;0
L 1.89053002 -1.92401004 1.91513996 -1.92401004 0 P 0 ;0
L 1.89053002 -1.92301004 1.91321998 -1.92301004 0 P 0 ;0
L 1.89053002 -1.92201004 1.90551004 -1.92201004 0 P 0 ;0
L 1.89438996 -1.97246004 1.91331004 -1.97246004 0 P 0 ;0
L 1.89106998 -1.97146004 1.89973002 -1.97146004 0 P 0 ;0
L 1.88878002 -1.97046004 1.8949 -1.97046004 0 P 0 ;0
L 1.88698002 -1.96946004 1.89206998 -1.96946004 0 P 0 ;0
L 1.88546004 -1.96846004 1.88986998 -1.96846004 0 P 0 ;0
L 1.88416998 -1.96746004 1.88808996 -1.96746004 0 P 0 ;0
L 1.88288002 -1.96646004 1.88655 -1.96646004 0 P 0 ;0
L 1.88176998 -1.96546004 1.88518002 -1.96546004 0 P 0 ;0
L 1.88068996 -1.96446004 1.88393996 -1.96446004 0 P 0 ;0
L 1.87968996 -1.96346004 1.88286004 -1.96346004 0 P 0 ;0
L 1.87878002 -1.96246004 1.88186004 -1.96246004 0 P 0 ;0
L 1.8786 -1.92046004 1.88126998 -1.92046004 0 P 0 ;0
L 1.87946998 -1.91946004 1.88223002 -1.91946004 0 P 0 ;0
L 1.88048002 -1.91846004 1.88321004 -1.91846004 0 P 0 ;0
L 1.88153996 -1.91746004 1.88436998 -1.91746004 0 P 0 ;0
L 1.88273002 -1.91646004 1.88558996 -1.91646004 0 P 0 ;0
L 1.88406004 -1.91546004 1.88696998 -1.91546004 0 P 0 ;0
L 1.88548996 -1.91446004 1.88853002 -1.91446004 0 P 0 ;0
L 1.88718002 -1.91346004 1.89041998 -1.91346004 0 P 0 ;0
L 1.90896004 -1.92963996 1.90921998 -1.92991998 0 P 0 ;0
L 1.90921998 -1.92991998 1.90945 -1.93021998 0 P 0 ;0
L 1.90945 -1.93021998 1.90966004 -1.93053002 0 P 0 ;0
L 1.90966004 -1.93053002 1.90983002 -1.93086004 0 P 0 ;0
L 1.90983002 -1.93086004 1.90998002 -1.93121004 0 P 0 ;0
L 1.90998002 -1.93121004 1.9101 -1.93156998 0 P 0 ;0
L 1.9101 -1.93156998 1.91018996 -1.93193996 0 P 0 ;0
L 1.91018996 -1.93193996 1.91023996 -1.93231004 0 P 0 ;0
L 1.91023996 -1.93231004 1.91026998 -1.93265 0 P 0 ;0
L 1.91026998 -1.93265 1.91026004 -1.93298002 0 P 0 ;0
L 1.91026004 -1.93298002 1.91023002 -1.93331004 0 P 0 ;0
L 1.91023002 -1.93331004 1.91016998 -1.93363996 0 P 0 ;0
L 1.91016998 -1.93363996 1.91008996 -1.93396004 0 P 0 ;0
L 1.91008996 -1.93396004 1.90998002 -1.93428002 0 P 0 ;0
L 1.90998002 -1.93428002 1.90983996 -1.93458002 0 P 0 ;0
L 1.90983996 -1.93458002 1.90968996 -1.93486998 0 P 0 ;0
L 1.90968996 -1.93486998 1.90951004 -1.93516004 0 P 0 ;0
L 1.90951004 -1.93516004 1.90921004 -1.93556004 0 P 0 ;0
L 1.90921004 -1.93556004 1.90888002 -1.93593002 0 P 0 ;0
L 1.90888002 -1.93593002 1.90853002 -1.93626998 0 P 0 ;0
L 1.90853002 -1.93626998 1.90815 -1.93658996 0 P 0 ;0
L 1.90815 -1.93658996 1.90773996 -1.93686998 0 P 0 ;0
L 1.90773996 -1.93686998 1.90731998 -1.93711998 0 P 0 ;0
L 1.90731998 -1.93711998 1.90686998 -1.93733996 0 P 0 ;0
L 1.90686998 -1.93733996 1.90615 -1.93761004 0 P 0 ;0
L 1.90615 -1.93761004 1.90541998 -1.93783002 0 P 0 ;0
L 1.90541998 -1.93783002 1.90466004 -1.93798002 0 P 0 ;0
L 1.90466004 -1.93798002 1.9039 -1.93808002 0 P 0 ;0
L 1.9039 -1.93808002 1.90311998 -1.9381 0 P 0 ;0
L 1.90311998 -1.9381 1.90196004 -1.93808002 0 P 0 ;0
L 1.90196004 -1.93808002 1.90078996 -1.93798996 0 P 0 ;0
L 1.90078996 -1.93798996 1.90068002 -1.93798002 0 P 0 ;0
L 1.90068002 -1.93798002 1.90058002 -1.93795 0 P 0 ;0
L 1.90058002 -1.93795 1.90046998 -1.93791998 0 P 0 ;0
L 1.90046998 -1.93791998 1.90038002 -1.93788002 0 P 0 ;0
L 1.90038002 -1.93788002 1.90028002 -1.93783002 0 P 0 ;0
L 1.90028002 -1.93783002 1.90018996 -1.93778002 0 P 0 ;0
L 1.90018996 -1.93778002 1.9001 -1.93771004 0 P 0 ;0
L 1.9001 -1.93771004 1.90001998 -1.93763996 0 P 0 ;0
L 1.90001998 -1.93763996 1.89988002 -1.93748002 0 P 0 ;0
L 1.89988002 -1.93748002 1.89978002 -1.93733996 0 P 0 ;0
L 1.89978002 -1.93733996 1.89961998 -1.93703996 0 P 0 ;0
L 1.89961998 -1.93703996 1.89956998 -1.93688002 0 P 0 ;0
L 1.89956998 -1.93688002 1.89951998 -1.93671004 0 P 0 ;0
L 1.89951998 -1.93671004 1.89948996 -1.93655 0 P 0 ;0
L 1.89948996 -1.93655 1.89946998 -1.93636998 0 P 0 ;0
L 1.89946998 -1.93636998 1.8994 -1.93323002 0 P 0 ;0
L 1.8994 -1.93323002 1.8994 -1.92833002 0 P 0 ;0
L 1.8994 -1.92833002 1.90353996 -1.92833002 0 P 0 ;0
L 1.90353996 -1.92833002 1.90436998 -1.92835 0 P 0 ;0
L 1.90436998 -1.92835 1.9052 -1.92843002 0 P 0 ;0
L 1.9052 -1.92843002 1.90603002 -1.92853996 0 P 0 ;0
L 1.90603002 -1.92853996 1.90683996 -1.92871004 0 P 0 ;0
L 1.90683996 -1.92871004 1.90751004 -1.9289 0 P 0 ;0
L 1.90751004 -1.9289 1.90818002 -1.92913002 0 P 0 ;0
L 1.90818002 -1.92913002 1.90851998 -1.92928996 0 P 0 ;0
L 1.90851998 -1.92928996 1.90868002 -1.92938996 0 P 0 ;0
L 1.90868002 -1.92938996 1.90883002 -1.92951004 0 P 0 ;0
L 1.90883002 -1.92951004 1.90896004 -1.92963996 0 P 0 ;0
L 1.91188996 -1.96001004 1.91638996 -1.96001004 0 P 0 ;0
L 1.91156998 -1.95901004 1.91926998 -1.95901004 0 P 0 ;0
L 1.91125 -1.95801004 1.91891998 -1.95801004 0 P 0 ;0
L 1.91091998 -1.95701004 1.91853002 -1.95701004 0 P 0 ;0
L 1.9106 -1.95601004 1.91811004 -1.95601004 0 P 0 ;0
L 1.91025 -1.95501004 1.91765 -1.95501004 0 P 0 ;0
L 1.90988996 -1.95401004 1.91718996 -1.95401004 0 P 0 ;0
L 1.90953002 -1.95301004 1.91673002 -1.95301004 0 P 0 ;0
L 1.90918002 -1.95201004 1.91626998 -1.95201004 0 P 0 ;0
L 1.90881998 -1.95101004 1.91576004 -1.95101004 0 P 0 ;0
L 1.90841004 -1.95001004 1.91523996 -1.95001004 0 P 0 ;0
L 1.90793996 -1.94901004 1.91471004 -1.94901004 0 P 0 ;0
L 1.90738996 -1.94801004 1.91418002 -1.94801004 0 P 0 ;0
L 1.90676998 -1.94701004 1.9136 -1.94701004 0 P 0 ;0
L 1.90598996 -1.94601004 1.91261004 -1.94601004 0 P 0 ;0
L 1.90495 -1.94501004 1.91175 -1.94501004 0 P 0 ;0
L 1.90325 -1.94401004 1.91133002 -1.94401004 0 P 0 ;0
L 1.90456004 -1.94001004 1.91383002 -1.94001004 0 P 0 ;0
L 1.90801004 -1.93901004 1.91523002 -1.93901004 0 P 0 ;0
L 1.90956998 -1.93801004 1.91635 -1.93801004 0 P 0 ;0
L 1.9106 -1.93701004 1.91718002 -1.93701004 0 P 0 ;0
L 1.91133996 -1.93601004 1.91781004 -1.93601004 0 P 0 ;0
L 1.91183996 -1.93501004 1.91826004 -1.93501004 0 P 0 ;0
L 1.91213002 -1.93401004 1.9186 -1.93401004 0 P 0 ;0
L 1.91226004 -1.93301004 1.9188 -1.93301004 0 P 0 ;0
L 1.91221998 -1.93201004 1.9189 -1.93201004 0 P 0 ;0
L 1.91201998 -1.93101004 1.9189 -1.93101004 0 P 0 ;0
L 1.91163996 -1.93001004 1.91878996 -1.93001004 0 P 0 ;0
L 1.91105 -1.92901004 1.91856998 -1.92901004 0 P 0 ;0
L 1.91013996 -1.92801004 1.91823002 -1.92801004 0 P 0 ;0
L 1.90816998 -1.92701004 1.91776004 -1.92701004 0 P 0 ;0
L 1.90313996 -1.94011004 1.90316998 -1.9401 0 P 0 ;0
L 1.90316998 -1.9401 1.9032 -1.9401 0 P 0 ;0
L 1.9032 -1.9401 1.90398002 -1.94006998 0 P 0 ;0
L 1.90398002 -1.94006998 1.90406004 -1.94006998 0 P 0 ;0
L 1.90406004 -1.94006998 1.90413996 -1.94006004 0 P 0 ;0
L 1.90413996 -1.94006004 1.9049 -1.93996998 0 P 0 ;0
L 1.9049 -1.93996998 1.90493996 -1.93996004 0 P 0 ;0
L 1.90493996 -1.93996004 1.90498996 -1.93996004 0 P 0 ;0
L 1.90498996 -1.93996004 1.90506998 -1.93993996 0 P 0 ;0
L 1.90506998 -1.93993996 1.90581998 -1.93978002 0 P 0 ;0
L 1.90581998 -1.93978002 1.90586004 -1.93978002 0 P 0 ;0
L 1.90586004 -1.93978002 1.90593996 -1.93976004 0 P 0 ;0
L 1.90593996 -1.93976004 1.90596998 -1.93973996 0 P 0 ;0
L 1.90596998 -1.93973996 1.90671004 -1.93953002 0 P 0 ;0
L 1.90671004 -1.93953002 1.90678996 -1.93951004 0 P 0 ;0
L 1.90678996 -1.93951004 1.90758996 -1.93921004 0 P 0 ;0
L 1.90758996 -1.93921004 1.90766004 -1.93916998 0 P 0 ;0
L 1.90766004 -1.93916998 1.9077 -1.93915 0 P 0 ;0
L 1.9077 -1.93915 1.90773996 -1.93913996 0 P 0 ;0
L 1.90773996 -1.93913996 1.90818996 -1.93891998 0 P 0 ;0
L 1.90818996 -1.93891998 1.90821998 -1.9389 0 P 0 ;0
L 1.90821998 -1.9389 1.90826004 -1.93888996 0 P 0 ;0
L 1.90826004 -1.93888996 1.90828996 -1.93886998 0 P 0 ;0
L 1.90828996 -1.93886998 1.90833002 -1.93885 0 P 0 ;0
L 1.90833002 -1.93885 1.90875 -1.9386 0 P 0 ;0
L 1.90875 -1.9386 1.90883002 -1.93856004 0 P 0 ;0
L 1.90883002 -1.93856004 1.90888996 -1.93851004 0 P 0 ;0
L 1.90888996 -1.93851004 1.90928996 -1.93823002 0 P 0 ;0
L 1.90928996 -1.93823002 1.90933002 -1.9382 0 P 0 ;0
L 1.90933002 -1.9382 1.90936004 -1.93818002 0 P 0 ;0
L 1.90936004 -1.93818002 1.90938996 -1.93815 0 P 0 ;0
L 1.90938996 -1.93815 1.90941998 -1.93813002 0 P 0 ;0
L 1.90941998 -1.93813002 1.9098 -1.93781998 0 P 0 ;0
L 1.9098 -1.93781998 1.90986004 -1.93776004 0 P 0 ;0
L 1.90986004 -1.93776004 1.90988996 -1.93773996 0 P 0 ;0
L 1.90988996 -1.93773996 1.90991998 -1.93771004 0 P 0 ;0
L 1.90991998 -1.93771004 1.91028002 -1.93736004 0 P 0 ;0
L 1.91028002 -1.93736004 1.91038996 -1.93725 0 P 0 ;0
L 1.91038996 -1.93725 1.91071004 -1.93688002 0 P 0 ;0
L 1.91071004 -1.93688002 1.91073996 -1.93685 0 P 0 ;0
L 1.91073996 -1.93685 1.91116004 -1.9363 0 P 0 ;0
L 1.91116004 -1.9363 1.9112 -1.93623002 0 P 0 ;0
L 1.9112 -1.93623002 1.91138002 -1.93595 0 P 0 ;0
L 1.91138002 -1.93595 1.9114 -1.93591004 0 P 0 ;0
L 1.9114 -1.93591004 1.91143996 -1.93585 0 P 0 ;0
L 1.91143996 -1.93585 1.91146004 -1.93581004 0 P 0 ;0
L 1.91146004 -1.93581004 1.91161004 -1.93551998 0 P 0 ;0
L 1.91161004 -1.93551998 1.91163002 -1.93548996 0 P 0 ;0
L 1.91163002 -1.93548996 1.91165 -1.93545 0 P 0 ;0
L 1.91165 -1.93545 1.91166004 -1.93541004 0 P 0 ;0
L 1.91166004 -1.93541004 1.91168002 -1.93538002 0 P 0 ;0
L 1.91168002 -1.93538002 1.91181004 -1.93506998 0 P 0 ;0
L 1.91181004 -1.93506998 1.91183996 -1.935 0 P 0 ;0
L 1.91183996 -1.935 1.91186004 -1.93496004 0 P 0 ;0
L 1.91186004 -1.93496004 1.91186998 -1.93493002 0 P 0 ;0
L 1.91186998 -1.93493002 1.91198002 -1.93461004 0 P 0 ;0
L 1.91198002 -1.93461004 1.91198996 -1.93456998 0 P 0 ;0
L 1.91198996 -1.93456998 1.912 -1.93453996 0 P 0 ;0
L 1.912 -1.93453996 1.9121 -1.93413996 0 P 0 ;0
L 1.9121 -1.93413996 1.91211998 -1.9341 0 P 0 ;0
L 1.91211998 -1.9341 1.91211998 -1.93406004 0 P 0 ;0
L 1.91211998 -1.93406004 1.91213002 -1.93401998 0 P 0 ;0
L 1.91213002 -1.93401998 1.91213996 -1.93398996 0 P 0 ;0
L 1.91213996 -1.93398996 1.9122 -1.93366004 0 P 0 ;0
L 1.9122 -1.93366004 1.91221004 -1.93358002 0 P 0 ;0
L 1.91221004 -1.93358002 1.91221004 -1.93353996 0 P 0 ;0
L 1.91221004 -1.93353996 1.91221998 -1.9335 0 P 0 ;0
L 1.91221998 -1.9335 1.91225 -1.93316998 0 P 0 ;0
L 1.91225 -1.93316998 1.91226004 -1.93308996 0 P 0 ;0
L 1.91226004 -1.93308996 1.91226004 -1.93268002 0 P 0 ;0
L 1.91226004 -1.93268002 1.91226998 -1.93263996 0 P 0 ;0
L 1.91226998 -1.93263996 1.91226998 -1.9326 0 P 0 ;0
L 1.91226998 -1.9326 1.91226004 -1.93251998 0 P 0 ;0
L 1.91226004 -1.93251998 1.91223996 -1.93218996 0 P 0 ;0
L 1.91223996 -1.93218996 1.91223996 -1.93215 0 P 0 ;0
L 1.91223996 -1.93215 1.91223002 -1.9321 0 P 0 ;0
L 1.91223002 -1.9321 1.91223002 -1.93206004 0 P 0 ;0
L 1.91223002 -1.93206004 1.91221998 -1.93201998 0 P 0 ;0
L 1.91221998 -1.93201998 1.91216998 -1.93163996 0 P 0 ;0
L 1.91216998 -1.93163996 1.91216004 -1.9316 0 P 0 ;0
L 1.91216004 -1.9316 1.91213996 -1.93151004 0 P 0 ;0
L 1.91213996 -1.93151004 1.91213002 -1.93146998 0 P 0 ;0
L 1.91213002 -1.93146998 1.91205 -1.93111004 0 P 0 ;0
L 1.91205 -1.93111004 1.91203996 -1.93106004 0 P 0 ;0
L 1.91203996 -1.93106004 1.91203002 -1.93101998 0 P 0 ;0
L 1.91203002 -1.93101998 1.91201004 -1.93098002 0 P 0 ;0
L 1.91201004 -1.93098002 1.912 -1.93093996 0 P 0 ;0
L 1.912 -1.93093996 1.91188002 -1.93058002 0 P 0 ;0
L 1.91188002 -1.93058002 1.91186998 -1.93053996 0 P 0 ;0
L 1.91186998 -1.93053996 1.91185 -1.9305 0 P 0 ;0
L 1.91185 -1.9305 1.91183996 -1.93046004 0 P 0 ;0
L 1.91183996 -1.93046004 1.91181998 -1.93043002 0 P 0 ;0
L 1.91181998 -1.93043002 1.91166998 -1.93008002 0 P 0 ;0
L 1.91166998 -1.93008002 1.91166004 -1.93003996 0 P 0 ;0
L 1.91166004 -1.93003996 1.9116 -1.92991998 0 P 0 ;0
L 1.9116 -1.92991998 1.91141998 -1.92958996 0 P 0 ;0
L 1.91141998 -1.92958996 1.9114 -1.92955 0 P 0 ;0
L 1.9114 -1.92955 1.91138002 -1.92951998 0 P 0 ;0
L 1.91138002 -1.92951998 1.91133002 -1.92945 0 P 0 ;0
L 1.91133002 -1.92945 1.91113002 -1.92913002 0 P 0 ;0
L 1.91113002 -1.92913002 1.91111004 -1.92908996 0 P 0 ;0
L 1.91111004 -1.92908996 1.91108996 -1.92906004 0 P 0 ;0
L 1.91108996 -1.92906004 1.91106004 -1.92901998 0 P 0 ;0
L 1.91106004 -1.92901998 1.91103002 -1.92898996 0 P 0 ;0
L 1.91103002 -1.92898996 1.9108 -1.92868996 0 P 0 ;0
L 1.9108 -1.92868996 1.91076998 -1.92866004 0 P 0 ;0
L 1.91076998 -1.92866004 1.91075 -1.92861998 0 P 0 ;0
L 1.91075 -1.92861998 1.91068996 -1.92856004 0 P 0 ;0
L 1.91068996 -1.92856004 1.91043002 -1.92828002 0 P 0 ;0
L 1.91043002 -1.92828002 1.91035 -1.9282 0 P 0 ;0
L 1.91035 -1.9282 1.91033002 -1.92816998 0 P 0 ;0
L 1.91033002 -1.92816998 1.91018996 -1.92803996 0 P 0 ;0
L 1.91018996 -1.92803996 1.91018002 -1.92803996 0 P 0 ;0
L 1.91018002 -1.92803996 1.91016004 -1.92801998 0 P 0 ;0
L 1.91016004 -1.92801998 1.91011998 -1.92798996 0 P 0 ;0
L 1.91011998 -1.92798996 1.91006004 -1.92793002 0 P 0 ;0
L 1.91006004 -1.92793002 1.90991004 -1.92781998 0 P 0 ;0
L 1.90991004 -1.92781998 1.90988002 -1.9278 0 P 0 ;0
L 1.90988002 -1.9278 1.90983996 -1.92776998 0 P 0 ;0
L 1.90983996 -1.92776998 1.90976998 -1.92771998 0 P 0 ;0
L 1.90976998 -1.92771998 1.90961004 -1.92761998 0 P 0 ;0
L 1.90961004 -1.92761998 1.90953996 -1.92756998 0 P 0 ;0
L 1.90953996 -1.92756998 1.9095 -1.92755 0 P 0 ;0
L 1.9095 -1.92755 1.90946998 -1.92753002 0 P 0 ;0
L 1.90946998 -1.92753002 1.9093 -1.92743996 0 P 0 ;0
L 1.9093 -1.92743996 1.90926004 -1.92741998 0 P 0 ;0
L 1.90926004 -1.92741998 1.90923002 -1.9274 0 P 0 ;0
L 1.90923002 -1.9274 1.90915 -1.92736998 0 P 0 ;0
L 1.90915 -1.92736998 1.90896998 -1.92728996 0 P 0 ;0
L 1.90896998 -1.92728996 1.90893996 -1.92728002 0 P 0 ;0
L 1.90893996 -1.92728002 1.9089 -1.92726004 0 P 0 ;0
L 1.9089 -1.92726004 1.90886998 -1.92725 0 P 0 ;0
L 1.90886998 -1.92725 1.90883002 -1.92723996 0 P 0 ;0
L 1.90883002 -1.92723996 1.90816004 -1.92701004 0 P 0 ;0
L 1.90816004 -1.92701004 1.90813996 -1.927 0 P 0 ;0
L 1.90813996 -1.927 1.9081 -1.92698996 0 P 0 ;0
L 1.9081 -1.92698996 1.90803996 -1.92696998 0 P 0 ;0
L 1.90803996 -1.92696998 1.90736998 -1.92678002 0 P 0 ;0
L 1.90736998 -1.92678002 1.90723996 -1.92675 0 P 0 ;0
L 1.90723996 -1.92675 1.90643002 -1.92658996 0 P 0 ;0
L 1.90643002 -1.92658996 1.90636998 -1.92656998 0 P 0 ;0
L 1.90636998 -1.92656998 1.90633996 -1.92656998 0 P 0 ;0
L 1.90633996 -1.92656998 1.90631004 -1.92656004 0 P 0 ;0
L 1.90631004 -1.92656004 1.90548996 -1.92645 0 P 0 ;0
L 1.90548996 -1.92645 1.90543996 -1.92643996 0 P 0 ;0
L 1.90543996 -1.92643996 1.9054 -1.92643002 0 P 0 ;0
L 1.9054 -1.92643002 1.90538002 -1.92643002 0 P 0 ;0
L 1.90538002 -1.92643002 1.90455 -1.92636004 0 P 0 ;0
L 1.90455 -1.92636004 1.90443002 -1.92636004 0 P 0 ;0
L 1.90443002 -1.92636004 1.9036 -1.92633002 0 P 0 ;0
L 1.9036 -1.92633002 1.8994 -1.92633002 0 P 0 ;0
L 1.8994 -1.92633002 1.89798002 -1.92691004 0 P 0 ;0
L 1.89798002 -1.92691004 1.8974 -1.92833002 0 P 0 ;0
L 1.8974 -1.92833002 1.8974 -1.93328002 0 P 0 ;0
L 1.8974 -1.93328002 1.89748002 -1.93643002 0 P 0 ;0
L 1.89748002 -1.93643002 1.89748002 -1.93656004 0 P 0 ;0
L 1.89748002 -1.93656004 1.8975 -1.93673002 0 P 0 ;0
L 1.8975 -1.93673002 1.89751004 -1.93681004 0 P 0 ;0
L 1.89751004 -1.93681004 1.89751998 -1.9369 0 P 0 ;0
L 1.89751998 -1.9369 1.89755 -1.93706004 0 P 0 ;0
L 1.89755 -1.93706004 1.89758002 -1.93718996 0 P 0 ;0
L 1.89758002 -1.93718996 1.89758996 -1.93723002 0 P 0 ;0
L 1.89758996 -1.93723002 1.89763002 -1.9374 0 P 0 ;0
L 1.89763002 -1.9374 1.89763996 -1.93743996 0 P 0 ;0
L 1.89763996 -1.93743996 1.89766004 -1.93748002 0 P 0 ;0
L 1.89766004 -1.93748002 1.89768002 -1.93756004 0 P 0 ;0
L 1.89768002 -1.93756004 1.89773996 -1.93771998 0 P 0 ;0
L 1.89773996 -1.93771998 1.89776004 -1.93776004 0 P 0 ;0
L 1.89776004 -1.93776004 1.89776998 -1.9378 0 P 0 ;0
L 1.89776998 -1.9378 1.89781004 -1.93788002 0 P 0 ;0
L 1.89781004 -1.93788002 1.89788002 -1.93803996 0 P 0 ;0
L 1.89788002 -1.93803996 1.8979 -1.93808002 0 P 0 ;0
L 1.8979 -1.93808002 1.89791998 -1.93811004 0 P 0 ;0
L 1.89791998 -1.93811004 1.89796004 -1.93818996 0 P 0 ;0
L 1.89796004 -1.93818996 1.89803996 -1.93833996 0 P 0 ;0
L 1.89803996 -1.93833996 1.89813996 -1.93848002 0 P 0 ;0
L 1.89813996 -1.93848002 1.89823002 -1.93861998 0 P 0 ;0
L 1.89823002 -1.93861998 1.89828002 -1.93868996 0 P 0 ;0
L 1.89828002 -1.93868996 1.89831004 -1.93873002 0 P 0 ;0
L 1.89831004 -1.93873002 1.89833996 -1.93876004 0 P 0 ;0
L 1.89833996 -1.93876004 1.8984 -1.93883996 0 P 0 ;0
L 1.8984 -1.93883996 1.89848996 -1.93893002 0 P 0 ;0
L 1.89848996 -1.93893002 1.89851004 -1.93896004 0 P 0 ;0
L 1.89851004 -1.93896004 1.89868002 -1.93913002 0 P 0 ;0
L 1.89868002 -1.93913002 1.89871004 -1.93915 0 P 0 ;0
L 1.89871004 -1.93915 1.89878996 -1.93921998 0 P 0 ;0
L 1.89878996 -1.93921998 1.89885 -1.93928002 0 P 0 ;0
L 1.89885 -1.93928002 1.89888002 -1.9393 0 P 0 ;0
L 1.89888002 -1.9393 1.89891998 -1.93931998 0 P 0 ;0
L 1.89891998 -1.93931998 1.89901004 -1.93938996 0 P 0 ;0
L 1.89901004 -1.93938996 1.89903996 -1.93941004 0 P 0 ;0
L 1.89903996 -1.93941004 1.89906998 -1.93943996 0 P 0 ;0
L 1.89906998 -1.93943996 1.8991 -1.93946004 0 P 0 ;0
L 1.8991 -1.93946004 1.89913996 -1.93948002 0 P 0 ;0
L 1.89913996 -1.93948002 1.89923002 -1.93953996 0 P 0 ;0
L 1.89923002 -1.93953996 1.89926998 -1.93956004 0 P 0 ;0
L 1.89926998 -1.93956004 1.8993 -1.93958002 0 P 0 ;0
L 1.8993 -1.93958002 1.89933996 -1.9396 0 P 0 ;0
L 1.89933996 -1.9396 1.89936998 -1.93961004 0 P 0 ;0
L 1.89936998 -1.93961004 1.89938002 -1.93961004 0 P 0 ;0
L 1.89938002 -1.93961004 1.89946998 -1.93966004 0 P 0 ;0
L 1.89946998 -1.93966004 1.89953996 -1.9397 0 P 0 ;0
L 1.89953996 -1.9397 1.89971998 -1.93976998 0 P 0 ;0
L 1.89971998 -1.93976998 1.89975 -1.93978996 0 P 0 ;0
L 1.89975 -1.93978996 1.89978996 -1.9398 0 P 0 ;0
L 1.89978996 -1.9398 1.89986998 -1.93983002 0 P 0 ;0
L 1.89986998 -1.93983002 1.89996998 -1.93986004 0 P 0 ;0
L 1.89996998 -1.93986004 1.90001004 -1.93986998 0 P 0 ;0
L 1.90001004 -1.93986998 1.90005 -1.93988996 0 P 0 ;0
L 1.90005 -1.93988996 1.90013002 -1.9399 0 P 0 ;0
L 1.90013002 -1.9399 1.90023002 -1.93993002 0 P 0 ;0
L 1.90023002 -1.93993002 1.90023996 -1.93993002 0 P 0 ;0
L 1.90023996 -1.93993002 1.90028002 -1.93993996 0 P 0 ;0
L 1.90028002 -1.93993996 1.90031004 -1.93995 0 P 0 ;0
L 1.90031004 -1.93995 1.90036004 -1.93995 0 P 0 ;0
L 1.90036004 -1.93995 1.9004 -1.93996004 0 P 0 ;0
L 1.9004 -1.93996004 1.9005 -1.93996998 0 P 0 ;0
L 1.9005 -1.93996998 1.90061004 -1.93998996 0 P 0 ;0
L 1.90061004 -1.93998996 1.90063996 -1.93998996 0 P 0 ;0
L 1.90063996 -1.93998996 1.90181004 -1.94006998 0 P 0 ;0
L 1.90181004 -1.94006998 1.90183996 -1.94008002 0 P 0 ;0
L 1.90183996 -1.94008002 1.90191004 -1.94008002 0 P 0 ;0
L 1.90191004 -1.94008002 1.90308002 -1.9401 0 P 0 ;0
L 1.90308002 -1.9401 1.90311004 -1.9401 0 P 0 ;0
L 1.90311004 -1.9401 1.90313996 -1.94011004 0 P 0 ;0
L 1.90841004 -1.97146004 1.91683996 -1.97146004 0 P 0 ;0
L 1.9135 -1.97046004 1.91931004 -1.97046004 0 P 0 ;0
L 1.91655 -1.96946004 1.92131004 -1.96946004 0 P 0 ;0
L 1.91891998 -1.96846004 1.92301004 -1.96846004 0 P 0 ;0
L 1.92088996 -1.96746004 1.9245 -1.96746004 0 P 0 ;0
L 1.92251004 -1.96646004 1.9258 -1.96646004 0 P 0 ;0
L 1.92391004 -1.96546004 1.92696004 -1.96546004 0 P 0 ;0
L 1.92513002 -1.96446004 1.92803002 -1.96446004 0 P 0 ;0
L 1.9262 -1.96346004 1.92898996 -1.96346004 0 P 0 ;0
L 1.92713996 -1.96246004 1.92986004 -1.96246004 0 P 0 ;0
L 1.928 -1.96146004 1.93068996 -1.96146004 0 P 0 ;0
L 1.92878002 -1.96046004 1.93143002 -1.96046004 0 P 0 ;0
L 1.92951004 -1.95946004 1.93216004 -1.95946004 0 P 0 ;0
L 1.93016998 -1.95846004 1.93278996 -1.95846004 0 P 0 ;0
L 1.93078002 -1.95746004 1.93341004 -1.95746004 0 P 0 ;0
L 1.93133002 -1.95646004 1.93396004 -1.95646004 0 P 0 ;0
L 1.93185 -1.95546004 1.93448996 -1.95546004 0 P 0 ;0
L 1.93231004 -1.95446004 1.93495 -1.95446004 0 P 0 ;0
L 1.93275 -1.95346004 1.93541004 -1.95346004 0 P 0 ;0
L 1.93311998 -1.95246004 1.93586004 -1.95246004 0 P 0 ;0
L 1.93348002 -1.95146004 1.93628996 -1.95146004 0 P 0 ;0
L 1.93376998 -1.95046004 1.93666004 -1.95046004 0 P 0 ;0
L 1.93405 -1.94946004 1.93693002 -1.94946004 0 P 0 ;0
L 1.93428002 -1.94846004 1.93715 -1.94846004 0 P 0 ;0
L 1.93446998 -1.94746004 1.93733002 -1.94746004 0 P 0 ;0
L 1.93466004 -1.94646004 1.93743002 -1.94646004 0 P 0 ;0
L 1.93478996 -1.94546004 1.93748996 -1.94546004 0 P 0 ;0
L 1.9349 -1.94446998 1.93751998 -1.94446998 0 P 0 ;0
L 1.93496998 -1.94346004 1.93755 -1.94346004 0 P 0 ;0
L 1.93501998 -1.94246004 1.93758002 -1.94246004 0 P 0 ;0
L 1.93505 -1.94146998 1.93758996 -1.94146998 0 P 0 ;0
L 1.93503002 -1.94046004 1.93755 -1.94046004 0 P 0 ;0
L 1.935 -1.93946004 1.93751998 -1.93946004 0 P 0 ;0
L 1.93491998 -1.93846004 1.93748002 -1.93846004 0 P 0 ;0
L 1.93481004 -1.93746004 1.93738996 -1.93746004 0 P 0 ;0
L 1.93468996 -1.93646004 1.93726998 -1.93646004 0 P 0 ;0
L 1.93451004 -1.93546004 1.93716004 -1.93546004 0 P 0 ;0
L 1.93433002 -1.93446004 1.93703996 -1.93446004 0 P 0 ;0
L 1.93408996 -1.93346004 1.93685 -1.93346004 0 P 0 ;0
L 1.93383002 -1.93246004 1.93666004 -1.93246004 0 P 0 ;0
L 1.93353002 -1.93146004 1.93638996 -1.93146004 0 P 0 ;0
L 1.9332 -1.93046004 1.93611998 -1.93046004 0 P 0 ;0
L 1.93283996 -1.92946004 1.93576998 -1.92946004 0 P 0 ;0
L 1.93241004 -1.92846004 1.93541004 -1.92846004 0 P 0 ;0
L 1.93198996 -1.92746004 1.93498002 -1.92746004 0 P 0 ;0
L 1.93146998 -1.92646004 1.93451004 -1.92646004 0 P 0 ;0
L 1.93096004 -1.92546004 1.93398002 -1.92546004 0 P 0 ;0
L 1.93035 -1.92446998 1.93338002 -1.92446998 0 P 0 ;0
L 1.92973002 -1.92346004 1.93275 -1.92346004 0 P 0 ;0
L 1.92903002 -1.92246004 1.93201004 -1.92246004 0 P 0 ;0
L 1.92831004 -1.92146004 1.93125 -1.92146004 0 P 0 ;0
L 1.92746998 -1.92046004 1.93041004 -1.92046004 0 P 0 ;0
L 1.92661004 -1.91946004 1.92948996 -1.91946004 0 P 0 ;0
L 1.92558996 -1.91846004 1.92851004 -1.91846004 0 P 0 ;0
L 1.9245 -1.91746004 1.92741998 -1.91746004 0 P 0 ;0
L 1.92328996 -1.91646004 1.92621998 -1.91646004 0 P 0 ;0
L 1.92188002 -1.91546004 1.92491998 -1.91546004 0 P 0 ;0
L 1.92026004 -1.91446004 1.92358996 -1.91446004 0 P 0 ;0
L 1.91835 -1.91346004 1.92208002 -1.91346004 0 P 0 ;0
L 1.82446998 -2.08323996 1.87608002 -2.08323996 0 P 0 ;0
L 1.82403002 -2.08223996 1.87601004 -2.08223996 0 P 0 ;0
L 1.8234 -2.08123996 1.87591004 -2.08123996 0 P 0 ;0
L 1.82256004 -2.08023996 1.87578002 -2.08023996 0 P 0 ;0
L 1.82166004 -2.07923996 1.87558996 -2.07923996 0 P 0 ;0
L 1.82061998 -2.07823996 1.87533002 -2.07823996 0 P 0 ;0
L 1.81946004 -2.07723996 1.87498996 -2.07723996 0 P 0 ;0
L 1.81818002 -2.07623996 1.8746 -2.07623996 0 P 0 ;0
L 1.8168 -2.07523996 1.87416998 -2.07523996 0 P 0 ;0
L 1.81541998 -2.07423996 1.87371004 -2.07423996 0 P 0 ;0
L 1.81403002 -2.07323996 1.87316998 -2.07323996 0 P 0 ;0
L 1.81265 -2.07223996 1.87261004 -2.07223996 0 P 0 ;0
L 1.81126998 -2.07123996 1.87196004 -2.07123996 0 P 0 ;0
L 1.80986004 -2.07023996 1.87128002 -2.07023996 0 P 0 ;0
L 1.80843996 -2.06923996 1.87051998 -2.06923996 0 P 0 ;0
L 1.80703002 -2.06823996 1.8697 -2.06823996 0 P 0 ;0
L 1.80561004 -2.06723996 1.86883002 -2.06723996 0 P 0 ;0
L 1.8042 -2.06623996 1.86796004 -2.06623996 0 P 0 ;0
L 1.80278002 -2.06523996 1.86705 -2.06523996 0 P 0 ;0
L 1.80136004 -2.06423996 1.86608002 -2.06423996 0 P 0 ;0
L 1.79995 -2.06323996 1.8651 -2.06323996 0 P 0 ;0
L 1.79865 -2.06223996 1.86411004 -2.06223996 0 P 0 ;0
L 1.79735 -2.06123996 1.86301998 -2.06123996 0 P 0 ;0
L 1.79605 -2.06023996 1.86193002 -2.06023996 0 P 0 ;0
L 1.79475 -2.05923996 1.86083996 -2.05923996 0 P 0 ;0
L 1.79345 -2.05823996 1.85966998 -2.05823996 0 P 0 ;0
L 1.79215 -2.05723996 1.85846004 -2.05723996 0 P 0 ;0
L 1.79088002 -2.05623996 1.85726004 -2.05623996 0 P 0 ;0
L 1.78971998 -2.05523996 1.85598996 -2.05523996 0 P 0 ;0
L 1.78856004 -2.05423996 1.85461998 -2.05423996 0 P 0 ;0
L 1.7874 -2.05323996 1.85326004 -2.05323996 0 P 0 ;0
L 1.78623002 -2.05223996 1.8519 -2.05223996 0 P 0 ;0
L 1.78506998 -2.05123996 1.85053996 -2.05123996 0 P 0 ;0
L 1.78398002 -2.05023996 1.84918002 -2.05023996 0 P 0 ;0
L 1.783 -2.04923996 1.84781004 -2.04923996 0 P 0 ;0
L 1.87086004 -2.03023996 1.87535 -2.03023996 0 P 0 ;0
L 1.91633002 -1.91473002 1.9183 -1.91565 0 P 0 ;0
L 1.9183 -1.91565 1.92018996 -1.91673002 0 P 0 ;0
L 1.92018996 -1.91673002 1.92196998 -1.91796998 0 P 0 ;0
L 1.92196998 -1.91796998 1.92365 -1.91936004 0 P 0 ;0
L 1.92365 -1.91936004 1.9252 -1.92088002 0 P 0 ;0
L 1.9252 -1.92088002 1.92661004 -1.92253996 0 P 0 ;0
L 1.92661004 -1.92253996 1.92795 -1.92436998 0 P 0 ;0
L 1.92795 -1.92436998 1.92913996 -1.9263 0 P 0 ;0
L 1.92913996 -1.9263 1.93018002 -1.92831998 0 P 0 ;0
L 1.93018002 -1.92831998 1.93106998 -1.93041004 0 P 0 ;0
L 1.93106998 -1.93041004 1.93178996 -1.93256004 0 P 0 ;0
L 1.93178996 -1.93256004 1.93236004 -1.93476004 0 P 0 ;0
L 1.93236004 -1.93476004 1.93276004 -1.93703996 0 P 0 ;0
L 1.93276004 -1.93703996 1.93298996 -1.93933996 0 P 0 ;0
L 1.93298996 -1.93933996 1.93306004 -1.94165 0 P 0 ;0
L 1.93306004 -1.94165 1.93295 -1.94396998 0 P 0 ;0
L 1.93295 -1.94396998 1.93268002 -1.94626004 0 P 0 ;0
L 1.93268002 -1.94626004 1.93223002 -1.94853996 0 P 0 ;0
L 1.93223002 -1.94853996 1.93161998 -1.95071998 0 P 0 ;0
L 1.93161998 -1.95071998 1.93085 -1.95285 0 P 0 ;0
L 1.93085 -1.95285 1.92991004 -1.95491004 0 P 0 ;0
L 1.92991004 -1.95491004 1.92881004 -1.95688996 0 P 0 ;0
L 1.92881004 -1.95688996 1.92756004 -1.95878002 0 P 0 ;0
L 1.92756004 -1.95878002 1.92616004 -1.96056998 0 P 0 ;0
L 1.92616004 -1.96056998 1.92493996 -1.9619 0 P 0 ;0
L 1.92493996 -1.9619 1.92361998 -1.96313996 0 P 0 ;0
L 1.92361998 -1.96313996 1.9222 -1.96426004 0 P 0 ;0
L 1.9222 -1.96426004 1.9207 -1.96526998 0 P 0 ;0
L 1.9207 -1.96526998 1.91911004 -1.96616998 0 P 0 ;0
L 1.91911004 -1.96616998 1.91686998 -1.96721004 0 P 0 ;0
L 1.91686998 -1.96721004 1.91456004 -1.96806998 0 P 0 ;0
L 1.91456004 -1.96806998 1.91218996 -1.96876004 0 P 0 ;0
L 1.91218996 -1.96876004 1.90975 -1.96926998 0 P 0 ;0
L 1.90975 -1.96926998 1.90725 -1.9696 0 P 0 ;0
L 1.90725 -1.9696 1.90473002 -1.96973996 0 P 0 ;0
L 1.90473002 -1.96973996 1.9022 -1.96968996 0 P 0 ;0
L 1.9022 -1.96968996 1.89966998 -1.96945 0 P 0 ;0
L 1.89966998 -1.96945 1.89778002 -1.96913002 0 P 0 ;0
L 1.89778002 -1.96913002 1.89591998 -1.96868996 0 P 0 ;0
L 1.89591998 -1.96868996 1.8941 -1.96811004 0 P 0 ;0
L 1.8941 -1.96811004 1.89231004 -1.96741004 0 P 0 ;0
L 1.89231004 -1.96741004 1.89058002 -1.96658002 0 P 0 ;0
L 1.89058002 -1.96658002 1.88875 -1.96553996 0 P 0 ;0
L 1.88875 -1.96553996 1.88698996 -1.96435 0 P 0 ;0
L 1.88698996 -1.96435 1.88533996 -1.96303002 0 P 0 ;0
L 1.88533996 -1.96303002 1.88378996 -1.9616 0 P 0 ;0
L 1.88378996 -1.9616 1.88235 -1.96003996 0 P 0 ;0
L 1.88235 -1.96003996 1.88103002 -1.95838996 0 P 0 ;0
L 1.88103002 -1.95838996 1.87983996 -1.95663002 0 P 0 ;0
L 1.87983996 -1.95663002 1.87861998 -1.95446998 0 P 0 ;0
L 1.87861998 -1.95446998 1.87758002 -1.9522 0 P 0 ;0
L 1.87758002 -1.9522 1.87673996 -1.94986004 0 P 0 ;0
L 1.87673996 -1.94986004 1.8761 -1.94745 0 P 0 ;0
L 1.8761 -1.94745 1.87568002 -1.945 0 P 0 ;0
L 1.87568002 -1.945 1.87546004 -1.94248996 0 P 0 ;0
L 1.87546004 -1.94248996 1.87546004 -1.93998996 0 P 0 ;0
L 1.87546004 -1.93998996 1.87566998 -1.93748996 0 P 0 ;0
L 1.87566998 -1.93748996 1.87608996 -1.93501998 0 P 0 ;0
L 1.87608996 -1.93501998 1.87671998 -1.9326 0 P 0 ;0
L 1.87671998 -1.9326 1.87755 -1.93023002 0 P 0 ;0
L 1.87755 -1.93023002 1.8786 -1.92793002 0 P 0 ;0
L 1.8786 -1.92793002 1.87981998 -1.92575 0 P 0 ;0
L 1.87981998 -1.92575 1.88123002 -1.92368002 0 P 0 ;0
L 1.88123002 -1.92368002 1.88281004 -1.92175 0 P 0 ;0
L 1.88281004 -1.92175 1.88455 -1.91996004 0 P 0 ;0
L 1.88455 -1.91996004 1.88643002 -1.91831998 0 P 0 ;0
L 1.88643002 -1.91831998 1.88845 -1.91686004 0 P 0 ;0
L 1.88845 -1.91686004 1.88986998 -1.91598996 0 P 0 ;0
L 1.88986998 -1.91598996 1.89135 -1.91523002 0 P 0 ;0
L 1.89135 -1.91523002 1.89288002 -1.91458996 0 P 0 ;0
L 1.89288002 -1.91458996 1.89446998 -1.91406004 0 P 0 ;0
L 1.89446998 -1.91406004 1.89688996 -1.91343996 0 P 0 ;0
L 1.89688996 -1.91343996 1.89935 -1.91298996 0 P 0 ;0
L 1.89935 -1.91298996 1.90183996 -1.91271004 0 P 0 ;0
L 1.90183996 -1.91271004 1.9044 -1.91261004 0 P 0 ;0
L 1.9044 -1.91261004 1.90695 -1.91268002 0 P 0 ;0
L 1.90695 -1.91268002 1.90948996 -1.91291998 0 P 0 ;0
L 1.90948996 -1.91291998 1.91181998 -1.91331998 0 P 0 ;0
L 1.91181998 -1.91331998 1.91408996 -1.91393002 0 P 0 ;0
L 1.91408996 -1.91393002 1.91633002 -1.91473002 0 P 0 ;0
L 1.89498002 -1.90801998 1.8922 -1.90893002 0 P 0 ;0
L 1.8922 -1.90893002 1.88948002 -1.91003002 0 P 0 ;0
L 1.88948002 -1.91003002 1.88686004 -1.91133002 0 P 0 ;0
L 1.88686004 -1.91133002 1.88431004 -1.91283996 0 P 0 ;0
L 1.88431004 -1.91283996 1.88201004 -1.91446004 0 P 0 ;0
L 1.88201004 -1.91446004 1.87985 -1.91626998 0 P 0 ;0
L 1.87985 -1.91626998 1.87785 -1.91826004 0 P 0 ;0
L 1.87785 -1.91826004 1.87601998 -1.92041004 0 P 0 ;0
L 1.87601998 -1.92041004 1.87441004 -1.92266998 0 P 0 ;0
L 1.87441004 -1.92266998 1.87298996 -1.92505 0 P 0 ;0
L 1.87298996 -1.92505 1.87178002 -1.92756004 0 P 0 ;0
L 1.87178002 -1.92756004 1.87078996 -1.93015 0 P 0 ;0
L 1.87078996 -1.93015 1.87 -1.93286998 0 P 0 ;0
L 1.87 -1.93286998 1.86943996 -1.93563996 0 P 0 ;0
L 1.86943996 -1.93563996 1.86908996 -1.93845 0 P 0 ;0
L 1.86908996 -1.93845 1.86898002 -1.94128996 0 P 0 ;0
L 1.86898002 -1.94128996 1.86911998 -1.94485 0 P 0 ;0
L 1.86911998 -1.94485 1.86953996 -1.94841004 0 P 0 ;0
L 1.86953996 -1.94841004 1.86996004 -1.95048996 0 P 0 ;0
L 1.86996004 -1.95048996 1.87053002 -1.95251998 0 P 0 ;0
L 1.87053002 -1.95251998 1.87125 -1.95451998 0 P 0 ;0
L 1.87125 -1.95451998 1.87211004 -1.95643002 0 P 0 ;0
L 1.87211004 -1.95643002 1.8731 -1.95826004 0 P 0 ;0
L 1.8731 -1.95826004 1.87423996 -1.96001998 0 P 0 ;0
L 1.87423996 -1.96001998 1.87636998 -1.96278996 0 P 0 ;0
L 1.87636998 -1.96278996 1.87871998 -1.96536998 0 P 0 ;0
L 1.87871998 -1.96536998 1.88145 -1.96788002 0 P 0 ;0
L 1.88145 -1.96788002 1.88436998 -1.97015 0 P 0 ;0
L 1.88436998 -1.97015 1.88621004 -1.97135 0 P 0 ;0
L 1.88621004 -1.97135 1.88813002 -1.97238002 0 P 0 ;0
L 1.88813002 -1.97238002 1.89013002 -1.97326004 0 P 0 ;0
L 1.89013002 -1.97326004 1.89228002 -1.97398996 0 P 0 ;0
L 1.89228002 -1.97398996 1.89446998 -1.97455 0 P 0 ;0
L 1.89446998 -1.97455 1.89671004 -1.97493996 0 P 0 ;0
L 1.89671004 -1.97493996 1.90076998 -1.97533996 0 P 0 ;0
L 1.90076998 -1.97533996 1.90485 -1.97546998 0 P 0 ;0
L 1.90485 -1.97546998 1.90821004 -1.97531998 0 P 0 ;0
L 1.90821004 -1.97531998 1.91153996 -1.97488996 0 P 0 ;0
L 1.91153996 -1.97488996 1.91481998 -1.97418996 0 P 0 ;0
L 1.91481998 -1.97418996 1.9171 -1.9735 0 P 0 ;0
L 1.9171 -1.9735 1.91933002 -1.97266004 0 P 0 ;0
L 1.91933002 -1.97266004 1.92148002 -1.97166004 0 P 0 ;0
L 1.92148002 -1.97166004 1.92356998 -1.97048996 0 P 0 ;0
L 1.92356998 -1.97048996 1.92553996 -1.96918996 0 P 0 ;0
L 1.92553996 -1.96918996 1.92741004 -1.96773996 0 P 0 ;0
L 1.92741004 -1.96773996 1.92916004 -1.96616998 0 P 0 ;0
L 1.92916004 -1.96616998 1.93081004 -1.96446004 0 P 0 ;0
L 1.93081004 -1.96446004 1.93236998 -1.96256998 0 P 0 ;0
L 1.93236998 -1.96256998 1.93381004 -1.96058996 0 P 0 ;0
L 1.93381004 -1.96058996 1.93511998 -1.95851004 0 P 0 ;0
L 1.93511998 -1.95851004 1.93628996 -1.95633996 0 P 0 ;0
L 1.93628996 -1.95633996 1.93803996 -1.95251998 0 P 0 ;0
L 1.93803996 -1.95251998 1.93858002 -1.95101998 0 P 0 ;0
L 1.93858002 -1.95101998 1.93898996 -1.94948002 0 P 0 ;0
L 1.93898996 -1.94948002 1.93928996 -1.94786998 0 P 0 ;0
L 1.93928996 -1.94786998 1.93946004 -1.94625 0 P 0 ;0
L 1.93946004 -1.94625 1.9396 -1.94178002 0 P 0 ;0
L 1.9396 -1.94178002 1.93946004 -1.93803996 0 P 0 ;0
L 1.93946004 -1.93803996 1.93905 -1.9343 0 P 0 ;0
L 1.93905 -1.9343 1.93863996 -1.93213996 0 P 0 ;0
L 1.93863996 -1.93213996 1.93808002 -1.93001998 0 P 0 ;0
L 1.93808002 -1.93001998 1.93736004 -1.92795 0 P 0 ;0
L 1.93736004 -1.92795 1.93653002 -1.92601004 0 P 0 ;0
L 1.93653002 -1.92601004 1.93555 -1.92415 0 P 0 ;0
L 1.93555 -1.92415 1.93441998 -1.92236004 0 P 0 ;0
L 1.93441998 -1.92236004 1.9331 -1.92056004 0 P 0 ;0
L 1.9331 -1.92056004 1.93166998 -1.91885 0 P 0 ;0
L 1.93166998 -1.91885 1.93011998 -1.91723002 0 P 0 ;0
L 1.93011998 -1.91723002 1.92896004 -1.91615 0 P 0 ;0
L 1.92896004 -1.91615 1.92775 -1.91511004 0 P 0 ;0
L 1.92775 -1.91511004 1.92493002 -1.91295 0 P 0 ;0
L 1.92493002 -1.91295 1.9221 -1.91108002 0 P 0 ;0
L 1.9221 -1.91108002 1.92095 -1.91043002 0 P 0 ;0
L 1.92095 -1.91043002 1.91975 -1.90985 0 P 0 ;0
L 1.91975 -1.90985 1.91796004 -1.90913996 0 P 0 ;0
L 1.91796004 -1.90913996 1.91613002 -1.90856004 0 P 0 ;0
L 1.91613002 -1.90856004 1.91423996 -1.9081 0 P 0 ;0
L 1.91423996 -1.9081 1.91086004 -1.90751998 0 P 0 ;0
L 1.91086004 -1.90751998 1.90743002 -1.90716004 0 P 0 ;0
L 1.90743002 -1.90716004 1.90401004 -1.90701004 0 P 0 ;0
L 1.90401004 -1.90701004 1.90058002 -1.90708002 0 P 0 ;0
L 1.90058002 -1.90708002 1.8987 -1.90726004 0 P 0 ;0
L 1.8987 -1.90726004 1.89683002 -1.90756998 0 P 0 ;0
L 1.89683002 -1.90756998 1.89498002 -1.90801998 0 P 0 ;0
L 1.86643002 -2.02923996 1.87525 -2.02923996 0 P 0 ;0
L 1.86176998 -2.02823996 1.87515 -2.02823996 0 P 0 ;0
L 1.85588996 -2.02723996 1.87505 -2.02723996 0 P 0 ;0
L 1.78365 -2.00523996 1.87281004 -2.00523996 0 P 0 ;0
L 1.78451004 -2.00423996 1.87271004 -2.00423996 0 P 0 ;0
L 1.78546998 -2.00323996 1.87261004 -2.00323996 0 P 0 ;0
L 1.78655 -2.00223996 1.8725 -2.00223996 0 P 0 ;0
L 1.78776004 -2.00123996 1.8724 -2.00123996 0 P 0 ;0
L 1.78915 -2.00023996 1.8723 -2.00023996 0 P 0 ;0
L 1.79078996 -1.99923996 1.8722 -1.99923996 0 P 0 ;0
L 1.79263996 -1.99823996 1.87208996 -1.99823996 0 P 0 ;0
L 1.79458996 -1.99723996 1.87198996 -1.99723996 0 P 0 ;0
L 1.79686998 -1.99623996 1.87188002 -1.99623996 0 P 0 ;0
L 1.79946004 -1.99523996 1.87178002 -1.99523996 0 P 0 ;0
L 1.80231004 -1.99423996 1.86961998 -1.99423996 0 P 0 ;0
L 1.80596004 -1.99323996 1.86218002 -1.99323996 0 P 0 ;0
L 1.81051004 -1.99223996 1.85398002 -1.99223996 0 P 0 ;0
L 1.81676004 -1.99123996 1.84395 -1.99123996 0 P 0 ;0
L 1.87786998 -1.96146004 1.88093996 -1.96146004 0 P 0 ;0
L 1.8771 -1.96046004 1.88013002 -1.96046004 0 P 0 ;0
L 1.87633996 -1.95946004 1.87933996 -1.95946004 0 P 0 ;0
L 1.87561998 -1.95846004 1.87866998 -1.95846004 0 P 0 ;0
L 1.87496998 -1.95746004 1.87801998 -1.95746004 0 P 0 ;0
L 1.8744 -1.95646004 1.87745 -1.95646004 0 P 0 ;0
L 1.87386998 -1.95546004 1.87688002 -1.95546004 0 P 0 ;0
L 1.87341998 -1.95446004 1.87641998 -1.95446004 0 P 0 ;0
L 1.87298996 -1.95346004 1.87596004 -1.95346004 0 P 0 ;0
L 1.87263002 -1.95246004 1.87555 -1.95246004 0 P 0 ;0
L 1.87231004 -1.95146004 1.87518996 -1.95146004 0 P 0 ;0
L 1.87203002 -1.95046004 1.87483002 -1.95046004 0 P 0 ;0
L 1.87178996 -1.94946004 1.87456998 -1.94946004 0 P 0 ;0
L 1.87158996 -1.94846004 1.87431004 -1.94846004 0 P 0 ;0
L 1.87143996 -1.94746004 1.87408002 -1.94746004 0 P 0 ;0
L 1.87133002 -1.94646004 1.8739 -1.94646004 0 P 0 ;0
L 1.87121004 -1.94546004 1.87373002 -1.94546004 0 P 0 ;0
L 1.8711 -1.94446998 1.87361998 -1.94446998 0 P 0 ;0
L 1.87106998 -1.94346004 1.87353996 -1.94346004 0 P 0 ;0
L 1.87103002 -1.94246004 1.87346004 -1.94246004 0 P 0 ;0
L 1.87098996 -1.94146998 1.87346004 -1.94146998 0 P 0 ;0
L 1.87101004 -1.94046004 1.87346004 -1.94046004 0 P 0 ;0
L 1.87106004 -1.93946004 1.87348996 -1.93946004 0 P 0 ;0
L 1.87111004 -1.93846004 1.87358002 -1.93846004 0 P 0 ;0
L 1.87123002 -1.93746004 1.87366004 -1.93746004 0 P 0 ;0
L 1.87135 -1.93646004 1.87381998 -1.93646004 0 P 0 ;0
L 1.87151004 -1.93546004 1.87398996 -1.93546004 0 P 0 ;0
L 1.87171998 -1.93446004 1.87416998 -1.93446004 0 P 0 ;0
L 1.87191998 -1.93346004 1.87443002 -1.93346004 0 P 0 ;0
L 1.8722 -1.93246004 1.87468996 -1.93246004 0 P 0 ;0
L 1.87248996 -1.93146004 1.875 -1.93146004 0 P 0 ;0
L 1.87281004 -1.93046004 1.87535 -1.93046004 0 P 0 ;0
L 1.87318996 -1.92946004 1.87571004 -1.92946004 0 P 0 ;0
L 1.87356998 -1.92846004 1.87616004 -1.92846004 0 P 0 ;0
L 1.87405 -1.92746004 1.87661004 -1.92746004 0 P 0 ;0
L 1.87453002 -1.92646004 1.87711998 -1.92646004 0 P 0 ;0
L 1.87506998 -1.92546004 1.87768996 -1.92546004 0 P 0 ;0
L 1.87566004 -1.92446998 1.87826998 -1.92446998 0 P 0 ;0
L 1.87628996 -1.92346004 1.87896004 -1.92346004 0 P 0 ;0
L 1.87701004 -1.92246004 1.87963996 -1.92246004 0 P 0 ;0
L 1.87775 -1.92146004 1.88046004 -1.92146004 0 P 0 ;0
L 1.90483996 -1.97346004 1.9009 -1.97333996 0 P 0 ;0
L 1.9009 -1.97333996 1.89698002 -1.97295 0 P 0 ;0
L 1.89698002 -1.97295 1.89488996 -1.97258996 0 P 0 ;0
L 1.89488996 -1.97258996 1.89285 -1.97206998 0 P 0 ;0
L 1.89285 -1.97206998 1.89086004 -1.97138996 0 P 0 ;0
L 1.89086004 -1.97138996 1.889 -1.97058002 0 P 0 ;0
L 1.889 -1.97058002 1.88723002 -1.96961998 0 P 0 ;0
L 1.88723002 -1.96961998 1.88553002 -1.96851998 0 P 0 ;0
L 1.88553002 -1.96851998 1.88273996 -1.96636004 0 P 0 ;0
L 1.88273996 -1.96636004 1.88013996 -1.96396004 0 P 0 ;0
L 1.88013996 -1.96396004 1.8779 -1.9615 0 P 0 ;0
L 1.8779 -1.9615 1.87588002 -1.95886998 0 P 0 ;0
L 1.87588002 -1.95886998 1.87483002 -1.95723996 0 P 0 ;0
L 1.87483002 -1.95723996 1.8739 -1.95553996 0 P 0 ;0
L 1.8739 -1.95553996 1.87311004 -1.95376998 0 P 0 ;0
L 1.87311004 -1.95376998 1.87243002 -1.95191004 0 P 0 ;0
L 1.87243002 -1.95191004 1.8719 -1.95001998 0 P 0 ;0
L 1.8719 -1.95001998 1.87151998 -1.9481 0 P 0 ;0
L 1.87151998 -1.9481 1.87111004 -1.94468996 0 P 0 ;0
L 1.87111004 -1.94468996 1.87098002 -1.94128996 0 P 0 ;0
L 1.87098002 -1.94128996 1.87108996 -1.93861004 0 P 0 ;0
L 1.87108996 -1.93861004 1.87141004 -1.93596998 0 P 0 ;0
L 1.87141004 -1.93596998 1.87195 -1.93335 0 P 0 ;0
L 1.87195 -1.93335 1.87268996 -1.93078996 0 P 0 ;0
L 1.87268996 -1.93078996 1.87361998 -1.92835 0 P 0 ;0
L 1.87361998 -1.92835 1.87475 -1.926 0 P 0 ;0
L 1.87475 -1.926 1.87608996 -1.92376004 0 P 0 ;0
L 1.87608996 -1.92376004 1.8776 -1.92163996 0 P 0 ;0
L 1.8776 -1.92163996 1.87931998 -1.91961998 0 P 0 ;0
L 1.87931998 -1.91961998 1.8812 -1.91775 0 P 0 ;0
L 1.8812 -1.91775 1.88323002 -1.91605 0 P 0 ;0
L 1.88323002 -1.91605 1.8854 -1.91451998 0 P 0 ;0
L 1.8854 -1.91451998 1.88781004 -1.91308996 0 P 0 ;0
L 1.88781004 -1.91308996 1.89031004 -1.91186004 0 P 0 ;0
L 1.89031004 -1.91186004 1.89288002 -1.9108 0 P 0 ;0
L 1.89288002 -1.9108 1.89553002 -1.90995 0 P 0 ;0
L 1.89553002 -1.90995 1.89723002 -1.90953002 0 P 0 ;0
L 1.89723002 -1.90953002 1.89896004 -1.90923996 0 P 0 ;0
L 1.89896004 -1.90923996 1.90068996 -1.90908002 0 P 0 ;0
L 1.90068996 -1.90908002 1.90398996 -1.90901004 0 P 0 ;0
L 1.90398996 -1.90901004 1.90728002 -1.90915 0 P 0 ;0
L 1.90728002 -1.90915 1.91058996 -1.90951004 0 P 0 ;0
L 1.91058996 -1.90951004 1.91383996 -1.91006004 0 P 0 ;0
L 1.91383996 -1.91006004 1.91558996 -1.91048996 0 P 0 ;0
L 1.91558996 -1.91048996 1.91728996 -1.91101998 0 P 0 ;0
L 1.91728996 -1.91101998 1.91895 -1.91168002 0 P 0 ;0
L 1.91895 -1.91168002 1.92001998 -1.9122 0 P 0 ;0
L 1.92001998 -1.9122 1.92105 -1.91278996 0 P 0 ;0
L 1.92105 -1.91278996 1.92376998 -1.91458002 0 P 0 ;0
L 1.92376998 -1.91458002 1.92648996 -1.91666998 0 P 0 ;0
L 1.92648996 -1.91666998 1.92763002 -1.91763996 0 P 0 ;0
L 1.92763002 -1.91763996 1.92871004 -1.91865 0 P 0 ;0
L 1.92871004 -1.91865 1.93018002 -1.92018996 0 P 0 ;0
L 1.93018002 -1.92018996 1.93153002 -1.9218 0 P 0 ;0
L 1.93153002 -1.9218 1.93276998 -1.92348996 0 P 0 ;0
L 1.93276998 -1.92348996 1.93381004 -1.92515 0 P 0 ;0
L 1.93381004 -1.92515 1.93471998 -1.92686998 0 P 0 ;0
L 1.93471998 -1.92686998 1.9355 -1.92866998 0 P 0 ;0
L 1.9355 -1.92866998 1.93616998 -1.93061004 0 P 0 ;0
L 1.93616998 -1.93061004 1.93668996 -1.93258002 0 P 0 ;0
L 1.93668996 -1.93258002 1.93706998 -1.93458996 0 P 0 ;0
L 1.93706998 -1.93458996 1.93746998 -1.93818996 0 P 0 ;0
L 1.93746998 -1.93818996 1.9376 -1.94178996 0 P 0 ;0
L 1.9376 -1.94178996 1.93746004 -1.94611004 0 P 0 ;0
L 1.93746004 -1.94611004 1.93731004 -1.94758996 0 P 0 ;0
L 1.93731004 -1.94758996 1.93705 -1.94903996 0 P 0 ;0
L 1.93705 -1.94903996 1.93666998 -1.95041998 0 P 0 ;0
L 1.93666998 -1.95041998 1.93618002 -1.95176004 0 P 0 ;0
L 1.93618002 -1.95176004 1.9345 -1.95545 0 P 0 ;0
L 1.9345 -1.95545 1.93338996 -1.9575 0 P 0 ;0
L 1.93338996 -1.9575 1.93216004 -1.95946998 0 P 0 ;0
L 1.93216004 -1.95946998 1.93078996 -1.96133996 0 P 0 ;0
L 1.93078996 -1.96133996 1.92931004 -1.96311998 0 P 0 ;0
L 1.92931004 -1.96311998 1.92776998 -1.96473002 0 P 0 ;0
L 1.92776998 -1.96473002 1.92613002 -1.96621004 0 P 0 ;0
L 1.92613002 -1.96621004 1.92438002 -1.96756004 0 P 0 ;0
L 1.92438002 -1.96756004 1.92253002 -1.96878002 0 P 0 ;0
L 1.92253002 -1.96878002 1.92056998 -1.96986998 0 P 0 ;0
L 1.92056998 -1.96986998 1.91855 -1.97081998 0 P 0 ;0
L 1.91855 -1.97081998 1.91646004 -1.97161004 0 P 0 ;0
L 1.91646004 -1.97161004 1.91433002 -1.97223996 0 P 0 ;0
L 1.91433002 -1.97223996 1.9112 -1.97291004 0 P 0 ;0
L 1.9112 -1.97291004 1.90803996 -1.97331998 0 P 0 ;0
L 1.90803996 -1.97331998 1.90483996 -1.97346004 0 P 0 ;0
L 1.90476004 -1.97173996 1.9048 -1.97173996 0 P 0 ;0
L 1.9048 -1.97173996 1.90483996 -1.97173002 0 P 0 ;0
L 1.90483996 -1.97173002 1.90736004 -1.9716 0 P 0 ;0
L 1.90736004 -1.9716 1.9074 -1.97158996 0 P 0 ;0
L 1.9074 -1.97158996 1.90746998 -1.97158996 0 P 0 ;0
L 1.90746998 -1.97158996 1.90751004 -1.97158002 0 P 0 ;0
L 1.90751004 -1.97158002 1.91001004 -1.97126004 0 P 0 ;0
L 1.91001004 -1.97126004 1.91005 -1.97125 0 P 0 ;0
L 1.91005 -1.97125 1.91008002 -1.97123996 0 P 0 ;0
L 1.91008002 -1.97123996 1.91011998 -1.97123996 0 P 0 ;0
L 1.91011998 -1.97123996 1.91016004 -1.97123002 0 P 0 ;0
L 1.91016004 -1.97123002 1.9126 -1.97071998 0 P 0 ;0
L 1.9126 -1.97071998 1.9126 -1.97071004 0 P 0 ;0
L 1.9126 -1.97071004 1.91266998 -1.97071004 0 P 0 ;0
L 1.91266998 -1.97071004 1.91271004 -1.97068996 0 P 0 ;0
L 1.91271004 -1.97068996 1.91275 -1.97068002 0 P 0 ;0
L 1.91275 -1.97068002 1.91511998 -1.96998996 0 P 0 ;0
L 1.91511998 -1.96998996 1.91515 -1.96998996 0 P 0 ;0
L 1.91515 -1.96998996 1.91518996 -1.96996998 0 P 0 ;0
L 1.91518996 -1.96996998 1.91523002 -1.96996004 0 P 0 ;0
L 1.91523002 -1.96996004 1.91526004 -1.96995 0 P 0 ;0
L 1.91526004 -1.96995 1.91756998 -1.96908002 0 P 0 ;0
L 1.91756998 -1.96908002 1.91761004 -1.96906998 0 P 0 ;0
L 1.91761004 -1.96906998 1.91768002 -1.96903996 0 P 0 ;0
L 1.91768002 -1.96903996 1.91771004 -1.96901998 0 P 0 ;0
L 1.91771004 -1.96901998 1.91995 -1.96798002 0 P 0 ;0
L 1.91995 -1.96798002 1.92001998 -1.96795 0 P 0 ;0
L 1.92001998 -1.96795 1.92005 -1.96793002 0 P 0 ;0
L 1.92005 -1.96793002 1.92008996 -1.96791004 0 P 0 ;0
L 1.92008996 -1.96791004 1.92168002 -1.96701998 0 P 0 ;0
L 1.92168002 -1.96701998 1.92171998 -1.967 0 P 0 ;0
L 1.92171998 -1.967 1.92175 -1.96698002 0 P 0 ;0
L 1.92175 -1.96698002 1.92178996 -1.96695 0 P 0 ;0
L 1.92178996 -1.96695 1.92181998 -1.96693002 0 P 0 ;0
L 1.92181998 -1.96693002 1.92331998 -1.96591998 0 P 0 ;0
L 1.92331998 -1.96591998 1.92336004 -1.9659 0 P 0 ;0
L 1.92336004 -1.9659 1.92341998 -1.96586004 0 P 0 ;0
L 1.92341998 -1.96586004 1.92345 -1.96583002 0 P 0 ;0
L 1.92345 -1.96583002 1.92486004 -1.9647 0 P 0 ;0
L 1.92486004 -1.9647 1.92493002 -1.96465 0 P 0 ;0
L 1.92493002 -1.96465 1.92496004 -1.96463002 0 P 0 ;0
L 1.92496004 -1.96463002 1.92498996 -1.9646 0 P 0 ;0
L 1.92498996 -1.9646 1.92631004 -1.96336998 0 P 0 ;0
L 1.92631004 -1.96336998 1.9264 -1.96328002 0 P 0 ;0
L 1.9264 -1.96328002 1.92641998 -1.96325 0 P 0 ;0
L 1.92641998 -1.96325 1.92763996 -1.96191998 0 P 0 ;0
L 1.92763996 -1.96191998 1.92766998 -1.96188996 0 P 0 ;0
L 1.92766998 -1.96188996 1.92768996 -1.96186004 0 P 0 ;0
L 1.92768996 -1.96186004 1.92771998 -1.96183002 0 P 0 ;0
L 1.92771998 -1.96183002 1.92773996 -1.9618 0 P 0 ;0
L 1.92773996 -1.9618 1.92913996 -1.96001004 0 P 0 ;0
L 1.92913996 -1.96001004 1.92918996 -1.95995 0 P 0 ;0
L 1.92918996 -1.95995 1.92921004 -1.95991004 0 P 0 ;0
L 1.92921004 -1.95991004 1.92923002 -1.95988002 0 P 0 ;0
L 1.92923002 -1.95988002 1.93048002 -1.95798996 0 P 0 ;0
L 1.93048002 -1.95798996 1.93051998 -1.95793002 0 P 0 ;0
L 1.93051998 -1.95793002 1.93053996 -1.95788996 0 P 0 ;0
L 1.93053996 -1.95788996 1.93056004 -1.95786004 0 P 0 ;0
L 1.93056004 -1.95786004 1.93166004 -1.95588002 0 P 0 ;0
L 1.93166004 -1.95588002 1.93171004 -1.95576998 0 P 0 ;0
L 1.93171004 -1.95576998 1.93173002 -1.95573996 0 P 0 ;0
L 1.93173002 -1.95573996 1.93266998 -1.95366998 0 P 0 ;0
L 1.93266998 -1.95366998 1.93271004 -1.95356998 0 P 0 ;0
L 1.93271004 -1.95356998 1.93273002 -1.95353002 0 P 0 ;0
L 1.93273002 -1.95353002 1.9335 -1.9514 0 P 0 ;0
L 1.9335 -1.9514 1.93351004 -1.95136998 0 P 0 ;0
L 1.93351004 -1.95136998 1.93353002 -1.95133002 0 P 0 ;0
L 1.93353002 -1.95133002 1.93355 -1.95125 0 P 0 ;0
L 1.93355 -1.95125 1.93416004 -1.94906998 0 P 0 ;0
L 1.93416004 -1.94906998 1.93416998 -1.94903002 0 P 0 ;0
L 1.93416998 -1.94903002 1.93418002 -1.949 0 P 0 ;0
L 1.93418002 -1.949 1.93418002 -1.94896004 0 P 0 ;0
L 1.93418002 -1.94896004 1.93418996 -1.94891998 0 P 0 ;0
L 1.93418996 -1.94891998 1.93463996 -1.94665 0 P 0 ;0
L 1.93463996 -1.94665 1.93463996 -1.94661004 0 P 0 ;0
L 1.93463996 -1.94661004 1.93465 -1.94656998 0 P 0 ;0
L 1.93465 -1.94656998 1.93466004 -1.9465 0 P 0 ;0
L 1.93466004 -1.9465 1.93493996 -1.9442 0 P 0 ;0
L 1.93493996 -1.9442 1.93493996 -1.94413002 0 P 0 ;0
L 1.93493996 -1.94413002 1.93495 -1.94408996 0 P 0 ;0
L 1.93495 -1.94408996 1.93495 -1.94406004 0 P 0 ;0
L 1.93495 -1.94406004 1.93505 -1.94173996 0 P 0 ;0
L 1.93505 -1.94173996 1.93506004 -1.94171004 0 P 0 ;0
L 1.93506004 -1.94171004 1.93506004 -1.9416 0 P 0 ;0
L 1.93506004 -1.9416 1.93498996 -1.93928996 0 P 0 ;0
L 1.93498996 -1.93928996 1.93498996 -1.93921004 0 P 0 ;0
L 1.93498996 -1.93921004 1.93498002 -1.93913996 0 P 0 ;0
L 1.93498002 -1.93913996 1.93475 -1.93683996 0 P 0 ;0
L 1.93475 -1.93683996 1.93473996 -1.93676998 0 P 0 ;0
L 1.93473996 -1.93676998 1.93473002 -1.93673002 0 P 0 ;0
L 1.93473002 -1.93673002 1.93473002 -1.93668996 0 P 0 ;0
L 1.93473002 -1.93668996 1.93433002 -1.93441004 0 P 0 ;0
L 1.93433002 -1.93441004 1.93431998 -1.93436998 0 P 0 ;0
L 1.93431998 -1.93436998 1.93431004 -1.93433996 0 P 0 ;0
L 1.93431004 -1.93433996 1.93428996 -1.93426004 0 P 0 ;0
L 1.93428996 -1.93426004 1.93373002 -1.93206004 0 P 0 ;0
L 1.93373002 -1.93206004 1.93368996 -1.93191998 0 P 0 ;0
L 1.93368996 -1.93191998 1.93296004 -1.92976998 0 P 0 ;0
L 1.93296004 -1.92976998 1.93293996 -1.9297 0 P 0 ;0
L 1.93293996 -1.9297 1.93291004 -1.92963002 0 P 0 ;0
L 1.93291004 -1.92963002 1.93201998 -1.92753996 0 P 0 ;0
L 1.93201998 -1.92753996 1.93196998 -1.92743002 0 P 0 ;0
L 1.93196998 -1.92743002 1.93196004 -1.9274 0 P 0 ;0
L 1.93196004 -1.9274 1.93091998 -1.92538996 0 P 0 ;0
L 1.93091998 -1.92538996 1.9309 -1.92536004 0 P 0 ;0
L 1.9309 -1.92536004 1.93088002 -1.92531998 0 P 0 ;0
L 1.93088002 -1.92531998 1.93086004 -1.92528996 0 P 0 ;0
L 1.93086004 -1.92528996 1.93083996 -1.92525 0 P 0 ;0
L 1.93083996 -1.92525 1.92965 -1.92331998 0 P 0 ;0
L 1.92965 -1.92331998 1.92956998 -1.9232 0 P 0 ;0
L 1.92956998 -1.9232 1.92823002 -1.92136004 0 P 0 ;0
L 1.92823002 -1.92136004 1.92818002 -1.9213 0 P 0 ;0
L 1.92818002 -1.9213 1.92816004 -1.92126998 0 P 0 ;0
L 1.92816004 -1.92126998 1.92813002 -1.92123996 0 P 0 ;0
L 1.92813002 -1.92123996 1.92671998 -1.91958002 0 P 0 ;0
L 1.92671998 -1.91958002 1.9266 -1.91946004 0 P 0 ;0
L 1.9266 -1.91946004 1.92505 -1.91793002 0 P 0 ;0
L 1.92505 -1.91793002 1.92498996 -1.91786998 0 P 0 ;0
L 1.92498996 -1.91786998 1.92493002 -1.91781998 0 P 0 ;0
L 1.92493002 -1.91781998 1.92325 -1.91643002 0 P 0 ;0
L 1.92325 -1.91643002 1.92318996 -1.91636998 0 P 0 ;0
L 1.92318996 -1.91636998 1.92311998 -1.91631998 0 P 0 ;0
L 1.92311998 -1.91631998 1.92133002 -1.91508002 0 P 0 ;0
L 1.92133002 -1.91508002 1.92126004 -1.91503996 0 P 0 ;0
L 1.92126004 -1.91503996 1.92121998 -1.91501004 0 P 0 ;0
L 1.92121998 -1.91501004 1.92118002 -1.91498996 0 P 0 ;0
L 1.92118002 -1.91498996 1.91928996 -1.91391004 0 P 0 ;0
L 1.91928996 -1.91391004 1.91926004 -1.91388996 0 P 0 ;0
L 1.91926004 -1.91388996 1.91913996 -1.91383002 0 P 0 ;0
L 1.91913996 -1.91383002 1.91716998 -1.91291004 0 P 0 ;0
L 1.91716998 -1.91291004 1.91711998 -1.91288996 0 P 0 ;0
L 1.91711998 -1.91288996 1.91705 -1.91286004 0 P 0 ;0
L 1.91705 -1.91286004 1.917 -1.91285 0 P 0 ;0
L 1.917 -1.91285 1.91476998 -1.91203996 0 P 0 ;0
L 1.91476998 -1.91203996 1.91468996 -1.91201998 0 P 0 ;0
L 1.91468996 -1.91201998 1.91465 -1.912 0 P 0 ;0
L 1.91465 -1.912 1.9146 -1.91198996 0 P 0 ;0
L 1.9146 -1.91198996 1.91233002 -1.91138996 0 P 0 ;0
L 1.91233002 -1.91138996 1.91228002 -1.91138002 0 P 0 ;0
L 1.91228002 -1.91138002 1.91223996 -1.91136998 0 P 0 ;0
L 1.91223996 -1.91136998 1.91216004 -1.91136004 0 P 0 ;0
L 1.91216004 -1.91136004 1.90983002 -1.91095 0 P 0 ;0
L 1.90983002 -1.91095 1.9098 -1.91093996 0 P 0 ;0
L 1.9098 -1.91093996 1.90976004 -1.91093996 0 P 0 ;0
L 1.90976004 -1.91093996 1.90971998 -1.91093002 0 P 0 ;0
L 1.90971998 -1.91093002 1.90968002 -1.91093002 0 P 0 ;0
L 1.90968002 -1.91093002 1.90713996 -1.91068996 0 P 0 ;0
L 1.90713996 -1.91068996 1.9071 -1.91068002 0 P 0 ;0
L 1.9071 -1.91068002 1.907 -1.91068002 0 P 0 ;0
L 1.907 -1.91068002 1.90445 -1.91061004 0 P 0 ;0
L 1.90445 -1.91061004 1.90431004 -1.91061004 0 P 0 ;0
L 1.90431004 -1.91061004 1.90176004 -1.91071004 0 P 0 ;0
L 1.90176004 -1.91071004 1.90173002 -1.91071998 0 P 0 ;0
L 1.90173002 -1.91071998 1.90166004 -1.91071998 0 P 0 ;0
L 1.90166004 -1.91071998 1.90161998 -1.91073002 0 P 0 ;0
L 1.90161998 -1.91073002 1.89913002 -1.911 0 P 0 ;0
L 1.89913002 -1.911 1.89906004 -1.91101004 0 P 0 ;0
L 1.89906004 -1.91101004 1.89901998 -1.91101998 0 P 0 ;0
L 1.89901998 -1.91101998 1.89898996 -1.91101998 0 P 0 ;0
L 1.89898996 -1.91101998 1.89653002 -1.91146998 0 P 0 ;0
L 1.89653002 -1.91146998 1.8965 -1.91148002 0 P 0 ;0
L 1.8965 -1.91148002 1.89646004 -1.91148002 0 P 0 ;0
L 1.89646004 -1.91148002 1.8964 -1.9115 0 P 0 ;0
L 1.8964 -1.9115 1.89396998 -1.91211998 0 P 0 ;0
L 1.89396998 -1.91211998 1.89393996 -1.91213002 0 P 0 ;0
L 1.89393996 -1.91213002 1.89383002 -1.91216004 0 P 0 ;0
L 1.89383002 -1.91216004 1.89225 -1.91268996 0 P 0 ;0
L 1.89225 -1.91268996 1.89218002 -1.91271998 0 P 0 ;0
L 1.89218002 -1.91271998 1.89211004 -1.91273996 0 P 0 ;0
L 1.89211004 -1.91273996 1.8921 -1.91273996 0 P 0 ;0
L 1.8921 -1.91273996 1.89058002 -1.91338996 0 P 0 ;0
L 1.89058002 -1.91338996 1.89043996 -1.91345 0 P 0 ;0
L 1.89043996 -1.91345 1.88896004 -1.91421004 0 P 0 ;0
L 1.88896004 -1.91421004 1.88893002 -1.91423002 0 P 0 ;0
L 1.88893002 -1.91423002 1.8889 -1.91423996 0 P 0 ;0
L 1.8889 -1.91423996 1.88886004 -1.91426004 0 P 0 ;0
L 1.88886004 -1.91426004 1.88883002 -1.91428002 0 P 0 ;0
L 1.88883002 -1.91428002 1.88741004 -1.91515 0 P 0 ;0
L 1.88741004 -1.91515 1.88733996 -1.91518996 0 P 0 ;0
L 1.88733996 -1.91518996 1.88728002 -1.91523996 0 P 0 ;0
L 1.88728002 -1.91523996 1.88526004 -1.9167 0 P 0 ;0
L 1.88526004 -1.9167 1.88521998 -1.91673002 0 P 0 ;0
L 1.88521998 -1.91673002 1.88518996 -1.91675 0 P 0 ;0
L 1.88518996 -1.91675 1.88516004 -1.91678002 0 P 0 ;0
L 1.88516004 -1.91678002 1.88511998 -1.91681004 0 P 0 ;0
L 1.88511998 -1.91681004 1.88323002 -1.91845 0 P 0 ;0
L 1.88323002 -1.91845 1.8832 -1.91846998 0 P 0 ;0
L 1.8832 -1.91846998 1.88311004 -1.91856004 0 P 0 ;0
L 1.88311004 -1.91856004 1.88136998 -1.92036004 0 P 0 ;0
L 1.88136998 -1.92036004 1.88128002 -1.92045 0 P 0 ;0
L 1.88128002 -1.92045 1.88125 -1.92048996 0 P 0 ;0
L 1.88125 -1.92048996 1.87968002 -1.92241998 0 P 0 ;0
L 1.87968002 -1.92241998 1.87965 -1.92245 0 P 0 ;0
L 1.87965 -1.92245 1.87961998 -1.92248996 0 P 0 ;0
L 1.87961998 -1.92248996 1.87956998 -1.92256004 0 P 0 ;0
L 1.87956998 -1.92256004 1.87816998 -1.92461998 0 P 0 ;0
L 1.87816998 -1.92461998 1.8781 -1.92473002 0 P 0 ;0
L 1.8781 -1.92473002 1.87808002 -1.92476998 0 P 0 ;0
L 1.87808002 -1.92476998 1.87685 -1.92695 0 P 0 ;0
L 1.87685 -1.92695 1.87683002 -1.92698996 0 P 0 ;0
L 1.87683002 -1.92698996 1.87681004 -1.92701998 0 P 0 ;0
L 1.87681004 -1.92701998 1.87678996 -1.92706998 0 P 0 ;0
L 1.87678996 -1.92706998 1.87676998 -1.92711004 0 P 0 ;0
L 1.87676998 -1.92711004 1.87573002 -1.92941004 0 P 0 ;0
L 1.87573002 -1.92941004 1.87571004 -1.92945 0 P 0 ;0
L 1.87571004 -1.92945 1.8757 -1.92948996 0 P 0 ;0
L 1.8757 -1.92948996 1.87568002 -1.92951998 0 P 0 ;0
L 1.87568002 -1.92951998 1.87566998 -1.92956998 0 P 0 ;0
L 1.87566998 -1.92956998 1.87483996 -1.93193002 0 P 0 ;0
L 1.87483996 -1.93193002 1.87481004 -1.93201004 0 P 0 ;0
L 1.87481004 -1.93201004 1.87478996 -1.93208996 0 P 0 ;0
L 1.87478996 -1.93208996 1.87416004 -1.93451998 0 P 0 ;0
L 1.87416004 -1.93451998 1.87413996 -1.93456004 0 P 0 ;0
L 1.87413996 -1.93456004 1.87413002 -1.9346 0 P 0 ;0
L 1.87413002 -1.9346 1.87413002 -1.93463996 0 P 0 ;0
L 1.87413002 -1.93463996 1.87411998 -1.93468002 0 P 0 ;0
L 1.87411998 -1.93468002 1.8737 -1.93715 0 P 0 ;0
L 1.8737 -1.93715 1.87368996 -1.93718996 0 P 0 ;0
L 1.87368996 -1.93718996 1.87368002 -1.93723996 0 P 0 ;0
L 1.87368002 -1.93723996 1.87368002 -1.93731998 0 P 0 ;0
L 1.87368002 -1.93731998 1.87346998 -1.93981998 0 P 0 ;0
L 1.87346998 -1.93981998 1.87346004 -1.93986004 0 P 0 ;0
L 1.87346004 -1.93986004 1.87346004 -1.94258002 0 P 0 ;0
L 1.87346004 -1.94258002 1.87346998 -1.94266004 0 P 0 ;0
L 1.87346998 -1.94266004 1.87368002 -1.94516998 0 P 0 ;0
L 1.87368002 -1.94516998 1.87368996 -1.94521004 0 P 0 ;0
L 1.87368996 -1.94521004 1.87368996 -1.94525 0 P 0 ;0
L 1.87368996 -1.94525 1.87371004 -1.94533996 0 P 0 ;0
L 1.87371004 -1.94533996 1.87413996 -1.94778996 0 P 0 ;0
L 1.87413996 -1.94778996 1.87413996 -1.94783996 0 P 0 ;0
L 1.87413996 -1.94783996 1.87416998 -1.94796004 0 P 0 ;0
L 1.87416998 -1.94796004 1.87481004 -1.95036998 0 P 0 ;0
L 1.87481004 -1.95036998 1.87483996 -1.95048996 0 P 0 ;0
L 1.87483996 -1.95048996 1.87486004 -1.95053002 0 P 0 ;0
L 1.87486004 -1.95053002 1.8757 -1.95288002 0 P 0 ;0
L 1.8757 -1.95288002 1.87571004 -1.95291998 0 P 0 ;0
L 1.87571004 -1.95291998 1.87575 -1.953 0 P 0 ;0
L 1.87575 -1.953 1.87576004 -1.95303996 0 P 0 ;0
L 1.87576004 -1.95303996 1.8768 -1.9553 0 P 0 ;0
L 1.8768 -1.9553 1.87686004 -1.95541998 0 P 0 ;0
L 1.87686004 -1.95541998 1.87688002 -1.95545 0 P 0 ;0
L 1.87688002 -1.95545 1.8781 -1.95761004 0 P 0 ;0
L 1.8781 -1.95761004 1.87811998 -1.95761004 0 P 0 ;0
L 1.87811998 -1.95761004 1.8781 -1.95761998 0 P 0 ;0
L 1.8781 -1.95761998 1.87813996 -1.95768996 0 P 0 ;0
L 1.87813996 -1.95768996 1.87816998 -1.95771998 0 P 0 ;0
L 1.87816998 -1.95771998 1.87818996 -1.95775 0 P 0 ;0
L 1.87818996 -1.95775 1.87938002 -1.95951004 0 P 0 ;0
L 1.87938002 -1.95951004 1.87943996 -1.9596 0 P 0 ;0
L 1.87943996 -1.9596 1.87946998 -1.95963002 0 P 0 ;0
L 1.87946998 -1.95963002 1.88078002 -1.96128996 0 P 0 ;0
L 1.88078002 -1.96128996 1.88081004 -1.96131998 0 P 0 ;0
L 1.88081004 -1.96131998 1.88083002 -1.96135 0 P 0 ;0
L 1.88083002 -1.96135 1.88086004 -1.96136998 0 P 0 ;0
L 1.88086004 -1.96136998 1.88088002 -1.9614 0 P 0 ;0
L 1.88088002 -1.9614 1.88231998 -1.96295 0 P 0 ;0
L 1.88231998 -1.96295 1.88233996 -1.96298002 0 P 0 ;0
L 1.88233996 -1.96298002 1.8824 -1.96303996 0 P 0 ;0
L 1.8824 -1.96303996 1.88243002 -1.96306004 0 P 0 ;0
L 1.88243002 -1.96306004 1.88398002 -1.9645 0 P 0 ;0
L 1.88398002 -1.9645 1.88401004 -1.96451998 0 P 0 ;0
L 1.88401004 -1.96451998 1.88403002 -1.96455 0 P 0 ;0
L 1.88403002 -1.96455 1.88406998 -1.96458002 0 P 0 ;0
L 1.88406998 -1.96458002 1.88408996 -1.9646 0 P 0 ;0
L 1.88408996 -1.9646 1.88575 -1.96591004 0 P 0 ;0
L 1.88575 -1.96591004 1.88578002 -1.96593996 0 P 0 ;0
L 1.88578002 -1.96593996 1.88586998 -1.966 0 P 0 ;0
L 1.88586998 -1.966 1.88761998 -1.96718996 0 P 0 ;0
L 1.88761998 -1.96718996 1.88766004 -1.96721004 0 P 0 ;0
L 1.88766004 -1.96721004 1.88775 -1.96726998 0 P 0 ;0
L 1.88775 -1.96726998 1.88958996 -1.96831998 0 P 0 ;0
L 1.88958996 -1.96831998 1.88965 -1.96836004 0 P 0 ;0
L 1.88965 -1.96836004 1.88968002 -1.96836998 0 P 0 ;0
L 1.88968002 -1.96836998 1.88971998 -1.96838996 0 P 0 ;0
L 1.88971998 -1.96838996 1.89145 -1.96921998 0 P 0 ;0
L 1.89145 -1.96921998 1.89151004 -1.96925 0 P 0 ;0
L 1.89151004 -1.96925 1.89155 -1.96926004 0 P 0 ;0
L 1.89155 -1.96926004 1.89158002 -1.96926998 0 P 0 ;0
L 1.89158002 -1.96926998 1.89336004 -1.96996998 0 P 0 ;0
L 1.89336004 -1.96996998 1.89336004 -1.96998002 0 P 0 ;0
L 1.89336004 -1.96998002 1.89346004 -1.97001004 0 P 0 ;0
L 1.89346004 -1.97001004 1.89348996 -1.97001998 0 P 0 ;0
L 1.89348996 -1.97001998 1.89531998 -1.9706 0 P 0 ;0
L 1.89531998 -1.9706 1.89536004 -1.97061004 0 P 0 ;0
L 1.89536004 -1.97061004 1.89541998 -1.97063002 0 P 0 ;0
L 1.89541998 -1.97063002 1.89546004 -1.97063002 0 P 0 ;0
L 1.89546004 -1.97063002 1.89731998 -1.97108002 0 P 0 ;0
L 1.89731998 -1.97108002 1.89741998 -1.9711 0 P 0 ;0
L 1.89741998 -1.9711 1.89746004 -1.9711 0 P 0 ;0
L 1.89746004 -1.9711 1.89746004 -1.97111004 0 P 0 ;0
L 1.89746004 -1.97111004 1.89933996 -1.97141998 0 P 0 ;0
L 1.89933996 -1.97141998 1.89936998 -1.97143002 0 P 0 ;0
L 1.89936998 -1.97143002 1.89941004 -1.97143002 0 P 0 ;0
L 1.89941004 -1.97143002 1.89945 -1.97143996 0 P 0 ;0
L 1.89945 -1.97143996 1.89948002 -1.97143996 0 P 0 ;0
L 1.89948002 -1.97143996 1.90201004 -1.97168002 0 P 0 ;0
L 1.90201004 -1.97168002 1.90205 -1.97168002 0 P 0 ;0
L 1.90205 -1.97168002 1.90208996 -1.97168996 0 P 0 ;0
L 1.90208996 -1.97168996 1.90216004 -1.97168996 0 P 0 ;0
L 1.90216004 -1.97168996 1.90468996 -1.97173996 0 P 0 ;0
L 1.90468996 -1.97173996 1.90476004 -1.97173996 0 P 0 ;0
L 1.80616004 -2.12823996 1.83348996 -2.12823996 0 P 0 ;0
L 1.79591998 -2.12723996 1.8396 -2.12723996 0 P 0 ;0
L 1.78818002 -2.12623996 1.84465 -2.12623996 0 P 0 ;0
L 1.82003996 -2.09123996 1.87618996 -2.09123996 0 P 0 ;0
L 1.82198996 -2.09023996 1.8762 -2.09023996 0 P 0 ;0
L 1.82325 -2.08923996 1.8762 -2.08923996 0 P 0 ;0
L 1.82411998 -2.08823996 1.87618996 -2.08823996 0 P 0 ;0
L 1.82463002 -2.08723996 1.87616998 -2.08723996 0 P 0 ;0
L 1.82488002 -2.08623996 1.87615 -2.08623996 0 P 0 ;0
L 1.82493002 -2.08523996 1.87613002 -2.08523996 0 P 0 ;0
L 1.82476998 -2.08423996 1.87611004 -2.08423996 0 P 0 ;0
L 1.64846004 -2.08295 1.73316998 -2.08295 0 P 0 ;0
L 1.64811998 -2.08195 1.73356998 -2.08195 0 P 0 ;0
L 1.64776998 -2.08095 1.73398002 -2.08095 0 P 0 ;0
L 1.64743002 -2.07995 1.73438002 -2.07995 0 P 0 ;0
L 1.64708996 -2.07895 1.73478996 -2.07895 0 P 0 ;0
L 1.64673996 -2.07795 1.7352 -2.07795 0 P 0 ;0
L 1.6464 -2.07695 1.7356 -2.07695 0 P 0 ;0
L 1.64605 -2.07595 1.73601004 -2.07595 0 P 0 ;0
L 1.64571004 -2.07495 1.73641004 -2.07495 0 P 0 ;0
L 1.64536004 -2.07395 1.73681004 -2.07395 0 P 0 ;0
L 1.64501998 -2.07295 1.73721998 -2.07295 0 P 0 ;0
L 1.64466998 -2.07195 1.73761998 -2.07195 0 P 0 ;0
L 1.64433002 -2.07095 1.73803002 -2.07095 0 P 0 ;0
L 1.64398002 -2.06995 1.69251004 -2.06995 0 P 0 ;0
L 1.69583002 -2.06995 1.73843996 -2.06995 0 P 0 ;0
L 1.64363002 -2.06895 1.69168002 -2.06895 0 P 0 ;0
L 1.69671998 -2.06895 1.73883996 -2.06895 0 P 0 ;0
L 1.64328996 -2.06795 1.69136004 -2.06795 0 P 0 ;0
L 1.69708996 -2.06795 1.73925 -2.06795 0 P 0 ;0
L 1.64293996 -2.06695 1.69108002 -2.06695 0 P 0 ;0
L 1.69738002 -2.06695 1.73965 -2.06695 0 P 0 ;0
L 1.64258996 -2.06595 1.6908 -2.06595 0 P 0 ;0
L 1.69768002 -2.06595 1.74006004 -2.06595 0 P 0 ;0
L 1.64223996 -2.06495 1.69051998 -2.06495 0 P 0 ;0
L 1.69796998 -2.06495 1.74046004 -2.06495 0 P 0 ;0
L 1.6419 -2.06395 1.69023002 -2.06395 0 P 0 ;0
L 1.69826998 -2.06395 1.74086004 -2.06395 0 P 0 ;0
L 1.64155 -2.06295 1.68996004 -2.06295 0 P 0 ;0
L 1.69856004 -2.06295 1.74126998 -2.06295 0 P 0 ;0
L 1.6412 -2.06195 1.68966998 -2.06195 0 P 0 ;0
L 1.69886004 -2.06195 1.74168002 -2.06195 0 P 0 ;0
L 1.64085 -2.06095 1.68938996 -2.06095 0 P 0 ;0
L 1.69915 -2.06095 1.74208002 -2.06095 0 P 0 ;0
L 1.6405 -2.05995 1.68911004 -2.05995 0 P 0 ;0
L 1.69945 -2.05995 1.74248002 -2.05995 0 P 0 ;0
L 1.64016004 -2.05895 1.68883002 -2.05895 0 P 0 ;0
L 1.69973996 -2.05895 1.74288996 -2.05895 0 P 0 ;0
L 1.63981004 -2.05795 1.68855 -2.05795 0 P 0 ;0
L 1.70003996 -2.05795 1.74328996 -2.05795 0 P 0 ;0
L 1.63946004 -2.05695 1.68826998 -2.05695 0 P 0 ;0
L 1.70033002 -2.05695 1.7437 -2.05695 0 P 0 ;0
L 1.63911004 -2.05595 1.68798996 -2.05595 0 P 0 ;0
L 1.70063002 -2.05595 1.7441 -2.05595 0 P 0 ;0
L 1.63876998 -2.05495 1.68771004 -2.05495 0 P 0 ;0
L 1.70091998 -2.05495 1.74451004 -2.05495 0 P 0 ;0
L 1.63841998 -2.05395 1.68741998 -2.05395 0 P 0 ;0
L 1.70121998 -2.05395 1.74491004 -2.05395 0 P 0 ;0
L 1.63806998 -2.05295 1.68713996 -2.05295 0 P 0 ;0
L 1.70151004 -2.05295 1.74531004 -2.05295 0 P 0 ;0
L 1.63771998 -2.05195 1.68686004 -2.05195 0 P 0 ;0
L 1.70181004 -2.05195 1.74571998 -2.05195 0 P 0 ;0
L 1.63738002 -2.05095 1.68658002 -2.05095 0 P 0 ;0
L 1.7021 -2.05095 1.74611998 -2.05095 0 P 0 ;0
L 1.63703002 -2.04995 1.6863 -2.04995 0 P 0 ;0
L 1.7024 -2.04995 1.74653002 -2.04995 0 P 0 ;0
L 1.63668002 -2.04895 1.68601998 -2.04895 0 P 0 ;0
L 1.70268996 -2.04895 1.74693002 -2.04895 0 P 0 ;0
L 1.63633002 -2.04795 1.68573996 -2.04795 0 P 0 ;0
L 1.70298996 -2.04795 1.74733002 -2.04795 0 P 0 ;0
L 1.63598002 -2.04695 1.68546004 -2.04695 0 P 0 ;0
L 1.70328002 -2.04695 1.74773996 -2.04695 0 P 0 ;0
L 1.63563996 -2.04595 1.68518002 -2.04595 0 P 0 ;0
L 1.70358002 -2.04595 1.74813996 -2.04595 0 P 0 ;0
L 1.63528996 -2.04495 1.6849 -2.04495 0 P 0 ;0
L 1.70386998 -2.04495 1.74855 -2.04495 0 P 0 ;0
L 1.63493996 -2.04395 1.68461004 -2.04395 0 P 0 ;0
L 1.70416998 -2.04395 1.74895 -2.04395 0 P 0 ;0
L 1.63458996 -2.04295 1.68433002 -2.04295 0 P 0 ;0
L 1.70446004 -2.04295 1.74936004 -2.04295 0 P 0 ;0
L 1.63425 -2.04195 1.68405 -2.04195 0 P 0 ;0
L 1.70475 -2.04195 1.74976004 -2.04195 0 P 0 ;0
L 1.6339 -2.04095 1.68376998 -2.04095 0 P 0 ;0
L 1.70503002 -2.04095 1.75016004 -2.04095 0 P 0 ;0
L 1.63355 -2.03995 1.68348996 -2.03995 0 P 0 ;0
L 1.70531998 -2.03995 1.75056998 -2.03995 0 P 0 ;0
L 1.6332 -2.03895 1.68321004 -2.03895 0 P 0 ;0
L 1.7056 -2.03895 1.75096998 -2.03895 0 P 0 ;0
L 1.63286004 -2.03795 1.68293002 -2.03795 0 P 0 ;0
L 1.70588996 -2.03795 1.75138002 -2.03795 0 P 0 ;0
L 1.63251004 -2.03695 1.68266004 -2.03695 0 P 0 ;0
L 1.70618002 -2.03695 1.75178002 -2.03695 0 P 0 ;0
L 1.63216004 -2.03595 1.68238002 -2.03595 0 P 0 ;0
L 1.70646998 -2.03595 1.75218996 -2.03595 0 P 0 ;0
L 1.63181004 -2.03495 1.6821 -2.03495 0 P 0 ;0
L 1.70675 -2.03495 1.75258996 -2.03495 0 P 0 ;0
L 1.63146998 -2.03395 1.68183002 -2.03395 0 P 0 ;0
L 1.70703996 -2.03395 1.75298996 -2.03395 0 P 0 ;0
L 1.63111998 -2.03295 1.68155 -2.03295 0 P 0 ;0
L 1.70733002 -2.03295 1.7534 -2.03295 0 P 0 ;0
L 1.63076998 -2.03195 1.68126998 -2.03195 0 P 0 ;0
L 1.70761004 -2.03195 1.75381004 -2.03195 0 P 0 ;0
L 1.63041998 -2.03095 1.68098996 -2.03095 0 P 0 ;0
L 1.7079 -2.03095 1.75421004 -2.03095 0 P 0 ;0
L 1.63006998 -2.02995 1.68071004 -2.02995 0 P 0 ;0
L 1.70818996 -2.02995 1.75461004 -2.02995 0 P 0 ;0
L 1.62973002 -2.02895 1.68043996 -2.02895 0 P 0 ;0
L 1.70846998 -2.02895 1.75501998 -2.02895 0 P 0 ;0
L 1.62938002 -2.02795 1.68016004 -2.02795 0 P 0 ;0
L 1.70876004 -2.02795 1.75541998 -2.02795 0 P 0 ;0
L 1.62903002 -2.02695 1.67988002 -2.02695 0 P 0 ;0
L 1.70905 -2.02695 1.75583002 -2.02695 0 P 0 ;0
L 1.62868002 -2.02595 1.6796 -2.02595 0 P 0 ;0
L 1.70933996 -2.02595 1.75623002 -2.02595 0 P 0 ;0
L 1.62831004 -2.02495 1.67933002 -2.02495 0 P 0 ;0
L 1.70961998 -2.02495 1.75663996 -2.02495 0 P 0 ;0
L 1.62793996 -2.02395 1.67905 -2.02395 0 P 0 ;0
L 1.70991004 -2.02395 1.75703996 -2.02395 0 P 0 ;0
L 1.62756998 -2.02295 1.67876998 -2.02295 0 P 0 ;0
L 1.7102 -2.02295 1.75743996 -2.02295 0 P 0 ;0
L 1.6272 -2.02195 1.6785 -2.02195 0 P 0 ;0
L 1.71048002 -2.02195 1.75785 -2.02195 0 P 0 ;0
L 1.62683002 -2.02095 1.67821998 -2.02095 0 P 0 ;0
L 1.71076004 -2.02095 1.75825 -2.02095 0 P 0 ;0
L 1.62646998 -2.01995 1.67793996 -2.01995 0 P 0 ;0
L 1.71101004 -2.01995 1.75866004 -2.01995 0 P 0 ;0
L 1.6261 -2.01895 1.67766004 -2.01895 0 P 0 ;0
L 1.71126998 -2.01895 1.75906004 -2.01895 0 P 0 ;0
L 1.62573002 -2.01795 1.67738996 -2.01795 0 P 0 ;0
L 1.71151998 -2.01795 1.75946998 -2.01795 0 P 0 ;0
L 1.62536004 -2.01695 1.67711004 -2.01695 0 P 0 ;0
L 1.71176998 -2.01695 1.75986998 -2.01695 0 P 0 ;0
L 1.62498996 -2.01595 1.67683002 -2.01595 0 P 0 ;0
L 1.71203002 -2.01595 1.76026998 -2.01595 0 P 0 ;0
L 1.62461998 -2.01495 1.67656004 -2.01495 0 P 0 ;0
L 1.71228002 -2.01495 1.76068002 -2.01495 0 P 0 ;0
L 1.62425 -2.01395 1.67628002 -2.01395 0 P 0 ;0
L 1.71253996 -2.01395 1.76108002 -2.01395 0 P 0 ;0
L 1.62388002 -2.01295 1.67601998 -2.01295 0 P 0 ;0
L 1.71278996 -2.01295 1.76148996 -2.01295 0 P 0 ;0
L 1.62351004 -2.01195 1.67576998 -2.01195 0 P 0 ;0
L 1.71305 -2.01195 1.76188996 -2.01195 0 P 0 ;0
L 1.62313996 -2.01095 1.67551998 -2.01095 0 P 0 ;0
L 1.7133 -2.01095 1.76228996 -2.01095 0 P 0 ;0
L 1.62276998 -2.00995 1.67528002 -2.00995 0 P 0 ;0
L 1.71355 -2.00995 1.7627 -2.00995 0 P 0 ;0
L 1.6224 -2.00895 1.67503002 -2.00895 0 P 0 ;0
L 1.71381004 -2.00895 1.7631 -2.00895 0 P 0 ;0
L 1.62203002 -2.00795 1.67478996 -2.00795 0 P 0 ;0
L 1.71406004 -2.00795 1.76351004 -2.00795 0 P 0 ;0
L 1.62166004 -2.00695 1.67453996 -2.00695 0 P 0 ;0
L 1.71431004 -2.00695 1.76391004 -2.00695 0 P 0 ;0
L 1.62128996 -2.00595 1.67428996 -2.00595 0 P 0 ;0
L 1.71453996 -2.00595 1.76431998 -2.00595 0 P 0 ;0
L 1.62091004 -2.00495 1.67405 -2.00495 0 P 0 ;0
L 1.71476998 -2.00495 1.76471998 -2.00495 0 P 0 ;0
L 1.62051998 -2.00395 1.6738 -2.00395 0 P 0 ;0
L 1.715 -2.00395 1.76511998 -2.00395 0 P 0 ;0
L 1.62013002 -2.00295 1.67355 -2.00295 0 P 0 ;0
L 1.71523002 -2.00295 1.76553002 -2.00295 0 P 0 ;0
L 1.61973996 -2.00195 1.67331004 -2.00195 0 P 0 ;0
L 1.71546004 -2.00195 1.76593996 -2.00195 0 P 0 ;0
L 1.61935 -2.00095 1.67306004 -2.00095 0 P 0 ;0
L 1.71568996 -2.00095 1.76633996 -2.00095 0 P 0 ;0
L 1.61896004 -1.99995 1.67283996 -1.99995 0 P 0 ;0
L 1.71591998 -1.99995 1.76673996 -1.99995 0 P 0 ;0
L 1.61856998 -1.99895 1.67261998 -1.99895 0 P 0 ;0
L 1.71613996 -1.99895 1.76715 -1.99895 0 P 0 ;0
L 1.71638002 -1.99795 1.76755 -1.99795 0 P 0 ;0
L 1.7166 -1.99695 1.76796004 -1.99695 0 P 0 ;0
L 1.71683002 -1.99595 1.76836004 -1.99595 0 P 0 ;0
L 1.71866998 -1.99495 1.76876998 -1.99495 0 P 0 ;0
L 1.78213996 -2.04823996 1.84641998 -2.04823996 0 P 0 ;0
L 1.78138002 -2.04723996 1.84498996 -2.04723996 0 P 0 ;0
L 1.78071004 -2.04623996 1.84356004 -2.04623996 0 P 0 ;0
L 1.7801 -2.04523996 1.84213996 -2.04523996 0 P 0 ;0
L 1.77956004 -2.04423996 1.84071004 -2.04423996 0 P 0 ;0
L 1.77908996 -2.04323996 1.83928002 -2.04323996 0 P 0 ;0
L 1.77866004 -2.04223996 1.83786004 -2.04223996 0 P 0 ;0
L 1.77831004 -2.04123996 1.83658996 -2.04123996 0 P 0 ;0
L 1.77796004 -2.04023996 1.83536004 -2.04023996 0 P 0 ;0
L 1.77761004 -2.03923996 1.83428002 -2.03923996 0 P 0 ;0
L 1.77733996 -2.03823996 1.83321998 -2.03823996 0 P 0 ;0
L 1.77706998 -2.03723996 1.83236998 -2.03723996 0 P 0 ;0
L 1.7768 -2.03623996 1.83171004 -2.03623996 0 P 0 ;0
L 1.7766 -2.03523996 1.83121004 -2.03523996 0 P 0 ;0
L 1.77641004 -2.03423996 1.83085 -2.03423996 0 P 0 ;0
L 1.77621004 -2.03323996 1.83071004 -2.03323996 0 P 0 ;0
L 1.77608002 -2.03223996 1.83076998 -2.03223996 0 P 0 ;0
L 1.77596004 -2.03123996 1.83106004 -2.03123996 0 P 0 ;0
L 1.77583996 -2.03023996 1.83158996 -2.03023996 0 P 0 ;0
L 1.77576004 -2.02923996 1.83238002 -2.02923996 0 P 0 ;0
L 1.7757 -2.02823996 1.83356998 -2.02823996 0 P 0 ;0
L 1.7757 -2.02723996 1.83591998 -2.02723996 0 P 0 ;0
L 1.77571998 -2.02623996 1.87495 -2.02623996 0 P 0 ;0
L 1.7758 -2.02523996 1.87485 -2.02523996 0 P 0 ;0
L 1.77588996 -2.02423996 1.87475 -2.02423996 0 P 0 ;0
L 1.77605 -2.02323996 1.87465 -2.02323996 0 P 0 ;0
L 1.77621004 -2.02223996 1.87455 -2.02223996 0 P 0 ;0
L 1.7764 -2.02123996 1.87445 -2.02123996 0 P 0 ;0
L 1.77665 -2.02023996 1.87433996 -2.02023996 0 P 0 ;0
L 1.7769 -2.01923996 1.87425 -2.01923996 0 P 0 ;0
L 1.7772 -2.01823996 1.87413996 -2.01823996 0 P 0 ;0
L 1.77753002 -2.01723996 1.87405 -2.01723996 0 P 0 ;0
L 1.77786004 -2.01623996 1.87393996 -2.01623996 0 P 0 ;0
L 1.77823002 -2.01523996 1.87383996 -2.01523996 0 P 0 ;0
L 1.77863996 -2.01423996 1.87373996 -2.01423996 0 P 0 ;0
L 1.77903996 -2.01323996 1.87363996 -2.01323996 0 P 0 ;0
L 1.7795 -2.01223996 1.87353996 -2.01223996 0 P 0 ;0
L 1.77998996 -2.01123996 1.87343996 -2.01123996 0 P 0 ;0
L 1.78046998 -2.01023996 1.87333002 -2.01023996 0 P 0 ;0
L 1.78103996 -2.00923996 1.87323002 -2.00923996 0 P 0 ;0
L 1.78161004 -2.00823996 1.87311998 -2.00823996 0 P 0 ;0
L 1.78221004 -2.00723996 1.87301998 -2.00723996 0 P 0 ;0
L 1.78288002 -2.00623996 1.87291998 -2.00623996 0 P 0 ;0
L 1.64213996 -2.14795 1.70566004 -2.14795 0 P 0 ;0
L 1.64518996 -2.14695 1.7062 -2.14695 0 P 0 ;0
L 1.64728996 -2.14595 1.70673996 -2.14595 0 P 0 ;0
L 1.64906998 -2.14495 1.70728002 -2.14495 0 P 0 ;0
L 1.65058002 -2.14395 1.70783002 -2.14395 0 P 0 ;0
L 1.6519 -2.14295 1.70836998 -2.14295 0 P 0 ;0
L 1.65311998 -2.14195 1.70881998 -2.14195 0 P 0 ;0
L 1.65416998 -2.14095 1.70926998 -2.14095 0 P 0 ;0
L 1.65508996 -2.13995 1.70973002 -2.13995 0 P 0 ;0
L 1.65588002 -2.13895 1.71018002 -2.13895 0 P 0 ;0
L 1.65658002 -2.13795 1.71063002 -2.13795 0 P 0 ;0
L 1.65726998 -2.13695 1.71108996 -2.13695 0 P 0 ;0
L 1.65791998 -2.13595 1.71153996 -2.13595 0 P 0 ;0
L 1.65853002 -2.13495 1.71198996 -2.13495 0 P 0 ;0
L 1.65913002 -2.13395 1.71245 -2.13395 0 P 0 ;0
L 1.65968002 -2.13295 1.7129 -2.13295 0 P 0 ;0
L 1.66021998 -2.13195 1.71331004 -2.13195 0 P 0 ;0
L 1.66071998 -2.13095 1.71371998 -2.13095 0 P 0 ;0
L 1.66121004 -2.12995 1.71411998 -2.12995 0 P 0 ;0
L 1.66166998 -2.12895 1.71453002 -2.12895 0 P 0 ;0
L 1.66201004 -2.12795 1.71493996 -2.12795 0 P 0 ;0
L 1.66223996 -2.12695 1.71533996 -2.12695 0 P 0 ;0
L 1.66235 -2.12595 1.71575 -2.12595 0 P 0 ;0
L 1.66236004 -2.12495 1.71615 -2.12495 0 P 0 ;0
L 1.66228002 -2.12395 1.71656004 -2.12395 0 P 0 ;0
L 1.66211998 -2.12295 1.71696004 -2.12295 0 P 0 ;0
L 1.66188002 -2.12195 1.71736004 -2.12195 0 P 0 ;0
L 1.66156004 -2.12095 1.71776998 -2.12095 0 P 0 ;0
L 1.66121004 -2.11995 1.71818002 -2.11995 0 P 0 ;0
L 1.66086998 -2.11895 1.71858002 -2.11895 0 P 0 ;0
L 1.66053002 -2.11795 1.71898996 -2.11795 0 P 0 ;0
L 1.66018002 -2.11695 1.71938996 -2.11695 0 P 0 ;0
L 1.65983996 -2.11595 1.7198 -2.11595 0 P 0 ;0
L 1.65948996 -2.11495 1.7202 -2.11495 0 P 0 ;0
L 1.65913996 -2.11395 1.72061004 -2.11395 0 P 0 ;0
L 1.6588 -2.11295 1.72101004 -2.11295 0 P 0 ;0
L 1.65846004 -2.11195 1.72141998 -2.11195 0 P 0 ;0
L 1.65811004 -2.11095 1.72181998 -2.11095 0 P 0 ;0
L 1.65776998 -2.10995 1.72223002 -2.10995 0 P 0 ;0
L 1.65741998 -2.10895 1.72263002 -2.10895 0 P 0 ;0
L 1.65708002 -2.10795 1.72303996 -2.10795 0 P 0 ;0
L 1.65673002 -2.10695 1.72343996 -2.10695 0 P 0 ;0
L 1.65638996 -2.10595 1.72385 -2.10595 0 P 0 ;0
L 1.65605 -2.10495 1.72425 -2.10495 0 P 0 ;0
L 1.6557 -2.10395 1.72466004 -2.10395 0 P 0 ;0
L 1.65536004 -2.10295 1.72506998 -2.10295 0 P 0 ;0
L 1.65501004 -2.10195 1.72546998 -2.10195 0 P 0 ;0
L 1.65466998 -2.10095 1.72588002 -2.10095 0 P 0 ;0
L 1.65431998 -2.09995 1.72628002 -2.09995 0 P 0 ;0
L 1.65398002 -2.09895 1.72668996 -2.09895 0 P 0 ;0
L 1.65363002 -2.09795 1.72708996 -2.09795 0 P 0 ;0
L 1.65328996 -2.09695 1.72748996 -2.09695 0 P 0 ;0
L 1.65293996 -2.09595 1.7279 -2.09595 0 P 0 ;0
L 1.6526 -2.09495 1.72831004 -2.09495 0 P 0 ;0
L 1.65225 -2.09395 1.72871004 -2.09395 0 P 0 ;0
L 1.65191004 -2.09295 1.72911998 -2.09295 0 P 0 ;0
L 1.65156998 -2.09195 1.72951998 -2.09195 0 P 0 ;0
L 1.65121998 -2.09095 1.72993002 -2.09095 0 P 0 ;0
L 1.65088002 -2.08995 1.73033002 -2.08995 0 P 0 ;0
L 1.65053002 -2.08895 1.73073996 -2.08895 0 P 0 ;0
L 1.65018996 -2.08795 1.73113996 -2.08795 0 P 0 ;0
L 1.64983996 -2.08695 1.73155 -2.08695 0 P 0 ;0
L 1.6495 -2.08595 1.73195 -2.08595 0 P 0 ;0
L 1.64915 -2.08495 1.73236004 -2.08495 0 P 0 ;0
L 1.64881004 -2.08395 1.73276004 -2.08395 0 P 0 ;0
L 1.81726998 -1.98915 1.81196004 -1.9899 0 P 0 ;0
L 1.81196004 -1.9899 1.80668996 -1.99096998 0 P 0 ;0
L 1.80668996 -1.99096998 1.8019 -1.99226004 0 P 0 ;0
L 1.8019 -1.99226004 1.79718996 -1.99391004 0 P 0 ;0
L 1.79718996 -1.99391004 1.79316004 -1.99568002 0 P 0 ;0
L 1.79316004 -1.99568002 1.78926998 -1.99778002 0 P 0 ;0
L 1.78926998 -1.99778002 1.78771004 -1.99878002 0 P 0 ;0
L 1.78771004 -1.99878002 1.78623002 -1.99988002 0 P 0 ;0
L 1.78623002 -1.99988002 1.78481004 -2.00108002 0 P 0 ;0
L 1.78481004 -2.00108002 1.78346998 -2.00238996 0 P 0 ;0
L 1.78346998 -2.00238996 1.78228996 -2.00371998 0 P 0 ;0
L 1.78228996 -2.00371998 1.78121004 -2.00513002 0 P 0 ;0
L 1.78121004 -2.00513002 1.78023002 -2.00661004 0 P 0 ;0
L 1.78023002 -2.00661004 1.77868002 -2.00933996 0 P 0 ;0
L 1.77868002 -2.00933996 1.77731998 -2.01216998 0 P 0 ;0
L 1.77731998 -2.01216998 1.77611004 -2.01516004 0 P 0 ;0
L 1.77611004 -2.01516004 1.77508996 -2.01823002 0 P 0 ;0
L 1.77508996 -2.01823002 1.77436998 -2.02111004 0 P 0 ;0
L 1.77436998 -2.02111004 1.77388996 -2.02406004 0 P 0 ;0
L 1.77388996 -2.02406004 1.77371998 -2.02603996 0 P 0 ;0
L 1.77371998 -2.02603996 1.77368996 -2.02801998 0 P 0 ;0
L 1.77368996 -2.02801998 1.7738 -2.03001998 0 P 0 ;0
L 1.7738 -2.03001998 1.7742 -2.03338996 0 P 0 ;0
L 1.7742 -2.03338996 1.77485 -2.03671004 0 P 0 ;0
L 1.77485 -2.03671004 1.77573002 -2.03993996 0 P 0 ;0
L 1.77573002 -2.03993996 1.77683996 -2.04308002 0 P 0 ;0
L 1.77683996 -2.04308002 1.7776 -2.04481998 0 P 0 ;0
L 1.7776 -2.04481998 1.7785 -2.04648996 0 P 0 ;0
L 1.7785 -2.04648996 1.77953002 -2.04808996 0 P 0 ;0
L 1.77953002 -2.04808996 1.78061004 -2.04953996 0 P 0 ;0
L 1.78061004 -2.04953996 1.78181004 -2.05091004 0 P 0 ;0
L 1.78181004 -2.05091004 1.78311004 -2.05218996 0 P 0 ;0
L 1.78311004 -2.05218996 1.78988996 -2.05801998 0 P 0 ;0
L 1.78988996 -2.05801998 1.79883996 -2.06491004 0 P 0 ;0
L 1.79883996 -2.06491004 1.80976998 -2.07261004 0 P 0 ;0
L 1.80976998 -2.07261004 1.81753002 -2.07823002 0 P 0 ;0
L 1.81753002 -2.07823002 1.81896998 -2.07943002 0 P 0 ;0
L 1.81896998 -2.07943002 1.82033002 -2.08073002 0 P 0 ;0
L 1.82033002 -2.08073002 1.82156998 -2.08213996 0 P 0 ;0
L 1.82156998 -2.08213996 1.82186004 -2.08251004 0 P 0 ;0
L 1.82186004 -2.08251004 1.82211004 -2.0829 0 P 0 ;0
L 1.82211004 -2.0829 1.82233002 -2.08331004 0 P 0 ;0
L 1.82233002 -2.08331004 1.82253002 -2.08373996 0 P 0 ;0
L 1.82253002 -2.08373996 1.82268002 -2.08418002 0 P 0 ;0
L 1.82268002 -2.08418002 1.82281004 -2.08463002 0 P 0 ;0
L 1.82281004 -2.08463002 1.8229 -2.0851 0 P 0 ;0
L 1.8229 -2.0851 1.82293002 -2.08533996 0 P 0 ;0
L 1.82293002 -2.08533996 1.82293996 -2.08558996 0 P 0 ;0
L 1.82293996 -2.08558996 1.82291998 -2.08583996 0 P 0 ;0
L 1.82291998 -2.08583996 1.82288002 -2.08608002 0 P 0 ;0
L 1.82288002 -2.08608002 1.82283002 -2.08631998 0 P 0 ;0
L 1.82283002 -2.08631998 1.82275 -2.08656004 0 P 0 ;0
L 1.82275 -2.08656004 1.82265 -2.08678996 0 P 0 ;0
L 1.82265 -2.08678996 1.82253996 -2.087 0 P 0 ;0
L 1.82253996 -2.087 1.8224 -2.08721004 0 P 0 ;0
L 1.8224 -2.08721004 1.82225 -2.08741004 0 P 0 ;0
L 1.82225 -2.08741004 1.82208996 -2.08758996 0 P 0 ;0
L 1.82208996 -2.08758996 1.8216 -2.08803996 0 P 0 ;0
L 1.8216 -2.08803996 1.82106998 -2.08845 0 P 0 ;0
L 1.82106998 -2.08845 1.82051004 -2.08881004 0 P 0 ;0
L 1.82051004 -2.08881004 1.81991998 -2.08911998 0 P 0 ;0
L 1.81991998 -2.08911998 1.81931004 -2.08936998 0 P 0 ;0
L 1.81931004 -2.08936998 1.81868002 -2.08958002 0 P 0 ;0
L 1.81868002 -2.08958002 1.81803002 -2.08973002 0 P 0 ;0
L 1.81803002 -2.08973002 1.81736004 -2.08981998 0 P 0 ;0
L 1.81736004 -2.08981998 1.81293002 -2.09001998 0 P 0 ;0
L 1.81293002 -2.09001998 1.80846998 -2.08986004 0 P 0 ;0
L 1.80846998 -2.08986004 1.80256998 -2.08923002 0 P 0 ;0
L 1.80256998 -2.08923002 1.79668002 -2.08818996 0 P 0 ;0
L 1.79668002 -2.08818996 1.78223002 -2.08458002 0 P 0 ;0
L 1.78223002 -2.08458002 1.77788996 -2.08338002 0 P 0 ;0
L 1.77788996 -2.08338002 1.77415 -2.08246004 0 P 0 ;0
L 1.77415 -2.08246004 1.77095 -2.08175 0 P 0 ;0
L 1.77095 -2.08175 1.7709 -2.08173996 0 P 0 ;0
L 1.7709 -2.08173996 1.77076998 -2.08173996 0 P 0 ;0
L 1.77076998 -2.08173996 1.77068996 -2.08176004 0 P 0 ;0
L 1.77068996 -2.08176004 1.77053002 -2.08183996 0 P 0 ;0
L 1.77053002 -2.08183996 1.77043002 -2.08193996 0 P 0 ;0
L 1.77043002 -2.08193996 1.77036998 -2.08201998 0 P 0 ;0
L 1.77036998 -2.08201998 1.77031998 -2.08211998 0 P 0 ;0
L 1.77031998 -2.08211998 1.7703 -2.08216998 0 P 0 ;0
L 1.7703 -2.08216998 1.77028996 -2.08223002 0 P 0 ;0
L 1.77028996 -2.08223002 1.77028002 -2.08228002 0 P 0 ;0
L 1.77028002 -2.08228002 1.77028002 -2.08238996 0 P 0 ;0
L 1.77028002 -2.08238996 1.77056998 -2.08838996 0 P 0 ;0
L 1.77056998 -2.08838996 1.77096004 -2.09526004 0 P 0 ;0
L 1.77096004 -2.09526004 1.77153996 -2.1033 0 P 0 ;0
L 1.77153996 -2.1033 1.77236004 -2.11291004 0 P 0 ;0
L 1.77236004 -2.11291004 1.77311004 -2.1194 0 P 0 ;0
L 1.77311004 -2.1194 1.77383002 -2.12398002 0 P 0 ;0
L 1.77383002 -2.12398002 1.77386004 -2.12411004 0 P 0 ;0
L 1.77386004 -2.12411004 1.7739 -2.12423002 0 P 0 ;0
L 1.7739 -2.12423002 1.77395 -2.12436004 0 P 0 ;0
L 1.77395 -2.12436004 1.77401004 -2.12448002 0 P 0 ;0
L 1.77401004 -2.12448002 1.77408002 -2.12458996 0 P 0 ;0
L 1.77408002 -2.12458996 1.77416004 -2.1247 0 P 0 ;0
L 1.77416004 -2.1247 1.77425 -2.1248 0 P 0 ;0
L 1.77425 -2.1248 1.77435 -2.12488996 0 P 0 ;0
L 1.77435 -2.12488996 1.77445 -2.12496998 0 P 0 ;0
L 1.77445 -2.12496998 1.77456998 -2.12505 0 P 0 ;0
L 1.77456998 -2.12505 1.77571004 -2.12568996 0 P 0 ;0
L 1.77571004 -2.12568996 1.7769 -2.12623996 0 P 0 ;0
L 1.7769 -2.12623996 1.77813002 -2.12668996 0 P 0 ;0
L 1.77813002 -2.12668996 1.7794 -2.12703996 0 P 0 ;0
L 1.7794 -2.12703996 1.78068996 -2.12728996 0 P 0 ;0
L 1.78068996 -2.12728996 1.79791998 -2.12951004 0 P 0 ;0
L 1.79791998 -2.12951004 1.81536004 -2.13106004 0 P 0 ;0
L 1.81536004 -2.13106004 1.82125 -2.13123996 0 P 0 ;0
L 1.82125 -2.13123996 1.82716004 -2.13098996 0 P 0 ;0
L 1.82716004 -2.13098996 1.83583996 -2.12998002 0 P 0 ;0
L 1.83583996 -2.12998002 1.84445 -2.12836004 0 P 0 ;0
L 1.84445 -2.12836004 1.84911998 -2.12711004 0 P 0 ;0
L 1.84911998 -2.12711004 1.85366004 -2.12548002 0 P 0 ;0
L 1.85366004 -2.12548002 1.85806998 -2.12348002 0 P 0 ;0
L 1.85806998 -2.12348002 1.86078996 -2.12196998 0 P 0 ;0
L 1.86078996 -2.12196998 1.8634 -2.12026998 0 P 0 ;0
L 1.8634 -2.12026998 1.86586998 -2.11836998 0 P 0 ;0
L 1.86586998 -2.11836998 1.86821004 -2.11628002 0 P 0 ;0
L 1.86821004 -2.11628002 1.87026004 -2.11413002 0 P 0 ;0
L 1.87026004 -2.11413002 1.8721 -2.11181998 0 P 0 ;0
L 1.8721 -2.11181998 1.87375 -2.10936004 0 P 0 ;0
L 1.87375 -2.10936004 1.87516998 -2.10673996 0 P 0 ;0
L 1.87516998 -2.10673996 1.87605 -2.10483996 0 P 0 ;0
L 1.87605 -2.10483996 1.87683996 -2.10291004 0 P 0 ;0
L 1.87683996 -2.10291004 1.8772 -2.10188002 0 P 0 ;0
L 1.8772 -2.10188002 1.87748996 -2.10083002 0 P 0 ;0
L 1.87748996 -2.10083002 1.87771004 -2.09976998 0 P 0 ;0
L 1.87771004 -2.09976998 1.87798002 -2.09788996 0 P 0 ;0
L 1.87798002 -2.09788996 1.87811998 -2.09601004 0 P 0 ;0
L 1.87811998 -2.09601004 1.87821004 -2.08966998 0 P 0 ;0
L 1.87821004 -2.08966998 1.8781 -2.08353996 0 P 0 ;0
L 1.8781 -2.08353996 1.87798002 -2.08166004 0 P 0 ;0
L 1.87798002 -2.08166004 1.87773002 -2.07976998 0 P 0 ;0
L 1.87773002 -2.07976998 1.87753002 -2.07873996 0 P 0 ;0
L 1.87753002 -2.07873996 1.87726998 -2.07773996 0 P 0 ;0
L 1.87726998 -2.07773996 1.87695 -2.07673996 0 P 0 ;0
L 1.87695 -2.07673996 1.87628996 -2.07505 0 P 0 ;0
L 1.87628996 -2.07505 1.87553002 -2.07338002 0 P 0 ;0
L 1.87553002 -2.07338002 1.87441004 -2.07133996 0 P 0 ;0
L 1.87441004 -2.07133996 1.87313996 -2.06938002 0 P 0 ;0
L 1.87313996 -2.06938002 1.87171004 -2.06751004 0 P 0 ;0
L 1.87171004 -2.06751004 1.8688 -2.06416004 0 P 0 ;0
L 1.8688 -2.06416004 1.86566998 -2.06095 0 P 0 ;0
L 1.86566998 -2.06095 1.86181998 -2.05741998 0 P 0 ;0
L 1.86181998 -2.05741998 1.85778002 -2.05406998 0 P 0 ;0
L 1.85778002 -2.05406998 1.84833996 -2.04715 0 P 0 ;0
L 1.84833996 -2.04715 1.83913996 -2.0407 0 P 0 ;0
L 1.83913996 -2.0407 1.83686004 -2.0389 0 P 0 ;0
L 1.83686004 -2.0389 1.83471998 -2.03691998 0 P 0 ;0
L 1.83471998 -2.03691998 1.83428002 -2.03643002 0 P 0 ;0
L 1.83428002 -2.03643002 1.83386998 -2.0359 0 P 0 ;0
L 1.83386998 -2.0359 1.83351004 -2.03535 0 P 0 ;0
L 1.83351004 -2.03535 1.83318996 -2.03476004 0 P 0 ;0
L 1.83318996 -2.03476004 1.83291998 -2.03415 0 P 0 ;0
L 1.83291998 -2.03415 1.83283996 -2.03393996 0 P 0 ;0
L 1.83283996 -2.03393996 1.83278002 -2.03371004 0 P 0 ;0
L 1.83278002 -2.03371004 1.83273002 -2.03348996 0 P 0 ;0
L 1.83273002 -2.03348996 1.83271004 -2.03326004 0 P 0 ;0
L 1.83271004 -2.03326004 1.8327 -2.03303002 0 P 0 ;0
L 1.8327 -2.03303002 1.83271004 -2.0328 0 P 0 ;0
L 1.83271004 -2.0328 1.83275 -2.03258002 0 P 0 ;0
L 1.83275 -2.03258002 1.83278996 -2.03235 0 P 0 ;0
L 1.83278996 -2.03235 1.83286004 -2.03213002 0 P 0 ;0
L 1.83286004 -2.03213002 1.83293996 -2.03191998 0 P 0 ;0
L 1.83293996 -2.03191998 1.83305 -2.03171004 0 P 0 ;0
L 1.83305 -2.03171004 1.83325 -2.03135 0 P 0 ;0
L 1.83325 -2.03135 1.83348996 -2.03101998 0 P 0 ;0
L 1.83348996 -2.03101998 1.83375 -2.03071004 0 P 0 ;0
L 1.83375 -2.03071004 1.83403002 -2.03041004 0 P 0 ;0
L 1.83403002 -2.03041004 1.83433996 -2.03015 0 P 0 ;0
L 1.83433996 -2.03015 1.83466998 -2.02991004 0 P 0 ;0
L 1.83466998 -2.02991004 1.83501998 -2.02968996 0 P 0 ;0
L 1.83501998 -2.02968996 1.83538002 -2.02951004 0 P 0 ;0
L 1.83538002 -2.02951004 1.83576004 -2.02936004 0 P 0 ;0
L 1.83576004 -2.02936004 1.83615 -2.02923996 0 P 0 ;0
L 1.83615 -2.02923996 1.83655 -2.02915 0 P 0 ;0
L 1.83655 -2.02915 1.8392 -2.02873996 0 P 0 ;0
L 1.8392 -2.02873996 1.84188002 -2.0285 0 P 0 ;0
L 1.84188002 -2.0285 1.84458002 -2.02841004 0 P 0 ;0
L 1.84458002 -2.02841004 1.84993996 -2.02858002 0 P 0 ;0
L 1.84993996 -2.02858002 1.85526998 -2.02916004 0 P 0 ;0
L 1.85526998 -2.02916004 1.86155 -2.03023002 0 P 0 ;0
L 1.86155 -2.03023002 1.86778002 -2.03158002 0 P 0 ;0
L 1.86778002 -2.03158002 1.8713 -2.03238996 0 P 0 ;0
L 1.8713 -2.03238996 1.87428996 -2.03303002 0 P 0 ;0
L 1.87428996 -2.03303002 1.8769 -2.03356004 0 P 0 ;0
L 1.8769 -2.03356004 1.87691998 -2.03356998 0 P 0 ;0
L 1.87691998 -2.03356998 1.87696004 -2.03356998 0 P 0 ;0
L 1.87696004 -2.03356998 1.87696998 -2.03356004 0 P 0 ;0
L 1.87696998 -2.03356004 1.87701004 -2.03356004 0 P 0 ;0
L 1.87701004 -2.03356004 1.87703996 -2.03353996 0 P 0 ;0
L 1.87703996 -2.03353996 1.87706004 -2.03353002 0 P 0 ;0
L 1.87706004 -2.03353002 1.87706998 -2.03351998 0 P 0 ;0
L 1.87706998 -2.03351998 1.87708996 -2.03351004 0 P 0 ;0
L 1.87708996 -2.03351004 1.8771 -2.03348996 0 P 0 ;0
L 1.8771 -2.03348996 1.87711004 -2.03348002 0 P 0 ;0
L 1.87711004 -2.03348002 1.87721998 -2.0333 0 P 0 ;0
L 1.87721998 -2.0333 1.87731998 -2.0331 0 P 0 ;0
L 1.87731998 -2.0331 1.8774 -2.0329 0 P 0 ;0
L 1.8774 -2.0329 1.87746004 -2.03268996 0 P 0 ;0
L 1.87746004 -2.03268996 1.87751004 -2.03248002 0 P 0 ;0
L 1.87751004 -2.03248002 1.87753002 -2.03226998 0 P 0 ;0
L 1.87753002 -2.03226998 1.87753996 -2.03205 0 P 0 ;0
L 1.87753996 -2.03205 1.87753002 -2.03183002 0 P 0 ;0
L 1.87753002 -2.03183002 1.87565 -2.01323996 0 P 0 ;0
L 1.87565 -2.01323996 1.87371004 -1.99451998 0 P 0 ;0
L 1.87371004 -1.99451998 1.8737 -1.99438996 0 P 0 ;0
L 1.8737 -1.99438996 1.87366998 -1.99426998 0 P 0 ;0
L 1.87366998 -1.99426998 1.87363002 -1.99415 0 P 0 ;0
L 1.87363002 -1.99415 1.87358002 -1.99403002 0 P 0 ;0
L 1.87358002 -1.99403002 1.87351998 -1.99391004 0 P 0 ;0
L 1.87351998 -1.99391004 1.87346004 -1.9938 0 P 0 ;0
L 1.87346004 -1.9938 1.87338002 -1.9937 0 P 0 ;0
L 1.87338002 -1.9937 1.87328996 -1.9936 0 P 0 ;0
L 1.87328996 -1.9936 1.8732 -1.99351004 0 P 0 ;0
L 1.8732 -1.99351004 1.8731 -1.99343002 0 P 0 ;0
L 1.8731 -1.99343002 1.87298996 -1.99335 0 P 0 ;0
L 1.87298996 -1.99335 1.87248002 -1.99305 0 P 0 ;0
L 1.87248002 -1.99305 1.87193996 -1.99278002 0 P 0 ;0
L 1.87193996 -1.99278002 1.87136998 -1.99256998 0 P 0 ;0
L 1.87136998 -1.99256998 1.87078996 -1.99241004 0 P 0 ;0
L 1.87078996 -1.99241004 1.8702 -1.9923 0 P 0 ;0
L 1.8702 -1.9923 1.85876004 -1.99076004 0 P 0 ;0
L 1.85876004 -1.99076004 1.84691998 -1.98943002 0 P 0 ;0
L 1.84691998 -1.98943002 1.83693002 -1.98876004 0 P 0 ;0
L 1.83693002 -1.98876004 1.8318 -1.98863002 0 P 0 ;0
L 1.8318 -1.98863002 1.82623002 -1.98866998 0 P 0 ;0
L 1.82623002 -1.98866998 1.82106004 -1.98883996 0 P 0 ;0
L 1.82106004 -1.98883996 1.81726998 -1.98915 0 P 0 ;0
L 1.78061004 -2.12523996 1.84838002 -2.12523996 0 P 0 ;0
L 1.77733002 -2.12423996 1.85121004 -2.12423996 0 P 0 ;0
L 1.77573996 -2.12323996 1.85376998 -2.12323996 0 P 0 ;0
L 1.77558002 -2.12223996 1.85596998 -2.12223996 0 P 0 ;0
L 1.77541998 -2.12123996 1.85798996 -2.12123996 0 P 0 ;0
L 1.77526998 -2.12023996 1.85978996 -2.12023996 0 P 0 ;0
L 1.77511004 -2.11923996 1.86131998 -2.11923996 0 P 0 ;0
L 1.77498996 -2.11823996 1.86276004 -2.11823996 0 P 0 ;0
L 1.77486998 -2.11723996 1.86406998 -2.11723996 0 P 0 ;0
L 1.77475 -2.11623996 1.86526004 -2.11623996 0 P 0 ;0
L 1.77463996 -2.11523996 1.86638002 -2.11523996 0 P 0 ;0
L 1.77451998 -2.11423996 1.8674 -2.11423996 0 P 0 ;0
L 1.77441004 -2.11323996 1.86835 -2.11323996 0 P 0 ;0
L 1.77431004 -2.11223996 1.86921004 -2.11223996 0 P 0 ;0
L 1.77421998 -2.11123996 1.87001004 -2.11123996 0 P 0 ;0
L 1.77413996 -2.11023996 1.87075 -2.11023996 0 P 0 ;0
L 1.77405 -2.10923996 1.87141998 -2.10923996 0 P 0 ;0
L 1.77396998 -2.10823996 1.87208002 -2.10823996 0 P 0 ;0
L 1.77388002 -2.10723996 1.87261998 -2.10723996 0 P 0 ;0
L 1.7738 -2.10623996 1.87316998 -2.10623996 0 P 0 ;0
L 1.77371004 -2.10523996 1.87366004 -2.10523996 0 P 0 ;0
L 1.77363002 -2.10423996 1.87411998 -2.10423996 0 P 0 ;0
L 1.77353996 -2.10323996 1.87453996 -2.10323996 0 P 0 ;0
L 1.77346998 -2.10223996 1.87495 -2.10223996 0 P 0 ;0
L 1.7734 -2.10123996 1.8753 -2.10123996 0 P 0 ;0
L 1.77333002 -2.10023996 1.87556998 -2.10023996 0 P 0 ;0
L 1.77325 -2.09923996 1.87576998 -2.09923996 0 P 0 ;0
L 1.77318002 -2.09823996 1.87591998 -2.09823996 0 P 0 ;0
L 1.77311004 -2.09723996 1.87603002 -2.09723996 0 P 0 ;0
L 1.77303996 -2.09623996 1.8761 -2.09623996 0 P 0 ;0
L 1.77296998 -2.09523996 1.87613002 -2.09523996 0 P 0 ;0
L 1.77291004 -2.09423996 1.87613996 -2.09423996 0 P 0 ;0
L 1.77285 -2.09323996 1.87616004 -2.09323996 0 P 0 ;0
L 1.77278996 -2.09223996 1.87616998 -2.09223996 0 P 0 ;0
L 1.77273002 -2.09123996 1.80256998 -2.09123996 0 P 0 ;0
L 1.77268002 -2.09023996 1.7968 -2.09023996 0 P 0 ;0
L 1.77261998 -2.08923996 1.79263002 -2.08923996 0 P 0 ;0
L 1.77256004 -2.08823996 1.78861998 -2.08823996 0 P 0 ;0
L 1.77251004 -2.08723996 1.7846 -2.08723996 0 P 0 ;0
L 1.77246004 -2.08623996 1.7807 -2.08623996 0 P 0 ;0
L 1.77241998 -2.08523996 1.77705 -2.08523996 0 P 0 ;0
L 1.77236998 -2.08423996 1.77293996 -2.08423996 0 P 0 ;0
L 1.62463996 -2.18195 1.65948996 -2.18195 0 P 0 ;0
L 1.61963996 -2.18095 1.66483002 -2.18095 0 P 0 ;0
L 1.61818002 -1.99795 1.6724 -1.99795 0 P 0 ;0
L 1.61778996 -1.99695 1.67218002 -1.99695 0 P 0 ;0
L 1.6174 -1.99595 1.67196004 -1.99595 0 P 0 ;0
L 1.61701004 -1.99495 1.67173996 -1.99495 0 P 0 ;0
L 1.61391998 -2.15695 1.70026004 -2.15695 0 P 0 ;0
L 1.61386004 -2.15595 1.70088002 -2.15595 0 P 0 ;0
L 1.61381004 -2.15495 1.70151004 -2.15495 0 P 0 ;0
L 1.61375 -2.15395 1.70213996 -2.15395 0 P 0 ;0
L 1.6137 -2.15295 1.70276004 -2.15295 0 P 0 ;0
L 1.61365 -2.15195 1.70338996 -2.15195 0 P 0 ;0
L 1.6136 -2.15095 1.70401004 -2.15095 0 P 0 ;0
L 1.61355 -2.14995 1.70456998 -2.14995 0 P 0 ;0
L 1.61348996 -2.14895 1.70511998 -2.14895 0 P 0 ;0
L 1.61343996 -2.14795 1.61738002 -2.14795 0 P 0 ;0
L 1.55341004 -2.08286998 1.60538002 -2.08286998 0 P 0 ;0
L 1.55286004 -2.08186998 1.60526998 -2.08186998 0 P 0 ;0
L 1.5521 -2.08086998 1.6051 -2.08086998 0 P 0 ;0
L 1.55126998 -2.07986998 1.6049 -2.07986998 0 P 0 ;0
L 1.55033996 -2.07886998 1.60463996 -2.07886998 0 P 0 ;0
L 1.54928996 -2.07786998 1.60433002 -2.07786998 0 P 0 ;0
L 1.54806998 -2.07686998 1.60398996 -2.07686998 0 P 0 ;0
L 1.5467 -2.07586998 1.60356998 -2.07586998 0 P 0 ;0
L 1.54531004 -2.07486998 1.6031 -2.07486998 0 P 0 ;0
L 1.54391004 -2.07386998 1.60258996 -2.07386998 0 P 0 ;0
L 1.54251004 -2.07286998 1.60201004 -2.07286998 0 P 0 ;0
L 1.54111998 -2.07186998 1.60138002 -2.07186998 0 P 0 ;0
L 1.53971998 -2.07086998 1.60068002 -2.07086998 0 P 0 ;0
L 1.53833002 -2.06986998 1.59993002 -2.06986998 0 P 0 ;0
L 1.53693002 -2.06886998 1.59908002 -2.06886998 0 P 0 ;0
L 1.53556004 -2.06786998 1.59821004 -2.06786998 0 P 0 ;0
L 1.53418996 -2.06686998 1.59733996 -2.06686998 0 P 0 ;0
L 1.53281998 -2.06586998 1.59646998 -2.06586998 0 P 0 ;0
L 1.53145 -2.06486998 1.5955 -2.06486998 0 P 0 ;0
L 1.53008002 -2.06386998 1.59453002 -2.06386998 0 P 0 ;0
L 1.52871004 -2.06286998 1.59356004 -2.06286998 0 P 0 ;0
L 1.52733996 -2.06186998 1.59253002 -2.06186998 0 P 0 ;0
L 1.52596998 -2.06086998 1.59145 -2.06086998 0 P 0 ;0
L 1.5246 -2.05986998 1.59038002 -2.05986998 0 P 0 ;0
L 1.52323002 -2.05886998 1.5893 -2.05886998 0 P 0 ;0
L 1.52186004 -2.05786998 1.58813996 -2.05786998 0 P 0 ;0
L 1.52053996 -2.05686998 1.58696004 -2.05686998 0 P 0 ;0
L 1.51935 -2.05586998 1.58576998 -2.05586998 0 P 0 ;0
L 1.51816004 -2.05486998 1.58456998 -2.05486998 0 P 0 ;0
L 1.51706998 -2.05386998 1.58321004 -2.05386998 0 P 0 ;0
L 1.51603996 -2.05286998 1.58185 -2.05286998 0 P 0 ;0
L 1.51501998 -2.05186998 1.58048996 -2.05186998 0 P 0 ;0
L 1.51408996 -2.05086998 1.57913002 -2.05086998 0 P 0 ;0
L 1.5132 -2.04986998 1.57776998 -2.04986998 0 P 0 ;0
L 1.51231998 -2.04886998 1.57641998 -2.04886998 0 P 0 ;0
L 1.51151004 -2.04786998 1.57505 -2.04786998 0 P 0 ;0
L 1.51075 -2.04686998 1.57365 -2.04686998 0 P 0 ;0
L 1.51008002 -2.04586998 1.57223002 -2.04586998 0 P 0 ;0
L 1.50945 -2.04486998 1.57081004 -2.04486998 0 P 0 ;0
L 1.50888002 -2.04386998 1.56938996 -2.04386998 0 P 0 ;0
L 1.50836004 -2.04286998 1.56796998 -2.04286998 0 P 0 ;0
L 1.5079 -2.04186998 1.56655 -2.04186998 0 P 0 ;0
L 1.50748002 -2.04086998 1.56518996 -2.04086998 0 P 0 ;0
L 1.50708996 -2.03986998 1.564 -2.03986998 0 P 0 ;0
L 1.50676004 -2.03886998 1.56296998 -2.03886998 0 P 0 ;0
L 1.50641998 -2.03786998 1.56206004 -2.03786998 0 P 0 ;0
L 1.50616998 -2.03686998 1.56125 -2.03686998 0 P 0 ;0
L 1.50591004 -2.03586998 1.56066998 -2.03586998 0 P 0 ;0
L 1.5057 -2.03486998 1.56031998 -2.03486998 0 P 0 ;0
L 1.50551998 -2.03386998 1.56016004 -2.03386998 0 P 0 ;0
L 1.50533996 -2.03286998 1.56016998 -2.03286998 0 P 0 ;0
L 1.50523996 -2.03186998 1.56036004 -2.03186998 0 P 0 ;0
L 1.50513002 -2.03086998 1.56071998 -2.03086998 0 P 0 ;0
L 1.50506998 -2.02986998 1.56131004 -2.02986998 0 P 0 ;0
L 1.50503996 -2.02886998 1.5622 -2.02886998 0 P 0 ;0
L 1.50501004 -2.02786998 1.56355 -2.02786998 0 P 0 ;0
L 1.50501998 -2.02686998 1.5657 -2.02686998 0 P 0 ;0
L 1.50506998 -2.02586998 1.60378996 -2.02586998 0 P 0 ;0
L 1.50511998 -2.02486998 1.60371004 -2.02486998 0 P 0 ;0
L 1.50521004 -2.02386998 1.60363996 -2.02386998 0 P 0 ;0
L 1.50533996 -2.02286998 1.60356998 -2.02286998 0 P 0 ;0
L 1.50546998 -2.02186998 1.6035 -2.02186998 0 P 0 ;0
L 1.50563996 -2.02086998 1.60343002 -2.02086998 0 P 0 ;0
L 1.50585 -2.01986998 1.60336004 -2.01986998 0 P 0 ;0
L 1.50606004 -2.01886998 1.60328996 -2.01886998 0 P 0 ;0
L 1.50633002 -2.01786998 1.60321998 -2.01786998 0 P 0 ;0
L 1.50661998 -2.01686998 1.60315 -2.01686998 0 P 0 ;0
L 1.50691004 -2.01586998 1.60308002 -2.01586998 0 P 0 ;0
L 1.50726998 -2.01486998 1.603 -2.01486998 0 P 0 ;0
L 1.50766004 -2.01386998 1.60293002 -2.01386998 0 P 0 ;0
L 1.50808996 -2.01286998 1.60285 -2.01286998 0 P 0 ;0
L 1.50856998 -2.01186998 1.60278002 -2.01186998 0 P 0 ;0
L 1.50908996 -2.01086998 1.6027 -2.01086998 0 P 0 ;0
L 1.50966004 -2.00986998 1.60261998 -2.00986998 0 P 0 ;0
L 1.51028996 -2.00886998 1.60255 -2.00886998 0 P 0 ;0
L 1.51096998 -2.00786998 1.60246998 -2.00786998 0 P 0 ;0
L 1.51171998 -2.00686998 1.6024 -2.00686998 0 P 0 ;0
L 1.51253996 -2.00586998 1.60233002 -2.00586998 0 P 0 ;0
L 1.51343996 -2.00486998 1.60225 -2.00486998 0 P 0 ;0
L 1.5144 -2.00386998 1.60218002 -2.00386998 0 P 0 ;0
L 1.51551998 -2.00286998 1.6021 -2.00286998 0 P 0 ;0
L 1.51663996 -2.00186998 1.60203002 -2.00186998 0 P 0 ;0
L 1.51795 -2.00086998 1.60195 -2.00086998 0 P 0 ;0
L 1.51928996 -1.99986998 1.60183996 -1.99986998 0 P 0 ;0
L 1.52086998 -1.99886998 1.60173002 -1.99886998 0 P 0 ;0
L 1.52258996 -1.99786998 1.60156998 -1.99786998 0 P 0 ;0
L 1.52451004 -1.99686998 1.60138996 -1.99686998 0 P 0 ;0
L 1.52686998 -1.99586998 1.60106998 -1.99586998 0 P 0 ;0
L 1.52976004 -1.99486998 1.59943996 -1.99486998 0 P 0 ;0
L 1.53283002 -1.99386998 1.59543002 -1.99386998 0 P 0 ;0
L 1.53678996 -1.99286998 1.59003996 -1.99286998 0 P 0 ;0
L 1.54173996 -1.99186998 1.58073996 -1.99186998 0 P 0 ;0
L 1.55036998 -1.99086998 1.56493002 -1.99086998 0 P 0 ;0
L 1.6036 -2.03086998 1.60413996 -2.03086998 0 P 0 ;0
L 1.59891004 -2.02986998 1.60406998 -2.02986998 0 P 0 ;0
L 1.59435 -2.02886998 1.604 -2.02886998 0 P 0 ;0
L 1.58838996 -2.02786998 1.60393002 -2.02786998 0 P 0 ;0
L 1.57981004 -2.02686998 1.60386004 -2.02686998 0 P 0 ;0
L 1.54575 -1.98923996 1.53931998 -1.99021998 0 P 0 ;0
L 1.53931998 -1.99021998 1.53298996 -1.99171998 0 P 0 ;0
L 1.53298996 -1.99171998 1.52678996 -1.99373996 0 P 0 ;0
L 1.52678996 -1.99373996 1.52376998 -1.995 0 P 0 ;0
L 1.52376998 -1.995 1.52086998 -1.99651004 0 P 0 ;0
L 1.52086998 -1.99651004 1.5181 -1.99826004 0 P 0 ;0
L 1.5181 -1.99826004 1.51548002 -2.00023002 0 P 0 ;0
L 1.51548002 -2.00023002 1.51301004 -2.00243002 0 P 0 ;0
L 1.51301004 -2.00243002 1.51128996 -2.00423002 0 P 0 ;0
L 1.51128996 -2.00423002 1.50971998 -2.00616004 0 P 0 ;0
L 1.50971998 -2.00616004 1.50831004 -2.00821004 0 P 0 ;0
L 1.50831004 -2.00821004 1.50706998 -2.01036998 0 P 0 ;0
L 1.50706998 -2.01036998 1.50598996 -2.01261998 0 P 0 ;0
L 1.50598996 -2.01261998 1.50508996 -2.01496998 0 P 0 ;0
L 1.50508996 -2.01496998 1.5042 -2.01801004 0 P 0 ;0
L 1.5042 -2.01801004 1.50355 -2.02111004 0 P 0 ;0
L 1.50355 -2.02111004 1.50313996 -2.02426004 0 P 0 ;0
L 1.50313996 -2.02426004 1.50298996 -2.02743002 0 P 0 ;0
L 1.50298996 -2.02743002 1.50308996 -2.03063002 0 P 0 ;0
L 1.50308996 -2.03063002 1.50338002 -2.03326998 0 P 0 ;0
L 1.50338002 -2.03326998 1.50385 -2.03588002 0 P 0 ;0
L 1.50385 -2.03588002 1.50451004 -2.03845 0 P 0 ;0
L 1.50451004 -2.03845 1.50535 -2.04096998 0 P 0 ;0
L 1.50535 -2.04096998 1.50633002 -2.0433 0 P 0 ;0
L 1.50633002 -2.0433 1.5075 -2.04553002 0 P 0 ;0
L 1.5075 -2.04553002 1.50883996 -2.04766998 0 P 0 ;0
L 1.50883996 -2.04766998 1.51036998 -2.04968996 0 P 0 ;0
L 1.51036998 -2.04968996 1.51323002 -2.05291998 0 P 0 ;0
L 1.51323002 -2.05291998 1.51631998 -2.05593996 0 P 0 ;0
L 1.51631998 -2.05593996 1.51961998 -2.05871004 0 P 0 ;0
L 1.51961998 -2.05871004 1.53591004 -2.0706 0 P 0 ;0
L 1.53591004 -2.0706 1.54668002 -2.07831004 0 P 0 ;0
L 1.54668002 -2.07831004 1.54793996 -2.07933996 0 P 0 ;0
L 1.54793996 -2.07933996 1.54911998 -2.08046998 0 P 0 ;0
L 1.54911998 -2.08046998 1.55021004 -2.08168002 0 P 0 ;0
L 1.55021004 -2.08168002 1.5512 -2.08298996 0 P 0 ;0
L 1.5512 -2.08298996 1.55136004 -2.08323002 0 P 0 ;0
L 1.55136004 -2.08323002 1.5515 -2.08348002 0 P 0 ;0
L 1.5515 -2.08348002 1.55161004 -2.08373996 0 P 0 ;0
L 1.55161004 -2.08373996 1.5517 -2.08401998 0 P 0 ;0
L 1.5517 -2.08401998 1.55176998 -2.0843 0 P 0 ;0
L 1.55176998 -2.0843 1.55181004 -2.08458002 0 P 0 ;0
L 1.55181004 -2.08458002 1.55183002 -2.08486998 0 P 0 ;0
L 1.55183002 -2.08486998 1.55181998 -2.08516004 0 P 0 ;0
L 1.55181998 -2.08516004 1.55178996 -2.08545 0 P 0 ;0
L 1.55178996 -2.08545 1.55173996 -2.08573002 0 P 0 ;0
L 1.55173996 -2.08573002 1.55166004 -2.086 0 P 0 ;0
L 1.55166004 -2.086 1.55156004 -2.08628002 0 P 0 ;0
L 1.55156004 -2.08628002 1.55136998 -2.08666998 0 P 0 ;0
L 1.55136998 -2.08666998 1.55115 -2.08703996 0 P 0 ;0
L 1.55115 -2.08703996 1.5509 -2.08738996 0 P 0 ;0
L 1.5509 -2.08738996 1.55063002 -2.08771998 0 P 0 ;0
L 1.55063002 -2.08771998 1.55033002 -2.08803002 0 P 0 ;0
L 1.55033002 -2.08803002 1.55 -2.08831004 0 P 0 ;0
L 1.55 -2.08831004 1.54966004 -2.08856004 0 P 0 ;0
L 1.54966004 -2.08856004 1.54928996 -2.08878996 0 P 0 ;0
L 1.54928996 -2.08878996 1.5489 -2.08898996 0 P 0 ;0
L 1.5489 -2.08898996 1.54786004 -2.08941004 0 P 0 ;0
L 1.54786004 -2.08941004 1.54678996 -2.08973996 0 P 0 ;0
L 1.54678996 -2.08973996 1.54568002 -2.08998002 0 P 0 ;0
L 1.54568002 -2.08998002 1.54456998 -2.09011998 0 P 0 ;0
L 1.54456998 -2.09011998 1.54343996 -2.09016998 0 P 0 ;0
L 1.54343996 -2.09016998 1.53906998 -2.09003002 0 P 0 ;0
L 1.53906998 -2.09003002 1.53468002 -2.08961998 0 P 0 ;0
L 1.53468002 -2.08961998 1.52908996 -2.08878996 0 P 0 ;0
L 1.52908996 -2.08878996 1.52351004 -2.08766004 0 P 0 ;0
L 1.52351004 -2.08766004 1.51005 -2.08418996 0 P 0 ;0
L 1.51005 -2.08418996 1.50631004 -2.08318002 0 P 0 ;0
L 1.50631004 -2.08318002 1.50308002 -2.08238996 0 P 0 ;0
L 1.50308002 -2.08238996 1.50033996 -2.08183002 0 P 0 ;0
L 1.50033996 -2.08183002 1.5003 -2.08181998 0 P 0 ;0
L 1.5003 -2.08181998 1.50016004 -2.08181998 0 P 0 ;0
L 1.50016004 -2.08181998 1.50011998 -2.08183002 0 P 0 ;0
L 1.50011998 -2.08183002 1.50006998 -2.08183996 0 P 0 ;0
L 1.50006998 -2.08183996 1.50003002 -2.08186004 0 P 0 ;0
L 1.50003002 -2.08186004 1.49998996 -2.08186998 0 P 0 ;0
L 1.49998996 -2.08186998 1.49995 -2.08188996 0 P 0 ;0
L 1.49995 -2.08188996 1.49991004 -2.08191998 0 P 0 ;0
L 1.49991004 -2.08191998 1.49988002 -2.08195 0 P 0 ;0
L 1.49988002 -2.08195 1.49983996 -2.08198002 0 P 0 ;0
L 1.49983996 -2.08198002 1.4997 -2.08213996 0 P 0 ;0
L 1.4997 -2.08213996 1.49956004 -2.08231998 0 P 0 ;0
L 1.49956004 -2.08231998 1.49943996 -2.0825 0 P 0 ;0
L 1.49943996 -2.0825 1.49933996 -2.0827 0 P 0 ;0
L 1.49933996 -2.0827 1.49925 -2.0829 0 P 0 ;0
L 1.49925 -2.0829 1.49918996 -2.08311004 0 P 0 ;0
L 1.49918996 -2.08311004 1.49913996 -2.08333002 0 P 0 ;0
L 1.49913996 -2.08333002 1.49911004 -2.08355 0 P 0 ;0
L 1.49911004 -2.08355 1.4991 -2.08376998 0 P 0 ;0
L 1.4991 -2.08376998 1.49911004 -2.08398996 0 P 0 ;0
L 1.49911004 -2.08398996 1.50071004 -2.10395 0 P 0 ;0
L 1.50071004 -2.10395 1.5024 -2.12403996 0 P 0 ;0
L 1.5024 -2.12403996 1.50241998 -2.12418002 0 P 0 ;0
L 1.50241998 -2.12418002 1.50246004 -2.12431004 0 P 0 ;0
L 1.50246004 -2.12431004 1.50248996 -2.12445 0 P 0 ;0
L 1.50248996 -2.12445 1.50255 -2.12456998 0 P 0 ;0
L 1.50255 -2.12456998 1.50261004 -2.1247 0 P 0 ;0
L 1.50261004 -2.1247 1.50276998 -2.12491998 0 P 0 ;0
L 1.50276998 -2.12491998 1.50286004 -2.12501998 0 P 0 ;0
L 1.50286004 -2.12501998 1.50296998 -2.12511998 0 P 0 ;0
L 1.50296998 -2.12511998 1.50308002 -2.12521004 0 P 0 ;0
L 1.50308002 -2.12521004 1.50318996 -2.12528002 0 P 0 ;0
L 1.50318996 -2.12528002 1.50331998 -2.12535 0 P 0 ;0
L 1.50331998 -2.12535 1.50343996 -2.1254 0 P 0 ;0
L 1.50343996 -2.1254 1.50391998 -2.12556004 0 P 0 ;0
L 1.50391998 -2.12556004 1.5044 -2.12568996 0 P 0 ;0
L 1.5044 -2.12568996 1.50848002 -2.12648996 0 P 0 ;0
L 1.50848002 -2.12648996 1.51328996 -2.12738002 0 P 0 ;0
L 1.51328996 -2.12738002 1.51873996 -2.12833996 0 P 0 ;0
L 1.51873996 -2.12833996 1.52606004 -2.12945 0 P 0 ;0
L 1.52606004 -2.12945 1.53343996 -2.13023002 0 P 0 ;0
L 1.53343996 -2.13023002 1.54886998 -2.13086998 0 P 0 ;0
L 1.54886998 -2.13086998 1.56305 -2.1303 0 P 0 ;0
L 1.56305 -2.1303 1.56666004 -2.12988996 0 P 0 ;0
L 1.56666004 -2.12988996 1.57023002 -2.12926998 0 P 0 ;0
L 1.57023002 -2.12926998 1.5738 -2.12843002 0 P 0 ;0
L 1.5738 -2.12843002 1.57945 -2.12668996 0 P 0 ;0
L 1.57945 -2.12668996 1.58498002 -2.12456998 0 P 0 ;0
L 1.58498002 -2.12456998 1.58793996 -2.12318002 0 P 0 ;0
L 1.58793996 -2.12318002 1.59078996 -2.12156004 0 P 0 ;0
L 1.59078996 -2.12156004 1.59348996 -2.11971998 0 P 0 ;0
L 1.59348996 -2.11971998 1.59525 -2.11833002 0 P 0 ;0
L 1.59525 -2.11833002 1.5969 -2.11681998 0 P 0 ;0
L 1.5969 -2.11681998 1.59846004 -2.11521004 0 P 0 ;0
L 1.59846004 -2.11521004 1.59991004 -2.11348002 0 P 0 ;0
L 1.59991004 -2.11348002 1.60175 -2.11093996 0 P 0 ;0
L 1.60175 -2.11093996 1.60338002 -2.10826998 0 P 0 ;0
L 1.60338002 -2.10826998 1.60481004 -2.10548002 0 P 0 ;0
L 1.60481004 -2.10548002 1.60573002 -2.10321004 0 P 0 ;0
L 1.60573002 -2.10321004 1.60646004 -2.10088002 0 P 0 ;0
L 1.60646004 -2.10088002 1.60698002 -2.09848996 0 P 0 ;0
L 1.60698002 -2.09848996 1.60756004 -2.09421998 0 P 0 ;0
L 1.60756004 -2.09421998 1.6078 -2.08991004 0 P 0 ;0
L 1.6078 -2.08991004 1.60768996 -2.08565 0 P 0 ;0
L 1.60768996 -2.08565 1.60723002 -2.08141998 0 P 0 ;0
L 1.60723002 -2.08141998 1.60691998 -2.07968002 0 P 0 ;0
L 1.60691998 -2.07968002 1.60646998 -2.07796998 0 P 0 ;0
L 1.60646998 -2.07796998 1.60591998 -2.0763 0 P 0 ;0
L 1.60591998 -2.0763 1.60523002 -2.07466998 0 P 0 ;0
L 1.60523002 -2.07466998 1.60411998 -2.07246998 0 P 0 ;0
L 1.60411998 -2.07246998 1.60281004 -2.07038002 0 P 0 ;0
L 1.60281004 -2.07038002 1.60131998 -2.06838996 0 P 0 ;0
L 1.60131998 -2.06838996 1.59803996 -2.06461998 0 P 0 ;0
L 1.59803996 -2.06461998 1.59455 -2.06101998 0 P 0 ;0
L 1.59455 -2.06101998 1.59031998 -2.05708996 0 P 0 ;0
L 1.59031998 -2.05708996 1.58586004 -2.05333996 0 P 0 ;0
L 1.58586004 -2.05333996 1.57588002 -2.04598996 0 P 0 ;0
L 1.57588002 -2.04598996 1.56685 -2.03963996 0 P 0 ;0
L 1.56685 -2.03963996 1.56578002 -2.03878996 0 P 0 ;0
L 1.56578002 -2.03878996 1.56476998 -2.03786004 0 P 0 ;0
L 1.56476998 -2.03786004 1.56383002 -2.03686998 0 P 0 ;0
L 1.56383002 -2.03686998 1.56295 -2.0358 0 P 0 ;0
L 1.56295 -2.0358 1.56276998 -2.03555 0 P 0 ;0
L 1.56276998 -2.03555 1.56261004 -2.03528002 0 P 0 ;0
L 1.56261004 -2.03528002 1.56246998 -2.035 0 P 0 ;0
L 1.56246998 -2.035 1.56236004 -2.03471998 0 P 0 ;0
L 1.56236004 -2.03471998 1.56226998 -2.03441998 0 P 0 ;0
L 1.56226998 -2.03441998 1.5622 -2.03411998 0 P 0 ;0
L 1.5622 -2.03411998 1.56216004 -2.03381998 0 P 0 ;0
L 1.56216004 -2.03381998 1.56213996 -2.03351004 0 P 0 ;0
L 1.56213996 -2.03351004 1.56215 -2.0332 0 P 0 ;0
L 1.56215 -2.0332 1.56218002 -2.03288996 0 P 0 ;0
L 1.56218002 -2.03288996 1.56225 -2.03253996 0 P 0 ;0
L 1.56225 -2.03253996 1.56233996 -2.03221004 0 P 0 ;0
L 1.56233996 -2.03221004 1.56246004 -2.03186998 0 P 0 ;0
L 1.56246004 -2.03186998 1.56261004 -2.03156004 0 P 0 ;0
L 1.56261004 -2.03156004 1.56278996 -2.03125 0 P 0 ;0
L 1.56278996 -2.03125 1.56298002 -2.03096004 0 P 0 ;0
L 1.56298002 -2.03096004 1.56321004 -2.03068996 0 P 0 ;0
L 1.56321004 -2.03068996 1.56345 -2.03043996 0 P 0 ;0
L 1.56345 -2.03043996 1.56371004 -2.0302 0 P 0 ;0
L 1.56371004 -2.0302 1.56416004 -2.02986004 0 P 0 ;0
L 1.56416004 -2.02986004 1.56463002 -2.02955 0 P 0 ;0
L 1.56463002 -2.02955 1.56511998 -2.02928002 0 P 0 ;0
L 1.56511998 -2.02928002 1.56561998 -2.02903002 0 P 0 ;0
L 1.56561998 -2.02903002 1.56611998 -2.02883996 0 P 0 ;0
L 1.56611998 -2.02883996 1.56663996 -2.02866998 0 P 0 ;0
L 1.56663996 -2.02866998 1.56716004 -2.02855 0 P 0 ;0
L 1.56716004 -2.02855 1.5677 -2.02846998 0 P 0 ;0
L 1.5677 -2.02846998 1.56926998 -2.02835 0 P 0 ;0
L 1.56926998 -2.02835 1.57085 -2.02833996 0 P 0 ;0
L 1.57085 -2.02833996 1.57725 -2.02866998 0 P 0 ;0
L 1.57725 -2.02866998 1.58205 -2.02906004 0 P 0 ;0
L 1.58205 -2.02906004 1.58746998 -2.02975 0 P 0 ;0
L 1.58746998 -2.02975 1.59271004 -2.03056998 0 P 0 ;0
L 1.59271004 -2.03056998 1.59681004 -2.03143002 0 P 0 ;0
L 1.59681004 -2.03143002 1.60016004 -2.03221998 0 P 0 ;0
L 1.60016004 -2.03221998 1.60308002 -2.03281004 0 P 0 ;0
L 1.60308002 -2.03281004 1.60553996 -2.03323996 0 P 0 ;0
L 1.60553996 -2.03323996 1.60568996 -2.03323996 0 P 0 ;0
L 1.60568996 -2.03323996 1.60576998 -2.03321998 0 P 0 ;0
L 1.60576998 -2.03321998 1.60586004 -2.03316004 0 P 0 ;0
L 1.60586004 -2.03316004 1.6059 -2.03313996 0 P 0 ;0
L 1.6059 -2.03313996 1.60591998 -2.03311004 0 P 0 ;0
L 1.60591998 -2.03311004 1.60598996 -2.03303996 0 P 0 ;0
L 1.60598996 -2.03303996 1.60605 -2.03296998 0 P 0 ;0
L 1.60605 -2.03296998 1.6061 -2.03288996 0 P 0 ;0
L 1.6061 -2.03288996 1.60618002 -2.03273002 0 P 0 ;0
L 1.60618002 -2.03273002 1.60621004 -2.03263002 0 P 0 ;0
L 1.60621004 -2.03263002 1.60623002 -2.03253996 0 P 0 ;0
L 1.60623002 -2.03253996 1.60625 -2.03236004 0 P 0 ;0
L 1.60625 -2.03236004 1.60623996 -2.03226004 0 P 0 ;0
L 1.60623996 -2.03226004 1.60508002 -2.01578002 0 P 0 ;0
L 1.60508002 -2.01578002 1.60393996 -2.00068002 0 P 0 ;0
L 1.60393996 -2.00068002 1.60368002 -1.99833996 0 P 0 ;0
L 1.60368002 -1.99833996 1.60326998 -1.99601004 0 P 0 ;0
L 1.60326998 -1.99601004 1.60321004 -1.99576998 0 P 0 ;0
L 1.60321004 -1.99576998 1.60313996 -1.99553002 0 P 0 ;0
L 1.60313996 -1.99553002 1.60303996 -1.9953 0 P 0 ;0
L 1.60303996 -1.9953 1.60293002 -1.99508002 0 P 0 ;0
L 1.60293002 -1.99508002 1.60281004 -1.99486004 0 P 0 ;0
L 1.60281004 -1.99486004 1.60261998 -1.9946 0 P 0 ;0
L 1.60261998 -1.9946 1.60241004 -1.99435 0 P 0 ;0
L 1.60241004 -1.99435 1.60218002 -1.99411998 0 P 0 ;0
L 1.60218002 -1.99411998 1.60191998 -1.99391004 0 P 0 ;0
L 1.60191998 -1.99391004 1.60161004 -1.99368996 0 P 0 ;0
L 1.60161004 -1.99368996 1.60128996 -1.99348996 0 P 0 ;0
L 1.60128996 -1.99348996 1.60095 -1.99331998 0 P 0 ;0
L 1.60095 -1.99331998 1.6006 -1.99316004 0 P 0 ;0
L 1.6006 -1.99316004 1.59966004 -1.99283002 0 P 0 ;0
L 1.59966004 -1.99283002 1.59871004 -1.99255 0 P 0 ;0
L 1.59871004 -1.99255 1.5933 -1.99135 0 P 0 ;0
L 1.5933 -1.99135 1.5878 -1.9905 0 P 0 ;0
L 1.5878 -1.9905 1.57285 -1.98915 0 P 0 ;0
L 1.57285 -1.98915 1.55763996 -1.98861004 0 P 0 ;0
L 1.55763996 -1.98861004 1.55171004 -1.98876004 0 P 0 ;0
L 1.55171004 -1.98876004 1.54575 -1.98923996 0 P 0 ;0
L 1.53011998 -2.12786998 1.5666 -2.12786998 0 P 0 ;0
L 1.52236004 -2.12686998 1.57168002 -2.12686998 0 P 0 ;0
L 1.51621998 -2.12586998 1.5753 -2.12586998 0 P 0 ;0
L 1.51071004 -2.12486998 1.57856004 -2.12486998 0 P 0 ;0
L 1.50553002 -2.12386998 1.58121004 -2.12386998 0 P 0 ;0
L 1.50431004 -2.12286998 1.58381998 -2.12286998 0 P 0 ;0
L 1.50423002 -2.12186998 1.58601998 -2.12186998 0 P 0 ;0
L 1.50413996 -2.12086998 1.58796004 -2.12086998 0 P 0 ;0
L 1.50406004 -2.11986998 1.58971004 -2.11986998 0 P 0 ;0
L 1.50396998 -2.11886998 1.59118002 -2.11886998 0 P 0 ;0
L 1.50388996 -2.11786998 1.5926 -2.11786998 0 P 0 ;0
L 1.50381004 -2.11686998 1.59386004 -2.11686998 0 P 0 ;0
L 1.50371998 -2.11586998 1.59496998 -2.11586998 0 P 0 ;0
L 1.50363996 -2.11486998 1.59601004 -2.11486998 0 P 0 ;0
L 1.50355 -2.11386998 1.59696998 -2.11386998 0 P 0 ;0
L 1.50346998 -2.11286998 1.59781004 -2.11286998 0 P 0 ;0
L 1.50338002 -2.11186998 1.5986 -2.11186998 0 P 0 ;0
L 1.5033 -2.11086998 1.59933002 -2.11086998 0 P 0 ;0
L 1.50321004 -2.10986998 1.60005 -2.10986998 0 P 0 ;0
L 1.50313002 -2.10886998 1.60066998 -2.10886998 0 P 0 ;0
L 1.50305 -2.10786998 1.60128002 -2.10786998 0 P 0 ;0
L 1.50296004 -2.10686998 1.60185 -2.10686998 0 P 0 ;0
L 1.50288002 -2.10586998 1.60236004 -2.10586998 0 P 0 ;0
L 1.50278996 -2.10486998 1.60286998 -2.10486998 0 P 0 ;0
L 1.50271004 -2.10386998 1.6033 -2.10386998 0 P 0 ;0
L 1.50263002 -2.10286998 1.60371004 -2.10286998 0 P 0 ;0
L 1.50255 -2.10186998 1.60405 -2.10186998 0 P 0 ;0
L 1.50246998 -2.10086998 1.60436004 -2.10086998 0 P 0 ;0
L 1.50238996 -2.09986998 1.60463002 -2.09986998 0 P 0 ;0
L 1.50231004 -2.09886998 1.60485 -2.09886998 0 P 0 ;0
L 1.50223002 -2.09786998 1.60505 -2.09786998 0 P 0 ;0
L 1.50215 -2.09686998 1.60518002 -2.09686998 0 P 0 ;0
L 1.50206998 -2.09586998 1.60531998 -2.09586998 0 P 0 ;0
L 1.50198996 -2.09486998 1.60545 -2.09486998 0 P 0 ;0
L 1.50191004 -2.09386998 1.60558002 -2.09386998 0 P 0 ;0
L 1.50183002 -2.09286998 1.60563002 -2.09286998 0 P 0 ;0
L 1.50175 -2.09186998 1.53725 -2.09186998 0 P 0 ;0
L 1.54638996 -2.09186998 1.60568996 -2.09186998 0 P 0 ;0
L 1.50166998 -2.09086998 1.5295 -2.09086998 0 P 0 ;0
L 1.54956998 -2.09086998 1.60573996 -2.09086998 0 P 0 ;0
L 1.50158996 -2.08986998 1.52436004 -2.08986998 0 P 0 ;0
L 1.55125 -2.08986998 1.60578996 -2.08986998 0 P 0 ;0
L 1.50151004 -2.08886998 1.52021004 -2.08886998 0 P 0 ;0
L 1.55226998 -2.08886998 1.60576998 -2.08886998 0 P 0 ;0
L 1.50143002 -2.08786998 1.51633002 -2.08786998 0 P 0 ;0
L 1.55298002 -2.08786998 1.60573996 -2.08786998 0 P 0 ;0
L 1.50133996 -2.08686998 1.51246004 -2.08686998 0 P 0 ;0
L 1.55346998 -2.08686998 1.60571998 -2.08686998 0 P 0 ;0
L 1.50126998 -2.08586998 1.50861998 -2.08586998 0 P 0 ;0
L 1.55375 -2.08586998 1.60568996 -2.08586998 0 P 0 ;0
L 1.50118002 -2.08486998 1.50481004 -2.08486998 0 P 0 ;0
L 1.55383002 -2.08486998 1.60558996 -2.08486998 0 P 0 ;0
L 1.55371998 -2.08386998 1.60548996 -2.08386998 0 P 0 ;0
L 1.54886998 -2.12886998 1.53358996 -2.12823996 0 P 0 ;0
L 1.53358996 -2.12823996 1.52631998 -2.12746998 0 P 0 ;0
L 1.52631998 -2.12746998 1.51906004 -2.12636998 0 P 0 ;0
L 1.51906004 -2.12636998 1.51363002 -2.12541004 0 P 0 ;0
L 1.51363002 -2.12541004 1.50886998 -2.12451998 0 P 0 ;0
L 1.50886998 -2.12451998 1.50483996 -2.12373996 0 P 0 ;0
L 1.50483996 -2.12373996 1.50448996 -2.12365 0 P 0 ;0
L 1.50448996 -2.12365 1.50438002 -2.12361004 0 P 0 ;0
L 1.50438002 -2.12361004 1.5027 -2.10378002 0 P 0 ;0
L 1.5027 -2.10378002 1.50111998 -2.08403002 0 P 0 ;0
L 1.50111998 -2.08403002 1.50263996 -2.08433996 0 P 0 ;0
L 1.50263996 -2.08433996 1.50581004 -2.08511004 0 P 0 ;0
L 1.50581004 -2.08511004 1.50955 -2.08611998 0 P 0 ;0
L 1.50955 -2.08611998 1.52306004 -2.08961004 0 P 0 ;0
L 1.52306004 -2.08961004 1.52311004 -2.08961998 0 P 0 ;0
L 1.52311004 -2.08961998 1.52875 -2.09076004 0 P 0 ;0
L 1.52875 -2.09076004 1.5288 -2.09076004 0 P 0 ;0
L 1.5288 -2.09076004 1.53443996 -2.09161004 0 P 0 ;0
L 1.53443996 -2.09161004 1.53893996 -2.09203002 0 P 0 ;0
L 1.53893996 -2.09203002 1.54346004 -2.09216998 0 P 0 ;0
L 1.54346004 -2.09216998 1.54473996 -2.09211004 0 P 0 ;0
L 1.54473996 -2.09211004 1.54603002 -2.09195 0 P 0 ;0
L 1.54603002 -2.09195 1.54728996 -2.09166998 0 P 0 ;0
L 1.54728996 -2.09166998 1.54853002 -2.09128996 0 P 0 ;0
L 1.54853002 -2.09128996 1.54973002 -2.09081004 0 P 0 ;0
L 1.54973002 -2.09081004 1.55026998 -2.09053996 0 P 0 ;0
L 1.55026998 -2.09053996 1.55076998 -2.09023002 0 P 0 ;0
L 1.55076998 -2.09023002 1.55118002 -2.08991998 0 P 0 ;0
L 1.55118002 -2.08991998 1.55118002 -2.08991004 0 P 0 ;0
L 1.55118002 -2.08991004 1.5512 -2.08991004 0 P 0 ;0
L 1.5512 -2.08991004 1.55125 -2.08986998 0 P 0 ;0
L 1.55125 -2.08986998 1.55131004 -2.08981998 0 P 0 ;0
L 1.55131004 -2.08981998 1.55126998 -2.08978002 0 P 0 ;0
L 1.55126998 -2.08978002 1.55136004 -2.08978002 0 P 0 ;0
L 1.55136004 -2.08978002 1.5517 -2.08948996 0 P 0 ;0
L 1.5517 -2.08948996 1.55206004 -2.08911998 0 P 0 ;0
L 1.55206004 -2.08911998 1.55205 -2.08911004 0 P 0 ;0
L 1.55205 -2.08911004 1.55206004 -2.08911004 0 P 0 ;0
L 1.55206004 -2.08911004 1.55211998 -2.08906004 0 P 0 ;0
L 1.55211998 -2.08906004 1.55248996 -2.08861004 0 P 0 ;0
L 1.55248996 -2.08861004 1.55283996 -2.08811998 0 P 0 ;0
L 1.55283996 -2.08811998 1.55313996 -2.08761004 0 P 0 ;0
L 1.55313996 -2.08761004 1.5534 -2.08706998 0 P 0 ;0
L 1.5534 -2.08706998 1.55356004 -2.08663002 0 P 0 ;0
L 1.55356004 -2.08663002 1.55368996 -2.08618996 0 P 0 ;0
L 1.55368996 -2.08618996 1.55376998 -2.08573996 0 P 0 ;0
L 1.55376998 -2.08573996 1.55378002 -2.08565 0 P 0 ;0
L 1.55378002 -2.08565 1.55381998 -2.08528002 0 P 0 ;0
L 1.55381998 -2.08528002 1.55383002 -2.08481998 0 P 0 ;0
L 1.55383002 -2.08481998 1.5538 -2.08436998 0 P 0 ;0
L 1.5538 -2.08436998 1.55373002 -2.08391998 0 P 0 ;0
L 1.55373002 -2.08391998 1.55361998 -2.08346998 0 P 0 ;0
L 1.55361998 -2.08346998 1.55348002 -2.08303996 0 P 0 ;0
L 1.55348002 -2.08303996 1.5533 -2.08261004 0 P 0 ;0
L 1.5533 -2.08261004 1.55308996 -2.08221004 0 P 0 ;0
L 1.55308996 -2.08221004 1.55283996 -2.08183002 0 P 0 ;0
L 1.55283996 -2.08183002 1.55175 -2.0804 0 P 0 ;0
L 1.55175 -2.0804 1.55055 -2.07908002 0 P 0 ;0
L 1.55055 -2.07908002 1.54926004 -2.07783996 0 P 0 ;0
L 1.54926004 -2.07783996 1.54788996 -2.07671998 0 P 0 ;0
L 1.54788996 -2.07671998 1.53706998 -2.06898002 0 P 0 ;0
L 1.53706998 -2.06898002 1.52085 -2.05713996 0 P 0 ;0
L 1.52085 -2.05713996 1.51766004 -2.05445 0 P 0 ;0
L 1.51766004 -2.05445 1.51468002 -2.05153996 0 P 0 ;0
L 1.51468002 -2.05153996 1.51191998 -2.04841998 0 P 0 ;0
L 1.51191998 -2.04841998 1.51048996 -2.04651998 0 P 0 ;0
L 1.51048996 -2.04651998 1.50923002 -2.04453002 0 P 0 ;0
L 1.50923002 -2.04453002 1.50813996 -2.04245 0 P 0 ;0
L 1.50813996 -2.04245 1.50721998 -2.04026004 0 P 0 ;0
L 1.50721998 -2.04026004 1.50643002 -2.03788002 0 P 0 ;0
L 1.50643002 -2.03788002 1.50581004 -2.03545 0 P 0 ;0
L 1.50581004 -2.03545 1.50536004 -2.03298996 0 P 0 ;0
L 1.50536004 -2.03298996 1.50508996 -2.0305 0 P 0 ;0
L 1.50508996 -2.0305 1.50498996 -2.02745 0 P 0 ;0
L 1.50498996 -2.02745 1.50513996 -2.02443996 0 P 0 ;0
L 1.50513996 -2.02443996 1.50551998 -2.02145 0 P 0 ;0
L 1.50551998 -2.02145 1.50613996 -2.0185 0 P 0 ;0
L 1.50613996 -2.0185 1.50698996 -2.01561004 0 P 0 ;0
L 1.50698996 -2.01561004 1.50783002 -2.01341004 0 P 0 ;0
L 1.50783002 -2.01341004 1.50883002 -2.0113 0 P 0 ;0
L 1.50883002 -2.0113 1.51 -2.00928002 0 P 0 ;0
L 1.51 -2.00928002 1.51133002 -2.00736004 0 P 0 ;0
L 1.51133002 -2.00736004 1.5128 -2.00555 0 P 0 ;0
L 1.5128 -2.00555 1.5144 -2.00386004 0 P 0 ;0
L 1.5144 -2.00386004 1.51675 -2.00176998 0 P 0 ;0
L 1.51675 -2.00176998 1.51923002 -1.9999 0 P 0 ;0
L 1.51923002 -1.9999 1.52186004 -1.99823996 0 P 0 ;0
L 1.52186004 -1.99823996 1.52461998 -1.99681004 0 P 0 ;0
L 1.52461998 -1.99681004 1.52748996 -1.99561004 0 P 0 ;0
L 1.52748996 -1.99561004 1.53353002 -1.99363996 0 P 0 ;0
L 1.53353002 -1.99363996 1.5397 -1.99218002 0 P 0 ;0
L 1.5397 -1.99218002 1.54598002 -1.99123002 0 P 0 ;0
L 1.54598002 -1.99123002 1.55181004 -1.99075 0 P 0 ;0
L 1.55181004 -1.99075 1.55763002 -1.99061998 0 P 0 ;0
L 1.55763002 -1.99061998 1.57273002 -1.99113996 0 P 0 ;0
L 1.57273002 -1.99113996 1.58755 -1.99248996 0 P 0 ;0
L 1.58755 -1.99248996 1.59293002 -1.99331998 0 P 0 ;0
L 1.59293002 -1.99331998 1.59821004 -1.99448996 0 P 0 ;0
L 1.59821004 -1.99448996 1.59905 -1.99473002 0 P 0 ;0
L 1.59905 -1.99473002 1.59986004 -1.99501998 0 P 0 ;0
L 1.59986004 -1.99501998 1.60008002 -1.99511998 0 P 0 ;0
L 1.60008002 -1.99511998 1.6003 -1.99523002 0 P 0 ;0
L 1.6003 -1.99523002 1.60051004 -1.99536004 0 P 0 ;0
L 1.60051004 -1.99536004 1.60071004 -1.9955 0 P 0 ;0
L 1.60071004 -1.9955 1.60083002 -1.99561004 0 P 0 ;0
L 1.60083002 -1.99561004 1.60093996 -1.99571004 0 P 0 ;0
L 1.60093996 -1.99571004 1.60103996 -1.99583002 0 P 0 ;0
L 1.60103996 -1.99583002 1.60111998 -1.99595 0 P 0 ;0
L 1.60111998 -1.99595 1.60116998 -1.99601998 0 P 0 ;0
L 1.60116998 -1.99601998 1.60121004 -1.99611004 0 P 0 ;0
L 1.60121004 -1.99611004 1.60125 -1.99621004 0 P 0 ;0
L 1.60125 -1.99621004 1.60128002 -1.9963 0 P 0 ;0
L 1.60128002 -1.9963 1.60131004 -1.99641004 0 P 0 ;0
L 1.60131004 -1.99641004 1.6017 -1.99861998 0 P 0 ;0
L 1.6017 -1.99861998 1.60195 -2.00086998 0 P 0 ;0
L 1.60195 -2.00086998 1.60308002 -2.01593002 0 P 0 ;0
L 1.60308002 -2.01593002 1.60415 -2.03096998 0 P 0 ;0
L 1.60415 -2.03096998 1.60345 -2.03083996 0 P 0 ;0
L 1.60345 -2.03083996 1.60058996 -2.03026004 0 P 0 ;0
L 1.60058996 -2.03026004 1.59723002 -2.02948002 0 P 0 ;0
L 1.59723002 -2.02948002 1.59721998 -2.02948002 0 P 0 ;0
L 1.59721998 -2.02948002 1.59306998 -2.0286 0 P 0 ;0
L 1.59306998 -2.0286 1.58776004 -2.02776998 0 P 0 ;0
L 1.58776004 -2.02776998 1.58226004 -2.02708002 0 P 0 ;0
L 1.58226004 -2.02708002 1.57738002 -2.02666998 0 P 0 ;0
L 1.57738002 -2.02666998 1.5709 -2.02633996 0 P 0 ;0
L 1.5709 -2.02633996 1.56918996 -2.02635 0 P 0 ;0
L 1.56918996 -2.02635 1.56746998 -2.02648996 0 P 0 ;0
L 1.56746998 -2.02648996 1.56678996 -2.02658996 0 P 0 ;0
L 1.56678996 -2.02658996 1.56611998 -2.02673996 0 P 0 ;0
L 1.56611998 -2.02673996 1.56546004 -2.02695 0 P 0 ;0
L 1.56546004 -2.02695 1.56481998 -2.0272 0 P 0 ;0
L 1.56481998 -2.0272 1.56418996 -2.0275 0 P 0 ;0
L 1.56418996 -2.0275 1.56358002 -2.02785 0 P 0 ;0
L 1.56358002 -2.02785 1.563 -2.02823002 0 P 0 ;0
L 1.563 -2.02823002 1.56245 -2.02865 0 P 0 ;0
L 1.56245 -2.02865 1.56206998 -2.02898996 0 P 0 ;0
L 1.56206998 -2.02898996 1.56171004 -2.02936004 0 P 0 ;0
L 1.56171004 -2.02936004 1.56138002 -2.02976004 0 P 0 ;0
L 1.56138002 -2.02976004 1.56108996 -2.03018996 0 P 0 ;0
L 1.56108996 -2.03018996 1.56083002 -2.03063996 0 P 0 ;0
L 1.56083002 -2.03063996 1.56061998 -2.0311 0 P 0 ;0
L 1.56061998 -2.0311 1.56043996 -2.03158996 0 P 0 ;0
L 1.56043996 -2.03158996 1.5603 -2.03208002 0 P 0 ;0
L 1.5603 -2.03208002 1.5602 -2.0326 0 P 0 ;0
L 1.5602 -2.0326 1.56015 -2.03308002 0 P 0 ;0
L 1.56015 -2.03308002 1.56013996 -2.03353996 0 P 0 ;0
L 1.56013996 -2.03353996 1.56016004 -2.03391004 0 P 0 ;0
L 1.56016004 -2.03391004 1.56048002 -2.03391004 0 P 0 ;0
L 1.56048002 -2.03391004 1.56016004 -2.03393002 0 P 0 ;0
L 1.56016004 -2.03393002 1.56016998 -2.03401004 0 P 0 ;0
L 1.56016998 -2.03401004 1.56023002 -2.03448002 0 P 0 ;0
L 1.56023002 -2.03448002 1.56025 -2.03456004 0 P 0 ;0
L 1.56025 -2.03456004 1.56033002 -2.03493002 0 P 0 ;0
L 1.56033002 -2.03493002 1.56046998 -2.03538002 0 P 0 ;0
L 1.56046998 -2.03538002 1.56063996 -2.03581998 0 P 0 ;0
L 1.56063996 -2.03581998 1.56085 -2.03623996 0 P 0 ;0
L 1.56085 -2.03623996 1.56108996 -2.03663996 0 P 0 ;0
L 1.56108996 -2.03663996 1.56136004 -2.03701998 0 P 0 ;0
L 1.56136004 -2.03701998 1.56233002 -2.03818996 0 P 0 ;0
L 1.56233002 -2.03818996 1.56336998 -2.03928996 0 P 0 ;0
L 1.56336998 -2.03928996 1.56448002 -2.04031004 0 P 0 ;0
L 1.56448002 -2.04031004 1.56566004 -2.04123996 0 P 0 ;0
L 1.56566004 -2.04123996 1.57471004 -2.04761998 0 P 0 ;0
L 1.57471004 -2.04761998 1.58461998 -2.05491004 0 P 0 ;0
L 1.58461998 -2.05491004 1.58898996 -2.05858996 0 P 0 ;0
L 1.58898996 -2.05858996 1.59315 -2.06245 0 P 0 ;0
L 1.59315 -2.06245 1.59656998 -2.06596998 0 P 0 ;0
L 1.59656998 -2.06596998 1.59976004 -2.06965 0 P 0 ;0
L 1.59976004 -2.06965 1.60116004 -2.07151004 0 P 0 ;0
L 1.60116004 -2.07151004 1.60238002 -2.07346004 0 P 0 ;0
L 1.60238002 -2.07346004 1.60341998 -2.0755 0 P 0 ;0
L 1.60341998 -2.0755 1.60403996 -2.077 0 P 0 ;0
L 1.60403996 -2.077 1.60456004 -2.07853996 0 P 0 ;0
L 1.60456004 -2.07853996 1.60496004 -2.08011004 0 P 0 ;0
L 1.60496004 -2.08011004 1.60525 -2.0817 0 P 0 ;0
L 1.60525 -2.0817 1.60568996 -2.08578002 0 P 0 ;0
L 1.60568996 -2.08578002 1.60578996 -2.08988002 0 P 0 ;0
L 1.60578996 -2.08988002 1.60556998 -2.09403002 0 P 0 ;0
L 1.60556998 -2.09403002 1.60501004 -2.09813996 0 P 0 ;0
L 1.60501004 -2.09813996 1.60451998 -2.10036998 0 P 0 ;0
L 1.60451998 -2.10036998 1.60383996 -2.10253996 0 P 0 ;0
L 1.60383996 -2.10253996 1.60298996 -2.10465 0 P 0 ;0
L 1.60298996 -2.10465 1.60163996 -2.1073 0 P 0 ;0
L 1.60163996 -2.1073 1.60008002 -2.10983002 0 P 0 ;0
L 1.60008002 -2.10983002 1.59833002 -2.11225 0 P 0 ;0
L 1.59833002 -2.11225 1.59696998 -2.11386998 0 P 0 ;0
L 1.59696998 -2.11386998 1.59551004 -2.11538996 0 P 0 ;0
L 1.59551004 -2.11538996 1.59395 -2.1168 0 P 0 ;0
L 1.59395 -2.1168 1.59231004 -2.11811004 0 P 0 ;0
L 1.59231004 -2.11811004 1.58973002 -2.11986004 0 P 0 ;0
L 1.58973002 -2.11986004 1.58701998 -2.1214 0 P 0 ;0
L 1.58701998 -2.1214 1.5842 -2.12273002 0 P 0 ;0
L 1.5842 -2.12273002 1.5788 -2.1248 0 P 0 ;0
L 1.5788 -2.1248 1.57326998 -2.12648996 0 P 0 ;0
L 1.57326998 -2.12648996 1.56983002 -2.12731004 0 P 0 ;0
L 1.56983002 -2.12731004 1.56638002 -2.12791004 0 P 0 ;0
L 1.56638002 -2.12791004 1.56288996 -2.1283 0 P 0 ;0
L 1.56288996 -2.1283 1.54886998 -2.12886998 0 P 0 ;0
L 1.35851998 -2.06545 1.47866004 -2.06545 0 P 0 ;0
L 1.35936004 -2.06445 1.47871004 -2.06445 0 P 0 ;0
L 1.36041004 -2.06345 1.47875 -2.06345 0 P 0 ;0
L 1.36163996 -2.06245 1.4788 -2.06245 0 P 0 ;0
L 1.36293996 -2.06145 1.47883996 -2.06145 0 P 0 ;0
L 1.36436004 -2.06045 1.47888996 -2.06045 0 P 0 ;0
L 1.36598002 -2.05945 1.47893996 -2.05945 0 P 0 ;0
L 1.36776004 -2.05845 1.47898996 -2.05845 0 P 0 ;0
L 1.36971004 -2.05745 1.47903002 -2.05745 0 P 0 ;0
L 1.37166004 -2.05645 1.47908002 -2.05645 0 P 0 ;0
L 1.37391004 -2.05545 1.47911998 -2.05545 0 P 0 ;0
L 1.37616998 -2.05445 1.47916998 -2.05445 0 P 0 ;0
L 1.37873002 -2.05345 1.47921004 -2.05345 0 P 0 ;0
L 1.38136004 -2.05245 1.47926004 -2.05245 0 P 0 ;0
L 1.36875 -2.03345 1.37108996 -2.03345 0 P 0 ;0
L 1.36886004 -2.03245 1.37385 -2.03245 0 P 0 ;0
L 1.36896998 -2.03145 1.37678002 -2.03145 0 P 0 ;0
L 1.36908996 -2.03045 1.3797 -2.03045 0 P 0 ;0
L 1.36921004 -2.02945 1.38261998 -2.02945 0 P 0 ;0
L 1.36933002 -2.02845 1.38638996 -2.02845 0 P 0 ;0
L 1.36946004 -2.02745 1.39023996 -2.02745 0 P 0 ;0
L 1.36958002 -2.02645 1.39503002 -2.02645 0 P 0 ;0
L 1.3697 -2.02545 1.40068002 -2.02545 0 P 0 ;0
L 1.36981998 -2.02445 1.41053996 -2.02445 0 P 0 ;0
L 1.36993996 -2.02345 1.47993996 -2.02345 0 P 0 ;0
L 1.37008002 -2.02245 1.47988002 -2.02245 0 P 0 ;0
L 1.37021004 -2.02145 1.47978002 -2.02145 0 P 0 ;0
L 1.37033996 -2.02045 1.47968002 -2.02045 0 P 0 ;0
L 1.37046998 -2.01945 1.47953002 -2.01945 0 P 0 ;0
L 1.3706 -2.01845 1.47936004 -2.01845 0 P 0 ;0
L 1.37073002 -2.01745 1.47918002 -2.01745 0 P 0 ;0
L 1.37086004 -2.01645 1.47893002 -2.01645 0 P 0 ;0
L 1.37098996 -2.01545 1.47868002 -2.01545 0 P 0 ;0
L 1.37113002 -2.01445 1.4784 -2.01445 0 P 0 ;0
L 1.37126998 -2.01345 1.47806004 -2.01345 0 P 0 ;0
L 1.3714 -2.01245 1.47773002 -2.01245 0 P 0 ;0
L 1.37153996 -2.01145 1.47733002 -2.01145 0 P 0 ;0
L 1.37168002 -2.01045 1.47691004 -2.01045 0 P 0 ;0
L 1.37181004 -2.00945 1.47641004 -2.00945 0 P 0 ;0
L 1.37195 -2.00845 1.47588996 -2.00845 0 P 0 ;0
L 1.37208002 -2.00745 1.47528002 -2.00745 0 P 0 ;0
L 1.37221004 -2.00645 1.47463996 -2.00645 0 P 0 ;0
L 1.37235 -2.00545 1.47391998 -2.00545 0 P 0 ;0
L 1.37248996 -2.00445 1.47311004 -2.00445 0 P 0 ;0
L 1.37261998 -2.00345 1.47225 -2.00345 0 P 0 ;0
L 1.37276004 -2.00245 1.47126998 -2.00245 0 P 0 ;0
L 1.3729 -2.00145 1.4702 -2.00145 0 P 0 ;0
L 1.37303002 -2.00045 1.46903996 -2.00045 0 P 0 ;0
L 1.37316998 -1.99945 1.46775 -1.99945 0 P 0 ;0
L 1.3733 -1.99845 1.46625 -1.99845 0 P 0 ;0
L 1.37343996 -1.99745 1.46455 -1.99745 0 P 0 ;0
L 1.37356998 -1.99645 1.46253996 -1.99645 0 P 0 ;0
L 1.37753002 -1.99545 1.46041004 -1.99545 0 P 0 ;0
L 1.38218996 -1.99445 1.45781004 -1.99445 0 P 0 ;0
L 1.42925 -2.08345 1.47785 -2.08345 0 P 0 ;0
L 1.42931998 -2.08245 1.47788996 -2.08245 0 P 0 ;0
L 1.42938002 -2.08145 1.47793002 -2.08145 0 P 0 ;0
L 1.42945 -2.08045 1.47796998 -2.08045 0 P 0 ;0
L 1.42951004 -2.07945 1.47801004 -2.07945 0 P 0 ;0
L 1.42958002 -2.07845 1.47806004 -2.07845 0 P 0 ;0
L 1.42963996 -2.07745 1.4781 -2.07745 0 P 0 ;0
L 1.4297 -2.07645 1.47815 -2.07645 0 P 0 ;0
L 1.42976998 -2.07545 1.4782 -2.07545 0 P 0 ;0
L 1.42983002 -2.07445 1.47825 -2.07445 0 P 0 ;0
L 1.4299 -2.07345 1.47828996 -2.07345 0 P 0 ;0
L 1.42963996 -2.07245 1.47833996 -2.07245 0 P 0 ;0
L 1.42918996 -2.07145 1.47838002 -2.07145 0 P 0 ;0
L 1.38425 -2.05145 1.47931004 -2.05145 0 P 0 ;0
L 1.38731998 -2.05045 1.47933996 -2.05045 0 P 0 ;0
L 1.39088002 -2.04945 1.47938002 -2.04945 0 P 0 ;0
L 1.3947 -2.04845 1.47941004 -2.04845 0 P 0 ;0
L 1.39851004 -2.04745 1.47945 -2.04745 0 P 0 ;0
L 1.40233002 -2.04645 1.47948002 -2.04645 0 P 0 ;0
L 1.40608002 -2.04545 1.47951004 -2.04545 0 P 0 ;0
L 1.40983002 -2.04445 1.47955 -2.04445 0 P 0 ;0
L 1.41306998 -2.04345 1.47958996 -2.04345 0 P 0 ;0
L 1.41591998 -2.04245 1.47961998 -2.04245 0 P 0 ;0
L 1.41876998 -2.04145 1.47965 -2.04145 0 P 0 ;0
L 1.42133996 -2.04045 1.47968996 -2.04045 0 P 0 ;0
L 1.42361998 -2.03945 1.47971998 -2.03945 0 P 0 ;0
L 1.42591004 -2.03845 1.47975 -2.03845 0 P 0 ;0
L 1.42805 -2.03745 1.47978002 -2.03745 0 P 0 ;0
L 1.42936004 -2.03645 1.47981004 -2.03645 0 P 0 ;0
L 1.43003002 -2.03545 1.47983002 -2.03545 0 P 0 ;0
L 1.43081998 -2.03445 1.47986004 -2.03445 0 P 0 ;0
L 1.43121004 -2.03345 1.47988002 -2.03345 0 P 0 ;0
L 1.43141998 -2.03245 1.4799 -2.03245 0 P 0 ;0
L 1.43146998 -2.03145 1.47993002 -2.03145 0 P 0 ;0
L 1.43136004 -2.03045 1.47996004 -2.03045 0 P 0 ;0
L 1.43108002 -2.02945 1.47998002 -2.02945 0 P 0 ;0
L 1.4306 -2.02845 1.48001004 -2.02845 0 P 0 ;0
L 1.42986998 -2.02745 1.48001004 -2.02745 0 P 0 ;0
L 1.42875 -2.02645 1.47998996 -2.02645 0 P 0 ;0
L 1.42658996 -2.02545 1.47996998 -2.02545 0 P 0 ;0
L 1.42203996 -2.02445 1.47996004 -2.02445 0 P 0 ;0
L 1.38748002 -1.99345 1.45483002 -1.99345 0 P 0 ;0
L 1.39331998 -1.99245 1.45108996 -1.99245 0 P 0 ;0
L 1.40051004 -1.99145 1.44503002 -1.99145 0 P 0 ;0
L 1.38096998 -2.12745 1.4051 -2.12745 0 P 0 ;0
L 1.37671004 -2.12645 1.41113996 -2.12645 0 P 0 ;0
L 1.3736 -2.12545 1.41238996 -2.12545 0 P 0 ;0
L 1.37096998 -2.12445 1.41268002 -2.12445 0 P 0 ;0
L 1.36876998 -2.12345 1.41296998 -2.12345 0 P 0 ;0
L 1.36685 -2.12245 1.41326998 -2.12245 0 P 0 ;0
L 1.36516004 -2.12145 1.41356004 -2.12145 0 P 0 ;0
L 1.36366004 -2.12045 1.41385 -2.12045 0 P 0 ;0
L 1.36225 -2.11945 1.41413996 -2.11945 0 P 0 ;0
L 1.361 -2.11845 1.41443002 -2.11845 0 P 0 ;0
L 1.35983002 -2.11745 1.41471998 -2.11745 0 P 0 ;0
L 1.35876004 -2.11645 1.41501004 -2.11645 0 P 0 ;0
L 1.42661998 -2.12445 1.47693002 -2.12445 0 P 0 ;0
L 1.42665 -2.12345 1.47693002 -2.12345 0 P 0 ;0
L 1.4267 -2.12245 1.47693002 -2.12245 0 P 0 ;0
L 1.42675 -2.12145 1.47693002 -2.12145 0 P 0 ;0
L 1.42681004 -2.12045 1.47693002 -2.12045 0 P 0 ;0
L 1.42686998 -2.11945 1.47693002 -2.11945 0 P 0 ;0
L 1.42691998 -2.11845 1.47693002 -2.11845 0 P 0 ;0
L 1.42698996 -2.11745 1.47693002 -2.11745 0 P 0 ;0
L 1.42705 -2.11645 1.47693002 -2.11645 0 P 0 ;0
L 1.42711004 -2.11545 1.47693002 -2.11545 0 P 0 ;0
L 1.42716998 -2.11445 1.47693002 -2.11445 0 P 0 ;0
L 1.42723002 -2.11345 1.47693996 -2.11345 0 P 0 ;0
L 1.4273 -2.11245 1.47695 -2.11245 0 P 0 ;0
L 1.42736998 -2.11145 1.47696004 -2.11145 0 P 0 ;0
L 1.42743996 -2.11045 1.47698002 -2.11045 0 P 0 ;0
L 1.42751004 -2.10945 1.47698996 -2.10945 0 P 0 ;0
L 1.42758002 -2.10845 1.47701004 -2.10845 0 P 0 ;0
L 1.42765 -2.10745 1.47703002 -2.10745 0 P 0 ;0
L 1.42771004 -2.10645 1.47703996 -2.10645 0 P 0 ;0
L 1.42778002 -2.10545 1.47706998 -2.10545 0 P 0 ;0
L 1.42783996 -2.10445 1.4771 -2.10445 0 P 0 ;0
L 1.42791004 -2.10345 1.47713002 -2.10345 0 P 0 ;0
L 1.42798002 -2.10245 1.47716004 -2.10245 0 P 0 ;0
L 1.42805 -2.10145 1.4772 -2.10145 0 P 0 ;0
L 1.42811004 -2.10045 1.47723002 -2.10045 0 P 0 ;0
L 1.40953002 -2.09945 1.41973002 -2.09945 0 P 0 ;0
L 1.42818002 -2.09945 1.47726004 -2.09945 0 P 0 ;0
L 1.41618002 -2.09845 1.41996998 -2.09845 0 P 0 ;0
L 1.42825 -2.09845 1.47728996 -2.09845 0 P 0 ;0
L 1.42831998 -2.09745 1.47733002 -2.09745 0 P 0 ;0
L 1.42838996 -2.09645 1.47736004 -2.09645 0 P 0 ;0
L 1.42846004 -2.09545 1.47738996 -2.09545 0 P 0 ;0
L 1.42851998 -2.09445 1.47741998 -2.09445 0 P 0 ;0
L 1.42858996 -2.09345 1.47746004 -2.09345 0 P 0 ;0
L 1.42866004 -2.09245 1.4775 -2.09245 0 P 0 ;0
L 1.42873002 -2.09145 1.47753996 -2.09145 0 P 0 ;0
L 1.42878996 -2.09045 1.47758002 -2.09045 0 P 0 ;0
L 1.42886004 -2.08945 1.47761998 -2.08945 0 P 0 ;0
L 1.42893002 -2.08845 1.47766004 -2.08845 0 P 0 ;0
L 1.42898996 -2.08745 1.4777 -2.08745 0 P 0 ;0
L 1.42906004 -2.08645 1.47773002 -2.08645 0 P 0 ;0
L 1.42911998 -2.08545 1.47776998 -2.08545 0 P 0 ;0
L 1.42918996 -2.08445 1.47781004 -2.08445 0 P 0 ;0
L 1.61686004 -2.17995 1.66846004 -2.17995 0 P 0 ;0
L 1.61591004 -2.17895 1.67158996 -2.17895 0 P 0 ;0
L 1.61553996 -2.17795 1.67431998 -2.17795 0 P 0 ;0
L 1.61526998 -2.17695 1.67675 -2.17695 0 P 0 ;0
L 1.61508002 -2.17595 1.67903996 -2.17595 0 P 0 ;0
L 1.61496998 -2.17495 1.68108002 -2.17495 0 P 0 ;0
L 1.61491004 -2.17395 1.68295 -2.17395 0 P 0 ;0
L 1.61485 -2.17295 1.68458996 -2.17295 0 P 0 ;0
L 1.61478996 -2.17195 1.6861 -2.17195 0 P 0 ;0
L 1.61473002 -2.17095 1.6875 -2.17095 0 P 0 ;0
L 1.61466998 -2.16995 1.68876998 -2.16995 0 P 0 ;0
L 1.61461004 -2.16895 1.68998002 -2.16895 0 P 0 ;0
L 1.61455 -2.16795 1.69108002 -2.16795 0 P 0 ;0
L 1.61448996 -2.16695 1.69211998 -2.16695 0 P 0 ;0
L 1.61443002 -2.16595 1.69316004 -2.16595 0 P 0 ;0
L 1.61436998 -2.16495 1.69411998 -2.16495 0 P 0 ;0
L 1.61431004 -2.16395 1.69498996 -2.16395 0 P 0 ;0
L 1.61425 -2.16295 1.69586004 -2.16295 0 P 0 ;0
L 1.61418996 -2.16195 1.69673002 -2.16195 0 P 0 ;0
L 1.61413002 -2.16095 1.69746998 -2.16095 0 P 0 ;0
L 1.61406998 -2.15995 1.6982 -2.15995 0 P 0 ;0
L 1.61401998 -2.15895 1.69893996 -2.15895 0 P 0 ;0
L 1.61396998 -2.15795 1.69963002 -2.15795 0 P 0 ;0
L 1.64433002 -2.18295 1.63151004 -2.18271004 0 P 0 ;0
L 1.63151004 -2.18271004 1.62658002 -2.18226998 0 P 0 ;0
L 1.62658002 -2.18226998 1.62168996 -2.18146998 0 P 0 ;0
L 1.62168996 -2.18146998 1.6201 -2.1811 0 P 0 ;0
L 1.6201 -2.1811 1.61853996 -2.18061004 0 P 0 ;0
L 1.61853996 -2.18061004 1.61701004 -2.18001998 0 P 0 ;0
L 1.61701004 -2.18001998 1.61686004 -2.17995 0 P 0 ;0
L 1.61686004 -2.17995 1.61671004 -2.17986998 0 P 0 ;0
L 1.61671004 -2.17986998 1.61656998 -2.17976998 0 P 0 ;0
L 1.61656998 -2.17976998 1.61643996 -2.17966998 0 P 0 ;0
L 1.61643996 -2.17966998 1.61631998 -2.17955 0 P 0 ;0
L 1.61631998 -2.17955 1.61621004 -2.17943002 0 P 0 ;0
L 1.61621004 -2.17943002 1.6161 -2.1793 0 P 0 ;0
L 1.6161 -2.1793 1.61601004 -2.17915 0 P 0 ;0
L 1.61601004 -2.17915 1.61593002 -2.179 0 P 0 ;0
L 1.61593002 -2.179 1.61586004 -2.17885 0 P 0 ;0
L 1.61586004 -2.17885 1.61553002 -2.17791004 0 P 0 ;0
L 1.61553002 -2.17791004 1.61526998 -2.17696004 0 P 0 ;0
L 1.61526998 -2.17696004 1.61508996 -2.17598996 0 P 0 ;0
L 1.61508996 -2.17598996 1.61496998 -2.17496998 0 P 0 ;0
L 1.61496998 -2.17496998 1.61408002 -2.16011004 0 P 0 ;0
L 1.61408002 -2.16011004 1.61341998 -2.14758996 0 P 0 ;0
L 1.61341998 -2.14758996 1.6202 -2.14821004 0 P 0 ;0
L 1.6202 -2.14821004 1.62023002 -2.14821004 0 P 0 ;0
L 1.62023002 -2.14821004 1.63216998 -2.14893996 0 P 0 ;0
L 1.63216998 -2.14893996 1.6349 -2.14893002 0 P 0 ;0
L 1.6349 -2.14893002 1.63761998 -2.14873002 0 P 0 ;0
L 1.63761998 -2.14873002 1.64031998 -2.14835 0 P 0 ;0
L 1.64031998 -2.14835 1.64198996 -2.14798996 0 P 0 ;0
L 1.64198996 -2.14798996 1.64363002 -2.14751998 0 P 0 ;0
L 1.64363002 -2.14751998 1.64523002 -2.14693002 0 P 0 ;0
L 1.64523002 -2.14693002 1.64678996 -2.14623002 0 P 0 ;0
L 1.64678996 -2.14623002 1.64888002 -2.14506998 0 P 0 ;0
L 1.64888002 -2.14506998 1.65086998 -2.14376004 0 P 0 ;0
L 1.65086998 -2.14376004 1.65093996 -2.14371004 0 P 0 ;0
L 1.65093996 -2.14371004 1.65275 -2.14228996 0 P 0 ;0
L 1.65275 -2.14228996 1.6539 -2.14123996 0 P 0 ;0
L 1.6539 -2.14123996 1.65496004 -2.14011004 0 P 0 ;0
L 1.65496004 -2.14011004 1.65591998 -2.13891004 0 P 0 ;0
L 1.65591998 -2.13891004 1.65755 -2.13653996 0 P 0 ;0
L 1.65755 -2.13653996 1.65901998 -2.13415 0 P 0 ;0
L 1.65901998 -2.13415 1.65903002 -2.13413002 0 P 0 ;0
L 1.65903002 -2.13413002 1.66035 -2.13171998 0 P 0 ;0
L 1.66035 -2.13171998 1.66155 -2.12925 0 P 0 ;0
L 1.66155 -2.12925 1.66183996 -2.12851998 0 P 0 ;0
L 1.66183996 -2.12851998 1.66206998 -2.12776004 0 P 0 ;0
L 1.66206998 -2.12776004 1.66223996 -2.12696998 0 P 0 ;0
L 1.66223996 -2.12696998 1.66233996 -2.12618002 0 P 0 ;0
L 1.66233996 -2.12618002 1.66236998 -2.12538996 0 P 0 ;0
L 1.66236998 -2.12538996 1.66233002 -2.12436004 0 P 0 ;0
L 1.66233002 -2.12436004 1.66221004 -2.12335 0 P 0 ;0
L 1.66221004 -2.12335 1.662 -2.12235 0 P 0 ;0
L 1.662 -2.12235 1.66171004 -2.12141004 0 P 0 ;0
L 1.66171004 -2.12141004 1.64438996 -2.07113002 0 P 0 ;0
L 1.64438996 -2.07113002 1.62871998 -2.02606004 0 P 0 ;0
L 1.62871998 -2.02606004 1.62116004 -2.00558996 0 P 0 ;0
L 1.62116004 -2.00558996 1.62116004 -2.00556998 0 P 0 ;0
L 1.62116004 -2.00556998 1.61681004 -1.99443996 0 P 0 ;0
L 1.61681004 -1.99443996 1.67163002 -1.99443996 0 P 0 ;0
L 1.67163002 -1.99443996 1.67301004 -2.00076004 0 P 0 ;0
L 1.67301004 -2.00076004 1.67613002 -2.01341998 0 P 0 ;0
L 1.67613002 -2.01341998 1.68331004 -2.03931998 0 P 0 ;0
L 1.68331004 -2.03931998 1.69153002 -2.06856998 0 P 0 ;0
L 1.69153002 -2.06856998 1.6916 -2.06876004 0 P 0 ;0
L 1.6916 -2.06876004 1.69168996 -2.06896998 0 P 0 ;0
L 1.69168996 -2.06896998 1.69181004 -2.06918002 0 P 0 ;0
L 1.69181004 -2.06918002 1.69193002 -2.06936998 0 P 0 ;0
L 1.69193002 -2.06936998 1.69208002 -2.06956004 0 P 0 ;0
L 1.69208002 -2.06956004 1.69223996 -2.06973002 0 P 0 ;0
L 1.69223996 -2.06973002 1.69241998 -2.06988002 0 P 0 ;0
L 1.69241998 -2.06988002 1.6926 -2.07001998 0 P 0 ;0
L 1.6926 -2.07001998 1.6928 -2.07015 0 P 0 ;0
L 1.6928 -2.07015 1.69301004 -2.07025 0 P 0 ;0
L 1.69301004 -2.07025 1.69323002 -2.07033996 0 P 0 ;0
L 1.69323002 -2.07033996 1.69346004 -2.07041004 0 P 0 ;0
L 1.69346004 -2.07041004 1.69368002 -2.07045 0 P 0 ;0
L 1.69368002 -2.07045 1.69391998 -2.07048002 0 P 0 ;0
L 1.69391998 -2.07048002 1.69413996 -2.07048996 0 P 0 ;0
L 1.69413996 -2.07048996 1.6944 -2.07048002 0 P 0 ;0
L 1.6944 -2.07048002 1.69465 -2.07045 0 P 0 ;0
L 1.69465 -2.07045 1.69488996 -2.07038996 0 P 0 ;0
L 1.69488996 -2.07038996 1.69513996 -2.07031998 0 P 0 ;0
L 1.69513996 -2.07031998 1.69536998 -2.07021998 0 P 0 ;0
L 1.69536998 -2.07021998 1.69558996 -2.0701 0 P 0 ;0
L 1.69558996 -2.0701 1.69581004 -2.06996998 0 P 0 ;0
L 1.69581004 -2.06996998 1.69601004 -2.06981998 0 P 0 ;0
L 1.69601004 -2.06981998 1.6962 -2.06965 0 P 0 ;0
L 1.6962 -2.06965 1.69636998 -2.06946004 0 P 0 ;0
L 1.69636998 -2.06946004 1.69653002 -2.06926004 0 P 0 ;0
L 1.69653002 -2.06926004 1.69666004 -2.06905 0 P 0 ;0
L 1.69666004 -2.06905 1.69678996 -2.06883002 0 P 0 ;0
L 1.69678996 -2.06883002 1.69688002 -2.0686 0 P 0 ;0
L 1.69688002 -2.0686 1.69695 -2.0684 0 P 0 ;0
L 1.69695 -2.0684 1.70426004 -2.04365 0 P 0 ;0
L 1.70426004 -2.04365 1.70426004 -2.04363002 0 P 0 ;0
L 1.70426004 -2.04363002 1.71066998 -2.0213 0 P 0 ;0
L 1.71066998 -2.0213 1.71068002 -2.02126004 0 P 0 ;0
L 1.71068002 -2.02126004 1.71431998 -2.00693996 0 P 0 ;0
L 1.71431998 -2.00693996 1.71706004 -1.99496998 0 P 0 ;0
L 1.71706004 -1.99496998 1.74335 -1.9947 0 P 0 ;0
L 1.74335 -1.9947 1.75403002 -1.99461004 0 P 0 ;0
L 1.75403002 -1.99461004 1.76301004 -1.99465 0 P 0 ;0
L 1.76301004 -1.99465 1.76886004 -1.99471004 0 P 0 ;0
L 1.76886004 -1.99471004 1.76883996 -1.99476004 0 P 0 ;0
L 1.76883996 -1.99476004 1.74021004 -2.06556004 0 P 0 ;0
L 1.74021004 -2.06556004 1.71298002 -2.13276998 0 P 0 ;0
L 1.71298002 -2.13276998 1.70836998 -2.14293996 0 P 0 ;0
L 1.70836998 -2.14293996 1.70413996 -2.15076004 0 P 0 ;0
L 1.70413996 -2.15076004 1.69941998 -2.15828996 0 P 0 ;0
L 1.69941998 -2.15828996 1.6967 -2.16198996 0 P 0 ;0
L 1.6967 -2.16198996 1.6937 -2.16541998 0 P 0 ;0
L 1.6937 -2.16541998 1.69041998 -2.1686 0 P 0 ;0
L 1.69041998 -2.1686 1.68793996 -2.17063002 0 P 0 ;0
L 1.68793996 -2.17063002 1.68535 -2.17248002 0 P 0 ;0
L 1.68535 -2.17248002 1.68263996 -2.17413996 0 P 0 ;0
L 1.68263996 -2.17413996 1.67981004 -2.17561004 0 P 0 ;0
L 1.67981004 -2.17561004 1.67525 -2.17761004 0 P 0 ;0
L 1.67525 -2.17761004 1.6706 -2.17931998 0 P 0 ;0
L 1.6706 -2.17931998 1.66586004 -2.18073002 0 P 0 ;0
L 1.66586004 -2.18073002 1.66141998 -2.1817 0 P 0 ;0
L 1.66141998 -2.1817 1.65691998 -2.18228996 0 P 0 ;0
L 1.65691998 -2.18228996 1.64433002 -2.18295 0 P 0 ;0
L 1.61928996 -2.00628002 1.62683996 -2.02673002 0 P 0 ;0
L 1.62683996 -2.02673002 1.6425 -2.07178002 0 P 0 ;0
L 1.6425 -2.07178002 1.65981004 -2.12201998 0 P 0 ;0
L 1.65981004 -2.12201998 1.66006004 -2.12283996 0 P 0 ;0
L 1.66006004 -2.12283996 1.66023002 -2.12368002 0 P 0 ;0
L 1.66023002 -2.12368002 1.66033996 -2.12451998 0 P 0 ;0
L 1.66033996 -2.12451998 1.66036998 -2.12538002 0 P 0 ;0
L 1.66036998 -2.12538002 1.66033996 -2.12601004 0 P 0 ;0
L 1.66033996 -2.12601004 1.66026998 -2.12663996 0 P 0 ;0
L 1.66026998 -2.12663996 1.66013996 -2.12725 0 P 0 ;0
L 1.66013996 -2.12725 1.65995 -2.12786004 0 P 0 ;0
L 1.65995 -2.12786004 1.65971004 -2.12843996 0 P 0 ;0
L 1.65971004 -2.12843996 1.65856998 -2.1308 0 P 0 ;0
L 1.65856998 -2.1308 1.6573 -2.13313002 0 P 0 ;0
L 1.6573 -2.13313002 1.65586998 -2.13545 0 P 0 ;0
L 1.65586998 -2.13545 1.65431004 -2.13771998 0 P 0 ;0
L 1.65431004 -2.13771998 1.65343996 -2.1388 0 P 0 ;0
L 1.65343996 -2.1388 1.65248996 -2.13981998 0 P 0 ;0
L 1.65248996 -2.13981998 1.65146004 -2.14076004 0 P 0 ;0
L 1.65146004 -2.14076004 1.64971004 -2.14213002 0 P 0 ;0
L 1.64971004 -2.14213002 1.64785 -2.14336004 0 P 0 ;0
L 1.64785 -2.14336004 1.64588996 -2.14443996 0 P 0 ;0
L 1.64588996 -2.14443996 1.64446998 -2.14508002 0 P 0 ;0
L 1.64446998 -2.14508002 1.64301004 -2.14561998 0 P 0 ;0
L 1.64301004 -2.14561998 1.64151004 -2.14605 0 P 0 ;0
L 1.64151004 -2.14605 1.63996998 -2.14636998 0 P 0 ;0
L 1.63996998 -2.14636998 1.63741004 -2.14673996 0 P 0 ;0
L 1.63741004 -2.14673996 1.63483002 -2.14693002 0 P 0 ;0
L 1.63483002 -2.14693002 1.63223002 -2.14693996 0 P 0 ;0
L 1.63223002 -2.14693996 1.62036004 -2.14621998 0 P 0 ;0
L 1.62036004 -2.14621998 1.6113 -2.14538002 0 P 0 ;0
L 1.6113 -2.14538002 1.61208996 -2.16023002 0 P 0 ;0
L 1.61208996 -2.16023002 1.61298002 -2.17515 0 P 0 ;0
L 1.61298002 -2.17515 1.6131 -2.17628002 0 P 0 ;0
L 1.6131 -2.17628002 1.61331998 -2.17741004 0 P 0 ;0
L 1.61331998 -2.17741004 1.61361998 -2.17851004 0 P 0 ;0
L 1.61361998 -2.17851004 1.614 -2.17958996 0 P 0 ;0
L 1.614 -2.17958996 1.61413996 -2.17988996 0 P 0 ;0
L 1.61413996 -2.17988996 1.61428996 -2.18018002 0 P 0 ;0
L 1.61428996 -2.18018002 1.61446998 -2.18045 0 P 0 ;0
L 1.61446998 -2.18045 1.61466998 -2.18071004 0 P 0 ;0
L 1.61466998 -2.18071004 1.61488996 -2.18095 0 P 0 ;0
L 1.61488996 -2.18095 1.61511998 -2.18116998 0 P 0 ;0
L 1.61511998 -2.18116998 1.61538002 -2.18138002 0 P 0 ;0
L 1.61538002 -2.18138002 1.61565 -2.18156004 0 P 0 ;0
L 1.61565 -2.18156004 1.61593002 -2.18173002 0 P 0 ;0
L 1.61593002 -2.18173002 1.61623002 -2.18186004 0 P 0 ;0
L 1.61623002 -2.18186004 1.61788002 -2.1825 0 P 0 ;0
L 1.61788002 -2.1825 1.61956998 -2.18301998 0 P 0 ;0
L 1.61956998 -2.18301998 1.6213 -2.18343002 0 P 0 ;0
L 1.6213 -2.18343002 1.62633002 -2.18426004 0 P 0 ;0
L 1.62633002 -2.18426004 1.6314 -2.18471004 0 P 0 ;0
L 1.6314 -2.18471004 1.64436004 -2.18495 0 P 0 ;0
L 1.64436004 -2.18495 1.65711004 -2.18428002 0 P 0 ;0
L 1.65711004 -2.18428002 1.66176998 -2.18366998 0 P 0 ;0
L 1.66176998 -2.18366998 1.66636004 -2.18266998 0 P 0 ;0
L 1.66636004 -2.18266998 1.67123002 -2.18121004 0 P 0 ;0
L 1.67123002 -2.18121004 1.676 -2.17946998 0 P 0 ;0
L 1.676 -2.17946998 1.68068002 -2.17741998 0 P 0 ;0
L 1.68068002 -2.17741998 1.68361998 -2.17588002 0 P 0 ;0
L 1.68361998 -2.17588002 1.68646004 -2.17415 0 P 0 ;0
L 1.68646004 -2.17415 1.68916004 -2.17221998 0 P 0 ;0
L 1.68916004 -2.17221998 1.69175 -2.17008996 0 P 0 ;0
L 1.69175 -2.17008996 1.69515 -2.1668 0 P 0 ;0
L 1.69515 -2.1668 1.69826004 -2.16323996 0 P 0 ;0
L 1.69826004 -2.16323996 1.70108002 -2.15941998 0 P 0 ;0
L 1.70108002 -2.15941998 1.70586004 -2.15176998 0 P 0 ;0
L 1.70586004 -2.15176998 1.71016004 -2.14383002 0 P 0 ;0
L 1.71016004 -2.14383002 1.71481998 -2.13356004 0 P 0 ;0
L 1.71481998 -2.13356004 1.74206998 -2.06631004 0 P 0 ;0
L 1.74206998 -2.06631004 1.77071004 -1.99548002 0 P 0 ;0
L 1.77071004 -1.99548002 1.77088002 -1.99498996 0 P 0 ;0
L 1.77088002 -1.99498996 1.77101998 -1.99448996 0 P 0 ;0
L 1.77101998 -1.99448996 1.77111998 -1.99398996 0 P 0 ;0
L 1.77111998 -1.99398996 1.77118002 -1.99346998 0 P 0 ;0
L 1.77118002 -1.99346998 1.7712 -1.99295 0 P 0 ;0
L 1.7712 -1.99295 1.7712 -1.99293002 0 P 0 ;0
L 1.7712 -1.99293002 1.77118996 -1.99286998 0 P 0 ;0
L 1.77118996 -1.99286998 1.77118002 -1.99286004 0 P 0 ;0
L 1.77118002 -1.99286004 1.77118002 -1.99283996 0 P 0 ;0
L 1.77118002 -1.99283996 1.77111004 -1.99276998 0 P 0 ;0
L 1.77111004 -1.99276998 1.77106998 -1.99275 0 P 0 ;0
L 1.77106998 -1.99275 1.77106004 -1.99273996 0 P 0 ;0
L 1.77106004 -1.99273996 1.771 -1.99273002 0 P 0 ;0
L 1.771 -1.99273002 1.77098002 -1.99273002 0 P 0 ;0
L 1.77098002 -1.99273002 1.76301004 -1.99265 0 P 0 ;0
L 1.76301004 -1.99265 1.75401998 -1.99261004 0 P 0 ;0
L 1.75401998 -1.99261004 1.74333002 -1.9927 0 P 0 ;0
L 1.74333002 -1.9927 1.71546004 -1.99298996 0 P 0 ;0
L 1.71546004 -1.99298996 1.71236998 -2.00646998 0 P 0 ;0
L 1.71236998 -2.00646998 1.70873996 -2.02078002 0 P 0 ;0
L 1.70873996 -2.02078002 1.70233996 -2.04308002 0 P 0 ;0
L 1.70233996 -2.04308002 1.69505 -2.0678 0 P 0 ;0
L 1.69505 -2.0678 1.69501998 -2.06788002 0 P 0 ;0
L 1.69501998 -2.06788002 1.69498996 -2.06795 0 P 0 ;0
L 1.69498996 -2.06795 1.69495 -2.06801998 0 P 0 ;0
L 1.69495 -2.06801998 1.69485 -2.06816004 0 P 0 ;0
L 1.69485 -2.06816004 1.69478996 -2.06821998 0 P 0 ;0
L 1.69478996 -2.06821998 1.69466998 -2.06831998 0 P 0 ;0
L 1.69466998 -2.06831998 1.69453002 -2.0684 0 P 0 ;0
L 1.69453002 -2.0684 1.69445 -2.06843002 0 P 0 ;0
L 1.69445 -2.06843002 1.69438002 -2.06846004 0 P 0 ;0
L 1.69438002 -2.06846004 1.69428996 -2.06846998 0 P 0 ;0
L 1.69428996 -2.06846998 1.69421004 -2.06848996 0 P 0 ;0
L 1.69421004 -2.06848996 1.69406998 -2.06848996 0 P 0 ;0
L 1.69406998 -2.06848996 1.69395 -2.06846998 0 P 0 ;0
L 1.69395 -2.06846998 1.69383002 -2.06843002 0 P 0 ;0
L 1.69383002 -2.06843002 1.69373002 -2.06836998 0 P 0 ;0
L 1.69373002 -2.06836998 1.69363002 -2.06828996 0 P 0 ;0
L 1.69363002 -2.06828996 1.69358996 -2.06823996 0 P 0 ;0
L 1.69358996 -2.06823996 1.69355 -2.0682 0 P 0 ;0
L 1.69355 -2.0682 1.69351998 -2.06815 0 P 0 ;0
L 1.69351998 -2.06815 1.69346004 -2.06803996 0 P 0 ;0
L 1.69346004 -2.06803996 1.69343996 -2.06798002 0 P 0 ;0
L 1.69343996 -2.06798002 1.68523002 -2.03878002 0 P 0 ;0
L 1.68523002 -2.03878002 1.67806998 -2.01291998 0 P 0 ;0
L 1.67806998 -2.01291998 1.67496004 -2.00031004 0 P 0 ;0
L 1.67496004 -2.00031004 1.67323002 -1.99243996 0 P 0 ;0
L 1.67323002 -1.99243996 1.61388002 -1.99243996 0 P 0 ;0
L 1.61388002 -1.99243996 1.61928996 -2.00628002 0 P 0 ;0
L 1.35018002 -2.08345 1.39488996 -2.08345 0 P 0 ;0
L 1.35026004 -2.08245 1.39586004 -2.08245 0 P 0 ;0
L 1.35041004 -2.08145 1.39708996 -2.08145 0 P 0 ;0
L 1.35058996 -2.08045 1.39853002 -2.08045 0 P 0 ;0
L 1.35083996 -2.07945 1.40031998 -2.07945 0 P 0 ;0
L 1.35116998 -2.07845 1.40271004 -2.07845 0 P 0 ;0
L 1.35158002 -2.07745 1.40561998 -2.07745 0 P 0 ;0
L 1.35203002 -2.07645 1.4092 -2.07645 0 P 0 ;0
L 1.35248002 -2.07545 1.41288996 -2.07545 0 P 0 ;0
L 1.35293002 -2.07445 1.4164 -2.07445 0 P 0 ;0
L 1.35338996 -2.07345 1.41975 -2.07345 0 P 0 ;0
L 1.35393996 -2.07245 1.42293996 -2.07245 0 P 0 ;0
L 1.35448996 -2.07145 1.42606998 -2.07145 0 P 0 ;0
L 1.35505 -2.07045 1.47843002 -2.07045 0 P 0 ;0
L 1.3557 -2.06945 1.47846998 -2.06945 0 P 0 ;0
L 1.35635 -2.06845 1.47851998 -2.06845 0 P 0 ;0
L 1.35701998 -2.06745 1.47856998 -2.06745 0 P 0 ;0
L 1.35776998 -2.06645 1.47861004 -2.06645 0 P 0 ;0
L 1.29346998 -2.00516004 1.33388996 -2.00516004 0 P 0 ;0
L 1.29448996 -2.00416004 1.33385 -2.00416004 0 P 0 ;0
L 1.29551004 -2.00316004 1.33381004 -2.00316004 0 P 0 ;0
L 1.29653996 -2.00216004 1.33376004 -2.00216004 0 P 0 ;0
L 1.29756004 -2.00116004 1.33371004 -2.00116004 0 P 0 ;0
L 1.29861998 -2.00016004 1.33366004 -2.00016004 0 P 0 ;0
L 1.29973002 -1.99916004 1.3336 -1.99916004 0 P 0 ;0
L 1.30101004 -1.99816004 1.33355 -1.99816004 0 P 0 ;0
L 1.30238996 -1.99716004 1.3335 -1.99716004 0 P 0 ;0
L 1.30393996 -1.99616004 1.33345 -1.99616004 0 P 0 ;0
L 1.30571004 -1.99516004 1.33338996 -1.99516004 0 P 0 ;0
L 1.3077 -1.99416004 1.33333002 -1.99416004 0 P 0 ;0
L 1.31001004 -1.99316004 1.33328002 -1.99316004 0 P 0 ;0
L 1.31288002 -1.99216004 1.33321998 -1.99216004 0 P 0 ;0
L 1.31688996 -1.99116004 1.33316004 -1.99116004 0 P 0 ;0
L 1.39798996 -1.98971998 1.39326998 -1.99043002 0 P 0 ;0
L 1.39326998 -1.99043002 1.38806998 -1.9913 0 P 0 ;0
L 1.38806998 -1.9913 1.38316004 -1.9922 0 P 0 ;0
L 1.38316004 -1.9922 1.37946004 -1.99296998 0 P 0 ;0
L 1.37946004 -1.99296998 1.3718 -1.99466998 0 P 0 ;0
L 1.3718 -1.99466998 1.36896004 -2.01553996 0 P 0 ;0
L 1.36896004 -2.01553996 1.36791004 -2.02358996 0 P 0 ;0
L 1.36791004 -2.02358996 1.36708002 -2.03043002 0 P 0 ;0
L 1.36708002 -2.03043002 1.36638996 -2.03646004 0 P 0 ;0
L 1.36638996 -2.03646004 1.36638002 -2.03648996 0 P 0 ;0
L 1.36638002 -2.03648996 1.36638996 -2.03653002 0 P 0 ;0
L 1.36638996 -2.03653002 1.36638996 -2.03656998 0 P 0 ;0
L 1.36638996 -2.03656998 1.3664 -2.03663996 0 P 0 ;0
L 1.3664 -2.03663996 1.36641998 -2.03666998 0 P 0 ;0
L 1.36641998 -2.03666998 1.36643002 -2.03671004 0 P 0 ;0
L 1.36643002 -2.03671004 1.36648996 -2.0368 0 P 0 ;0
L 1.36648996 -2.0368 1.36656004 -2.03686004 0 P 0 ;0
L 1.36656004 -2.03686004 1.3666 -2.03688996 0 P 0 ;0
L 1.3666 -2.03688996 1.36663002 -2.03691004 0 P 0 ;0
L 1.36663002 -2.03691004 1.36666004 -2.03691004 0 P 0 ;0
L 1.36666004 -2.03691004 1.36671004 -2.03693002 0 P 0 ;0
L 1.36671004 -2.03693002 1.36676998 -2.03693002 0 P 0 ;0
L 1.36676998 -2.03693002 1.36685 -2.03691998 0 P 0 ;0
L 1.36685 -2.03691998 1.36895 -2.03628002 0 P 0 ;0
L 1.36895 -2.03628002 1.37143002 -2.03545 0 P 0 ;0
L 1.37143002 -2.03545 1.37428996 -2.03441004 0 P 0 ;0
L 1.37428996 -2.03441004 1.38346004 -2.03126998 0 P 0 ;0
L 1.38346004 -2.03126998 1.39251998 -2.02891998 0 P 0 ;0
L 1.39251998 -2.02891998 1.40156004 -2.02731998 0 P 0 ;0
L 1.40156004 -2.02731998 1.41068002 -2.02643996 0 P 0 ;0
L 1.41068002 -2.02643996 1.41566998 -2.02628002 0 P 0 ;0
L 1.41566998 -2.02628002 1.42066004 -2.02633996 0 P 0 ;0
L 1.42066004 -2.02633996 1.42221004 -2.02646998 0 P 0 ;0
L 1.42221004 -2.02646998 1.42375 -2.02671998 0 P 0 ;0
L 1.42375 -2.02671998 1.42525 -2.0271 0 P 0 ;0
L 1.42525 -2.0271 1.42671998 -2.02761004 0 P 0 ;0
L 1.42671998 -2.02761004 1.42706004 -2.02776004 0 P 0 ;0
L 1.42706004 -2.02776004 1.42738002 -2.02793002 0 P 0 ;0
L 1.42738002 -2.02793002 1.42768002 -2.02813996 0 P 0 ;0
L 1.42768002 -2.02813996 1.42796998 -2.02836004 0 P 0 ;0
L 1.42796998 -2.02836004 1.42823002 -2.02861004 0 P 0 ;0
L 1.42823002 -2.02861004 1.42848002 -2.02888996 0 P 0 ;0
L 1.42848002 -2.02888996 1.4287 -2.02918002 0 P 0 ;0
L 1.4287 -2.02918002 1.42888996 -2.02948996 0 P 0 ;0
L 1.42888996 -2.02948996 1.42906004 -2.02981004 0 P 0 ;0
L 1.42906004 -2.02981004 1.4292 -2.03015 0 P 0 ;0
L 1.4292 -2.03015 1.42931998 -2.0305 0 P 0 ;0
L 1.42931998 -2.0305 1.4294 -2.03086004 0 P 0 ;0
L 1.4294 -2.03086004 1.42945 -2.03121998 0 P 0 ;0
L 1.42945 -2.03121998 1.42946998 -2.03158002 0 P 0 ;0
L 1.42946998 -2.03158002 1.42946004 -2.03195 0 P 0 ;0
L 1.42946004 -2.03195 1.42941998 -2.03231004 0 P 0 ;0
L 1.42941998 -2.03231004 1.42935 -2.03266998 0 P 0 ;0
L 1.42935 -2.03266998 1.42925 -2.03301998 0 P 0 ;0
L 1.42925 -2.03301998 1.42911998 -2.03336004 0 P 0 ;0
L 1.42911998 -2.03336004 1.42896004 -2.03368996 0 P 0 ;0
L 1.42896004 -2.03368996 1.42875 -2.03405 0 P 0 ;0
L 1.42875 -2.03405 1.42851004 -2.03438996 0 P 0 ;0
L 1.42851004 -2.03438996 1.42825 -2.03471004 0 P 0 ;0
L 1.42825 -2.03471004 1.42796004 -2.03501004 0 P 0 ;0
L 1.42796004 -2.03501004 1.42765 -2.03528996 0 P 0 ;0
L 1.42765 -2.03528996 1.42731998 -2.03553996 0 P 0 ;0
L 1.42731998 -2.03553996 1.42696998 -2.03576004 0 P 0 ;0
L 1.42696998 -2.03576004 1.4266 -2.03596004 0 P 0 ;0
L 1.4266 -2.03596004 1.41951004 -2.03906004 0 P 0 ;0
L 1.41951004 -2.03906004 1.4109 -2.04208996 0 P 0 ;0
L 1.4109 -2.04208996 1.40178002 -2.04451998 0 P 0 ;0
L 1.40178002 -2.04451998 1.3878 -2.04818996 0 P 0 ;0
L 1.3878 -2.04818996 1.38176998 -2.05015 0 P 0 ;0
L 1.38176998 -2.05015 1.3758 -2.05243002 0 P 0 ;0
L 1.3758 -2.05243002 1.37086998 -2.0546 0 P 0 ;0
L 1.37086998 -2.0546 1.36603996 -2.05708002 0 P 0 ;0
L 1.36603996 -2.05708002 1.36356004 -2.05856004 0 P 0 ;0
L 1.36356004 -2.05856004 1.36118996 -2.06023002 0 P 0 ;0
L 1.36118996 -2.06023002 1.35895 -2.06206004 0 P 0 ;0
L 1.35895 -2.06206004 1.35805 -2.06291004 0 P 0 ;0
L 1.35805 -2.06291004 1.35721998 -2.06385 0 P 0 ;0
L 1.35721998 -2.06385 1.35518996 -2.06655 0 P 0 ;0
L 1.35518996 -2.06655 1.3532 -2.06961998 0 P 0 ;0
L 1.3532 -2.06961998 1.35156004 -2.07263002 0 P 0 ;0
L 1.35156004 -2.07263002 1.34951004 -2.07718002 0 P 0 ;0
L 1.34951004 -2.07718002 1.34911004 -2.07825 0 P 0 ;0
L 1.34911004 -2.07825 1.34878996 -2.07935 0 P 0 ;0
L 1.34878996 -2.07935 1.34853002 -2.08046998 0 P 0 ;0
L 1.34853002 -2.08046998 1.34825 -2.08238002 0 P 0 ;0
L 1.34825 -2.08238002 1.34811998 -2.08431004 0 P 0 ;0
L 1.34811998 -2.08431004 1.348 -2.09128996 0 P 0 ;0
L 1.348 -2.09128996 1.3481 -2.09761004 0 P 0 ;0
L 1.3481 -2.09761004 1.34823002 -2.09961004 0 P 0 ;0
L 1.34823002 -2.09961004 1.34846998 -2.10161004 0 P 0 ;0
L 1.34846998 -2.10161004 1.34876998 -2.10321998 0 P 0 ;0
L 1.34876998 -2.10321998 1.3492 -2.10478996 0 P 0 ;0
L 1.3492 -2.10478996 1.3498 -2.10648996 0 P 0 ;0
L 1.3498 -2.10648996 1.3505 -2.10815 0 P 0 ;0
L 1.3505 -2.10815 1.35178996 -2.11066004 0 P 0 ;0
L 1.35178996 -2.11066004 1.35328002 -2.11305 0 P 0 ;0
L 1.35328002 -2.11305 1.35496998 -2.1153 0 P 0 ;0
L 1.35496998 -2.1153 1.35685 -2.1174 0 P 0 ;0
L 1.35685 -2.1174 1.35891998 -2.11933996 0 P 0 ;0
L 1.35891998 -2.11933996 1.36126998 -2.12121998 0 P 0 ;0
L 1.36126998 -2.12121998 1.36373996 -2.12293002 0 P 0 ;0
L 1.36373996 -2.12293002 1.36633002 -2.12446004 0 P 0 ;0
L 1.36633002 -2.12446004 1.36901004 -2.1258 0 P 0 ;0
L 1.36901004 -2.1258 1.3718 -2.12695 0 P 0 ;0
L 1.3718 -2.12695 1.37578996 -2.12828002 0 P 0 ;0
L 1.37578996 -2.12828002 1.37986998 -2.12928996 0 P 0 ;0
L 1.37986998 -2.12928996 1.38401998 -2.12998996 0 P 0 ;0
L 1.38401998 -2.12998996 1.3882 -2.13036004 0 P 0 ;0
L 1.3882 -2.13036004 1.39443002 -2.13045 0 P 0 ;0
L 1.39443002 -2.13045 1.40066004 -2.13006998 0 P 0 ;0
L 1.40066004 -2.13006998 1.40685 -2.12923002 0 P 0 ;0
L 1.40685 -2.12923002 1.41371004 -2.12801998 0 P 0 ;0
L 1.41371004 -2.12801998 1.41583002 -2.12081004 0 P 0 ;0
L 1.41583002 -2.12081004 1.41953996 -2.10798996 0 P 0 ;0
L 1.41953996 -2.10798996 1.42135 -2.10126998 0 P 0 ;0
L 1.42135 -2.10126998 1.42236998 -2.097 0 P 0 ;0
L 1.42236998 -2.097 1.42238996 -2.09691004 0 P 0 ;0
L 1.42238996 -2.09691004 1.4224 -2.09681998 0 P 0 ;0
L 1.4224 -2.09681998 1.4224 -2.09673996 0 P 0 ;0
L 1.4224 -2.09673996 1.42238002 -2.09656004 0 P 0 ;0
L 1.42238002 -2.09656004 1.42235 -2.09648002 0 P 0 ;0
L 1.42235 -2.09648002 1.42233002 -2.09638996 0 P 0 ;0
L 1.42233002 -2.09638996 1.42225 -2.09623002 0 P 0 ;0
L 1.42225 -2.09623002 1.4222 -2.09616004 0 P 0 ;0
L 1.4222 -2.09616004 1.42213996 -2.09608996 0 P 0 ;0
L 1.42213996 -2.09608996 1.42208996 -2.09601998 0 P 0 ;0
L 1.42208996 -2.09601998 1.42203996 -2.09598996 0 P 0 ;0
L 1.42203996 -2.09598996 1.42198996 -2.09595 0 P 0 ;0
L 1.42198996 -2.09595 1.42188996 -2.09588996 0 P 0 ;0
L 1.42188996 -2.09588996 1.42183002 -2.09586004 0 P 0 ;0
L 1.42183002 -2.09586004 1.42178002 -2.09585 0 P 0 ;0
L 1.42178002 -2.09585 1.42171998 -2.09583002 0 P 0 ;0
L 1.42171998 -2.09583002 1.42166004 -2.09581998 0 P 0 ;0
L 1.42166004 -2.09581998 1.42153996 -2.09581998 0 P 0 ;0
L 1.42153996 -2.09581998 1.41978002 -2.09591004 0 P 0 ;0
L 1.41978002 -2.09591004 1.41763996 -2.09615 0 P 0 ;0
L 1.41763996 -2.09615 1.41521998 -2.09658002 0 P 0 ;0
L 1.41521998 -2.09658002 1.4107 -2.09733002 0 P 0 ;0
L 1.4107 -2.09733002 1.40613002 -2.09775 0 P 0 ;0
L 1.40613002 -2.09775 1.40481004 -2.09778002 0 P 0 ;0
L 1.40481004 -2.09778002 1.40348996 -2.09771998 0 P 0 ;0
L 1.40348996 -2.09771998 1.40216998 -2.09756004 0 P 0 ;0
L 1.40216998 -2.09756004 1.40086998 -2.0973 0 P 0 ;0
L 1.40086998 -2.0973 1.39958996 -2.09695 0 P 0 ;0
L 1.39958996 -2.09695 1.39895 -2.09671998 0 P 0 ;0
L 1.39895 -2.09671998 1.39831998 -2.09643002 0 P 0 ;0
L 1.39831998 -2.09643002 1.39773002 -2.0961 0 P 0 ;0
L 1.39773002 -2.0961 1.39716004 -2.09571004 0 P 0 ;0
L 1.39716004 -2.09571004 1.39663002 -2.09528002 0 P 0 ;0
L 1.39663002 -2.09528002 1.39613996 -2.0948 0 P 0 ;0
L 1.39613996 -2.0948 1.39568002 -2.09428002 0 P 0 ;0
L 1.39568002 -2.09428002 1.39533996 -2.09381998 0 P 0 ;0
L 1.39533996 -2.09381998 1.39505 -2.09333996 0 P 0 ;0
L 1.39505 -2.09333996 1.39478996 -2.09281998 0 P 0 ;0
L 1.39478996 -2.09281998 1.39456998 -2.09228996 0 P 0 ;0
L 1.39456998 -2.09228996 1.3944 -2.09173996 0 P 0 ;0
L 1.3944 -2.09173996 1.39428002 -2.09118996 0 P 0 ;0
L 1.39428002 -2.09118996 1.39421004 -2.09061998 0 P 0 ;0
L 1.39421004 -2.09061998 1.39418002 -2.09003996 0 P 0 ;0
L 1.39418002 -2.09003996 1.39421004 -2.08943002 0 P 0 ;0
L 1.39421004 -2.08943002 1.39428002 -2.08883002 0 P 0 ;0
L 1.39428002 -2.08883002 1.39441004 -2.08823002 0 P 0 ;0
L 1.39441004 -2.08823002 1.3946 -2.08765 0 P 0 ;0
L 1.3946 -2.08765 1.39483002 -2.08708002 0 P 0 ;0
L 1.39483002 -2.08708002 1.39511004 -2.08653996 0 P 0 ;0
L 1.39511004 -2.08653996 1.39555 -2.08583996 0 P 0 ;0
L 1.39555 -2.08583996 1.39603996 -2.08518002 0 P 0 ;0
L 1.39603996 -2.08518002 1.39658002 -2.08456004 0 P 0 ;0
L 1.39658002 -2.08456004 1.39716004 -2.08396998 0 P 0 ;0
L 1.39716004 -2.08396998 1.39778002 -2.08343002 0 P 0 ;0
L 1.39778002 -2.08343002 1.39878996 -2.08266998 0 P 0 ;0
L 1.39878996 -2.08266998 1.39985 -2.08196998 0 P 0 ;0
L 1.39985 -2.08196998 1.40096004 -2.08135 0 P 0 ;0
L 1.40096004 -2.08135 1.40211998 -2.08081004 0 P 0 ;0
L 1.40211998 -2.08081004 1.40503002 -2.07971004 0 P 0 ;0
L 1.40503002 -2.07971004 1.40801998 -2.07881998 0 P 0 ;0
L 1.40801998 -2.07881998 1.41128996 -2.07796004 0 P 0 ;0
L 1.41128996 -2.07796004 1.41506004 -2.07691998 0 P 0 ;0
L 1.41506004 -2.07691998 1.41871998 -2.07585 0 P 0 ;0
L 1.41871998 -2.07585 1.42165 -2.07495 0 P 0 ;0
L 1.42165 -2.07495 1.42791998 -2.07295 0 P 0 ;0
L 1.42791998 -2.07295 1.42731998 -2.08241004 0 P 0 ;0
L 1.42731998 -2.08241004 1.42701004 -2.08708002 0 P 0 ;0
L 1.42701004 -2.08708002 1.42658002 -2.09353996 0 P 0 ;0
L 1.42658002 -2.09353996 1.4261 -2.10055 0 P 0 ;0
L 1.4261 -2.10055 1.42566998 -2.10706004 0 P 0 ;0
L 1.42566998 -2.10706004 1.42525 -2.11306004 0 P 0 ;0
L 1.42525 -2.11306004 1.42491998 -2.11851998 0 P 0 ;0
L 1.42491998 -2.11851998 1.42466004 -2.1231 0 P 0 ;0
L 1.42466004 -2.1231 1.42461004 -2.12471004 0 P 0 ;0
L 1.42461004 -2.12471004 1.4246 -2.12716004 0 P 0 ;0
L 1.4246 -2.12716004 1.47893002 -2.12716004 0 P 0 ;0
L 1.47893002 -2.12716004 1.47893002 -2.11358002 0 P 0 ;0
L 1.47893002 -2.11358002 1.47905 -2.10616998 0 P 0 ;0
L 1.47905 -2.10616998 1.47943996 -2.09385 0 P 0 ;0
L 1.47943996 -2.09385 1.48 -2.07968996 0 P 0 ;0
L 1.48 -2.07968996 1.48066004 -2.0655 0 P 0 ;0
L 1.48066004 -2.0655 1.4813 -2.05168996 0 P 0 ;0
L 1.4813 -2.05168996 1.48175 -2.03873996 0 P 0 ;0
L 1.48175 -2.03873996 1.48201998 -2.02785 0 P 0 ;0
L 1.48201998 -2.02785 1.48191998 -2.02286004 0 P 0 ;0
L 1.48191998 -2.02286004 1.48165 -2.01995 0 P 0 ;0
L 1.48165 -2.01995 1.48115 -2.01708002 0 P 0 ;0
L 1.48115 -2.01708002 1.48043996 -2.01425 0 P 0 ;0
L 1.48043996 -2.01425 1.47951004 -2.01146998 0 P 0 ;0
L 1.47951004 -2.01146998 1.47866998 -2.00946998 0 P 0 ;0
L 1.47866998 -2.00946998 1.47768002 -2.00753996 0 P 0 ;0
L 1.47768002 -2.00753996 1.47655 -2.00568002 0 P 0 ;0
L 1.47655 -2.00568002 1.47528002 -2.00391998 0 P 0 ;0
L 1.47528002 -2.00391998 1.47388002 -2.00225 0 P 0 ;0
L 1.47388002 -2.00225 1.47228996 -2.00063002 0 P 0 ;0
L 1.47228996 -2.00063002 1.4706 -1.99911998 0 P 0 ;0
L 1.4706 -1.99911998 1.4688 -1.99773002 0 P 0 ;0
L 1.4688 -1.99773002 1.46691004 -1.99648002 0 P 0 ;0
L 1.46691004 -1.99648002 1.46491998 -1.99535 0 P 0 ;0
L 1.46491998 -1.99535 1.46098996 -1.99351004 0 P 0 ;0
L 1.46098996 -1.99351004 1.45693002 -1.99196998 0 P 0 ;0
L 1.45693002 -1.99196998 1.45276004 -1.99076004 0 P 0 ;0
L 1.45276004 -1.99076004 1.44953996 -1.99006004 0 P 0 ;0
L 1.44953996 -1.99006004 1.44628996 -1.98956004 0 P 0 ;0
L 1.44628996 -1.98956004 1.44298002 -1.98923996 0 P 0 ;0
L 1.44298002 -1.98923996 1.42695 -1.98856998 0 P 0 ;0
L 1.42695 -1.98856998 1.41038996 -1.98865 0 P 0 ;0
L 1.41038996 -1.98865 1.4042 -1.98901004 0 P 0 ;0
L 1.4042 -1.98901004 1.39798996 -1.98971998 0 P 0 ;0
L 1.35778996 -2.11545 1.4153 -2.11545 0 P 0 ;0
L 1.35688996 -2.11445 1.41558996 -2.11445 0 P 0 ;0
L 1.35608002 -2.11345 1.41588002 -2.11345 0 P 0 ;0
L 1.35533002 -2.11245 1.41616998 -2.11245 0 P 0 ;0
L 1.35463996 -2.11145 1.41646004 -2.11145 0 P 0 ;0
L 1.35401004 -2.11045 1.41675 -2.11045 0 P 0 ;0
L 1.35341004 -2.10945 1.41703996 -2.10945 0 P 0 ;0
L 1.3529 -2.10845 1.41733002 -2.10845 0 P 0 ;0
L 1.35238002 -2.10745 1.41761998 -2.10745 0 P 0 ;0
L 1.35195 -2.10645 1.41788002 -2.10645 0 P 0 ;0
L 1.35155 -2.10545 1.41816004 -2.10545 0 P 0 ;0
L 1.3512 -2.10445 1.41841998 -2.10445 0 P 0 ;0
L 1.35091004 -2.10345 1.41868996 -2.10345 0 P 0 ;0
L 1.35066004 -2.10245 1.41896004 -2.10245 0 P 0 ;0
L 1.35046998 -2.10145 1.41923002 -2.10145 0 P 0 ;0
L 1.35033996 -2.10045 1.41948996 -2.10045 0 P 0 ;0
L 1.35021998 -2.09945 1.40141004 -2.09945 0 P 0 ;0
L 1.35016004 -2.09845 1.39791004 -2.09845 0 P 0 ;0
L 1.3501 -2.09745 1.39616004 -2.09745 0 P 0 ;0
L 1.35008002 -2.09645 1.39496004 -2.09645 0 P 0 ;0
L 1.35006998 -2.09545 1.39406004 -2.09545 0 P 0 ;0
L 1.35005 -2.09445 1.39338002 -2.09445 0 P 0 ;0
L 1.35003996 -2.09345 1.39288002 -2.09345 0 P 0 ;0
L 1.35001998 -2.09245 1.39253002 -2.09245 0 P 0 ;0
L 1.35001004 -2.09145 1.3923 -2.09145 0 P 0 ;0
L 1.35001998 -2.09045 1.3922 -2.09045 0 P 0 ;0
L 1.35003002 -2.08945 1.3922 -2.08945 0 P 0 ;0
L 1.35005 -2.08845 1.39231998 -2.08845 0 P 0 ;0
L 1.35006998 -2.08745 1.39256004 -2.08745 0 P 0 ;0
L 1.35008002 -2.08645 1.39293002 -2.08645 0 P 0 ;0
L 1.3501 -2.08545 1.39343002 -2.08545 0 P 0 ;0
L 1.35011004 -2.08445 1.39408996 -2.08445 0 P 0 ;0
L 1.39438002 -2.12845 1.3883 -2.12836004 0 P 0 ;0
L 1.3883 -2.12836004 1.38426998 -2.128 0 P 0 ;0
L 1.38426998 -2.128 1.38028002 -2.12733002 0 P 0 ;0
L 1.38028002 -2.12733002 1.37635 -2.12636004 0 P 0 ;0
L 1.37635 -2.12636004 1.37248996 -2.12508002 0 P 0 ;0
L 1.37248996 -2.12508002 1.36983996 -2.12398002 0 P 0 ;0
L 1.36983996 -2.12398002 1.36728996 -2.1227 0 P 0 ;0
L 1.36728996 -2.1227 1.36481998 -2.12123996 0 P 0 ;0
L 1.36481998 -2.12123996 1.36246004 -2.11961004 0 P 0 ;0
L 1.36246004 -2.11961004 1.36023002 -2.11781998 0 P 0 ;0
L 1.36023002 -2.11781998 1.35828996 -2.116 0 P 0 ;0
L 1.35828996 -2.116 1.35651998 -2.11403002 0 P 0 ;0
L 1.35651998 -2.11403002 1.35493002 -2.11191004 0 P 0 ;0
L 1.35493002 -2.11191004 1.35353002 -2.10966998 0 P 0 ;0
L 1.35353002 -2.10966998 1.35231004 -2.10731004 0 P 0 ;0
L 1.35231004 -2.10731004 1.35166998 -2.10576998 0 P 0 ;0
L 1.35166998 -2.10576998 1.35111004 -2.1042 0 P 0 ;0
L 1.35111004 -2.1042 1.35071998 -2.10276004 0 P 0 ;0
L 1.35071998 -2.10276004 1.35045 -2.1013 0 P 0 ;0
L 1.35045 -2.1013 1.35021998 -2.09943002 0 P 0 ;0
L 1.35021998 -2.09943002 1.3501 -2.09753002 0 P 0 ;0
L 1.3501 -2.09753002 1.35001004 -2.09128002 0 P 0 ;0
L 1.35001004 -2.09128002 1.35011998 -2.0844 0 P 0 ;0
L 1.35011998 -2.0844 1.35023996 -2.08258996 0 P 0 ;0
L 1.35023996 -2.08258996 1.3505 -2.08083996 0 P 0 ;0
L 1.3505 -2.08083996 1.35071998 -2.07985 0 P 0 ;0
L 1.35071998 -2.07985 1.35101004 -2.07888002 0 P 0 ;0
L 1.35101004 -2.07888002 1.35136004 -2.07793002 0 P 0 ;0
L 1.35136004 -2.07793002 1.35335 -2.07351998 0 P 0 ;0
L 1.35335 -2.07351998 1.35491998 -2.07065 0 P 0 ;0
L 1.35491998 -2.07065 1.35683002 -2.0677 0 P 0 ;0
L 1.35683002 -2.0677 1.35876998 -2.06511004 0 P 0 ;0
L 1.35876998 -2.06511004 1.35948996 -2.0643 0 P 0 ;0
L 1.35948996 -2.0643 1.36026998 -2.06356004 0 P 0 ;0
L 1.36026998 -2.06356004 1.3624 -2.06181998 0 P 0 ;0
L 1.3624 -2.06181998 1.36465 -2.06023996 0 P 0 ;0
L 1.36465 -2.06023996 1.36701004 -2.05883002 0 P 0 ;0
L 1.36701004 -2.05883002 1.37173002 -2.05641004 0 P 0 ;0
L 1.37173002 -2.05641004 1.37656004 -2.05426998 0 P 0 ;0
L 1.37656004 -2.05426998 1.38243002 -2.05203996 0 P 0 ;0
L 1.38243002 -2.05203996 1.38836004 -2.0501 0 P 0 ;0
L 1.38836004 -2.0501 1.4023 -2.04645 0 P 0 ;0
L 1.4023 -2.04645 1.41148996 -2.044 0 P 0 ;0
L 1.41148996 -2.044 1.42016998 -2.04095 0 P 0 ;0
L 1.42016998 -2.04095 1.42016998 -2.04093996 0 P 0 ;0
L 1.42016998 -2.04093996 1.42021004 -2.04093996 0 P 0 ;0
L 1.42021004 -2.04093996 1.42023996 -2.04093002 0 P 0 ;0
L 1.42023996 -2.04093002 1.42746998 -2.03776004 0 P 0 ;0
L 1.42746998 -2.03776004 1.42753002 -2.03773002 0 P 0 ;0
L 1.42753002 -2.03773002 1.42796998 -2.03748996 0 P 0 ;0
L 1.42796998 -2.03748996 1.42846004 -2.03718996 0 P 0 ;0
L 1.42846004 -2.03718996 1.42891998 -2.03683996 0 P 0 ;0
L 1.42891998 -2.03683996 1.42935 -2.03646004 0 P 0 ;0
L 1.42935 -2.03646004 1.42975 -2.03603996 0 P 0 ;0
L 1.42975 -2.03603996 1.43011004 -2.0356 0 P 0 ;0
L 1.43011004 -2.0356 1.43016004 -2.03553002 0 P 0 ;0
L 1.43016004 -2.03553002 1.4299 -2.03535 0 P 0 ;0
L 1.4299 -2.03535 1.43028002 -2.03535 0 P 0 ;0
L 1.43028002 -2.03535 1.43043996 -2.03513002 0 P 0 ;0
L 1.43043996 -2.03513002 1.43048002 -2.03506004 0 P 0 ;0
L 1.43048002 -2.03506004 1.43041998 -2.03501998 0 P 0 ;0
L 1.43041998 -2.03501998 1.4305 -2.03501998 0 P 0 ;0
L 1.4305 -2.03501998 1.43073002 -2.03463002 0 P 0 ;0
L 1.43073002 -2.03463002 1.43096004 -2.03415 0 P 0 ;0
L 1.43096004 -2.03415 1.43115 -2.03365 0 P 0 ;0
L 1.43115 -2.03365 1.4313 -2.03313002 0 P 0 ;0
L 1.4313 -2.03313002 1.4314 -2.03261004 0 P 0 ;0
L 1.4314 -2.03261004 1.43146004 -2.03208002 0 P 0 ;0
L 1.43146004 -2.03208002 1.43146998 -2.03155 0 P 0 ;0
L 1.43146998 -2.03155 1.43143996 -2.03101004 0 P 0 ;0
L 1.43143996 -2.03101004 1.43143002 -2.03093002 0 P 0 ;0
L 1.43143002 -2.03093002 1.43136004 -2.03048996 0 P 0 ;0
L 1.43136004 -2.03048996 1.43125 -2.02996998 0 P 0 ;0
L 1.43125 -2.02996998 1.43108002 -2.02946004 0 P 0 ;0
L 1.43108002 -2.02946004 1.43086998 -2.02896004 0 P 0 ;0
L 1.43086998 -2.02896004 1.43063002 -2.02848996 0 P 0 ;0
L 1.43063002 -2.02848996 1.43033996 -2.02803996 0 P 0 ;0
L 1.43033996 -2.02803996 1.43001998 -2.02761004 0 P 0 ;0
L 1.43001998 -2.02761004 1.42966004 -2.02721004 0 P 0 ;0
L 1.42966004 -2.02721004 1.42928002 -2.02685 0 P 0 ;0
L 1.42928002 -2.02685 1.42886004 -2.02651998 0 P 0 ;0
L 1.42886004 -2.02651998 1.42841998 -2.02623002 0 P 0 ;0
L 1.42841998 -2.02623002 1.42795 -2.02596998 0 P 0 ;0
L 1.42795 -2.02596998 1.42746004 -2.02575 0 P 0 ;0
L 1.42746004 -2.02575 1.42583002 -2.02518002 0 P 0 ;0
L 1.42583002 -2.02518002 1.42416004 -2.02476004 0 P 0 ;0
L 1.42416004 -2.02476004 1.42245 -2.02448002 0 P 0 ;0
L 1.42245 -2.02448002 1.42075 -2.02435 0 P 0 ;0
L 1.42075 -2.02435 1.41565 -2.02428002 0 P 0 ;0
L 1.41565 -2.02428002 1.4156 -2.02428002 0 P 0 ;0
L 1.4156 -2.02428002 1.41055 -2.02445 0 P 0 ;0
L 1.41055 -2.02445 1.41048002 -2.02445 0 P 0 ;0
L 1.41048002 -2.02445 1.40128996 -2.02533996 0 P 0 ;0
L 1.40128996 -2.02533996 1.39208996 -2.02696998 0 P 0 ;0
L 1.39208996 -2.02696998 1.38288002 -2.02936004 0 P 0 ;0
L 1.38288002 -2.02936004 1.37363002 -2.03251998 0 P 0 ;0
L 1.37363002 -2.03251998 1.37076998 -2.03356004 0 P 0 ;0
L 1.37076998 -2.03356004 1.36865 -2.03426998 0 P 0 ;0
L 1.36865 -2.03426998 1.36906004 -2.03066998 0 P 0 ;0
L 1.36906004 -2.03066998 1.36988996 -2.02383996 0 P 0 ;0
L 1.36988996 -2.02383996 1.37095 -2.01581004 0 P 0 ;0
L 1.37095 -2.01581004 1.37358996 -1.99631998 0 P 0 ;0
L 1.37358996 -1.99631998 1.37988002 -1.99491998 0 P 0 ;0
L 1.37988002 -1.99491998 1.38353996 -1.99416998 0 P 0 ;0
L 1.38353996 -1.99416998 1.38841998 -1.99326998 0 P 0 ;0
L 1.38841998 -1.99326998 1.39358002 -1.9924 0 P 0 ;0
L 1.39358002 -1.9924 1.39825 -1.9917 0 P 0 ;0
L 1.39825 -1.9917 1.40436998 -1.991 0 P 0 ;0
L 1.40436998 -1.991 1.41045 -1.99065 0 P 0 ;0
L 1.41045 -1.99065 1.42691004 -1.99056998 0 P 0 ;0
L 1.42691004 -1.99056998 1.44283996 -1.99123996 0 P 0 ;0
L 1.44283996 -1.99123996 1.44603996 -1.99153996 0 P 0 ;0
L 1.44603996 -1.99153996 1.44918002 -1.99203002 0 P 0 ;0
L 1.44918002 -1.99203002 1.45226004 -1.9927 0 P 0 ;0
L 1.45226004 -1.9927 1.4563 -1.99386998 0 P 0 ;0
L 1.4563 -1.99386998 1.46021004 -1.99535 0 P 0 ;0
L 1.46021004 -1.99535 1.464 -1.99713002 0 P 0 ;0
L 1.464 -1.99713002 1.46586004 -1.99818996 0 P 0 ;0
L 1.46586004 -1.99818996 1.46763996 -1.99936004 0 P 0 ;0
L 1.46763996 -1.99936004 1.46931998 -2.00066004 0 P 0 ;0
L 1.46931998 -2.00066004 1.47091004 -2.00206998 0 P 0 ;0
L 1.47091004 -2.00206998 1.47238996 -2.00358996 0 P 0 ;0
L 1.47238996 -2.00358996 1.4737 -2.00515 0 P 0 ;0
L 1.4737 -2.00515 1.47488002 -2.00678996 0 P 0 ;0
L 1.47488002 -2.00678996 1.47593996 -2.00851004 0 P 0 ;0
L 1.47593996 -2.00851004 1.47686004 -2.01031004 0 P 0 ;0
L 1.47686004 -2.01031004 1.47763996 -2.01216998 0 P 0 ;0
L 1.47763996 -2.01216998 1.47851998 -2.01481004 0 P 0 ;0
L 1.47851998 -2.01481004 1.47918996 -2.01748996 0 P 0 ;0
L 1.47918996 -2.01748996 1.47966004 -2.02021998 0 P 0 ;0
L 1.47966004 -2.02021998 1.47993002 -2.02296998 0 P 0 ;0
L 1.47993002 -2.02296998 1.48001998 -2.02783996 0 P 0 ;0
L 1.48001998 -2.02783996 1.47975 -2.03868996 0 P 0 ;0
L 1.47975 -2.03868996 1.4793 -2.05161004 0 P 0 ;0
L 1.4793 -2.05161004 1.47866004 -2.06543002 0 P 0 ;0
L 1.47866004 -2.06543002 1.47801004 -2.07961004 0 P 0 ;0
L 1.47801004 -2.07961004 1.47743996 -2.09378996 0 P 0 ;0
L 1.47743996 -2.09378996 1.47705 -2.10613002 0 P 0 ;0
L 1.47705 -2.10613002 1.47693002 -2.11356004 0 P 0 ;0
L 1.47693002 -2.11356004 1.47693002 -2.12516004 0 P 0 ;0
L 1.47693002 -2.12516004 1.42661004 -2.12516004 0 P 0 ;0
L 1.42661004 -2.12516004 1.42661004 -2.12473996 0 P 0 ;0
L 1.42661004 -2.12473996 1.42666004 -2.12318002 0 P 0 ;0
L 1.42666004 -2.12318002 1.42691004 -2.11863996 0 P 0 ;0
L 1.42691004 -2.11863996 1.42725 -2.1132 0 P 0 ;0
L 1.42725 -2.1132 1.42766004 -2.1072 0 P 0 ;0
L 1.42766004 -2.1072 1.42766004 -2.10718996 0 P 0 ;0
L 1.42766004 -2.10718996 1.4281 -2.10068996 0 P 0 ;0
L 1.4281 -2.10068996 1.42858002 -2.09368002 0 P 0 ;0
L 1.42858002 -2.09368002 1.42901004 -2.08721004 0 P 0 ;0
L 1.42901004 -2.08721004 1.42901004 -2.0872 0 P 0 ;0
L 1.42901004 -2.0872 1.42931004 -2.08256004 0 P 0 ;0
L 1.42931004 -2.08256004 1.42991998 -2.07308002 0 P 0 ;0
L 1.42991998 -2.07308002 1.42916004 -2.07136998 0 P 0 ;0
L 1.42916004 -2.07136998 1.42731998 -2.07105 0 P 0 ;0
L 1.42731998 -2.07105 1.42105 -2.07303996 0 P 0 ;0
L 1.42105 -2.07303996 1.41815 -2.07393002 0 P 0 ;0
L 1.41815 -2.07393002 1.41451004 -2.075 0 P 0 ;0
L 1.41451004 -2.075 1.41076004 -2.07603002 0 P 0 ;0
L 1.41076004 -2.07603002 1.40748002 -2.0769 0 P 0 ;0
L 1.40748002 -2.0769 1.40438996 -2.07781004 0 P 0 ;0
L 1.40438996 -2.07781004 1.40431998 -2.07783996 0 P 0 ;0
L 1.40431998 -2.07783996 1.40133996 -2.07896998 0 P 0 ;0
L 1.40133996 -2.07896998 1.40005 -2.07956998 0 P 0 ;0
L 1.40005 -2.07956998 1.39881998 -2.08026004 0 P 0 ;0
L 1.39881998 -2.08026004 1.39763996 -2.08103002 0 P 0 ;0
L 1.39763996 -2.08103002 1.39651998 -2.08188002 0 P 0 ;0
L 1.39651998 -2.08188002 1.39578996 -2.08251004 0 P 0 ;0
L 1.39578996 -2.08251004 1.39573996 -2.08256004 0 P 0 ;0
L 1.39573996 -2.08256004 1.3951 -2.08318996 0 P 0 ;0
L 1.3951 -2.08318996 1.39446998 -2.08393002 0 P 0 ;0
L 1.39446998 -2.08393002 1.3939 -2.08471004 0 P 0 ;0
L 1.3939 -2.08471004 1.39336998 -2.08553996 0 P 0 ;0
L 1.39336998 -2.08553996 1.39301004 -2.08623996 0 P 0 ;0
L 1.39301004 -2.08623996 1.39271004 -2.08696998 0 P 0 ;0
L 1.39271004 -2.08696998 1.39248002 -2.08771998 0 P 0 ;0
L 1.39248002 -2.08771998 1.39231004 -2.08848996 0 P 0 ;0
L 1.39231004 -2.08848996 1.39221004 -2.08926004 0 P 0 ;0
L 1.39221004 -2.08926004 1.39218002 -2.09003996 0 P 0 ;0
L 1.39218002 -2.09003996 1.39221004 -2.0908 0 P 0 ;0
L 1.39221004 -2.0908 1.39231004 -2.09153002 0 P 0 ;0
L 1.39231004 -2.09153002 1.39246998 -2.09226004 0 P 0 ;0
L 1.39246998 -2.09226004 1.39268996 -2.09296998 0 P 0 ;0
L 1.39268996 -2.09296998 1.39296004 -2.09365 0 P 0 ;0
L 1.39296004 -2.09365 1.3933 -2.09431004 0 P 0 ;0
L 1.3933 -2.09431004 1.39368996 -2.09493996 0 P 0 ;0
L 1.39368996 -2.09493996 1.39411998 -2.09553996 0 P 0 ;0
L 1.39411998 -2.09553996 1.39468996 -2.09618002 0 P 0 ;0
L 1.39468996 -2.09618002 1.3953 -2.09678002 0 P 0 ;0
L 1.3953 -2.09678002 1.39596004 -2.09731998 0 P 0 ;0
L 1.39596004 -2.09731998 1.39666998 -2.0978 0 P 0 ;0
L 1.39666998 -2.0978 1.39673996 -2.09783996 0 P 0 ;0
L 1.39673996 -2.09783996 1.39741004 -2.09821998 0 P 0 ;0
L 1.39741004 -2.09821998 1.39748996 -2.09825 0 P 0 ;0
L 1.39748996 -2.09825 1.39818996 -2.09856998 0 P 0 ;0
L 1.39818996 -2.09856998 1.39898996 -2.09886004 0 P 0 ;0
L 1.39898996 -2.09886004 1.39906998 -2.09888002 0 P 0 ;0
L 1.39906998 -2.09888002 1.40043996 -2.09888002 0 P 0 ;0
L 1.40043996 -2.09888002 1.40033996 -2.09923002 0 P 0 ;0
L 1.40033996 -2.09923002 1.40041998 -2.09925 0 P 0 ;0
L 1.40041998 -2.09925 1.40186004 -2.09953002 0 P 0 ;0
L 1.40186004 -2.09953002 1.40331004 -2.09971004 0 P 0 ;0
L 1.40331004 -2.09971004 1.40478002 -2.09978002 0 P 0 ;0
L 1.40478002 -2.09978002 1.40625 -2.09975 0 P 0 ;0
L 1.40625 -2.09975 1.41096004 -2.09931004 0 P 0 ;0
L 1.41096004 -2.09931004 1.41556998 -2.09855 0 P 0 ;0
L 1.41556998 -2.09855 1.41791998 -2.09813002 0 P 0 ;0
L 1.41791998 -2.09813002 1.41995 -2.09791004 0 P 0 ;0
L 1.41995 -2.09791004 1.4201 -2.0979 0 P 0 ;0
L 1.4201 -2.0979 1.41941004 -2.10078002 0 P 0 ;0
L 1.41941004 -2.10078002 1.41761004 -2.10745 0 P 0 ;0
L 1.41761004 -2.10745 1.41391004 -2.12025 0 P 0 ;0
L 1.41391004 -2.12025 1.41215 -2.12626998 0 P 0 ;0
L 1.41215 -2.12626998 1.40655 -2.12725 0 P 0 ;0
L 1.40655 -2.12725 1.40046004 -2.12808002 0 P 0 ;0
L 1.40046004 -2.12808002 1.39438002 -2.12845 0 P 0 ;0
L 1.15303002 -2.08283002 1.20788996 -2.08283002 0 P 0 ;0
L 1.15398996 -2.08183002 1.20795 -2.08183002 0 P 0 ;0
L 1.15483002 -2.08083002 1.208 -2.08083002 0 P 0 ;0
L 1.15555 -2.07983002 1.20805 -2.07983002 0 P 0 ;0
L 1.15621998 -2.07883002 1.2081 -2.07883002 0 P 0 ;0
L 1.15681998 -2.07783002 1.20816004 -2.07783002 0 P 0 ;0
L 1.15733002 -2.07683002 1.20821004 -2.07683002 0 P 0 ;0
L 1.15778996 -2.07583002 1.20826004 -2.07583002 0 P 0 ;0
L 1.15818002 -2.07483002 1.20831004 -2.07483002 0 P 0 ;0
L 1.15853996 -2.07383002 1.20836998 -2.07383002 0 P 0 ;0
L 1.15881998 -2.07283002 1.20841998 -2.07283002 0 P 0 ;0
L 1.1591 -2.07183002 1.20846998 -2.07183002 0 P 0 ;0
L 1.15938002 -2.07083002 1.20853002 -2.07083002 0 P 0 ;0
L 1.1596 -2.06983002 1.20858002 -2.06983002 0 P 0 ;0
L 1.15981004 -2.06883002 1.20863996 -2.06883002 0 P 0 ;0
L 1.16001004 -2.06783002 1.20868996 -2.06783002 0 P 0 ;0
L 1.1602 -2.06683002 1.20875 -2.06683002 0 P 0 ;0
L 1.16033996 -2.06583002 1.2088 -2.06583002 0 P 0 ;0
L 1.16048996 -2.06483002 1.20886004 -2.06483002 0 P 0 ;0
L 1.16063996 -2.06383002 1.20891998 -2.06383002 0 P 0 ;0
L 1.16078002 -2.06283002 1.20896998 -2.06283002 0 P 0 ;0
L 1.16088996 -2.06183002 1.20903002 -2.06183002 0 P 0 ;0
L 1.16098996 -2.06083002 1.20908002 -2.06083002 0 P 0 ;0
L 1.16108996 -2.05983002 1.20913996 -2.05983002 0 P 0 ;0
L 1.16118002 -2.05883002 1.20918996 -2.05883002 0 P 0 ;0
L 1.16128002 -2.05783002 1.20925 -2.05783002 0 P 0 ;0
L 1.16133996 -2.05683002 1.2093 -2.05683002 0 P 0 ;0
L 1.1614 -2.05583002 1.20936004 -2.05583002 0 P 0 ;0
L 1.16146004 -2.05483002 1.20941004 -2.05483002 0 P 0 ;0
L 1.16151998 -2.05383002 1.20946998 -2.05383002 0 P 0 ;0
L 1.16158002 -2.05283002 1.20951998 -2.05283002 0 P 0 ;0
L 1.16163996 -2.05183002 1.20958002 -2.05183002 0 P 0 ;0
L 1.1617 -2.05083002 1.20963996 -2.05083002 0 P 0 ;0
L 1.16175 -2.04983002 1.2097 -2.04983002 0 P 0 ;0
L 1.16181004 -2.04883002 1.20975 -2.04883002 0 P 0 ;0
L 1.16186998 -2.04783002 1.20981004 -2.04783002 0 P 0 ;0
L 1.16193002 -2.04683002 1.20986998 -2.04683002 0 P 0 ;0
L 1.16198996 -2.04583002 1.20993002 -2.04583002 0 P 0 ;0
L 1.16205 -2.04483002 1.20998996 -2.04483002 0 P 0 ;0
L 1.16211004 -2.04383002 1.21005 -2.04383002 0 P 0 ;0
L 1.16215 -2.04283002 1.2101 -2.04283002 0 P 0 ;0
L 1.1622 -2.04183002 1.21016004 -2.04183002 0 P 0 ;0
L 1.16225 -2.04083002 1.21021998 -2.04083002 0 P 0 ;0
L 1.16228996 -2.03983002 1.21028002 -2.03983002 0 P 0 ;0
L 1.16233996 -2.03883002 1.21033996 -2.03883002 0 P 0 ;0
L 1.16238002 -2.03783002 1.2104 -2.03783002 0 P 0 ;0
L 1.16243002 -2.03683002 1.21046004 -2.03683002 0 P 0 ;0
L 1.16246998 -2.03583002 1.21051004 -2.03583002 0 P 0 ;0
L 1.16251998 -2.03483002 1.21056998 -2.03483002 0 P 0 ;0
L 1.16256998 -2.03383002 1.21063996 -2.03383002 0 P 0 ;0
L 1.16261004 -2.03283002 1.2107 -2.03283002 0 P 0 ;0
L 1.16266004 -2.03183002 1.21076004 -2.03183002 0 P 0 ;0
L 1.1627 -2.03083002 1.21083002 -2.03083002 0 P 0 ;0
L 1.16015 -1.97631004 1.17066004 -1.97631004 0 P 0 ;0
L 1.15961998 -1.97531004 1.17026004 -1.97531004 0 P 0 ;0
L 1.1591 -1.97431004 1.16986998 -1.97431004 0 P 0 ;0
L 1.15856998 -1.97331004 1.16946998 -1.97331004 0 P 0 ;0
L 1.15803996 -1.97231004 1.16903002 -1.97231004 0 P 0 ;0
L 1.15746998 -1.97131004 1.16858996 -1.97131004 0 P 0 ;0
L 1.1569 -1.97031004 1.16815 -1.97031004 0 P 0 ;0
L 1.15631998 -1.96931004 1.16771004 -1.96931004 0 P 0 ;0
L 1.15573996 -1.96831004 1.16726998 -1.96831004 0 P 0 ;0
L 1.15516004 -1.96731004 1.16681998 -1.96731004 0 P 0 ;0
L 1.15458996 -1.96631004 1.16638002 -1.96631004 0 P 0 ;0
L 1.15398002 -1.96531004 1.16593996 -1.96531004 0 P 0 ;0
L 1.1533 -1.96431004 1.16548996 -1.96431004 0 P 0 ;0
L 1.15261998 -1.96331004 1.16503002 -1.96331004 0 P 0 ;0
L 1.15193996 -1.96231004 1.16448002 -1.96231004 0 P 0 ;0
L 1.15126004 -1.96131004 1.16393002 -1.96131004 0 P 0 ;0
L 1.15058002 -1.96031004 1.16338002 -1.96031004 0 P 0 ;0
L 1.1499 -1.95931004 1.16283002 -1.95931004 0 P 0 ;0
L 1.1491 -1.95831004 1.16228996 -1.95831004 0 P 0 ;0
L 1.14831004 -1.95731004 1.16173996 -1.95731004 0 P 0 ;0
L 1.14751004 -1.95631004 1.16118996 -1.95631004 0 P 0 ;0
L 1.14671004 -1.95531004 1.16063996 -1.95531004 0 P 0 ;0
L 1.14591998 -1.95431004 1.16008996 -1.95431004 0 P 0 ;0
L 1.14511998 -1.95331004 1.15943996 -1.95331004 0 P 0 ;0
L 1.1442 -1.95231004 1.15878002 -1.95231004 0 P 0 ;0
L 1.14326998 -1.95131004 1.15811004 -1.95131004 0 P 0 ;0
L 1.14233996 -1.95031004 1.15745 -1.95031004 0 P 0 ;0
L 1.14141004 -1.94931004 1.15678002 -1.94931004 0 P 0 ;0
L 1.14048996 -1.94831004 1.15611998 -1.94831004 0 P 0 ;0
L 1.1395 -1.94731004 1.15545 -1.94731004 0 P 0 ;0
L 1.13843002 -1.94631004 1.15478996 -1.94631004 0 P 0 ;0
L 1.13736004 -1.94531004 1.15411998 -1.94531004 0 P 0 ;0
L 1.13628996 -1.94431004 1.15333002 -1.94431004 0 P 0 ;0
L 1.13521004 -1.94331004 1.15253002 -1.94331004 0 P 0 ;0
L 1.13413996 -1.94231004 1.15173996 -1.94231004 0 P 0 ;0
L 1.13306998 -1.94131004 1.15093996 -1.94131004 0 P 0 ;0
L 1.132 -1.94031004 1.15013996 -1.94031004 0 P 0 ;0
L 1.13081004 -1.93931004 1.14935 -1.93931004 0 P 0 ;0
L 1.12958002 -1.93831004 1.14855 -1.93831004 0 P 0 ;0
L 1.12833996 -1.93731004 1.14775 -1.93731004 0 P 0 ;0
L 1.1271 -1.93631004 1.14688996 -1.93631004 0 P 0 ;0
L 1.12586004 -1.93531004 1.14593996 -1.93531004 0 P 0 ;0
L 1.12461998 -1.93431004 1.14498996 -1.93431004 0 P 0 ;0
L 1.12338002 -1.93331004 1.14405 -1.93331004 0 P 0 ;0
L 1.12203002 -1.93231004 1.1431 -1.93231004 0 P 0 ;0
L 1.1206 -1.93131004 1.14216004 -1.93131004 0 P 0 ;0
L 1.11916004 -1.93031004 1.14121004 -1.93031004 0 P 0 ;0
L 1.11771998 -1.92931004 1.14026998 -1.92931004 0 P 0 ;0
L 1.11628996 -1.92831004 1.13931998 -1.92831004 0 P 0 ;0
L 1.11483996 -1.92731004 1.13838002 -1.92731004 0 P 0 ;0
L 1.11338996 -1.92631004 1.13743002 -1.92631004 0 P 0 ;0
L 1.11171998 -1.92531004 1.13648996 -1.92531004 0 P 0 ;0
L 1.11005 -1.92431004 1.13538002 -1.92431004 0 P 0 ;0
L 1.10838002 -1.92331004 1.13426998 -1.92331004 0 P 0 ;0
L 1.1067 -1.92231004 1.13315 -1.92231004 0 P 0 ;0
L 1.10503002 -1.92131004 1.13203002 -1.92131004 0 P 0 ;0
L 1.10336004 -1.92031004 1.13091998 -1.92031004 0 P 0 ;0
L 1.1015 -1.91931004 1.1298 -1.91931004 0 P 0 ;0
L 1.09955 -1.91831004 1.12868002 -1.91831004 0 P 0 ;0
L 1.16275 -2.02983002 1.21088996 -2.02983002 0 P 0 ;0
L 1.16278996 -2.02883002 1.21095 -2.02883002 0 P 0 ;0
L 1.16283996 -2.02783002 1.21101004 -2.02783002 0 P 0 ;0
L 1.16226998 -2.02683002 1.21108002 -2.02683002 0 P 0 ;0
L 1.16153996 -2.02583002 1.21113996 -2.02583002 0 P 0 ;0
L 1.15846004 -2.02483002 1.2112 -2.02483002 0 P 0 ;0
L 1.10036004 -2.00383002 1.21255 -2.00383002 0 P 0 ;0
L 1.10226004 -2.00283002 1.2126 -2.00283002 0 P 0 ;0
L 1.10433996 -2.00183002 1.21266998 -2.00183002 0 P 0 ;0
L 1.1065 -2.00083002 1.21273002 -2.00083002 0 P 0 ;0
L 1.10886998 -1.99983002 1.21278996 -1.99983002 0 P 0 ;0
L 1.11138002 -1.99883002 1.21285 -1.99883002 0 P 0 ;0
L 1.11436998 -1.99783002 1.21288002 -1.99783002 0 P 0 ;0
L 1.11748996 -1.99683002 1.21255 -1.99683002 0 P 0 ;0
L 1.12061998 -1.99583002 1.2089 -1.99583002 0 P 0 ;0
L 1.12433996 -1.99483002 1.2036 -1.99483002 0 P 0 ;0
L 1.12863996 -1.99383002 1.19728002 -1.99383002 0 P 0 ;0
L 1.13295 -1.99283002 1.19096998 -1.99283002 0 P 0 ;0
L 1.13985 -1.99183002 1.18111998 -1.99183002 0 P 0 ;0
L 1.14948002 -1.99083002 1.1651 -1.99083002 0 P 0 ;0
L 1.24218002 -2.08316004 1.29143996 -2.08316004 0 P 0 ;0
L 1.24223002 -2.08216004 1.29151004 -2.08216004 0 P 0 ;0
L 1.24228002 -2.08116004 1.29158996 -2.08116004 0 P 0 ;0
L 1.24233996 -2.08016004 1.29166004 -2.08016004 0 P 0 ;0
L 1.24238996 -2.07916004 1.29173002 -2.07916004 0 P 0 ;0
L 1.24245 -2.07816004 1.29181004 -2.07816004 0 P 0 ;0
L 1.2425 -2.07716004 1.29188002 -2.07716004 0 P 0 ;0
L 1.24256004 -2.07616004 1.29195 -2.07616004 0 P 0 ;0
L 1.24261004 -2.07516004 1.29203002 -2.07516004 0 P 0 ;0
L 1.24266998 -2.07416004 1.2921 -2.07416004 0 P 0 ;0
L 1.24271998 -2.07316004 1.29216998 -2.07316004 0 P 0 ;0
L 1.24278002 -2.07216004 1.29223996 -2.07216004 0 P 0 ;0
L 1.24283002 -2.07116004 1.29231998 -2.07116004 0 P 0 ;0
L 1.24288002 -2.07016004 1.29238996 -2.07016004 0 P 0 ;0
L 1.24293002 -2.06916004 1.29246004 -2.06916004 0 P 0 ;0
L 1.24296998 -2.06816004 1.29253002 -2.06816004 0 P 0 ;0
L 1.24301998 -2.06716004 1.29261004 -2.06716004 0 P 0 ;0
L 1.24306004 -2.06616004 1.2927 -2.06616004 0 P 0 ;0
L 1.24311004 -2.06516004 1.29281004 -2.06516004 0 P 0 ;0
L 1.24315 -2.06416004 1.29291998 -2.06416004 0 P 0 ;0
L 1.2432 -2.06316004 1.29303002 -2.06316004 0 P 0 ;0
L 1.24323996 -2.06216004 1.29315 -2.06216004 0 P 0 ;0
L 1.24328996 -2.06116004 1.29331998 -2.06116004 0 P 0 ;0
L 1.24333002 -2.06016004 1.2935 -2.06016004 0 P 0 ;0
L 1.24338002 -2.05916004 1.29366998 -2.05916004 0 P 0 ;0
L 1.24341998 -2.05816004 1.29385 -2.05816004 0 P 0 ;0
L 1.24346998 -2.05716004 1.29408996 -2.05716004 0 P 0 ;0
L 1.24351004 -2.05616004 1.29433996 -2.05616004 0 P 0 ;0
L 1.24355 -2.05516004 1.29458996 -2.05516004 0 P 0 ;0
L 1.2436 -2.05416004 1.29485 -2.05416004 0 P 0 ;0
L 1.24363996 -2.05316004 1.29516998 -2.05316004 0 P 0 ;0
L 1.24368996 -2.05216004 1.29551998 -2.05216004 0 P 0 ;0
L 1.24373002 -2.05116004 1.29586004 -2.05116004 0 P 0 ;0
L 1.24378002 -2.05016004 1.29621004 -2.05016004 0 P 0 ;0
L 1.24383002 -2.04916004 1.29663996 -2.04916004 0 P 0 ;0
L 1.24386998 -2.04816004 1.29708002 -2.04816004 0 P 0 ;0
L 1.24391004 -2.04716004 1.29753002 -2.04716004 0 P 0 ;0
L 1.24396004 -2.04616004 1.29796998 -2.04616004 0 P 0 ;0
L 1.244 -2.04516004 1.29851004 -2.04516004 0 P 0 ;0
L 1.24405 -2.04416004 1.2991 -2.04416004 0 P 0 ;0
L 1.24408996 -2.04316004 1.29975 -2.04316004 0 P 0 ;0
L 1.24413996 -2.04216004 1.3005 -2.04216004 0 P 0 ;0
L 1.24418002 -2.04116004 1.30131998 -2.04116004 0 P 0 ;0
L 1.24423002 -2.04016004 1.30223002 -2.04016004 0 P 0 ;0
L 1.24426998 -2.03916004 1.30326998 -2.03916004 0 P 0 ;0
L 1.24431998 -2.03816004 1.30446004 -2.03816004 0 P 0 ;0
L 1.24436004 -2.03716004 1.30581998 -2.03716004 0 P 0 ;0
L 1.24441004 -2.03616004 1.30738002 -2.03616004 0 P 0 ;0
L 1.24445 -2.03516004 1.30923002 -2.03516004 0 P 0 ;0
L 1.24448996 -2.03416004 1.31156004 -2.03416004 0 P 0 ;0
L 1.24453996 -2.03316004 1.31478996 -2.03316004 0 P 0 ;0
L 1.24458996 -2.03216004 1.32013002 -2.03216004 0 P 0 ;0
L 1.24461998 -2.03116004 1.33481004 -2.03116004 0 P 0 ;0
L 1.24463996 -2.03016004 1.33478002 -2.03016004 0 P 0 ;0
L 1.24466004 -2.02916004 1.33473996 -2.02916004 0 P 0 ;0
L 1.24468002 -2.02816004 1.33471004 -2.02816004 0 P 0 ;0
L 1.2447 -2.02716004 1.33468002 -2.02716004 0 P 0 ;0
L 1.24471998 -2.02616004 1.33463996 -2.02616004 0 P 0 ;0
L 1.24473996 -2.02516004 1.3346 -2.02516004 0 P 0 ;0
L 1.24476004 -2.02416004 1.33456998 -2.02416004 0 P 0 ;0
L 1.24478002 -2.02316004 1.33453002 -2.02316004 0 P 0 ;0
L 1.2448 -2.02216004 1.3345 -2.02216004 0 P 0 ;0
L 1.24481998 -2.02116004 1.33446998 -2.02116004 0 P 0 ;0
L 1.24483996 -2.02016004 1.33443002 -2.02016004 0 P 0 ;0
L 1.24486004 -2.01916004 1.3344 -2.01916004 0 P 0 ;0
L 1.24488002 -2.01816004 1.33436004 -2.01816004 0 P 0 ;0
L 1.2449 -2.01716004 1.33433002 -2.01716004 0 P 0 ;0
L 1.24491998 -2.01616004 1.33428996 -2.01616004 0 P 0 ;0
L 1.24493996 -2.01516004 1.33426004 -2.01516004 0 P 0 ;0
L 1.24496004 -2.01416004 1.33421998 -2.01416004 0 P 0 ;0
L 1.24498002 -2.01316004 1.33418996 -2.01316004 0 P 0 ;0
L 1.245 -2.01216004 1.33415 -2.01216004 0 P 0 ;0
L 1.24501998 -2.01116004 1.33411998 -2.01116004 0 P 0 ;0
L 1.24503996 -2.01016004 1.33408002 -2.01016004 0 P 0 ;0
L 1.24506004 -2.00916004 1.33403996 -2.00916004 0 P 0 ;0
L 1.24508002 -2.00816004 1.334 -2.00816004 0 P 0 ;0
L 1.2451 -2.00716004 1.33396004 -2.00716004 0 P 0 ;0
L 1.24511998 -2.00616004 1.33393002 -2.00616004 0 P 0 ;0
L 1.24513996 -2.00516004 1.29098996 -2.00516004 0 P 0 ;0
L 1.24513996 -2.00416004 1.29033002 -2.00416004 0 P 0 ;0
L 1.24513996 -2.00316004 1.29005 -2.00316004 0 P 0 ;0
L 1.24513996 -2.00216004 1.29005 -2.00216004 0 P 0 ;0
L 1.24513996 -2.00116004 1.29005 -2.00116004 0 P 0 ;0
L 1.24515 -2.00016004 1.29005 -2.00016004 0 P 0 ;0
L 1.24515 -1.99916004 1.29005 -1.99916004 0 P 0 ;0
L 1.24515 -1.99816004 1.29005 -1.99816004 0 P 0 ;0
L 1.24515 -1.99716004 1.29005 -1.99716004 0 P 0 ;0
L 1.24515 -1.99616004 1.29005 -1.99616004 0 P 0 ;0
L 1.24515 -1.99516004 1.29005 -1.99516004 0 P 0 ;0
L 1.16085 -2.02753002 1.1601 -2.04393002 0 P 0 ;0
L 1.1601 -2.04393002 1.15928996 -2.05771998 0 P 0 ;0
L 1.15928996 -2.05771998 1.15883996 -2.06228002 0 P 0 ;0
L 1.15883996 -2.06228002 1.15818002 -2.06681998 0 P 0 ;0
L 1.15818002 -2.06681998 1.15751004 -2.07006998 0 P 0 ;0
L 1.15751004 -2.07006998 1.15661004 -2.07328996 0 P 0 ;0
L 1.15661004 -2.07328996 1.15616004 -2.07453996 0 P 0 ;0
L 1.15616004 -2.07453996 1.15563002 -2.07576998 0 P 0 ;0
L 1.15563002 -2.07576998 1.15501998 -2.07696004 0 P 0 ;0
L 1.15501998 -2.07696004 1.15433002 -2.0781 0 P 0 ;0
L 1.15433002 -2.0781 1.1534 -2.07941998 0 P 0 ;0
L 1.1534 -2.07941998 1.15236004 -2.08066004 0 P 0 ;0
L 1.15236004 -2.08066004 1.15123002 -2.08181998 0 P 0 ;0
L 1.15123002 -2.08181998 1.15001004 -2.08286998 0 P 0 ;0
L 1.15001004 -2.08286998 1.14871004 -2.08383002 0 P 0 ;0
L 1.14871004 -2.08383002 1.14733002 -2.08468002 0 P 0 ;0
L 1.14733002 -2.08468002 1.14591004 -2.0854 0 P 0 ;0
L 1.14591004 -2.0854 1.14443996 -2.086 0 P 0 ;0
L 1.14443996 -2.086 1.14291004 -2.08648002 0 P 0 ;0
L 1.14291004 -2.08648002 1.14136004 -2.08683002 0 P 0 ;0
L 1.14136004 -2.08683002 1.13976998 -2.08703996 0 P 0 ;0
L 1.13976998 -2.08703996 1.13816004 -2.08713002 0 P 0 ;0
L 1.13816004 -2.08713002 1.13656998 -2.08708002 0 P 0 ;0
L 1.13656998 -2.08708002 1.13498996 -2.0869 0 P 0 ;0
L 1.13498996 -2.0869 1.13341998 -2.08658996 0 P 0 ;0
L 1.13341998 -2.08658996 1.13188996 -2.08615 0 P 0 ;0
L 1.13188996 -2.08615 1.1304 -2.08558996 0 P 0 ;0
L 1.1304 -2.08558996 1.12895 -2.08488996 0 P 0 ;0
L 1.12895 -2.08488996 1.12756998 -2.08408002 0 P 0 ;0
L 1.12756998 -2.08408002 1.12625 -2.08315 0 P 0 ;0
L 1.12625 -2.08315 1.12501004 -2.08211998 0 P 0 ;0
L 1.12501004 -2.08211998 1.12386004 -2.081 0 P 0 ;0
L 1.12386004 -2.081 1.12281004 -2.07978002 0 P 0 ;0
L 1.12281004 -2.07978002 1.12183996 -2.07846998 0 P 0 ;0
L 1.12183996 -2.07846998 1.1211 -2.07726004 0 P 0 ;0
L 1.1211 -2.07726004 1.12046998 -2.07598996 0 P 0 ;0
L 1.12046998 -2.07598996 1.11996004 -2.07466998 0 P 0 ;0
L 1.11996004 -2.07466998 1.11955 -2.07331004 0 P 0 ;0
L 1.11955 -2.07331004 1.11926998 -2.07191004 0 P 0 ;0
L 1.11926998 -2.07191004 1.11868002 -2.06693996 0 P 0 ;0
L 1.11868002 -2.06693996 1.11848002 -2.06191004 0 P 0 ;0
L 1.11848002 -2.06191004 1.11871004 -2.05668002 0 P 0 ;0
L 1.11871004 -2.05668002 1.11936004 -2.05148002 0 P 0 ;0
L 1.11936004 -2.05148002 1.11978996 -2.04936998 0 P 0 ;0
L 1.11978996 -2.04936998 1.12036998 -2.0473 0 P 0 ;0
L 1.12036998 -2.0473 1.12108996 -2.04528002 0 P 0 ;0
L 1.12108996 -2.04528002 1.12196004 -2.04331998 0 P 0 ;0
L 1.12196004 -2.04331998 1.1229 -2.04153996 0 P 0 ;0
L 1.1229 -2.04153996 1.12396998 -2.03985 0 P 0 ;0
L 1.12396998 -2.03985 1.12516998 -2.03823002 0 P 0 ;0
L 1.12516998 -2.03823002 1.12735 -2.03573996 0 P 0 ;0
L 1.12735 -2.03573996 1.12973002 -2.03345 0 P 0 ;0
L 1.12973002 -2.03345 1.13223996 -2.03141998 0 P 0 ;0
L 1.13223996 -2.03141998 1.13491998 -2.02961004 0 P 0 ;0
L 1.13491998 -2.02961004 1.13611004 -2.02893002 0 P 0 ;0
L 1.13611004 -2.02893002 1.13735 -2.02833996 0 P 0 ;0
L 1.13735 -2.02833996 1.13861998 -2.02781998 0 P 0 ;0
L 1.13861998 -2.02781998 1.13993996 -2.0274 0 P 0 ;0
L 1.13993996 -2.0274 1.14191004 -2.02693002 0 P 0 ;0
L 1.14191004 -2.02693002 1.14391004 -2.02663002 0 P 0 ;0
L 1.14391004 -2.02663002 1.14935 -2.02626004 0 P 0 ;0
L 1.14935 -2.02626004 1.15471004 -2.0263 0 P 0 ;0
L 1.15471004 -2.0263 1.15591004 -2.02638996 0 P 0 ;0
L 1.15591004 -2.02638996 1.1571 -2.02656998 0 P 0 ;0
L 1.1571 -2.02656998 1.15828002 -2.02683996 0 P 0 ;0
L 1.15828002 -2.02683996 1.16085 -2.02753002 0 P 0 ;0
L 1.13876998 -2.14783002 1.20233002 -2.14783002 0 P 0 ;0
L 1.14236998 -2.14683002 1.20266004 -2.14683002 0 P 0 ;0
L 1.14481004 -2.14583002 1.20296004 -2.14583002 0 P 0 ;0
L 1.1467 -2.14483002 1.20325 -2.14483002 0 P 0 ;0
L 1.14826004 -2.14383002 1.20353002 -2.14383002 0 P 0 ;0
L 1.1496 -2.14283002 1.20373996 -2.14283002 0 P 0 ;0
L 1.15078996 -2.14183002 1.20395 -2.14183002 0 P 0 ;0
L 1.15186004 -2.14083002 1.20415 -2.14083002 0 P 0 ;0
L 1.15278996 -2.13983002 1.20431998 -2.13983002 0 P 0 ;0
L 1.15361998 -2.13883002 1.20446004 -2.13883002 0 P 0 ;0
L 1.15436004 -2.13783002 1.20458002 -2.13783002 0 P 0 ;0
L 1.155 -2.13683002 1.20466998 -2.13683002 0 P 0 ;0
L 1.15556998 -2.13583002 1.20475 -2.13583002 0 P 0 ;0
L 1.15608996 -2.13483002 1.20481998 -2.13483002 0 P 0 ;0
L 1.15653996 -2.13383002 1.20488996 -2.13383002 0 P 0 ;0
L 1.15691004 -2.13283002 1.20496004 -2.13283002 0 P 0 ;0
L 1.15723996 -2.13183002 1.20503002 -2.13183002 0 P 0 ;0
L 1.15751998 -2.13083002 1.2051 -2.13083002 0 P 0 ;0
L 1.15773002 -2.12983002 1.20516004 -2.12983002 0 P 0 ;0
L 1.15793002 -2.12883002 1.20523002 -2.12883002 0 P 0 ;0
L 1.15806004 -2.12783002 1.2053 -2.12783002 0 P 0 ;0
L 1.15816998 -2.12683002 1.20536998 -2.12683002 0 P 0 ;0
L 1.15821004 -2.12583002 1.20543996 -2.12583002 0 P 0 ;0
L 1.11716004 -2.12483002 1.12726004 -2.12483002 0 P 0 ;0
L 1.15823996 -2.12483002 1.20551004 -2.12483002 0 P 0 ;0
L 1.10911998 -2.12383002 1.1352 -2.12383002 0 P 0 ;0
L 1.15821998 -2.12383002 1.20556998 -2.12383002 0 P 0 ;0
L 1.10468996 -2.12283002 1.14018996 -2.12283002 0 P 0 ;0
L 1.1582 -2.12283002 1.20563996 -2.12283002 0 P 0 ;0
L 1.10131004 -2.12183002 1.14366998 -2.12183002 0 P 0 ;0
L 1.15818002 -2.12183002 1.2057 -2.12183002 0 P 0 ;0
L 1.15808996 -2.12083002 1.20576004 -2.12083002 0 P 0 ;0
L 1.15781004 -2.11983002 1.20583002 -2.11983002 0 P 0 ;0
L 1.15721004 -2.11883002 1.20588002 -2.11883002 0 P 0 ;0
L 1.14146004 -2.08883002 1.20758002 -2.08883002 0 P 0 ;0
L 1.14525 -2.08783002 1.20763002 -2.08783002 0 P 0 ;0
L 1.14751004 -2.08683002 1.20768002 -2.08683002 0 P 0 ;0
L 1.14928002 -2.08583002 1.20773002 -2.08583002 0 P 0 ;0
L 1.15073002 -2.08483002 1.20778996 -2.08483002 0 P 0 ;0
L 1.15196004 -2.08383002 1.20783996 -2.08383002 0 P 0 ;0
L 1.13818996 -2.08913002 1.13826998 -2.08913002 0 P 0 ;0
L 1.13826998 -2.08913002 1.13988002 -2.08903996 0 P 0 ;0
L 1.13988002 -2.08903996 1.13996004 -2.08903996 0 P 0 ;0
L 1.13996004 -2.08903996 1.14001004 -2.08903002 0 P 0 ;0
L 1.14001004 -2.08903002 1.14005 -2.08901998 0 P 0 ;0
L 1.14005 -2.08901998 1.14163002 -2.08881004 0 P 0 ;0
L 1.14163002 -2.08881004 1.14166998 -2.0888 0 P 0 ;0
L 1.14166998 -2.0888 1.14171004 -2.0888 0 P 0 ;0
L 1.14171004 -2.0888 1.14178996 -2.08878002 0 P 0 ;0
L 1.14178996 -2.08878002 1.14335 -2.08843002 0 P 0 ;0
L 1.14335 -2.08843002 1.14351004 -2.08838996 0 P 0 ;0
L 1.14351004 -2.08838996 1.14503002 -2.08791004 0 P 0 ;0
L 1.14503002 -2.08791004 1.14511004 -2.08788996 0 P 0 ;0
L 1.14511004 -2.08788996 1.14515 -2.08786998 0 P 0 ;0
L 1.14515 -2.08786998 1.14518996 -2.08786004 0 P 0 ;0
L 1.14518996 -2.08786004 1.14666004 -2.08725 0 P 0 ;0
L 1.14666004 -2.08725 1.14673996 -2.08721998 0 P 0 ;0
L 1.14673996 -2.08721998 1.14678002 -2.0872 0 P 0 ;0
L 1.14678002 -2.0872 1.14681998 -2.08718996 0 P 0 ;0
L 1.14681998 -2.08718996 1.14823996 -2.08646998 0 P 0 ;0
L 1.14823996 -2.08646998 1.14826998 -2.08645 0 P 0 ;0
L 1.14826998 -2.08645 1.14835 -2.08641004 0 P 0 ;0
L 1.14835 -2.08641004 1.14838002 -2.08638002 0 P 0 ;0
L 1.14838002 -2.08638002 1.14976004 -2.08553002 0 P 0 ;0
L 1.14976004 -2.08553002 1.14978996 -2.08551004 0 P 0 ;0
L 1.14978996 -2.08551004 1.14983002 -2.08548996 0 P 0 ;0
L 1.14983002 -2.08548996 1.14988996 -2.08543996 0 P 0 ;0
L 1.14988996 -2.08543996 1.1512 -2.08448996 0 P 0 ;0
L 1.1512 -2.08448996 1.15126004 -2.08443996 0 P 0 ;0
L 1.15126004 -2.08443996 1.15128996 -2.08441004 0 P 0 ;0
L 1.15128996 -2.08441004 1.15131998 -2.08438996 0 P 0 ;0
L 1.15131998 -2.08438996 1.15253996 -2.08333002 0 P 0 ;0
L 1.15253996 -2.08333002 1.15256998 -2.0833 0 P 0 ;0
L 1.15256998 -2.0833 1.1526 -2.08328002 0 P 0 ;0
L 1.1526 -2.08328002 1.15263002 -2.08323996 0 P 0 ;0
L 1.15263002 -2.08323996 1.15266004 -2.08321998 0 P 0 ;0
L 1.15266004 -2.08321998 1.15378996 -2.08206004 0 P 0 ;0
L 1.15378996 -2.08206004 1.15376004 -2.08203996 0 P 0 ;0
L 1.15376004 -2.08203996 1.15381998 -2.08203996 0 P 0 ;0
L 1.15381998 -2.08203996 1.15383996 -2.082 0 P 0 ;0
L 1.15383996 -2.082 1.15386998 -2.08196998 0 P 0 ;0
L 1.15386998 -2.08196998 1.1539 -2.08195 0 P 0 ;0
L 1.1539 -2.08195 1.15493002 -2.08071004 0 P 0 ;0
L 1.15493002 -2.08071004 1.15493002 -2.0807 0 P 0 ;0
L 1.15493002 -2.0807 1.15496004 -2.08066998 0 P 0 ;0
L 1.15496004 -2.08066998 1.15498002 -2.08063996 0 P 0 ;0
L 1.15498002 -2.08063996 1.15501004 -2.08061004 0 P 0 ;0
L 1.15501004 -2.08061004 1.15503002 -2.08058002 0 P 0 ;0
L 1.15503002 -2.08058002 1.15596004 -2.07926004 0 P 0 ;0
L 1.15596004 -2.07926004 1.15603996 -2.07913996 0 P 0 ;0
L 1.15603996 -2.07913996 1.15673002 -2.07798996 0 P 0 ;0
L 1.15673002 -2.07798996 1.15676998 -2.07793002 0 P 0 ;0
L 1.15676998 -2.07793002 1.15678996 -2.07786998 0 P 0 ;0
L 1.15678996 -2.07786998 1.15741004 -2.07668996 0 P 0 ;0
L 1.15741004 -2.07668996 1.15743996 -2.07663002 0 P 0 ;0
L 1.15743996 -2.07663002 1.15746004 -2.07656998 0 P 0 ;0
L 1.15746004 -2.07656998 1.15746998 -2.07656998 0 P 0 ;0
L 1.15746998 -2.07656998 1.158 -2.07533996 0 P 0 ;0
L 1.158 -2.07533996 1.15801004 -2.07531004 0 P 0 ;0
L 1.15801004 -2.07531004 1.15803002 -2.07528002 0 P 0 ;0
L 1.15803002 -2.07528002 1.15805 -2.07521998 0 P 0 ;0
L 1.15805 -2.07521998 1.15848996 -2.07396004 0 P 0 ;0
L 1.15848996 -2.07396004 1.15841004 -2.07393002 0 P 0 ;0
L 1.15841004 -2.07393002 1.15851004 -2.07393002 0 P 0 ;0
L 1.15851004 -2.07393002 1.15851998 -2.0739 0 P 0 ;0
L 1.15851998 -2.0739 1.15853002 -2.07386004 0 P 0 ;0
L 1.15853002 -2.07386004 1.15853996 -2.07383002 0 P 0 ;0
L 1.15853996 -2.07383002 1.15943996 -2.07061004 0 P 0 ;0
L 1.15943996 -2.07061004 1.15945 -2.07058002 0 P 0 ;0
L 1.15945 -2.07058002 1.15946004 -2.07053996 0 P 0 ;0
L 1.15946004 -2.07053996 1.15946998 -2.07051004 0 P 0 ;0
L 1.15946998 -2.07051004 1.15946998 -2.07046998 0 P 0 ;0
L 1.15946998 -2.07046998 1.16013996 -2.06723002 0 P 0 ;0
L 1.16013996 -2.06723002 1.16013996 -2.0672 0 P 0 ;0
L 1.16013996 -2.0672 1.16016004 -2.06713996 0 P 0 ;0
L 1.16016004 -2.06713996 1.16016004 -2.06711004 0 P 0 ;0
L 1.16016004 -2.06711004 1.16081998 -2.06256004 0 P 0 ;0
L 1.16081998 -2.06256004 1.16081998 -2.06253996 0 P 0 ;0
L 1.16081998 -2.06253996 1.16083002 -2.0625 0 P 0 ;0
L 1.16083002 -2.0625 1.16083002 -2.06246998 0 P 0 ;0
L 1.16083002 -2.06246998 1.16126998 -2.05791004 0 P 0 ;0
L 1.16126998 -2.05791004 1.16128002 -2.0579 0 P 0 ;0
L 1.16128002 -2.0579 1.16128002 -2.05783996 0 P 0 ;0
L 1.16128002 -2.05783996 1.1621 -2.04405 0 P 0 ;0
L 1.1621 -2.04405 1.1621 -2.04401998 0 P 0 ;0
L 1.1621 -2.04401998 1.16285 -2.02761998 0 P 0 ;0
L 1.16285 -2.02761998 1.16136998 -2.0256 0 P 0 ;0
L 1.16136998 -2.0256 1.15878996 -2.02491004 0 P 0 ;0
L 1.15878996 -2.02491004 1.15878002 -2.0249 0 P 0 ;0
L 1.15878002 -2.0249 1.15871998 -2.02488996 0 P 0 ;0
L 1.15871998 -2.02488996 1.15755 -2.02461998 0 P 0 ;0
L 1.15755 -2.02461998 1.15746998 -2.0246 0 P 0 ;0
L 1.15746998 -2.0246 1.1574 -2.0246 0 P 0 ;0
L 1.1574 -2.0246 1.15621004 -2.02441004 0 P 0 ;0
L 1.15621004 -2.02441004 1.15616998 -2.02441004 0 P 0 ;0
L 1.15616998 -2.02441004 1.1561 -2.0244 0 P 0 ;0
L 1.1561 -2.0244 1.15606004 -2.02438996 0 P 0 ;0
L 1.15606004 -2.02438996 1.15486004 -2.0243 0 P 0 ;0
L 1.15486004 -2.0243 1.15471998 -2.0243 0 P 0 ;0
L 1.15471998 -2.0243 1.14936004 -2.02426004 0 P 0 ;0
L 1.14936004 -2.02426004 1.14928996 -2.02426004 0 P 0 ;0
L 1.14928996 -2.02426004 1.14925 -2.02426998 0 P 0 ;0
L 1.14925 -2.02426998 1.14921004 -2.02426998 0 P 0 ;0
L 1.14921004 -2.02426998 1.14376998 -2.02463996 0 P 0 ;0
L 1.14376998 -2.02463996 1.1437 -2.02463996 0 P 0 ;0
L 1.1437 -2.02463996 1.14365 -2.02465 0 P 0 ;0
L 1.14365 -2.02465 1.14361004 -2.02465 0 P 0 ;0
L 1.14361004 -2.02465 1.14161998 -2.02495 0 P 0 ;0
L 1.14161998 -2.02495 1.14161004 -2.02495 0 P 0 ;0
L 1.14161004 -2.02495 1.14153002 -2.02496998 0 P 0 ;0
L 1.14153002 -2.02496998 1.14148996 -2.02496998 0 P 0 ;0
L 1.14148996 -2.02496998 1.14143996 -2.02498996 0 P 0 ;0
L 1.14143996 -2.02498996 1.13946998 -2.02545 0 P 0 ;0
L 1.13946998 -2.02545 1.13943996 -2.02546998 0 P 0 ;0
L 1.13943996 -2.02546998 1.1394 -2.02546998 0 P 0 ;0
L 1.1394 -2.02546998 1.13933002 -2.0255 0 P 0 ;0
L 1.13933002 -2.0255 1.13801004 -2.02591998 0 P 0 ;0
L 1.13801004 -2.02591998 1.13798002 -2.02593002 0 P 0 ;0
L 1.13798002 -2.02593002 1.13793996 -2.02593996 0 P 0 ;0
L 1.13793996 -2.02593996 1.13788002 -2.02596998 0 P 0 ;0
L 1.13788002 -2.02596998 1.1366 -2.02648002 0 P 0 ;0
L 1.1366 -2.02648002 1.13653996 -2.0265 0 P 0 ;0
L 1.13653996 -2.0265 1.13648002 -2.02653002 0 P 0 ;0
L 1.13648002 -2.02653002 1.13523996 -2.02713002 0 P 0 ;0
L 1.13523996 -2.02713002 1.13518002 -2.02716004 0 P 0 ;0
L 1.13518002 -2.02716004 1.13515 -2.02716998 0 P 0 ;0
L 1.13515 -2.02716998 1.13511998 -2.02718996 0 P 0 ;0
L 1.13511998 -2.02718996 1.13393002 -2.02786998 0 P 0 ;0
L 1.13393002 -2.02786998 1.13388996 -2.02788996 0 P 0 ;0
L 1.13388996 -2.02788996 1.1338 -2.02795 0 P 0 ;0
L 1.1338 -2.02795 1.13111998 -2.02976004 0 P 0 ;0
L 1.13111998 -2.02976004 1.13105 -2.02981004 0 P 0 ;0
L 1.13105 -2.02981004 1.13101004 -2.02983996 0 P 0 ;0
L 1.13101004 -2.02983996 1.13098002 -2.02986004 0 P 0 ;0
L 1.13098002 -2.02986004 1.12846998 -2.03188996 0 P 0 ;0
L 1.12846998 -2.03188996 1.12838002 -2.03198002 0 P 0 ;0
L 1.12838002 -2.03198002 1.12833996 -2.03201004 0 P 0 ;0
L 1.12833996 -2.03201004 1.12596004 -2.0343 0 P 0 ;0
L 1.12596004 -2.0343 1.12593996 -2.03433002 0 P 0 ;0
L 1.12593996 -2.03433002 1.1259 -2.03436004 0 P 0 ;0
L 1.1259 -2.03436004 1.12588002 -2.03438996 0 P 0 ;0
L 1.12588002 -2.03438996 1.12585 -2.03443002 0 P 0 ;0
L 1.12585 -2.03443002 1.12366998 -2.03691004 0 P 0 ;0
L 1.12366998 -2.03691004 1.12363996 -2.03695 0 P 0 ;0
L 1.12363996 -2.03695 1.12361998 -2.03698002 0 P 0 ;0
L 1.12361998 -2.03698002 1.12358996 -2.03701004 0 P 0 ;0
L 1.12358996 -2.03701004 1.12356998 -2.03703996 0 P 0 ;0
L 1.12356998 -2.03703996 1.12236998 -2.03865 0 P 0 ;0
L 1.12236998 -2.03865 1.12233996 -2.03868996 0 P 0 ;0
L 1.12233996 -2.03868996 1.12233002 -2.03871004 0 P 0 ;0
L 1.12233002 -2.03871004 1.12228996 -2.03878002 0 P 0 ;0
L 1.12228996 -2.03878002 1.12121004 -2.04046998 0 P 0 ;0
L 1.12121004 -2.04046998 1.12118996 -2.0405 0 P 0 ;0
L 1.12118996 -2.0405 1.12116998 -2.04053996 0 P 0 ;0
L 1.12116998 -2.04053996 1.12115 -2.04056998 0 P 0 ;0
L 1.12115 -2.04056998 1.12113996 -2.04061004 0 P 0 ;0
L 1.12113996 -2.04061004 1.12018996 -2.04238002 0 P 0 ;0
L 1.12018996 -2.04238002 1.12016004 -2.04245 0 P 0 ;0
L 1.12016004 -2.04245 1.12013996 -2.04248002 0 P 0 ;0
L 1.12013996 -2.04248002 1.12013002 -2.04251004 0 P 0 ;0
L 1.12013002 -2.04251004 1.11926004 -2.04446998 0 P 0 ;0
L 1.11926004 -2.04446998 1.11925 -2.0445 0 P 0 ;0
L 1.11925 -2.0445 1.11923002 -2.04453996 0 P 0 ;0
L 1.11923002 -2.04453996 1.11921998 -2.04458002 0 P 0 ;0
L 1.11921998 -2.04458002 1.11921004 -2.04461004 0 P 0 ;0
L 1.11921004 -2.04461004 1.11848002 -2.04663002 0 P 0 ;0
L 1.11848002 -2.04663002 1.11846998 -2.04666004 0 P 0 ;0
L 1.11846998 -2.04666004 1.11846004 -2.0467 0 P 0 ;0
L 1.11846004 -2.0467 1.11843996 -2.04676998 0 P 0 ;0
L 1.11843996 -2.04676998 1.11786004 -2.04883996 0 P 0 ;0
L 1.11786004 -2.04883996 1.11785 -2.04886998 0 P 0 ;0
L 1.11785 -2.04886998 1.11783996 -2.04891004 0 P 0 ;0
L 1.11783996 -2.04891004 1.11783996 -2.04893996 0 P 0 ;0
L 1.11783996 -2.04893996 1.11783002 -2.04896998 0 P 0 ;0
L 1.11783002 -2.04896998 1.11783002 -2.04898002 0 P 0 ;0
L 1.11783002 -2.04898002 1.1174 -2.05108002 0 P 0 ;0
L 1.1174 -2.05108002 1.1174 -2.05111998 0 P 0 ;0
L 1.1174 -2.05111998 1.11738996 -2.05116004 0 P 0 ;0
L 1.11738996 -2.05116004 1.11738002 -2.05118996 0 P 0 ;0
L 1.11738002 -2.05118996 1.11738002 -2.05123002 0 P 0 ;0
L 1.11738002 -2.05123002 1.11673002 -2.05643002 0 P 0 ;0
L 1.11673002 -2.05643002 1.11671998 -2.05646998 0 P 0 ;0
L 1.11671998 -2.05646998 1.11671998 -2.05655 0 P 0 ;0
L 1.11671998 -2.05655 1.11671004 -2.05658996 0 P 0 ;0
L 1.11671004 -2.05658996 1.11648996 -2.06181998 0 P 0 ;0
L 1.11648996 -2.06181998 1.11648002 -2.06186998 0 P 0 ;0
L 1.11648002 -2.06186998 1.11648002 -2.06195 0 P 0 ;0
L 1.11648002 -2.06195 1.11648996 -2.06198996 0 P 0 ;0
L 1.11648996 -2.06198996 1.11668002 -2.06696998 0 P 0 ;0
L 1.11668002 -2.06696998 1.11768002 -2.06696998 0 P 0 ;0
L 1.11768002 -2.06696998 1.11668002 -2.06701004 0 P 0 ;0
L 1.11668002 -2.06701004 1.11668002 -2.06713002 0 P 0 ;0
L 1.11668002 -2.06713002 1.11668996 -2.06716998 0 P 0 ;0
L 1.11668996 -2.06716998 1.11728002 -2.07215 0 P 0 ;0
L 1.11728002 -2.07215 1.11728996 -2.07218996 0 P 0 ;0
L 1.11728996 -2.07218996 1.11728996 -2.07223002 0 P 0 ;0
L 1.11728996 -2.07223002 1.11731004 -2.07231004 0 P 0 ;0
L 1.11731004 -2.07231004 1.11758996 -2.07371004 0 P 0 ;0
L 1.11758996 -2.07371004 1.1176 -2.07375 0 P 0 ;0
L 1.1176 -2.07375 1.11761004 -2.0738 0 P 0 ;0
L 1.11761004 -2.0738 1.11761998 -2.07383996 0 P 0 ;0
L 1.11761998 -2.07383996 1.11763996 -2.07388002 0 P 0 ;0
L 1.11763996 -2.07388002 1.11803996 -2.07523996 0 P 0 ;0
L 1.11803996 -2.07523996 1.11806004 -2.07531998 0 P 0 ;0
L 1.11806004 -2.07531998 1.11808002 -2.07536004 0 P 0 ;0
L 1.11808002 -2.07536004 1.11808996 -2.07541004 0 P 0 ;0
L 1.11808996 -2.07541004 1.11861004 -2.07673002 0 P 0 ;0
L 1.11861004 -2.07673002 1.11863996 -2.07681004 0 P 0 ;0
L 1.11863996 -2.07681004 1.11866004 -2.07683996 0 P 0 ;0
L 1.11866004 -2.07683996 1.11868002 -2.07688002 0 P 0 ;0
L 1.11868002 -2.07688002 1.11931004 -2.07815 0 P 0 ;0
L 1.11931004 -2.07815 1.11935 -2.07823002 0 P 0 ;0
L 1.11935 -2.07823002 1.1194 -2.0783 0 P 0 ;0
L 1.1194 -2.0783 1.12013996 -2.07951998 0 P 0 ;0
L 1.12013996 -2.07951998 1.12021004 -2.07961998 0 P 0 ;0
L 1.12021004 -2.07961998 1.12023002 -2.07965 0 P 0 ;0
L 1.12023002 -2.07965 1.12023002 -2.07966004 0 P 0 ;0
L 1.12023002 -2.07966004 1.1212 -2.08096998 0 P 0 ;0
L 1.1212 -2.08096998 1.12123996 -2.08103002 0 P 0 ;0
L 1.12123996 -2.08103002 1.12126998 -2.08106004 0 P 0 ;0
L 1.12126998 -2.08106004 1.12128996 -2.08108996 0 P 0 ;0
L 1.12128996 -2.08108996 1.12235 -2.08231004 0 P 0 ;0
L 1.12235 -2.08231004 1.12238002 -2.08233996 0 P 0 ;0
L 1.12238002 -2.08233996 1.1224 -2.08236998 0 P 0 ;0
L 1.1224 -2.08236998 1.12246004 -2.08243002 0 P 0 ;0
L 1.12246004 -2.08243002 1.12361004 -2.08355 0 P 0 ;0
L 1.12361004 -2.08355 1.12366998 -2.08361004 0 P 0 ;0
L 1.12366998 -2.08361004 1.1237 -2.08363002 0 P 0 ;0
L 1.1237 -2.08363002 1.12373002 -2.08366004 0 P 0 ;0
L 1.12373002 -2.08366004 1.12496998 -2.08468996 0 P 0 ;0
L 1.12496998 -2.08468996 1.125 -2.08471004 0 P 0 ;0
L 1.125 -2.08471004 1.12503002 -2.08473996 0 P 0 ;0
L 1.12503002 -2.08473996 1.12506998 -2.08476004 0 P 0 ;0
L 1.12506998 -2.08476004 1.1251 -2.08478996 0 P 0 ;0
L 1.1251 -2.08478996 1.12641998 -2.08571004 0 P 0 ;0
L 1.12641998 -2.08571004 1.12645 -2.08573002 0 P 0 ;0
L 1.12645 -2.08573002 1.12648002 -2.08576004 0 P 0 ;0
L 1.12648002 -2.08576004 1.12651004 -2.08578002 0 P 0 ;0
L 1.12651004 -2.08578002 1.12655 -2.0858 0 P 0 ;0
L 1.12655 -2.0858 1.12793996 -2.08661004 0 P 0 ;0
L 1.12793996 -2.08661004 1.12801004 -2.08665 0 P 0 ;0
L 1.12801004 -2.08665 1.12805 -2.08666998 0 P 0 ;0
L 1.12805 -2.08666998 1.12808002 -2.08668996 0 P 0 ;0
L 1.12808002 -2.08668996 1.12808996 -2.08668996 0 P 0 ;0
L 1.12808996 -2.08668996 1.12953996 -2.08738996 0 P 0 ;0
L 1.12953996 -2.08738996 1.12961998 -2.08743002 0 P 0 ;0
L 1.12961998 -2.08743002 1.12965 -2.08743996 0 P 0 ;0
L 1.12965 -2.08743996 1.1297 -2.08746004 0 P 0 ;0
L 1.1297 -2.08746004 1.13118002 -2.08801998 0 P 0 ;0
L 1.13118002 -2.08801998 1.13133996 -2.08808002 0 P 0 ;0
L 1.13133996 -2.08808002 1.13286998 -2.08851004 0 P 0 ;0
L 1.13286998 -2.08851004 1.13295 -2.08853996 0 P 0 ;0
L 1.13295 -2.08853996 1.13303996 -2.08855 0 P 0 ;0
L 1.13303996 -2.08855 1.1346 -2.08886004 0 P 0 ;0
L 1.1346 -2.08886004 1.13471998 -2.08888996 0 P 0 ;0
L 1.13471998 -2.08888996 1.13476004 -2.08888996 0 P 0 ;0
L 1.13476004 -2.08888996 1.13633996 -2.08906998 0 P 0 ;0
L 1.13633996 -2.08906998 1.13638996 -2.08908002 0 P 0 ;0
L 1.13638996 -2.08908002 1.13651004 -2.08908002 0 P 0 ;0
L 1.13651004 -2.08908002 1.1381 -2.08913002 0 P 0 ;0
L 1.1381 -2.08913002 1.13818996 -2.08913002 0 P 0 ;0
L 1.31623996 -1.98923996 1.3135 -1.98988002 0 P 0 ;0
L 1.3135 -1.98988002 1.31078996 -1.99071004 0 P 0 ;0
L 1.31078996 -1.99071004 1.30813002 -1.99175 0 P 0 ;0
L 1.30813002 -1.99175 1.30553996 -1.99296998 0 P 0 ;0
L 1.30553996 -1.99296998 1.30308996 -1.99431998 0 P 0 ;0
L 1.30308996 -1.99431998 1.30073996 -1.99585 0 P 0 ;0
L 1.30073996 -1.99585 1.29863996 -1.99746004 0 P 0 ;0
L 1.29863996 -1.99746004 1.29666004 -1.99923996 0 P 0 ;0
L 1.29666004 -1.99923996 1.29205 -2.00375 0 P 0 ;0
L 1.29205 -2.00375 1.29205 -1.99243996 0 P 0 ;0
L 1.29205 -1.99243996 1.24316004 -1.99243996 0 P 0 ;0
L 1.24316004 -1.99243996 1.24313996 -2.00521004 0 P 0 ;0
L 1.24313996 -2.00521004 1.24261004 -2.03151004 0 P 0 ;0
L 1.24261004 -2.03151004 1.24086998 -2.07046004 0 P 0 ;0
L 1.24086998 -2.07046004 1.23873996 -2.10921004 0 P 0 ;0
L 1.23873996 -2.10921004 1.23811998 -2.11641998 0 P 0 ;0
L 1.23811998 -2.11641998 1.23711998 -2.12361998 0 P 0 ;0
L 1.23711998 -2.12361998 1.23655 -2.12716004 0 P 0 ;0
L 1.23655 -2.12716004 1.29205 -2.12716004 0 P 0 ;0
L 1.29205 -2.12716004 1.29206998 -2.11766004 0 P 0 ;0
L 1.29206998 -2.11766004 1.29238996 -2.10283996 0 P 0 ;0
L 1.29238996 -2.10283996 1.29336004 -2.08431004 0 P 0 ;0
L 1.29336004 -2.08431004 1.29463996 -2.06673002 0 P 0 ;0
L 1.29463996 -2.06673002 1.29511004 -2.06253002 0 P 0 ;0
L 1.29511004 -2.06253002 1.29583996 -2.05836004 0 P 0 ;0
L 1.29583996 -2.05836004 1.29683002 -2.05446998 0 P 0 ;0
L 1.29683002 -2.05446998 1.29813996 -2.05068996 0 P 0 ;0
L 1.29813996 -2.05068996 1.29978002 -2.04701998 0 P 0 ;0
L 1.29978002 -2.04701998 1.30056998 -2.04556998 0 P 0 ;0
L 1.30056998 -2.04556998 1.30146998 -2.04418996 0 P 0 ;0
L 1.30146998 -2.04418996 1.30246998 -2.04288002 0 P 0 ;0
L 1.30246998 -2.04288002 1.30356998 -2.04165 0 P 0 ;0
L 1.30356998 -2.04165 1.30475 -2.0405 0 P 0 ;0
L 1.30475 -2.0405 1.30603996 -2.03945 0 P 0 ;0
L 1.30603996 -2.03945 1.30773996 -2.03826004 0 P 0 ;0
L 1.30773996 -2.03826004 1.30953002 -2.03723002 0 P 0 ;0
L 1.30953002 -2.03723002 1.31141004 -2.03635 0 P 0 ;0
L 1.31141004 -2.03635 1.31335 -2.03563002 0 P 0 ;0
L 1.31335 -2.03563002 1.31535 -2.03508002 0 P 0 ;0
L 1.31535 -2.03508002 1.31973996 -2.03423002 0 P 0 ;0
L 1.31973996 -2.03423002 1.32416004 -2.03366998 0 P 0 ;0
L 1.32416004 -2.03366998 1.32863002 -2.0334 0 P 0 ;0
L 1.32863002 -2.0334 1.33688002 -2.03318002 0 P 0 ;0
L 1.33688002 -2.03318002 1.33613002 -2.01151004 0 P 0 ;0
L 1.33613002 -2.01151004 1.33581004 -2.00315 0 P 0 ;0
L 1.33581004 -2.00315 1.33543996 -1.99596004 0 P 0 ;0
L 1.33543996 -1.99596004 1.33508002 -1.98971004 0 P 0 ;0
L 1.33508002 -1.98971004 1.33503996 -1.98945 0 P 0 ;0
L 1.33503996 -1.98945 1.335 -1.98931998 0 P 0 ;0
L 1.335 -1.98931998 1.33496004 -1.9892 0 P 0 ;0
L 1.33496004 -1.9892 1.3349 -1.98908002 0 P 0 ;0
L 1.3349 -1.98908002 1.33483996 -1.98896998 0 P 0 ;0
L 1.33483996 -1.98896998 1.33476998 -1.98886004 0 P 0 ;0
L 1.33476998 -1.98886004 1.33468996 -1.98876004 0 P 0 ;0
L 1.33468996 -1.98876004 1.3346 -1.98866998 0 P 0 ;0
L 1.3346 -1.98866998 1.33451004 -1.98858996 0 P 0 ;0
L 1.33451004 -1.98858996 1.3344 -1.98851998 0 P 0 ;0
L 1.3344 -1.98851998 1.3343 -1.98845 0 P 0 ;0
L 1.3343 -1.98845 1.33418002 -1.98838996 0 P 0 ;0
L 1.33418002 -1.98838996 1.33406998 -1.98833996 0 P 0 ;0
L 1.33406998 -1.98833996 1.33395 -1.9883 0 P 0 ;0
L 1.33395 -1.9883 1.33383002 -1.98828002 0 P 0 ;0
L 1.33383002 -1.98828002 1.3337 -1.98826004 0 P 0 ;0
L 1.3337 -1.98826004 1.33356998 -1.98825 0 P 0 ;0
L 1.33356998 -1.98825 1.32756998 -1.98823002 0 P 0 ;0
L 1.32756998 -1.98823002 1.32135 -1.98853996 0 P 0 ;0
L 1.32135 -1.98853996 1.31878996 -1.98881998 0 P 0 ;0
L 1.31878996 -1.98881998 1.31623996 -1.98923996 0 P 0 ;0
L 1.2389 -2.12516004 1.29006004 -2.12516004 0 P 0 ;0
L 1.23906998 -2.12416004 1.29006004 -2.12416004 0 P 0 ;0
L 1.23921004 -2.12316004 1.29006004 -2.12316004 0 P 0 ;0
L 1.23933996 -2.12216004 1.29006004 -2.12216004 0 P 0 ;0
L 1.23948996 -2.12116004 1.29006004 -2.12116004 0 P 0 ;0
L 1.23961998 -2.12016004 1.29006998 -2.12016004 0 P 0 ;0
L 1.23976004 -2.11916004 1.29006998 -2.11916004 0 P 0 ;0
L 1.2399 -2.11816004 1.29006998 -2.11816004 0 P 0 ;0
L 1.24003996 -2.11716004 1.29008002 -2.11716004 0 P 0 ;0
L 1.24015 -2.11616004 1.2901 -2.11616004 0 P 0 ;0
L 1.24023996 -2.11516004 1.29011998 -2.11516004 0 P 0 ;0
L 1.24033002 -2.11416004 1.29013996 -2.11416004 0 P 0 ;0
L 1.24041004 -2.11316004 1.29016004 -2.11316004 0 P 0 ;0
L 1.24048996 -2.11216004 1.29018996 -2.11216004 0 P 0 ;0
L 1.24058002 -2.11116004 1.29021004 -2.11116004 0 P 0 ;0
L 1.24066998 -2.11016004 1.29023002 -2.11016004 0 P 0 ;0
L 1.24075 -2.10916004 1.29025 -2.10916004 0 P 0 ;0
L 1.2408 -2.10816004 1.29026998 -2.10816004 0 P 0 ;0
L 1.24086004 -2.10716004 1.29028996 -2.10716004 0 P 0 ;0
L 1.24091004 -2.10616004 1.29031998 -2.10616004 0 P 0 ;0
L 1.24096998 -2.10516004 1.29033996 -2.10516004 0 P 0 ;0
L 1.24101998 -2.10416004 1.29036004 -2.10416004 0 P 0 ;0
L 1.24108002 -2.10316004 1.29038002 -2.10316004 0 P 0 ;0
L 1.24113002 -2.10216004 1.29041998 -2.10216004 0 P 0 ;0
L 1.24118002 -2.10116004 1.29046998 -2.10116004 0 P 0 ;0
L 1.24123996 -2.10016004 1.29053002 -2.10016004 0 P 0 ;0
L 1.24128996 -2.09916004 1.29058002 -2.09916004 0 P 0 ;0
L 1.24135 -2.09816004 1.29063002 -2.09816004 0 P 0 ;0
L 1.2414 -2.09716004 1.29068002 -2.09716004 0 P 0 ;0
L 1.24146004 -2.09616004 1.29073996 -2.09616004 0 P 0 ;0
L 1.24151004 -2.09516004 1.29078996 -2.09516004 0 P 0 ;0
L 1.24156998 -2.09416004 1.29083996 -2.09416004 0 P 0 ;0
L 1.24161998 -2.09316004 1.2909 -2.09316004 0 P 0 ;0
L 1.24168002 -2.09216004 1.29095 -2.09216004 0 P 0 ;0
L 1.24173002 -2.09116004 1.291 -2.09116004 0 P 0 ;0
L 1.24178996 -2.09016004 1.29105 -2.09016004 0 P 0 ;0
L 1.24183996 -2.08916004 1.2911 -2.08916004 0 P 0 ;0
L 1.2419 -2.08816004 1.29116004 -2.08816004 0 P 0 ;0
L 1.24196004 -2.08716004 1.29121004 -2.08716004 0 P 0 ;0
L 1.24201004 -2.08616004 1.29126998 -2.08616004 0 P 0 ;0
L 1.24206998 -2.08516004 1.29131998 -2.08516004 0 P 0 ;0
L 1.24211998 -2.08416004 1.29136998 -2.08416004 0 P 0 ;0
L 1.2389 -2.12516004 1.2391 -2.12393002 0 P 0 ;0
L 1.2391 -2.12393002 1.2391 -2.1239 0 P 0 ;0
L 1.2391 -2.1239 1.24011004 -2.11665 0 P 0 ;0
L 1.24011004 -2.11665 1.24073002 -2.10935 0 P 0 ;0
L 1.24073002 -2.10935 1.24073996 -2.10931998 0 P 0 ;0
L 1.24073996 -2.10931998 1.24286004 -2.07056004 0 P 0 ;0
L 1.24286004 -2.07056004 1.24461004 -2.03158002 0 P 0 ;0
L 1.24461004 -2.03158002 1.24513996 -2.00523002 0 P 0 ;0
L 1.24513996 -2.00523002 1.24515 -1.99443996 0 P 0 ;0
L 1.24515 -1.99443996 1.29005 -1.99443996 0 P 0 ;0
L 1.29005 -1.99443996 1.29005 -2.00375 0 P 0 ;0
L 1.29005 -2.00375 1.29128002 -2.0056 0 P 0 ;0
L 1.29128002 -2.0056 1.29345 -2.00518002 0 P 0 ;0
L 1.29345 -2.00518002 1.29803002 -2.0007 0 P 0 ;0
L 1.29803002 -2.0007 1.29991998 -1.999 0 P 0 ;0
L 1.29991998 -1.999 1.30188996 -1.99748996 0 P 0 ;0
L 1.30188996 -1.99748996 1.30411998 -1.99603996 0 P 0 ;0
L 1.30411998 -1.99603996 1.30645 -1.99475 0 P 0 ;0
L 1.30645 -1.99475 1.30891998 -1.99358996 0 P 0 ;0
L 1.30891998 -1.99358996 1.31145 -1.9926 0 P 0 ;0
L 1.31145 -1.9926 1.31401998 -1.99181004 0 P 0 ;0
L 1.31401998 -1.99181004 1.31663996 -1.9912 0 P 0 ;0
L 1.31663996 -1.9912 1.31906004 -1.9908 0 P 0 ;0
L 1.31906004 -1.9908 1.32151004 -1.99053002 0 P 0 ;0
L 1.32151004 -1.99053002 1.32761998 -1.99023002 0 P 0 ;0
L 1.32761998 -1.99023002 1.3331 -1.99025 0 P 0 ;0
L 1.3331 -1.99025 1.33345 -1.99608002 0 P 0 ;0
L 1.33345 -1.99608002 1.33381004 -2.00323002 0 P 0 ;0
L 1.33381004 -2.00323002 1.33413002 -2.01158996 0 P 0 ;0
L 1.33413002 -2.01158996 1.33413002 -2.0116 0 P 0 ;0
L 1.33413002 -2.0116 1.33481998 -2.03123002 0 P 0 ;0
L 1.33481998 -2.03123002 1.32853996 -2.0314 0 P 0 ;0
L 1.32853996 -2.0314 1.32398002 -2.03166998 0 P 0 ;0
L 1.32398002 -2.03166998 1.31941998 -2.03225 0 P 0 ;0
L 1.31941998 -2.03225 1.31488996 -2.03313002 0 P 0 ;0
L 1.31488996 -2.03313002 1.31273996 -2.03373002 0 P 0 ;0
L 1.31273996 -2.03373002 1.31063996 -2.0345 0 P 0 ;0
L 1.31063996 -2.0345 1.3086 -2.03545 0 P 0 ;0
L 1.3086 -2.03545 1.30666004 -2.03656998 0 P 0 ;0
L 1.30666004 -2.03656998 1.30658996 -2.03661998 0 P 0 ;0
L 1.30658996 -2.03661998 1.30483002 -2.03786004 0 P 0 ;0
L 1.30483002 -2.03786004 1.30341998 -2.03901004 0 P 0 ;0
L 1.30341998 -2.03901004 1.30336998 -2.03906004 0 P 0 ;0
L 1.30336998 -2.03906004 1.30211998 -2.04026004 0 P 0 ;0
L 1.30211998 -2.04026004 1.30093002 -2.0416 0 P 0 ;0
L 1.30093002 -2.0416 1.29983002 -2.04303996 0 P 0 ;0
L 1.29983002 -2.04303996 1.29978996 -2.0431 0 P 0 ;0
L 1.29978996 -2.0431 1.29885 -2.04453996 0 P 0 ;0
L 1.29885 -2.04453996 1.29798996 -2.04613002 0 P 0 ;0
L 1.29798996 -2.04613002 1.29631998 -2.04986998 0 P 0 ;0
L 1.29631998 -2.04986998 1.29628002 -2.04995 0 P 0 ;0
L 1.29628002 -2.04995 1.29625 -2.05003002 0 P 0 ;0
L 1.29625 -2.05003002 1.29491998 -2.0539 0 P 0 ;0
L 1.29491998 -2.0539 1.29388996 -2.05793996 0 P 0 ;0
L 1.29388996 -2.05793996 1.29386998 -2.05801998 0 P 0 ;0
L 1.29386998 -2.05801998 1.29313996 -2.06221004 0 P 0 ;0
L 1.29313996 -2.06221004 1.29313002 -2.06223996 0 P 0 ;0
L 1.29313002 -2.06223996 1.29311998 -2.0623 0 P 0 ;0
L 1.29311998 -2.0623 1.29265 -2.06655 0 P 0 ;0
L 1.29265 -2.06655 1.29136998 -2.08418996 0 P 0 ;0
L 1.29136998 -2.08418996 1.29038996 -2.10276998 0 P 0 ;0
L 1.29038996 -2.10276998 1.29006998 -2.11763002 0 P 0 ;0
L 1.29006998 -2.11763002 1.29006004 -2.12516004 0 P 0 ;0
L 1.29006004 -2.12516004 1.2389 -2.12516004 0 P 0 ;0
L 1.09846998 -2.00483002 1.21248002 -2.00483002 0 P 0 ;0
L 1.09838002 -2.12083002 1.14708002 -2.12083002 0 P 0 ;0
L 1.11933002 -2.18283002 1.15161998 -2.18283002 0 P 0 ;0
L 1.11001998 -2.18183002 1.15838002 -2.18183002 0 P 0 ;0
L 1.10246998 -2.18083002 1.16333996 -2.18083002 0 P 0 ;0
L 1.04061004 -1.89731004 1.09978002 -1.89731004 0 P 0 ;0
L 1.03565 -1.89631004 1.09821004 -1.89631004 0 P 0 ;0
L 1.03068996 -1.89531004 1.09661004 -1.89531004 0 P 0 ;0
L 1.02573002 -1.89431004 1.09475 -1.89431004 0 P 0 ;0
L 1.019 -1.89331004 1.09288002 -1.89331004 0 P 0 ;0
L 1.01163996 -1.89231004 1.09101998 -1.89231004 0 P 0 ;0
L 0.99518996 -1.89131004 1.08916004 -1.89131004 0 P 0 ;0
L 0.87011998 -1.88331004 1.07278996 -1.88331004 0 P 0 ;0
L 0.86963996 -1.88231004 1.07053002 -1.88231004 0 P 0 ;0
L 0.86916004 -1.88131004 1.06828002 -1.88131004 0 P 0 ;0
L 0.86863002 -1.88031004 1.06603002 -1.88031004 0 P 0 ;0
L 0.86806998 -1.87931004 1.06351004 -1.87931004 0 P 0 ;0
L 0.8675 -1.87831004 1.06076998 -1.87831004 0 P 0 ;0
L 0.86693002 -1.87731004 1.05803996 -1.87731004 0 P 0 ;0
L 0.86631004 -1.87631004 1.05531004 -1.87631004 0 P 0 ;0
L 0.86563996 -1.87531004 1.05256998 -1.87531004 0 P 0 ;0
L 0.86498002 -1.87431004 1.04983996 -1.87431004 0 P 0 ;0
L 0.86431998 -1.87331004 1.0471 -1.87331004 0 P 0 ;0
L 0.86356004 -1.87231004 1.04376004 -1.87231004 0 P 0 ;0
L 0.86278996 -1.87131004 1.04041998 -1.87131004 0 P 0 ;0
L 0.86203002 -1.87031004 1.03708002 -1.87031004 0 P 0 ;0
L 0.86118996 -1.86931004 1.03373996 -1.86931004 0 P 0 ;0
L 0.8603 -1.86831004 1.0304 -1.86831004 0 P 0 ;0
L 0.85941004 -1.86731004 1.02656998 -1.86731004 0 P 0 ;0
L 0.8585 -1.86631004 1.02231998 -1.86631004 0 P 0 ;0
L 0.85756998 -1.86531004 1.01806998 -1.86531004 0 P 0 ;0
L 0.85663002 -1.86431004 1.01381998 -1.86431004 0 P 0 ;0
L 0.85568996 -1.86331004 1.00931998 -1.86331004 0 P 0 ;0
L 0.85481004 -1.86231004 1.00335 -1.86231004 0 P 0 ;0
L 0.85916998 -1.86131004 0.99738002 -1.86131004 0 P 0 ;0
L 0.86716998 -1.86031004 0.99141998 -1.86031004 0 P 0 ;0
L 0.87476998 -1.89731004 0.89943002 -1.89731004 0 P 0 ;0
L 0.87453996 -1.89631004 0.90426004 -1.89631004 0 P 0 ;0
L 0.87431004 -1.89531004 0.9097 -1.89531004 0 P 0 ;0
L 0.87406998 -1.89431004 0.91608002 -1.89431004 0 P 0 ;0
L 0.87383002 -1.89331004 0.92246004 -1.89331004 0 P 0 ;0
L 0.87355 -1.89231004 0.93086004 -1.89231004 0 P 0 ;0
L 0.87323002 -1.89131004 0.95553002 -1.89131004 0 P 0 ;0
L 0.87291004 -1.89031004 1.08728996 -1.89031004 0 P 0 ;0
L 0.87258996 -1.88931004 1.08543002 -1.88931004 0 P 0 ;0
L 0.87223002 -1.88831004 1.08356998 -1.88831004 0 P 0 ;0
L 0.87183002 -1.88731004 1.0817 -1.88731004 0 P 0 ;0
L 0.87143002 -1.88631004 1.07955 -1.88631004 0 P 0 ;0
L 0.87103002 -1.88531004 1.07728996 -1.88531004 0 P 0 ;0
L 0.8706 -1.88431004 1.07503996 -1.88431004 0 P 0 ;0
L 0.87525 -1.85931004 0.98545 -1.85931004 0 P 0 ;0
L 0.88421004 -1.85831004 0.97621004 -1.85831004 0 P 0 ;0
L 0.89393002 -1.85731004 0.96606998 -1.85731004 0 P 0 ;0
L 0.9106 -1.85631004 0.95203002 -1.85631004 0 P 0 ;0
L 1.08716004 -1.91231004 1.12151004 -1.91231004 0 P 0 ;0
L 1.08486004 -1.91131004 1.12018996 -1.91131004 0 P 0 ;0
L 1.08256004 -1.91031004 1.11886004 -1.91031004 0 P 0 ;0
L 1.08023002 -1.90931004 1.11753996 -1.90931004 0 P 0 ;0
L 1.07738002 -1.90831004 1.11621004 -1.90831004 0 P 0 ;0
L 1.07453002 -1.90731004 1.11488996 -1.90731004 0 P 0 ;0
L 1.07168996 -1.90631004 1.11356998 -1.90631004 0 P 0 ;0
L 1.06883996 -1.90531004 1.11223996 -1.90531004 0 P 0 ;0
L 1.066 -1.90431004 1.11076998 -1.90431004 0 P 0 ;0
L 1.06315 -1.90331004 1.1092 -1.90331004 0 P 0 ;0
L 1.0599 -1.90231004 1.10763002 -1.90231004 0 P 0 ;0
L 1.05611998 -1.90131004 1.10606004 -1.90131004 0 P 0 ;0
L 1.05235 -1.90031004 1.10448996 -1.90031004 0 P 0 ;0
L 1.04856998 -1.89931004 1.10291998 -1.89931004 0 P 0 ;0
L 1.04478996 -1.89831004 1.10135 -1.89831004 0 P 0 ;0
L 0.98815 -2.08316004 1.03726998 -2.08316004 0 P 0 ;0
L 0.98818002 -2.08216004 1.03731004 -2.08216004 0 P 0 ;0
L 0.98821998 -2.08116004 1.03735 -2.08116004 0 P 0 ;0
L 0.98825 -2.08016004 1.03738996 -2.08016004 0 P 0 ;0
L 0.98828002 -2.07916004 1.03743002 -2.07916004 0 P 0 ;0
L 0.98831998 -2.07816004 1.03746998 -2.07816004 0 P 0 ;0
L 0.98835 -2.07716004 1.03751004 -2.07716004 0 P 0 ;0
L 0.98838002 -2.07616004 1.03755 -2.07616004 0 P 0 ;0
L 0.98841998 -2.07516004 1.03758002 -2.07516004 0 P 0 ;0
L 0.98845 -2.07416004 1.03761004 -2.07416004 0 P 0 ;0
L 0.98848002 -2.07316004 1.03763996 -2.07316004 0 P 0 ;0
L 0.98851004 -2.07216004 1.03768002 -2.07216004 0 P 0 ;0
L 0.98855 -2.07116004 1.03771004 -2.07116004 0 P 0 ;0
L 0.98858002 -2.07016004 1.03773996 -2.07016004 0 P 0 ;0
L 0.98858996 -2.06916004 1.03776998 -2.06916004 0 P 0 ;0
L 0.98858996 -2.06816004 1.0378 -2.06816004 0 P 0 ;0
L 0.98858996 -2.06716004 1.03783002 -2.06716004 0 P 0 ;0
L 0.98858002 -2.06616004 1.03786004 -2.06616004 0 P 0 ;0
L 0.98856998 -2.06516004 1.0379 -2.06516004 0 P 0 ;0
L 0.98856998 -2.06416004 1.03793002 -2.06416004 0 P 0 ;0
L 0.98856998 -2.06316004 1.03796004 -2.06316004 0 P 0 ;0
L 0.98856004 -2.06216004 1.03798996 -2.06216004 0 P 0 ;0
L 0.98855 -2.06116004 1.03801998 -2.06116004 0 P 0 ;0
L 0.98855 -2.06016004 1.03805 -2.06016004 0 P 0 ;0
L 0.98853996 -2.05916004 1.03808002 -2.05916004 0 P 0 ;0
L 0.98853996 -2.05816004 1.0381 -2.05816004 0 P 0 ;0
L 0.98853002 -2.05716004 1.03811998 -2.05716004 0 P 0 ;0
L 0.98848002 -2.05616004 1.03815 -2.05616004 0 P 0 ;0
L 0.98841004 -2.05516004 1.03818002 -2.05516004 0 P 0 ;0
L 0.98835 -2.05416004 1.0382 -2.05416004 0 P 0 ;0
L 0.98828002 -2.05316004 1.03821998 -2.05316004 0 P 0 ;0
L 0.98821004 -2.05216004 1.03825 -2.05216004 0 P 0 ;0
L 0.98815 -2.05116004 1.03826998 -2.05116004 0 P 0 ;0
L 0.98808996 -2.05016004 1.03828996 -2.05016004 0 P 0 ;0
L 0.98801998 -2.04916004 1.03831998 -2.04916004 0 P 0 ;0
L 0.98796004 -2.04816004 1.03833996 -2.04816004 0 P 0 ;0
L 0.98788996 -2.04716004 1.03836004 -2.04716004 0 P 0 ;0
L 0.98783002 -2.04616004 1.03838996 -2.04616004 0 P 0 ;0
L 0.98768996 -2.04516004 1.0384 -2.04516004 0 P 0 ;0
L 0.98756004 -2.04416004 1.03841004 -2.04416004 0 P 0 ;0
L 0.98738002 -2.04316004 1.03841998 -2.04316004 0 P 0 ;0
L 0.98716004 -2.04216004 1.03843002 -2.04216004 0 P 0 ;0
L 0.98691998 -2.04116004 1.03843996 -2.04116004 0 P 0 ;0
L 0.98661998 -2.04016004 1.03845 -2.04016004 0 P 0 ;0
L 0.98631998 -2.03916004 1.03846004 -2.03916004 0 P 0 ;0
L 0.98593996 -2.03816004 1.03846998 -2.03816004 0 P 0 ;0
L 0.98546998 -2.03716004 1.03848002 -2.03716004 0 P 0 ;0
L 0.98491004 -2.03616004 1.03846998 -2.03616004 0 P 0 ;0
L 0.98425 -2.03516004 1.03846004 -2.03516004 0 P 0 ;0
L 0.98346004 -2.03416004 1.03846004 -2.03416004 0 P 0 ;0
L 0.98251998 -2.03316004 1.03843996 -2.03316004 0 P 0 ;0
L 0.98138002 -2.03216004 1.03843002 -2.03216004 0 P 0 ;0
L 0.97998996 -2.03116004 1.03841998 -2.03116004 0 P 0 ;0
L 0.97813996 -2.03016004 1.03841004 -2.03016004 0 P 0 ;0
L 0.97491004 -2.02916004 1.0384 -2.02916004 0 P 0 ;0
L 0.94763996 -2.00716004 1.03293996 -2.00716004 0 P 0 ;0
L 0.94978996 -2.00616004 1.03231998 -2.00616004 0 P 0 ;0
L 0.95081004 -2.00516004 1.0317 -2.00516004 0 P 0 ;0
L 0.95183002 -2.00416004 1.03098002 -2.00416004 0 P 0 ;0
L 0.95285 -2.00316004 1.03023002 -2.00316004 0 P 0 ;0
L 0.95388996 -2.00216004 1.02936004 -2.00216004 0 P 0 ;0
L 0.95498002 -2.00116004 1.02841998 -2.00116004 0 P 0 ;0
L 0.95621998 -2.00016004 1.02738996 -2.00016004 0 P 0 ;0
L 0.95761998 -1.99916004 1.0262 -1.99916004 0 P 0 ;0
L 0.9592 -1.99816004 1.02486004 -1.99816004 0 P 0 ;0
L 0.96083996 -1.99716004 1.02335 -1.99716004 0 P 0 ;0
L 0.9627 -1.99616004 1.02161004 -1.99616004 0 P 0 ;0
L 0.96468996 -1.99516004 1.01951998 -1.99516004 0 P 0 ;0
L 0.96685 -1.99416004 1.01683002 -1.99416004 0 P 0 ;0
L 0.96936998 -1.99316004 1.01378002 -1.99316004 0 P 0 ;0
L 0.97236998 -1.99216004 1.00981004 -1.99216004 0 P 0 ;0
L 0.97676004 -1.99116004 1.00456998 -1.99116004 0 P 0 ;0
L 1.06713996 -2.08283002 1.12288002 -2.08283002 0 P 0 ;0
L 1.06698996 -2.08183002 1.12193996 -2.08183002 0 P 0 ;0
L 1.06686004 -2.08083002 1.12108996 -2.08083002 0 P 0 ;0
L 1.06673996 -2.07983002 1.12036004 -2.07983002 0 P 0 ;0
L 1.06661998 -2.07883002 1.11971998 -2.07883002 0 P 0 ;0
L 1.06653002 -2.07783002 1.11916004 -2.07783002 0 P 0 ;0
L 1.06648002 -2.07683002 1.11866004 -2.07683002 0 P 0 ;0
L 1.06641998 -2.07583002 1.11826004 -2.07583002 0 P 0 ;0
L 1.06636998 -2.07483002 1.11791998 -2.07483002 0 P 0 ;0
L 1.06631998 -2.07383002 1.11761998 -2.07383002 0 P 0 ;0
L 1.06626004 -2.07283002 1.11741998 -2.07283002 0 P 0 ;0
L 1.06621004 -2.07183002 1.11723996 -2.07183002 0 P 0 ;0
L 1.06616004 -2.07083002 1.11711998 -2.07083002 0 P 0 ;0
L 1.06616004 -2.06983002 1.11701004 -2.06983002 0 P 0 ;0
L 1.06616004 -2.06883002 1.11688996 -2.06883002 0 P 0 ;0
L 1.06616998 -2.06783002 1.11676998 -2.06783002 0 P 0 ;0
L 1.06618002 -2.06683002 1.11666998 -2.06683002 0 P 0 ;0
L 1.06618996 -2.06583002 1.11663002 -2.06583002 0 P 0 ;0
L 1.0662 -2.06483002 1.11658996 -2.06483002 0 P 0 ;0
L 1.06621004 -2.06383002 1.11656004 -2.06383002 0 P 0 ;0
L 1.06623002 -2.06283002 1.11651998 -2.06283002 0 P 0 ;0
L 1.06631004 -2.06183002 1.11648996 -2.06183002 0 P 0 ;0
L 1.06638002 -2.06083002 1.11653002 -2.06083002 0 P 0 ;0
L 1.06645 -2.05983002 1.11656998 -2.05983002 0 P 0 ;0
L 1.06651998 -2.05883002 1.11661998 -2.05883002 0 P 0 ;0
L 1.06658996 -2.05783002 1.11666004 -2.05783002 0 P 0 ;0
L 1.06666998 -2.05683002 1.11671004 -2.05683002 0 P 0 ;0
L 1.06673996 -2.05583002 1.11681004 -2.05583002 0 P 0 ;0
L 1.06686004 -2.05483002 1.11693002 -2.05483002 0 P 0 ;0
L 1.067 -2.05383002 1.11705 -2.05383002 0 P 0 ;0
L 1.06713996 -2.05283002 1.11718002 -2.05283002 0 P 0 ;0
L 1.06728002 -2.05183002 1.11731004 -2.05183002 0 P 0 ;0
L 1.06741998 -2.05083002 1.11746004 -2.05083002 0 P 0 ;0
L 1.06756004 -2.04983002 1.11766004 -2.04983002 0 P 0 ;0
L 1.0677 -2.04883002 1.11786004 -2.04883002 0 P 0 ;0
L 1.06786004 -2.04783002 1.11813996 -2.04783002 0 P 0 ;0
L 1.06806998 -2.04683002 1.11841998 -2.04683002 0 P 0 ;0
L 1.06828002 -2.04583002 1.11876998 -2.04583002 0 P 0 ;0
L 1.06848996 -2.04483002 1.11913002 -2.04483002 0 P 0 ;0
L 1.06871004 -2.04383002 1.11955 -2.04383002 0 P 0 ;0
L 1.06898996 -2.04283002 1.11998996 -2.04283002 0 P 0 ;0
L 1.06928002 -2.04183002 1.12048002 -2.04183002 0 P 0 ;0
L 1.06956004 -2.04083002 1.12101004 -2.04083002 0 P 0 ;0
L 1.06985 -2.03983002 1.12161998 -2.03983002 0 P 0 ;0
L 1.07021004 -2.03883002 1.12225 -2.03883002 0 P 0 ;0
L 1.07056998 -2.03783002 1.12298002 -2.03783002 0 P 0 ;0
L 1.07093002 -2.03683002 1.12373996 -2.03683002 0 P 0 ;0
L 1.07128996 -2.03583002 1.12461998 -2.03583002 0 P 0 ;0
L 1.07173002 -2.03483002 1.12548996 -2.03483002 0 P 0 ;0
L 1.07216998 -2.03383002 1.12646004 -2.03383002 0 P 0 ;0
L 1.07261998 -2.03283002 1.12748996 -2.03283002 0 P 0 ;0
L 1.07308002 -2.03183002 1.12855 -2.03183002 0 P 0 ;0
L 1.07361998 -2.03083002 1.12978996 -2.03083002 0 P 0 ;0
L 1.09761004 -1.91731004 1.12756998 -1.91731004 0 P 0 ;0
L 1.09566004 -1.91631004 1.12645 -1.91631004 0 P 0 ;0
L 1.09371004 -1.91531004 1.12533002 -1.91531004 0 P 0 ;0
L 1.09176004 -1.91431004 1.12416004 -1.91431004 0 P 0 ;0
L 1.08946004 -1.91331004 1.12283996 -1.91331004 0 P 0 ;0
L 1.07415 -2.02983002 1.13101998 -2.02983002 0 P 0 ;0
L 1.07468996 -2.02883002 1.13248996 -2.02883002 0 P 0 ;0
L 1.07528996 -2.02783002 1.134 -2.02783002 0 P 0 ;0
L 1.07591998 -2.02683002 1.13586004 -2.02683002 0 P 0 ;0
L 1.07656004 -2.02583002 1.13828996 -2.02583002 0 P 0 ;0
L 1.07721004 -2.02483002 1.14243002 -2.02483002 0 P 0 ;0
L 1.07795 -2.02383002 1.21126998 -2.02383002 0 P 0 ;0
L 1.07868002 -2.02283002 1.21133002 -2.02283002 0 P 0 ;0
L 1.07941998 -2.02183002 1.2114 -2.02183002 0 P 0 ;0
L 1.08021004 -2.02083002 1.21146004 -2.02083002 0 P 0 ;0
L 1.08103996 -2.01983002 1.21153002 -2.01983002 0 P 0 ;0
L 1.08186998 -2.01883002 1.2116 -2.01883002 0 P 0 ;0
L 1.08273002 -2.01783002 1.21166004 -2.01783002 0 P 0 ;0
L 1.08366998 -2.01683002 1.21173002 -2.01683002 0 P 0 ;0
L 1.0846 -2.01583002 1.2118 -2.01583002 0 P 0 ;0
L 1.08555 -2.01483002 1.21186004 -2.01483002 0 P 0 ;0
L 1.08661004 -2.01383002 1.21193002 -2.01383002 0 P 0 ;0
L 1.08766998 -2.01283002 1.21198996 -2.01283002 0 P 0 ;0
L 1.08873002 -2.01183002 1.21205 -2.01183002 0 P 0 ;0
L 1.0898 -2.01083002 1.21211998 -2.01083002 0 P 0 ;0
L 1.09098996 -2.00983002 1.21218002 -2.00983002 0 P 0 ;0
L 1.09225 -2.00883002 1.21223996 -2.00883002 0 P 0 ;0
L 1.09358996 -2.00783002 1.2123 -2.00783002 0 P 0 ;0
L 1.09506998 -2.00683002 1.21236004 -2.00683002 0 P 0 ;0
L 1.09668996 -2.00583002 1.21241998 -2.00583002 0 P 0 ;0
L 0.98546998 -2.12516004 1.03548996 -2.12516004 0 P 0 ;0
L 0.98558996 -2.12416004 1.03553996 -2.12416004 0 P 0 ;0
L 0.9857 -2.12316004 1.03558002 -2.12316004 0 P 0 ;0
L 0.98581004 -2.12216004 1.03561998 -2.12216004 0 P 0 ;0
L 0.98591004 -2.12116004 1.03566998 -2.12116004 0 P 0 ;0
L 0.98598996 -2.12016004 1.03571004 -2.12016004 0 P 0 ;0
L 0.98608002 -2.11916004 1.03575 -2.11916004 0 P 0 ;0
L 0.98616998 -2.11816004 1.0358 -2.11816004 0 P 0 ;0
L 0.98625 -2.11716004 1.03583996 -2.11716004 0 P 0 ;0
L 0.98633996 -2.11616004 1.03588002 -2.11616004 0 P 0 ;0
L 0.98641998 -2.11516004 1.03593002 -2.11516004 0 P 0 ;0
L 0.98651004 -2.11416004 1.03596998 -2.11416004 0 P 0 ;0
L 0.9866 -2.11316004 1.03601004 -2.11316004 0 P 0 ;0
L 0.98668002 -2.11216004 1.03605 -2.11216004 0 P 0 ;0
L 0.98676998 -2.11116004 1.0361 -2.11116004 0 P 0 ;0
L 0.98685 -2.11016004 1.03613996 -2.11016004 0 P 0 ;0
L 0.98693996 -2.10916004 1.03618002 -2.10916004 0 P 0 ;0
L 0.987 -2.10816004 1.03623002 -2.10816004 0 P 0 ;0
L 0.98705 -2.10716004 1.03626998 -2.10716004 0 P 0 ;0
L 0.9871 -2.10616004 1.03631004 -2.10616004 0 P 0 ;0
L 0.98716004 -2.10516004 1.03636004 -2.10516004 0 P 0 ;0
L 0.9872 -2.10416004 1.0364 -2.10416004 0 P 0 ;0
L 0.98725 -2.10316004 1.03643996 -2.10316004 0 P 0 ;0
L 0.98731004 -2.10216004 1.03648002 -2.10216004 0 P 0 ;0
L 0.98735 -2.10116004 1.03653002 -2.10116004 0 P 0 ;0
L 0.9874 -2.10016004 1.03656998 -2.10016004 0 P 0 ;0
L 0.98746004 -2.09916004 1.03661004 -2.09916004 0 P 0 ;0
L 0.98751004 -2.09816004 1.03666004 -2.09816004 0 P 0 ;0
L 0.98755 -2.09716004 1.0367 -2.09716004 0 P 0 ;0
L 0.9876 -2.09616004 1.03673996 -2.09616004 0 P 0 ;0
L 0.98766004 -2.09516004 1.03678996 -2.09516004 0 P 0 ;0
L 0.9877 -2.09416004 1.03683002 -2.09416004 0 P 0 ;0
L 0.98775 -2.09316004 1.03686998 -2.09316004 0 P 0 ;0
L 0.98781004 -2.09216004 1.03691998 -2.09216004 0 P 0 ;0
L 0.98785 -2.09116004 1.03696004 -2.09116004 0 P 0 ;0
L 0.9879 -2.09016004 1.037 -2.09016004 0 P 0 ;0
L 0.98796004 -2.08916004 1.03703996 -2.08916004 0 P 0 ;0
L 0.98798996 -2.08816004 1.03706998 -2.08816004 0 P 0 ;0
L 0.98801998 -2.08716004 1.03711004 -2.08716004 0 P 0 ;0
L 0.98805 -2.08616004 1.03715 -2.08616004 0 P 0 ;0
L 0.98808996 -2.08516004 1.03718996 -2.08516004 0 P 0 ;0
L 0.98811998 -2.08416004 1.03723002 -2.08416004 0 P 0 ;0
L 1.08216998 -2.15683002 1.19803996 -2.15683002 0 P 0 ;0
L 1.0821 -2.15583002 1.19861004 -2.15583002 0 P 0 ;0
L 1.08201998 -2.15483002 1.19918002 -2.15483002 0 P 0 ;0
L 1.08195 -2.15383002 1.1997 -2.15383002 0 P 0 ;0
L 1.08188996 -2.15283002 1.20018002 -2.15283002 0 P 0 ;0
L 1.08183002 -2.15183002 1.20066004 -2.15183002 0 P 0 ;0
L 1.08176998 -2.15083002 1.20113996 -2.15083002 0 P 0 ;0
L 1.08171998 -2.14983002 1.20153996 -2.14983002 0 P 0 ;0
L 1.08166004 -2.14883002 1.20193002 -2.14883002 0 P 0 ;0
L 1.0816 -2.14783002 1.11538996 -2.14783002 0 P 0 ;0
L 1.08155 -2.14683002 1.10903002 -2.14683002 0 P 0 ;0
L 1.0815 -2.14583002 1.10415 -2.14583002 0 P 0 ;0
L 1.08146004 -2.14483002 1.09953002 -2.14483002 0 P 0 ;0
L 1.08141004 -2.14383002 1.09563996 -2.14383002 0 P 0 ;0
L 1.08136004 -2.14283002 1.09183996 -2.14283002 0 P 0 ;0
L 1.08131004 -2.14183002 1.08821004 -2.14183002 0 P 0 ;0
L 1.08133002 -2.14083002 1.08471998 -2.14083002 0 P 0 ;0
L 1.09586998 -2.11983002 1.14965 -2.11983002 0 P 0 ;0
L 1.09361998 -2.11883002 1.15221998 -2.11883002 0 P 0 ;0
L 1.09158996 -2.11783002 1.20595 -2.11783002 0 P 0 ;0
L 1.08988002 -2.11683002 1.20601004 -2.11683002 0 P 0 ;0
L 1.08823996 -2.11583002 1.20606998 -2.11583002 0 P 0 ;0
L 1.08678996 -2.11483002 1.20613002 -2.11483002 0 P 0 ;0
L 1.08541004 -2.11383002 1.20618996 -2.11383002 0 P 0 ;0
L 1.08416998 -2.11283002 1.20625 -2.11283002 0 P 0 ;0
L 1.08295 -2.11183002 1.20631004 -2.11183002 0 P 0 ;0
L 1.08188002 -2.11083002 1.20638002 -2.11083002 0 P 0 ;0
L 1.08081998 -2.10983002 1.20643996 -2.10983002 0 P 0 ;0
L 1.07986004 -2.10883002 1.2065 -2.10883002 0 P 0 ;0
L 1.07895 -2.10783002 1.20656004 -2.10783002 0 P 0 ;0
L 1.07803002 -2.10683002 1.20661998 -2.10683002 0 P 0 ;0
L 1.07723996 -2.10583002 1.20666998 -2.10583002 0 P 0 ;0
L 1.07646004 -2.10483002 1.20671998 -2.10483002 0 P 0 ;0
L 1.07568002 -2.10383002 1.20678002 -2.10383002 0 P 0 ;0
L 1.075 -2.10283002 1.20683002 -2.10283002 0 P 0 ;0
L 1.07433002 -2.10183002 1.20688002 -2.10183002 0 P 0 ;0
L 1.07366998 -2.10083002 1.20693996 -2.10083002 0 P 0 ;0
L 1.07308996 -2.09983002 1.20698996 -2.09983002 0 P 0 ;0
L 1.07253002 -2.09883002 1.20705 -2.09883002 0 P 0 ;0
L 1.07198002 -2.09783002 1.2071 -2.09783002 0 P 0 ;0
L 1.07146998 -2.09683002 1.20715 -2.09683002 0 P 0 ;0
L 1.07101998 -2.09583002 1.2072 -2.09583002 0 P 0 ;0
L 1.07056998 -2.09483002 1.20726004 -2.09483002 0 P 0 ;0
L 1.07013002 -2.09383002 1.20731004 -2.09383002 0 P 0 ;0
L 1.06976998 -2.09283002 1.20736004 -2.09283002 0 P 0 ;0
L 1.06941998 -2.09183002 1.20741998 -2.09183002 0 P 0 ;0
L 1.06906004 -2.09083002 1.20746998 -2.09083002 0 P 0 ;0
L 1.06876004 -2.08983002 1.20753002 -2.08983002 0 P 0 ;0
L 1.06848996 -2.08883002 1.13443002 -2.08883002 0 P 0 ;0
L 1.06821998 -2.08783002 1.13068002 -2.08783002 0 P 0 ;0
L 1.06795 -2.08683002 1.12836998 -2.08683002 0 P 0 ;0
L 1.06771998 -2.08583002 1.1266 -2.08583002 0 P 0 ;0
L 1.06753002 -2.08483002 1.12516004 -2.08483002 0 P 0 ;0
L 1.06733002 -2.08383002 1.12393996 -2.08383002 0 P 0 ;0
L 0.90273996 -1.85456998 0.89068996 -1.85558002 0 P 0 ;0
L 0.89068996 -1.85558002 0.87421004 -1.85741998 0 P 0 ;0
L 0.87421004 -1.85741998 0.85783002 -1.85946998 0 P 0 ;0
L 0.85783002 -1.85946998 0.85526998 -1.8599 0 P 0 ;0
L 0.85526998 -1.8599 0.85276004 -1.86055 0 P 0 ;0
L 0.85276004 -1.86055 0.85255 -1.86063996 0 P 0 ;0
L 0.85255 -1.86063996 0.85248996 -1.86068996 0 P 0 ;0
L 0.85248996 -1.86068996 0.85243002 -1.86073002 0 P 0 ;0
L 0.85243002 -1.86073002 0.85238002 -1.86078002 0 P 0 ;0
L 0.85238002 -1.86078002 0.85233002 -1.86083996 0 P 0 ;0
L 0.85233002 -1.86083996 0.85225 -1.86096004 0 P 0 ;0
L 0.85225 -1.86096004 0.85218002 -1.8611 0 P 0 ;0
L 0.85218002 -1.8611 0.85216004 -1.86116998 0 P 0 ;0
L 0.85216004 -1.86116998 0.85215 -1.86123996 0 P 0 ;0
L 0.85215 -1.86123996 0.85213996 -1.86136998 0 P 0 ;0
L 0.85213996 -1.86136998 0.85213002 -1.86148996 0 P 0 ;0
L 0.85213002 -1.86148996 0.85213996 -1.86161998 0 P 0 ;0
L 0.85213996 -1.86161998 0.85215 -1.86173996 0 P 0 ;0
L 0.85215 -1.86173996 0.85218002 -1.86186998 0 P 0 ;0
L 0.85218002 -1.86186998 0.85221004 -1.86198996 0 P 0 ;0
L 0.85221004 -1.86198996 0.85225 -1.8621 0 P 0 ;0
L 0.85225 -1.8621 0.85231004 -1.86221998 0 P 0 ;0
L 0.85231004 -1.86221998 0.85236998 -1.86233002 0 P 0 ;0
L 0.85236998 -1.86233002 0.85281998 -1.863 0 P 0 ;0
L 0.85281998 -1.863 0.8533 -1.86363996 0 P 0 ;0
L 0.8533 -1.86363996 0.85383002 -1.86425 0 P 0 ;0
L 0.85383002 -1.86425 0.85736004 -1.86801998 0 P 0 ;0
L 0.85736004 -1.86801998 0.86013002 -1.87113002 0 P 0 ;0
L 0.86013002 -1.87113002 0.86266004 -1.87443002 0 P 0 ;0
L 0.86266004 -1.87443002 0.86501004 -1.87798996 0 P 0 ;0
L 0.86501004 -1.87798996 0.86711998 -1.88171004 0 P 0 ;0
L 0.86711998 -1.88171004 0.86896998 -1.88553996 0 P 0 ;0
L 0.86896998 -1.88553996 0.87055 -1.8895 0 P 0 ;0
L 0.87055 -1.8895 0.8718 -1.89343002 0 P 0 ;0
L 0.8718 -1.89343002 0.87276004 -1.89745 0 P 0 ;0
L 0.87276004 -1.89745 0.87371004 -1.90195 0 P 0 ;0
L 0.87371004 -1.90195 0.87383002 -1.90236004 0 P 0 ;0
L 0.87383002 -1.90236004 0.87396998 -1.90276004 0 P 0 ;0
L 0.87396998 -1.90276004 0.87416004 -1.90313996 0 P 0 ;0
L 0.87416004 -1.90313996 0.87436998 -1.90351004 0 P 0 ;0
L 0.87436998 -1.90351004 0.87443002 -1.9036 0 P 0 ;0
L 0.87443002 -1.9036 0.87456998 -1.90376004 0 P 0 ;0
L 0.87456998 -1.90376004 0.87465 -1.90381998 0 P 0 ;0
L 0.87465 -1.90381998 0.87473002 -1.90388996 0 P 0 ;0
L 0.87473002 -1.90388996 0.87481998 -1.90393996 0 P 0 ;0
L 0.87481998 -1.90393996 0.87491998 -1.90398996 0 P 0 ;0
L 0.87491998 -1.90398996 0.87501004 -1.90403002 0 P 0 ;0
L 0.87501004 -1.90403002 0.87521004 -1.90408996 0 P 0 ;0
L 0.87521004 -1.90408996 0.87531998 -1.9041 0 P 0 ;0
L 0.87531998 -1.9041 0.87573002 -1.90413002 0 P 0 ;0
L 0.87573002 -1.90413002 0.87613996 -1.90411998 0 P 0 ;0
L 0.87613996 -1.90411998 0.87653996 -1.90408002 0 P 0 ;0
L 0.87653996 -1.90408002 0.87695 -1.90401004 0 P 0 ;0
L 0.87695 -1.90401004 0.90756004 -1.89766998 0 P 0 ;0
L 0.90756004 -1.89766998 0.92603996 -1.89478002 0 P 0 ;0
L 0.92603996 -1.89478002 0.93486004 -1.89393996 0 P 0 ;0
L 0.93486004 -1.89393996 0.94371004 -1.8935 0 P 0 ;0
L 0.94371004 -1.8935 0.97045 -1.89308002 0 P 0 ;0
L 0.97045 -1.89308002 0.99468996 -1.89328996 0 P 0 ;0
L 0.99468996 -1.89328996 1.01021004 -1.89413996 0 P 0 ;0
L 1.01021004 -1.89413996 1.0241 -1.89601998 0 P 0 ;0
L 1.0241 -1.89601998 1.04188002 -1.89961004 0 P 0 ;0
L 1.04188002 -1.89961004 1.06095 -1.90466004 0 P 0 ;0
L 1.06095 -1.90466004 1.07963996 -1.91123002 0 P 0 ;0
L 1.07963996 -1.91123002 1.09093996 -1.91613002 0 P 0 ;0
L 1.09093996 -1.91613002 1.10186998 -1.92175 0 P 0 ;0
L 1.10186998 -1.92175 1.11243996 -1.92806998 0 P 0 ;0
L 1.11243996 -1.92806998 1.12163002 -1.93446998 0 P 0 ;0
L 1.12163002 -1.93446998 1.13033002 -1.94148996 0 P 0 ;0
L 1.13033002 -1.94148996 1.1385 -1.94911004 0 P 0 ;0
L 1.1385 -1.94911004 1.14358996 -1.9546 0 P 0 ;0
L 1.14358996 -1.9546 1.14825 -1.96045 0 P 0 ;0
L 1.14825 -1.96045 1.15246998 -1.96663002 0 P 0 ;0
L 1.15246998 -1.96663002 1.15623002 -1.97316004 0 P 0 ;0
L 1.15623002 -1.97316004 1.15895 -1.97831004 0 P 0 ;0
L 1.15895 -1.97831004 1.17358996 -1.97831004 0 P 0 ;0
L 1.17358996 -1.97831004 1.17135 -1.9726 0 P 0 ;0
L 1.17135 -1.9726 1.16696004 -1.96266998 0 P 0 ;0
L 1.16696004 -1.96266998 1.16171998 -1.95313002 0 P 0 ;0
L 1.16171998 -1.95313002 1.1557 -1.94406998 0 P 0 ;0
L 1.1557 -1.94406998 1.14885 -1.93548002 0 P 0 ;0
L 1.14885 -1.93548002 1.13778996 -1.92378002 0 P 0 ;0
L 1.13778996 -1.92378002 1.12576998 -1.91301998 0 P 0 ;0
L 1.12576998 -1.91301998 1.11283996 -1.90326004 0 P 0 ;0
L 1.11283996 -1.90326004 1.09783002 -1.89368996 0 P 0 ;0
L 1.09783002 -1.89368996 1.08213002 -1.88526998 0 P 0 ;0
L 1.08213002 -1.88526998 1.06576998 -1.87801004 0 P 0 ;0
L 1.06576998 -1.87801004 1.04776004 -1.87141998 0 P 0 ;0
L 1.04776004 -1.87141998 1.02938002 -1.86591998 0 P 0 ;0
L 1.02938002 -1.86591998 1.01058002 -1.8615 0 P 0 ;0
L 1.01058002 -1.8615 0.98441998 -1.85711004 0 P 0 ;0
L 0.98441998 -1.85711004 0.95781004 -1.85448996 0 P 0 ;0
L 0.95781004 -1.85448996 0.93061004 -1.85366004 0 P 0 ;0
L 0.93061004 -1.85366004 0.90273996 -1.85456998 0 P 0 ;0
L 1.16015 -1.97631004 1.15798002 -1.97218996 0 P 0 ;0
L 1.15798002 -1.97218996 1.15796004 -1.97216004 0 P 0 ;0
L 1.15796004 -1.97216004 1.15416004 -1.96556998 0 P 0 ;0
L 1.15416004 -1.96556998 1.15411998 -1.96551004 0 P 0 ;0
L 1.15411998 -1.96551004 1.14986004 -1.95926004 0 P 0 ;0
L 1.14986004 -1.95926004 1.14981998 -1.95921004 0 P 0 ;0
L 1.14981998 -1.95921004 1.14511004 -1.9533 0 P 0 ;0
L 1.14511004 -1.9533 1.13991998 -1.9477 0 P 0 ;0
L 1.13991998 -1.9477 1.13986004 -1.94765 0 P 0 ;0
L 1.13986004 -1.94765 1.13163996 -1.93998002 0 P 0 ;0
L 1.13163996 -1.93998002 1.12283002 -1.93286004 0 P 0 ;0
L 1.12283002 -1.93286004 1.11351998 -1.92638996 0 P 0 ;0
L 1.11351998 -1.92638996 1.10283996 -1.92 0 P 0 ;0
L 1.10283996 -1.92 1.0918 -1.91433002 0 P 0 ;0
L 1.0918 -1.91433002 1.08036998 -1.90936004 0 P 0 ;0
L 1.08036998 -1.90936004 1.06153002 -1.90273996 0 P 0 ;0
L 1.06153002 -1.90273996 1.06146004 -1.90273002 0 P 0 ;0
L 1.06146004 -1.90273002 1.04233002 -1.89766004 0 P 0 ;0
L 1.04233002 -1.89766004 1.02443002 -1.89405 0 P 0 ;0
L 1.02443002 -1.89405 1.0104 -1.89213996 0 P 0 ;0
L 1.0104 -1.89213996 0.99475 -1.89128996 0 P 0 ;0
L 0.99475 -1.89128996 0.97045 -1.89108002 0 P 0 ;0
L 0.97045 -1.89108002 0.94365 -1.8915 0 P 0 ;0
L 0.94365 -1.8915 0.94361998 -1.8915 0 P 0 ;0
L 0.94361998 -1.8915 0.93471998 -1.89195 0 P 0 ;0
L 0.93471998 -1.89195 0.92578996 -1.89278996 0 P 0 ;0
L 0.92578996 -1.89278996 0.9072 -1.89571004 0 P 0 ;0
L 0.9072 -1.89571004 0.87656998 -1.90203996 0 P 0 ;0
L 0.87656998 -1.90203996 0.87626998 -1.9021 0 P 0 ;0
L 0.87626998 -1.9021 0.87601998 -1.90211998 0 P 0 ;0
L 0.87601998 -1.90211998 0.87588996 -1.90213002 0 P 0 ;0
L 0.87588996 -1.90213002 0.87583002 -1.90198996 0 P 0 ;0
L 0.87583002 -1.90198996 0.87573002 -1.90175 0 P 0 ;0
L 0.87573002 -1.90175 0.87566004 -1.90146998 0 P 0 ;0
L 0.87566004 -1.90146998 0.87471004 -1.89701004 0 P 0 ;0
L 0.87471004 -1.89701004 0.8747 -1.89698996 0 P 0 ;0
L 0.8747 -1.89698996 0.87373002 -1.89288996 0 P 0 ;0
L 0.87373002 -1.89288996 0.87243002 -1.88881998 0 P 0 ;0
L 0.87243002 -1.88881998 0.8724 -1.88876004 0 P 0 ;0
L 0.8724 -1.88876004 0.8708 -1.88473996 0 P 0 ;0
L 0.8708 -1.88473996 0.8689 -1.88078002 0 P 0 ;0
L 0.8689 -1.88078002 0.86671998 -1.87693996 0 P 0 ;0
L 0.86671998 -1.87693996 0.86428996 -1.87326004 0 P 0 ;0
L 0.86428996 -1.87326004 0.86166998 -1.86985 0 P 0 ;0
L 0.86166998 -1.86985 0.85883996 -1.86668002 0 P 0 ;0
L 0.85883996 -1.86668002 0.85883002 -1.86666004 0 P 0 ;0
L 0.85883002 -1.86666004 0.85531998 -1.86291004 0 P 0 ;0
L 0.85531998 -1.86291004 0.85486004 -1.86238002 0 P 0 ;0
L 0.85486004 -1.86238002 0.85466004 -1.86211998 0 P 0 ;0
L 0.85466004 -1.86211998 0.8557 -1.86186004 0 P 0 ;0
L 0.8557 -1.86186004 0.85811998 -1.86145 0 P 0 ;0
L 0.85811998 -1.86145 0.87443996 -1.85941004 0 P 0 ;0
L 0.87443996 -1.85941004 0.89088996 -1.85756998 0 P 0 ;0
L 0.89088996 -1.85756998 0.90286004 -1.85656998 0 P 0 ;0
L 0.90286004 -1.85656998 0.93061004 -1.85566004 0 P 0 ;0
L 0.93061004 -1.85566004 0.95768002 -1.85648996 0 P 0 ;0
L 0.95768002 -1.85648996 0.98416004 -1.8591 0 P 0 ;0
L 0.98416004 -1.8591 1.01018996 -1.86346004 0 P 0 ;0
L 1.01018996 -1.86346004 1.02886004 -1.86785 0 P 0 ;0
L 1.02886004 -1.86785 1.04711998 -1.87331998 0 P 0 ;0
L 1.04711998 -1.87331998 1.06501004 -1.87986004 0 P 0 ;0
L 1.06501004 -1.87986004 1.08125 -1.88706998 0 P 0 ;0
L 1.08125 -1.88706998 1.09681004 -1.89541998 0 P 0 ;0
L 1.09681004 -1.89541998 1.1117 -1.9049 0 P 0 ;0
L 1.1117 -1.9049 1.1245 -1.91456998 0 P 0 ;0
L 1.1245 -1.91456998 1.13638996 -1.92521004 0 P 0 ;0
L 1.13638996 -1.92521004 1.14733996 -1.93678996 0 P 0 ;0
L 1.14733996 -1.93678996 1.15408002 -1.94525 0 P 0 ;0
L 1.15408002 -1.94525 1.16001004 -1.95416998 0 P 0 ;0
L 1.16001004 -1.95416998 1.16516004 -1.96355 0 P 0 ;0
L 1.16516004 -1.96355 1.1695 -1.97336998 0 P 0 ;0
L 1.1695 -1.97336998 1.17066004 -1.97631004 0 P 0 ;0
L 1.17066004 -1.97631004 1.16015 -1.97631004 0 P 0 ;0
L 0.87563002 -1.90131004 0.8801 -1.90131004 0 P 0 ;0
L 0.87541004 -1.90031004 0.88493996 -1.90031004 0 P 0 ;0
L 0.8752 -1.89931004 0.88976998 -1.89931004 0 P 0 ;0
L 0.87498996 -1.89831004 0.8946 -1.89831004 0 P 0 ;0
L 0.89423002 -2.08316004 0.94355 -2.08316004 0 P 0 ;0
L 0.89428996 -2.08216004 0.9436 -2.08216004 0 P 0 ;0
L 0.89435 -2.08116004 0.94365 -2.08116004 0 P 0 ;0
L 0.89441004 -2.08016004 0.9437 -2.08016004 0 P 0 ;0
L 0.89446004 -2.07916004 0.94375 -2.07916004 0 P 0 ;0
L 0.89451998 -2.07816004 0.94378996 -2.07816004 0 P 0 ;0
L 0.89458002 -2.07716004 0.94383996 -2.07716004 0 P 0 ;0
L 0.89463996 -2.07616004 0.94388996 -2.07616004 0 P 0 ;0
L 0.8947 -2.07516004 0.94393996 -2.07516004 0 P 0 ;0
L 0.89475 -2.07416004 0.94398002 -2.07416004 0 P 0 ;0
L 0.89481004 -2.07316004 0.94403002 -2.07316004 0 P 0 ;0
L 0.89486998 -2.07216004 0.94408002 -2.07216004 0 P 0 ;0
L 0.89493002 -2.07116004 0.94415 -2.07116004 0 P 0 ;0
L 0.89498996 -2.07016004 0.94426004 -2.07016004 0 P 0 ;0
L 0.89505 -2.06916004 0.94436998 -2.06916004 0 P 0 ;0
L 0.8951 -2.06816004 0.94448002 -2.06816004 0 P 0 ;0
L 0.89516004 -2.06716004 0.94458996 -2.06716004 0 P 0 ;0
L 0.89521998 -2.06616004 0.9447 -2.06616004 0 P 0 ;0
L 0.89526998 -2.06516004 0.94481004 -2.06516004 0 P 0 ;0
L 0.89531004 -2.06416004 0.94491998 -2.06416004 0 P 0 ;0
L 0.89535 -2.06316004 0.94503002 -2.06316004 0 P 0 ;0
L 0.8954 -2.06216004 0.94513996 -2.06216004 0 P 0 ;0
L 0.89543996 -2.06116004 0.94531998 -2.06116004 0 P 0 ;0
L 0.89548996 -2.06016004 0.94551004 -2.06016004 0 P 0 ;0
L 0.89553002 -2.05916004 0.9457 -2.05916004 0 P 0 ;0
L 0.89558002 -2.05816004 0.94588996 -2.05816004 0 P 0 ;0
L 0.89561998 -2.05716004 0.94608002 -2.05716004 0 P 0 ;0
L 0.89566998 -2.05616004 0.94626998 -2.05616004 0 P 0 ;0
L 0.89571004 -2.05516004 0.94646998 -2.05516004 0 P 0 ;0
L 0.89575 -2.05416004 0.94666004 -2.05416004 0 P 0 ;0
L 0.8958 -2.05316004 0.94685 -2.05316004 0 P 0 ;0
L 0.89583996 -2.05216004 0.94708002 -2.05216004 0 P 0 ;0
L 0.89588996 -2.05116004 0.94735 -2.05116004 0 P 0 ;0
L 0.89593996 -2.05016004 0.94761998 -2.05016004 0 P 0 ;0
L 0.89598002 -2.04916004 0.9479 -2.04916004 0 P 0 ;0
L 0.89601998 -2.04816004 0.94825 -2.04816004 0 P 0 ;0
L 0.89606998 -2.04716004 0.94858996 -2.04716004 0 P 0 ;0
L 0.89611004 -2.04616004 0.94893002 -2.04616004 0 P 0 ;0
L 0.89616004 -2.04516004 0.94935 -2.04516004 0 P 0 ;0
L 0.8962 -2.04416004 0.94976998 -2.04416004 0 P 0 ;0
L 0.89625 -2.04316004 0.9502 -2.04316004 0 P 0 ;0
L 0.89628002 -2.04216004 0.95068996 -2.04216004 0 P 0 ;0
L 0.89631004 -2.04116004 0.95118996 -2.04116004 0 P 0 ;0
L 0.89633996 -2.04016004 0.95168996 -2.04016004 0 P 0 ;0
L 0.89638002 -2.03916004 0.95228002 -2.03916004 0 P 0 ;0
L 0.89641004 -2.03816004 0.95291004 -2.03816004 0 P 0 ;0
L 0.89643996 -2.03716004 0.95363002 -2.03716004 0 P 0 ;0
L 0.89646998 -2.03616004 0.95445 -2.03616004 0 P 0 ;0
L 0.89651004 -2.03516004 0.95535 -2.03516004 0 P 0 ;0
L 0.89653996 -2.03416004 0.95636998 -2.03416004 0 P 0 ;0
L 0.89656998 -2.03316004 0.95756998 -2.03316004 0 P 0 ;0
L 0.8966 -2.03216004 0.95893996 -2.03216004 0 P 0 ;0
L 0.89663996 -2.03116004 0.96055 -2.03116004 0 P 0 ;0
L 0.89666998 -2.03016004 0.96278002 -2.03016004 0 P 0 ;0
L 0.8967 -2.02916004 0.96676004 -2.02916004 0 P 0 ;0
L 0.89673996 -2.02816004 1.03838996 -2.02816004 0 P 0 ;0
L 0.89676998 -2.02716004 1.03838002 -2.02716004 0 P 0 ;0
L 0.8968 -2.02616004 1.03833996 -2.02616004 0 P 0 ;0
L 0.89683996 -2.02516004 1.03828996 -2.02516004 0 P 0 ;0
L 0.89686998 -2.02416004 1.03823002 -2.02416004 0 P 0 ;0
L 0.8969 -2.02316004 1.03816004 -2.02316004 0 P 0 ;0
L 0.89693996 -2.02216004 1.0381 -2.02216004 0 P 0 ;0
L 0.89696998 -2.02116004 1.03803996 -2.02116004 0 P 0 ;0
L 0.897 -2.02016004 1.0379 -2.02016004 0 P 0 ;0
L 0.89703002 -2.01916004 1.03773996 -2.01916004 0 P 0 ;0
L 0.89706004 -2.01816004 1.03751998 -2.01816004 0 P 0 ;0
L 0.89708996 -2.01716004 1.03728002 -2.01716004 0 P 0 ;0
L 0.89711998 -2.01616004 1.03698996 -2.01616004 0 P 0 ;0
L 0.89713996 -2.01516004 1.03668002 -2.01516004 0 P 0 ;0
L 0.89716998 -2.01416004 1.03631004 -2.01416004 0 P 0 ;0
L 0.8972 -2.01316004 1.03591998 -2.01316004 0 P 0 ;0
L 0.89721998 -2.01216004 1.03548996 -2.01216004 0 P 0 ;0
L 0.89725 -2.01116004 1.03505 -2.01116004 0 P 0 ;0
L 0.89726998 -2.01016004 1.03458002 -2.01016004 0 P 0 ;0
L 0.8973 -2.00916004 1.03405 -2.00916004 0 P 0 ;0
L 0.89733002 -2.00816004 1.03351998 -2.00816004 0 P 0 ;0
L 0.89736004 -2.00716004 0.94676004 -2.00716004 0 P 0 ;0
L 0.89738002 -2.00616004 0.9461 -2.00616004 0 P 0 ;0
L 0.89741004 -2.00516004 0.94563996 -2.00516004 0 P 0 ;0
L 0.89743996 -2.00416004 0.94563996 -2.00416004 0 P 0 ;0
L 0.89746004 -2.00316004 0.94563996 -2.00316004 0 P 0 ;0
L 0.89748996 -2.00216004 0.94563996 -2.00216004 0 P 0 ;0
L 0.89751004 -2.00116004 0.94563996 -2.00116004 0 P 0 ;0
L 0.89753996 -2.00016004 0.94563996 -2.00016004 0 P 0 ;0
L 0.89756998 -1.99916004 0.94563996 -1.99916004 0 P 0 ;0
L 0.8976 -1.99816004 0.94563996 -1.99816004 0 P 0 ;0
L 0.89761998 -1.99716004 0.94563996 -1.99716004 0 P 0 ;0
L 0.89765 -1.99616004 0.94563996 -1.99616004 0 P 0 ;0
L 0.89768002 -1.99516004 0.94563996 -1.99516004 0 P 0 ;0
L 0.97546998 -1.98933996 0.97236998 -1.99006004 0 P 0 ;0
L 0.97236998 -1.99006004 0.96931998 -1.99103002 0 P 0 ;0
L 0.96931998 -1.99103002 0.96603002 -1.99233002 0 P 0 ;0
L 0.96603002 -1.99233002 0.96281004 -1.99383002 0 P 0 ;0
L 0.96281004 -1.99383002 0.95976004 -1.99546998 0 P 0 ;0
L 0.95976004 -1.99546998 0.95681004 -1.99728996 0 P 0 ;0
L 0.95681004 -1.99728996 0.95521004 -1.99841004 0 P 0 ;0
L 0.95521004 -1.99841004 0.95368996 -1.99963002 0 P 0 ;0
L 0.95368996 -1.99963002 0.95223996 -2.00095 0 P 0 ;0
L 0.95223996 -2.00095 0.94763996 -2.00546998 0 P 0 ;0
L 0.94763996 -2.00546998 0.94763996 -1.99243996 0 P 0 ;0
L 0.94763996 -1.99243996 0.89575 -1.99243996 0 P 0 ;0
L 0.89575 -1.99243996 0.89505 -2.01878002 0 P 0 ;0
L 0.89505 -2.01878002 0.89423996 -2.04316004 0 P 0 ;0
L 0.89423996 -2.04316004 0.89321998 -2.0661 0 P 0 ;0
L 0.89321998 -2.0661 0.89198996 -2.08728996 0 P 0 ;0
L 0.89198996 -2.08728996 0.89055 -2.1063 0 P 0 ;0
L 0.89055 -2.1063 0.88993996 -2.11358002 0 P 0 ;0
L 0.88993996 -2.11358002 0.88943002 -2.11988002 0 P 0 ;0
L 0.88943002 -2.11988002 0.88898996 -2.12533996 0 P 0 ;0
L 0.88898996 -2.12533996 0.88896004 -2.12613002 0 P 0 ;0
L 0.88896004 -2.12613002 0.88896998 -2.12621004 0 P 0 ;0
L 0.88896998 -2.12621004 0.88898002 -2.12625 0 P 0 ;0
L 0.88898002 -2.12625 0.88898996 -2.12628002 0 P 0 ;0
L 0.88898996 -2.12628002 0.88901998 -2.12636004 0 P 0 ;0
L 0.88901998 -2.12636004 0.88903996 -2.12638996 0 P 0 ;0
L 0.88903996 -2.12638996 0.88906998 -2.12641998 0 P 0 ;0
L 0.88906998 -2.12641998 0.88908996 -2.12645 0 P 0 ;0
L 0.88908996 -2.12645 0.88911998 -2.12646998 0 P 0 ;0
L 0.88911998 -2.12646998 0.88915 -2.1265 0 P 0 ;0
L 0.88915 -2.1265 0.88921004 -2.12653996 0 P 0 ;0
L 0.88921004 -2.12653996 0.88925 -2.12655 0 P 0 ;0
L 0.88925 -2.12655 0.88928002 -2.12656004 0 P 0 ;0
L 0.88928002 -2.12656004 0.88931998 -2.12658002 0 P 0 ;0
L 0.88931998 -2.12658002 0.8894 -2.12658002 0 P 0 ;0
L 0.8894 -2.12658002 0.89648002 -2.12686998 0 P 0 ;0
L 0.89648002 -2.12686998 0.90518996 -2.1271 0 P 0 ;0
L 0.90518996 -2.1271 0.9165 -2.12716004 0 P 0 ;0
L 0.9165 -2.12716004 0.94403996 -2.12716004 0 P 0 ;0
L 0.94403996 -2.12716004 0.94468996 -2.10135 0 P 0 ;0
L 0.94468996 -2.10135 0.9461 -2.07171998 0 P 0 ;0
L 0.9461 -2.07171998 0.94713002 -2.06233002 0 P 0 ;0
L 0.94713002 -2.06233002 0.9489 -2.05308002 0 P 0 ;0
L 0.9489 -2.05308002 0.94975 -2.04995 0 P 0 ;0
L 0.94975 -2.04995 0.9508 -2.04688996 0 P 0 ;0
L 0.9508 -2.04688996 0.95205 -2.0439 0 P 0 ;0
L 0.95205 -2.0439 0.95351004 -2.041 0 P 0 ;0
L 0.95351004 -2.041 0.9544 -2.03951004 0 P 0 ;0
L 0.9544 -2.03951004 0.95541998 -2.03811004 0 P 0 ;0
L 0.95541998 -2.03811004 0.95655 -2.03678996 0 P 0 ;0
L 0.95655 -2.03678996 0.95778996 -2.03556998 0 P 0 ;0
L 0.95778996 -2.03556998 0.95911998 -2.03446998 0 P 0 ;0
L 0.95911998 -2.03446998 0.96056998 -2.03346998 0 P 0 ;0
L 0.96056998 -2.03346998 0.96151004 -2.03291004 0 P 0 ;0
L 0.96151004 -2.03291004 0.96248996 -2.03243002 0 P 0 ;0
L 0.96248996 -2.03243002 0.96351004 -2.03201998 0 P 0 ;0
L 0.96351004 -2.03201998 0.96455 -2.03168996 0 P 0 ;0
L 0.96455 -2.03168996 0.96613002 -2.0313 0 P 0 ;0
L 0.96613002 -2.0313 0.96773002 -2.03101998 0 P 0 ;0
L 0.96773002 -2.03101998 0.96935 -2.03086004 0 P 0 ;0
L 0.96935 -2.03086004 0.97095 -2.03081004 0 P 0 ;0
L 0.97095 -2.03081004 0.97255 -2.03086998 0 P 0 ;0
L 0.97255 -2.03086998 0.97413002 -2.03105 0 P 0 ;0
L 0.97413002 -2.03105 0.97513002 -2.03123996 0 P 0 ;0
L 0.97513002 -2.03123996 0.9761 -2.03151004 0 P 0 ;0
L 0.9761 -2.03151004 0.97706004 -2.03186004 0 P 0 ;0
L 0.97706004 -2.03186004 0.97796998 -2.0323 0 P 0 ;0
L 0.97796998 -2.0323 0.97885 -2.0328 0 P 0 ;0
L 0.97885 -2.0328 0.97968002 -2.03336998 0 P 0 ;0
L 0.97968002 -2.03336998 0.98046998 -2.03398996 0 P 0 ;0
L 0.98046998 -2.03398996 0.98121998 -2.03468002 0 P 0 ;0
L 0.98121998 -2.03468002 0.98191004 -2.03541998 0 P 0 ;0
L 0.98191004 -2.03541998 0.98253996 -2.0362 0 P 0 ;0
L 0.98253996 -2.0362 0.9831 -2.03703002 0 P 0 ;0
L 0.9831 -2.03703002 0.9836 -2.03788996 0 P 0 ;0
L 0.9836 -2.03788996 0.98403996 -2.0388 0 P 0 ;0
L 0.98403996 -2.0388 0.9844 -2.03973996 0 P 0 ;0
L 0.9844 -2.03973996 0.98505 -2.04188996 0 P 0 ;0
L 0.98505 -2.04188996 0.98553002 -2.04408002 0 P 0 ;0
L 0.98553002 -2.04408002 0.98583002 -2.0463 0 P 0 ;0
L 0.98583002 -2.0463 0.98653002 -2.05705 0 P 0 ;0
L 0.98653002 -2.05705 0.9866 -2.06961004 0 P 0 ;0
L 0.9866 -2.06961004 0.98596004 -2.08908002 0 P 0 ;0
L 0.98596004 -2.08908002 0.98498002 -2.10858002 0 P 0 ;0
L 0.98498002 -2.10858002 0.98388002 -2.12146998 0 P 0 ;0
L 0.98388002 -2.12146998 0.98323002 -2.12716004 0 P 0 ;0
L 0.98323002 -2.12716004 1.03741004 -2.12716004 0 P 0 ;0
L 1.03741004 -2.12716004 1.03896004 -2.09103002 0 P 0 ;0
L 1.03896004 -2.09103002 1.03956004 -2.0759 0 P 0 ;0
L 1.03956004 -2.0759 1.04005 -2.06025 0 P 0 ;0
L 1.04005 -2.06025 1.04038996 -2.04626004 0 P 0 ;0
L 1.04038996 -2.04626004 1.04048002 -2.03698996 0 P 0 ;0
L 1.04048002 -2.03698996 1.04036998 -2.02651998 0 P 0 ;0
L 1.04036998 -2.02651998 1.04003996 -2.02096998 0 P 0 ;0
L 1.04003996 -2.02096998 1.03975 -2.01895 0 P 0 ;0
L 1.03975 -2.01895 1.0393 -2.01693996 0 P 0 ;0
L 1.0393 -2.01693996 1.03868996 -2.01483996 0 P 0 ;0
L 1.03868996 -2.01483996 1.03793996 -2.01278002 0 P 0 ;0
L 1.03793996 -2.01278002 1.03658996 -2.00968002 0 P 0 ;0
L 1.03658996 -2.00968002 1.03501004 -2.00668996 0 P 0 ;0
L 1.03501004 -2.00668996 1.0332 -2.0038 0 P 0 ;0
L 1.0332 -2.0038 1.03186998 -2.002 0 P 0 ;0
L 1.03186998 -2.002 1.0304 -2.0003 0 P 0 ;0
L 1.0304 -2.0003 1.0288 -1.99873002 0 P 0 ;0
L 1.0288 -1.99873002 1.02708002 -1.99728996 0 P 0 ;0
L 1.02708002 -1.99728996 1.02518002 -1.99593002 0 P 0 ;0
L 1.02518002 -1.99593002 1.02318002 -1.99471998 0 P 0 ;0
L 1.02318002 -1.99471998 1.0211 -1.99365 0 P 0 ;0
L 1.0211 -1.99365 1.01893002 -1.99273996 0 P 0 ;0
L 1.01893002 -1.99273996 1.01358996 -1.99098996 0 P 0 ;0
L 1.01358996 -1.99098996 1.0081 -1.98971004 0 P 0 ;0
L 1.0081 -1.98971004 1.00428996 -1.98908996 0 P 0 ;0
L 1.00428996 -1.98908996 1.00043996 -1.98868002 0 P 0 ;0
L 1.00043996 -1.98868002 0.99138002 -1.98826004 0 P 0 ;0
L 0.99138002 -1.98826004 0.98251998 -1.98846998 0 P 0 ;0
L 0.98251998 -1.98846998 0.97898996 -1.98878996 0 P 0 ;0
L 0.97898996 -1.98878996 0.97546998 -1.98933996 0 P 0 ;0
L 0.91651004 -2.12516004 0.94208996 -2.12516004 0 P 0 ;0
L 0.8911 -2.12416004 0.94211004 -2.12416004 0 P 0 ;0
L 0.89118002 -2.12316004 0.94213996 -2.12316004 0 P 0 ;0
L 0.89125 -2.12216004 0.94216004 -2.12216004 0 P 0 ;0
L 0.89133002 -2.12116004 0.94218996 -2.12116004 0 P 0 ;0
L 0.89141004 -2.12016004 0.94221004 -2.12016004 0 P 0 ;0
L 0.89148996 -2.11916004 0.94223996 -2.11916004 0 P 0 ;0
L 0.89156998 -2.11816004 0.94226998 -2.11816004 0 P 0 ;0
L 0.89166004 -2.11716004 0.94228996 -2.11716004 0 P 0 ;0
L 0.89173996 -2.11616004 0.94231004 -2.11616004 0 P 0 ;0
L 0.89181998 -2.11516004 0.94233996 -2.11516004 0 P 0 ;0
L 0.8919 -2.11416004 0.94236004 -2.11416004 0 P 0 ;0
L 0.89198002 -2.11316004 0.94238996 -2.11316004 0 P 0 ;0
L 0.89206998 -2.11216004 0.94241998 -2.11216004 0 P 0 ;0
L 0.89215 -2.11116004 0.94243996 -2.11116004 0 P 0 ;0
L 0.89223002 -2.11016004 0.94246998 -2.11016004 0 P 0 ;0
L 0.89231998 -2.10916004 0.94248996 -2.10916004 0 P 0 ;0
L 0.8924 -2.10816004 0.94251998 -2.10816004 0 P 0 ;0
L 0.89248002 -2.10716004 0.94255 -2.10716004 0 P 0 ;0
L 0.89256998 -2.10616004 0.94256998 -2.10616004 0 P 0 ;0
L 0.89263996 -2.10516004 0.94258996 -2.10516004 0 P 0 ;0
L 0.89271004 -2.10416004 0.94261998 -2.10416004 0 P 0 ;0
L 0.89278996 -2.10316004 0.94263996 -2.10316004 0 P 0 ;0
L 0.89286998 -2.10216004 0.94266998 -2.10216004 0 P 0 ;0
L 0.89293996 -2.10116004 0.9427 -2.10116004 0 P 0 ;0
L 0.89301998 -2.10016004 0.94275 -2.10016004 0 P 0 ;0
L 0.89308996 -2.09916004 0.94278996 -2.09916004 0 P 0 ;0
L 0.89316998 -2.09816004 0.94283996 -2.09816004 0 P 0 ;0
L 0.89325 -2.09716004 0.94288996 -2.09716004 0 P 0 ;0
L 0.89331998 -2.09616004 0.94293996 -2.09616004 0 P 0 ;0
L 0.8934 -2.09516004 0.94298002 -2.09516004 0 P 0 ;0
L 0.89346998 -2.09416004 0.94303002 -2.09416004 0 P 0 ;0
L 0.89355 -2.09316004 0.94308002 -2.09316004 0 P 0 ;0
L 0.89361998 -2.09216004 0.94313002 -2.09216004 0 P 0 ;0
L 0.8937 -2.09116004 0.94318002 -2.09116004 0 P 0 ;0
L 0.89378002 -2.09016004 0.94321998 -2.09016004 0 P 0 ;0
L 0.89385 -2.08916004 0.94326998 -2.08916004 0 P 0 ;0
L 0.89393002 -2.08816004 0.94331998 -2.08816004 0 P 0 ;0
L 0.894 -2.08716004 0.94336004 -2.08716004 0 P 0 ;0
L 0.89406004 -2.08616004 0.94341004 -2.08616004 0 P 0 ;0
L 0.89411998 -2.08516004 0.94346004 -2.08516004 0 P 0 ;0
L 0.89418002 -2.08416004 0.94351004 -2.08416004 0 P 0 ;0
L 0.91651004 -2.12516004 0.90521998 -2.1251 0 P 0 ;0
L 0.90521998 -2.1251 0.89655 -2.12486998 0 P 0 ;0
L 0.89655 -2.12486998 0.89106004 -2.12465 0 P 0 ;0
L 0.89106004 -2.12465 0.89141998 -2.12003996 0 P 0 ;0
L 0.89141998 -2.12003996 0.89193996 -2.11373996 0 P 0 ;0
L 0.89193996 -2.11373996 0.89253996 -2.10645 0 P 0 ;0
L 0.89253996 -2.10645 0.89398002 -2.08741998 0 P 0 ;0
L 0.89398002 -2.08741998 0.89521998 -2.06621998 0 P 0 ;0
L 0.89521998 -2.06621998 0.89521998 -2.06618996 0 P 0 ;0
L 0.89521998 -2.06618996 0.89623996 -2.04323002 0 P 0 ;0
L 0.89623996 -2.04323002 0.89703996 -2.01883002 0 P 0 ;0
L 0.89703996 -2.01883002 0.8977 -1.99443996 0 P 0 ;0
L 0.8977 -1.99443996 0.94563996 -1.99443996 0 P 0 ;0
L 0.94563996 -1.99443996 0.94563996 -2.00546998 0 P 0 ;0
L 0.94563996 -2.00546998 0.94686004 -2.00731004 0 P 0 ;0
L 0.94686004 -2.00731004 0.94903002 -2.00688996 0 P 0 ;0
L 0.94903002 -2.00688996 0.95361998 -2.00241004 0 P 0 ;0
L 0.95361998 -2.00241004 0.95498996 -2.00115 0 P 0 ;0
L 0.95498996 -2.00115 0.95641998 -2.00001004 0 P 0 ;0
L 0.95641998 -2.00001004 0.9579 -1.99896004 0 P 0 ;0
L 0.9579 -1.99896004 0.96076004 -1.9972 0 P 0 ;0
L 0.96076004 -1.9972 0.9637 -1.99561998 0 P 0 ;0
L 0.9637 -1.99561998 0.96683002 -1.99416998 0 P 0 ;0
L 0.96683002 -1.99416998 0.96998996 -1.99291998 0 P 0 ;0
L 0.96998996 -1.99291998 0.9729 -1.99198996 0 P 0 ;0
L 0.9729 -1.99198996 0.97586004 -1.9913 0 P 0 ;0
L 0.97586004 -1.9913 0.97923002 -1.99076998 0 P 0 ;0
L 0.97923002 -1.99076998 0.98263002 -1.99046998 0 P 0 ;0
L 0.98263002 -1.99046998 0.99136004 -1.99026004 0 P 0 ;0
L 0.99136004 -1.99026004 1.00028996 -1.99066998 0 P 0 ;0
L 1.00028996 -1.99066998 1.00403002 -1.99108002 0 P 0 ;0
L 1.00403002 -1.99108002 1.00771004 -1.99166998 0 P 0 ;0
L 1.00771004 -1.99166998 1.01305 -1.99291998 0 P 0 ;0
L 1.01305 -1.99291998 1.01823002 -1.99461998 0 P 0 ;0
L 1.01823002 -1.99461998 1.02026004 -1.99546998 0 P 0 ;0
L 1.02026004 -1.99546998 1.02221004 -1.99646998 0 P 0 ;0
L 1.02221004 -1.99646998 1.02408002 -1.9976 0 P 0 ;0
L 1.02408002 -1.9976 1.02585 -1.99886998 0 P 0 ;0
L 1.02585 -1.99886998 1.02746004 -2.00021004 0 P 0 ;0
L 1.02746004 -2.00021004 1.02893996 -2.00166998 0 P 0 ;0
L 1.02893996 -2.00166998 1.03031004 -2.00325 0 P 0 ;0
L 1.03031004 -2.00325 1.03155 -2.00493002 0 P 0 ;0
L 1.03155 -2.00493002 1.03326998 -2.00768002 0 P 0 ;0
L 1.03326998 -2.00768002 1.03478002 -2.01055 0 P 0 ;0
L 1.03478002 -2.01055 1.03608002 -2.01351998 0 P 0 ;0
L 1.03608002 -2.01351998 1.03678996 -2.01546998 0 P 0 ;0
L 1.03678996 -2.01546998 1.03736004 -2.01743002 0 P 0 ;0
L 1.03736004 -2.01743002 1.03778002 -2.0193 0 P 0 ;0
L 1.03778002 -2.0193 1.03805 -2.02116998 0 P 0 ;0
L 1.03805 -2.02116998 1.03836998 -2.02658996 0 P 0 ;0
L 1.03836998 -2.02658996 1.03848002 -2.03698996 0 P 0 ;0
L 1.03848002 -2.03698996 1.03838996 -2.04623002 0 P 0 ;0
L 1.03838996 -2.04623002 1.03805 -2.06018996 0 P 0 ;0
L 1.03805 -2.06018996 1.03756004 -2.07583002 0 P 0 ;0
L 1.03756004 -2.07583002 1.03696998 -2.09095 0 P 0 ;0
L 1.03696998 -2.09095 1.03548996 -2.12516004 0 P 0 ;0
L 1.03548996 -2.12516004 0.98546998 -2.12516004 0 P 0 ;0
L 0.98546998 -2.12516004 0.98586998 -2.12166004 0 P 0 ;0
L 0.98586998 -2.12166004 0.98696998 -2.10871998 0 P 0 ;0
L 0.98696998 -2.10871998 0.98796004 -2.08916004 0 P 0 ;0
L 0.98796004 -2.08916004 0.9886 -2.06963002 0 P 0 ;0
L 0.9886 -2.06963002 0.98853002 -2.05698002 0 P 0 ;0
L 0.98853002 -2.05698002 0.98781998 -2.0461 0 P 0 ;0
L 0.98781998 -2.0461 0.9875 -2.04373002 0 P 0 ;0
L 0.9875 -2.04373002 0.98748002 -2.04365 0 P 0 ;0
L 0.98748002 -2.04365 0.98698996 -2.04138996 0 P 0 ;0
L 0.98698996 -2.04138996 0.9863 -2.03908002 0 P 0 ;0
L 0.9863 -2.03908002 0.98588002 -2.038 0 P 0 ;0
L 0.98588002 -2.038 0.98538002 -2.03696004 0 P 0 ;0
L 0.98538002 -2.03696004 0.9848 -2.03596004 0 P 0 ;0
L 0.9848 -2.03596004 0.98413996 -2.03501004 0 P 0 ;0
L 0.98413996 -2.03501004 0.98341998 -2.03411004 0 P 0 ;0
L 0.98341998 -2.03411004 0.98336998 -2.03405 0 P 0 ;0
L 0.98336998 -2.03405 0.98263002 -2.03326004 0 P 0 ;0
L 0.98263002 -2.03326004 0.98176998 -2.03246998 0 P 0 ;0
L 0.98176998 -2.03246998 0.98086998 -2.03175 0 P 0 ;0
L 0.98086998 -2.03175 0.97991004 -2.0311 0 P 0 ;0
L 0.97991004 -2.0311 0.9789 -2.03051998 0 P 0 ;0
L 0.9789 -2.03051998 0.97783002 -2.03001998 0 P 0 ;0
L 0.97783002 -2.03001998 0.97673002 -2.02961004 0 P 0 ;0
L 0.97673002 -2.02961004 0.97663996 -2.02958002 0 P 0 ;0
L 0.97663996 -2.02958002 0.97558996 -2.02928996 0 P 0 ;0
L 0.97558996 -2.02928996 0.97443002 -2.02906998 0 P 0 ;0
L 0.97443002 -2.02906998 0.9727 -2.02888002 0 P 0 ;0
L 0.9727 -2.02888002 0.97261998 -2.02886998 0 P 0 ;0
L 0.97261998 -2.02886998 0.97096004 -2.02881004 0 P 0 ;0
L 0.97096004 -2.02881004 0.96921004 -2.02886004 0 P 0 ;0
L 0.96921004 -2.02886004 0.96745 -2.02903996 0 P 0 ;0
L 0.96745 -2.02903996 0.96571004 -2.02933996 0 P 0 ;0
L 0.96571004 -2.02933996 0.964 -2.02976004 0 P 0 ;0
L 0.964 -2.02976004 0.96283002 -2.03013996 0 P 0 ;0
L 0.96283002 -2.03013996 0.96168002 -2.0306 0 P 0 ;0
L 0.96168002 -2.0306 0.96056998 -2.03115 0 P 0 ;0
L 0.96056998 -2.03115 0.95948996 -2.03178002 0 P 0 ;0
L 0.95948996 -2.03178002 0.95791004 -2.03286998 0 P 0 ;0
L 0.95791004 -2.03286998 0.95645 -2.03408996 0 P 0 ;0
L 0.95645 -2.03408996 0.95508996 -2.03541998 0 P 0 ;0
L 0.95508996 -2.03541998 0.95383996 -2.03686998 0 P 0 ;0
L 0.95383996 -2.03686998 0.9538 -2.03693002 0 P 0 ;0
L 0.9538 -2.03693002 0.95273002 -2.03841004 0 P 0 ;0
L 0.95273002 -2.03841004 0.95175 -2.04003996 0 P 0 ;0
L 0.95175 -2.04003996 0.95023002 -2.04306004 0 P 0 ;0
L 0.95023002 -2.04306004 0.94896004 -2.04611004 0 P 0 ;0
L 0.94896004 -2.04611004 0.94893002 -2.04616998 0 P 0 ;0
L 0.94893002 -2.04616998 0.94783002 -2.04936004 0 P 0 ;0
L 0.94783002 -2.04936004 0.94695 -2.05263002 0 P 0 ;0
L 0.94695 -2.05263002 0.94515 -2.06203002 0 P 0 ;0
L 0.94515 -2.06203002 0.9441 -2.07156004 0 P 0 ;0
L 0.9441 -2.07156004 0.9427 -2.10128002 0 P 0 ;0
L 0.9427 -2.10128002 0.94208996 -2.12516004 0 P 0 ;0
L 0.94208996 -2.12516004 0.91651004 -2.12516004 0 P 0 ;0
L 0.93143002 -2.21261998 1.00578996 -2.21261998 0 P 0 ;0
L 0.94051004 -2.21161998 1.00803002 -2.21161998 0 P 0 ;0
L 0.94941998 -2.21061998 1.01026004 -2.21061998 0 P 0 ;0
L 0.9555 -2.20961998 1.0125 -2.20961998 0 P 0 ;0
L 0.96158002 -2.20861998 1.01473996 -2.20861998 0 P 0 ;0
L 0.96766004 -2.20761998 1.01696998 -2.20761998 0 P 0 ;0
L 0.97373002 -2.20661998 1.01921004 -2.20661998 0 P 0 ;0
L 0.97981004 -2.20561998 1.02145 -2.20561998 0 P 0 ;0
L 0.98498996 -2.20461998 1.02368996 -2.20461998 0 P 0 ;0
L 0.98973996 -2.20361998 1.02591998 -2.20361998 0 P 0 ;0
L 0.99448996 -2.20261998 1.02816004 -2.20261998 0 P 0 ;0
L 0.99923996 -2.20161998 1.0304 -2.20161998 0 P 0 ;0
L 1.00398996 -2.20061998 1.03243996 -2.20061998 0 P 0 ;0
L 1.00875 -2.19961998 1.0344 -2.19961998 0 P 0 ;0
L 1.01348996 -2.19861998 1.03636998 -2.19861998 0 P 0 ;0
L 1.0178 -2.19761998 1.03833996 -2.19761998 0 P 0 ;0
L 1.02168996 -2.19661998 1.04031004 -2.19661998 0 P 0 ;0
L 1.02558002 -2.19561998 1.04228002 -2.19561998 0 P 0 ;0
L 1.02946998 -2.19461998 1.04415 -2.19461998 0 P 0 ;0
L 1.03336004 -2.19361998 1.04596998 -2.19361998 0 P 0 ;0
L 1.03725 -2.19261998 1.04778996 -2.19261998 0 P 0 ;0
L 1.04113996 -2.19161998 1.0496 -2.19161998 0 P 0 ;0
L 1.14356998 -1.98926998 1.13261004 -1.99086004 0 P 0 ;0
L 1.13261004 -1.99086004 1.12165 -1.9934 0 P 0 ;0
L 1.12165 -1.9934 1.11125 -1.99673002 0 P 0 ;0
L 1.11125 -1.99673002 1.10658002 -1.99858996 0 P 0 ;0
L 1.10658002 -1.99858996 1.10198996 -2.00071004 0 P 0 ;0
L 1.10198996 -2.00071004 1.09653002 -2.00358996 0 P 0 ;0
L 1.09653002 -2.00358996 1.09436998 -2.00488996 0 P 0 ;0
L 1.09436998 -2.00488996 1.09226004 -2.00631004 0 P 0 ;0
L 1.09226004 -2.00631004 1.09028002 -2.00781004 0 P 0 ;0
L 1.09028002 -2.00781004 1.08836998 -2.00941998 0 P 0 ;0
L 1.08836998 -2.00941998 1.08405 -2.0135 0 P 0 ;0
L 1.08405 -2.0135 1.08096998 -2.01678996 0 P 0 ;0
L 1.08096998 -2.01678996 1.07808002 -2.02026998 0 P 0 ;0
L 1.07808002 -2.02026998 1.0754 -2.02393002 0 P 0 ;0
L 1.0754 -2.02393002 1.07313996 -2.02748002 0 P 0 ;0
L 1.07313996 -2.02748002 1.07116004 -2.03118996 0 P 0 ;0
L 1.07116004 -2.03118996 1.06943996 -2.03505 0 P 0 ;0
L 1.06943996 -2.03505 1.06795 -2.03918996 0 P 0 ;0
L 1.06795 -2.03918996 1.06673996 -2.04343996 0 P 0 ;0
L 1.06673996 -2.04343996 1.06583002 -2.04778002 0 P 0 ;0
L 1.06583002 -2.04778002 1.06476998 -2.05538996 0 P 0 ;0
L 1.06476998 -2.05538996 1.06421004 -2.06306004 0 P 0 ;0
L 1.06421004 -2.06306004 1.06415 -2.07076004 0 P 0 ;0
L 1.06415 -2.07076004 1.06456998 -2.0785 0 P 0 ;0
L 1.06456998 -2.0785 1.06508996 -2.08276004 0 P 0 ;0
L 1.06508996 -2.08276004 1.06591004 -2.08696004 0 P 0 ;0
L 1.06591004 -2.08696004 1.06703002 -2.09108002 0 P 0 ;0
L 1.06703002 -2.09108002 1.06833002 -2.09473002 0 P 0 ;0
L 1.06833002 -2.09473002 1.06991998 -2.09823996 0 P 0 ;0
L 1.06991998 -2.09823996 1.0718 -2.10161998 0 P 0 ;0
L 1.0718 -2.10161998 1.07398002 -2.10491998 0 P 0 ;0
L 1.07398002 -2.10491998 1.07641998 -2.10803002 0 P 0 ;0
L 1.07641998 -2.10803002 1.07908996 -2.11095 0 P 0 ;0
L 1.07908996 -2.11095 1.08175 -2.11345 0 P 0 ;0
L 1.08175 -2.11345 1.08458996 -2.11573996 0 P 0 ;0
L 1.08458996 -2.11573996 1.08758996 -2.1178 0 P 0 ;0
L 1.08758996 -2.1178 1.09073002 -2.11963996 0 P 0 ;0
L 1.09073002 -2.11963996 1.094 -2.12123996 0 P 0 ;0
L 1.094 -2.12123996 1.0986 -2.12306998 0 P 0 ;0
L 1.0986 -2.12306998 1.10331004 -2.12456004 0 P 0 ;0
L 1.10331004 -2.12456004 1.10811004 -2.12568996 0 P 0 ;0
L 1.10811004 -2.12568996 1.11298002 -2.12646998 0 P 0 ;0
L 1.11298002 -2.12646998 1.1182 -2.12693002 0 P 0 ;0
L 1.1182 -2.12693002 1.12343996 -2.12703002 0 P 0 ;0
L 1.12343996 -2.12703002 1.12866998 -2.12676004 0 P 0 ;0
L 1.12866998 -2.12676004 1.13388002 -2.12613002 0 P 0 ;0
L 1.13388002 -2.12613002 1.14086004 -2.12473996 0 P 0 ;0
L 1.14086004 -2.12473996 1.1477 -2.12273996 0 P 0 ;0
L 1.1477 -2.12273996 1.15433996 -2.12015 0 P 0 ;0
L 1.15433996 -2.12015 1.1545 -2.12008996 0 P 0 ;0
L 1.1545 -2.12008996 1.15466004 -2.12003996 0 P 0 ;0
L 1.15466004 -2.12003996 1.15483002 -2.12001004 0 P 0 ;0
L 1.15483002 -2.12001004 1.15498996 -2.11998996 0 P 0 ;0
L 1.15498996 -2.11998996 1.15533002 -2.11998996 0 P 0 ;0
L 1.15533002 -2.11998996 1.15538996 -2.12 0 P 0 ;0
L 1.15538996 -2.12 1.15545 -2.12001998 0 P 0 ;0
L 1.15545 -2.12001998 1.15551004 -2.12003002 0 P 0 ;0
L 1.15551004 -2.12003002 1.15556004 -2.12006004 0 P 0 ;0
L 1.15556004 -2.12006004 1.15561004 -2.12008002 0 P 0 ;0
L 1.15561004 -2.12008002 1.15566004 -2.12011004 0 P 0 ;0
L 1.15566004 -2.12011004 1.15571004 -2.12015 0 P 0 ;0
L 1.15571004 -2.12015 1.15575 -2.12018996 0 P 0 ;0
L 1.15575 -2.12018996 1.15578996 -2.12023996 0 P 0 ;0
L 1.15578996 -2.12023996 1.15583002 -2.12028002 0 P 0 ;0
L 1.15583002 -2.12028002 1.15586004 -2.12033996 0 P 0 ;0
L 1.15586004 -2.12033996 1.15588002 -2.12038996 0 P 0 ;0
L 1.15588002 -2.12038996 1.15591004 -2.12043996 0 P 0 ;0
L 1.15591004 -2.12043996 1.15601998 -2.12076004 0 P 0 ;0
L 1.15601998 -2.12076004 1.1561 -2.12108002 0 P 0 ;0
L 1.1561 -2.12108002 1.15616004 -2.12141998 0 P 0 ;0
L 1.15616004 -2.12141998 1.15618002 -2.12175 0 P 0 ;0
L 1.15618002 -2.12175 1.15623996 -2.12505 0 P 0 ;0
L 1.15623996 -2.12505 1.15616004 -2.12688002 0 P 0 ;0
L 1.15616004 -2.12688002 1.15593002 -2.12871004 0 P 0 ;0
L 1.15593002 -2.12871004 1.15553996 -2.13051998 0 P 0 ;0
L 1.15553996 -2.13051998 1.15516004 -2.1318 0 P 0 ;0
L 1.15516004 -2.1318 1.1547 -2.13305 0 P 0 ;0
L 1.1547 -2.13305 1.15415 -2.13426004 0 P 0 ;0
L 1.15415 -2.13426004 1.15351004 -2.13545 0 P 0 ;0
L 1.15351004 -2.13545 1.15278996 -2.1366 0 P 0 ;0
L 1.15278996 -2.1366 1.15198002 -2.13768996 0 P 0 ;0
L 1.15198002 -2.13768996 1.15111004 -2.13873002 0 P 0 ;0
L 1.15111004 -2.13873002 1.15016004 -2.13971004 0 P 0 ;0
L 1.15016004 -2.13971004 1.14876004 -2.14096004 0 P 0 ;0
L 1.14876004 -2.14096004 1.14726004 -2.1421 0 P 0 ;0
L 1.14726004 -2.1421 1.14566998 -2.14311004 0 P 0 ;0
L 1.14566998 -2.14311004 1.144 -2.144 0 P 0 ;0
L 1.144 -2.144 1.14226004 -2.14476004 0 P 0 ;0
L 1.14226004 -2.14476004 1.14046004 -2.14536998 0 P 0 ;0
L 1.14046004 -2.14536998 1.13863002 -2.14583002 0 P 0 ;0
L 1.13863002 -2.14583002 1.13676004 -2.14613996 0 P 0 ;0
L 1.13676004 -2.14613996 1.13041998 -2.14663996 0 P 0 ;0
L 1.13041998 -2.14663996 1.12403996 -2.1466 0 P 0 ;0
L 1.12403996 -2.1466 1.11621998 -2.14593996 0 P 0 ;0
L 1.11621998 -2.14593996 1.10843996 -2.14471004 0 P 0 ;0
L 1.10843996 -2.14471004 1.09946998 -2.14276998 0 P 0 ;0
L 1.09946998 -2.14276998 1.0905 -2.14041004 0 P 0 ;0
L 1.0905 -2.14041004 1.07963996 -2.13728996 0 P 0 ;0
L 1.07963996 -2.13728996 1.07936004 -2.1401 0 P 0 ;0
L 1.07936004 -2.1401 1.07931004 -2.14103996 0 P 0 ;0
L 1.07931004 -2.14103996 1.07931998 -2.14198002 0 P 0 ;0
L 1.07931998 -2.14198002 1.07956998 -2.14735 0 P 0 ;0
L 1.07956998 -2.14735 1.07993996 -2.15375 0 P 0 ;0
L 1.07993996 -2.15375 1.08045 -2.16081998 0 P 0 ;0
L 1.08045 -2.16081998 1.08181004 -2.17873002 0 P 0 ;0
L 1.08181004 -2.17873002 1.08996004 -2.18061004 0 P 0 ;0
L 1.08996004 -2.18061004 1.09951004 -2.18246004 0 P 0 ;0
L 1.09951004 -2.18246004 1.11243996 -2.18416998 0 P 0 ;0
L 1.11243996 -2.18416998 1.1254 -2.18543002 0 P 0 ;0
L 1.1254 -2.18543002 1.13508002 -2.18583002 0 P 0 ;0
L 1.13508002 -2.18583002 1.14765 -2.18528996 0 P 0 ;0
L 1.14765 -2.18528996 1.15368002 -2.18461004 0 P 0 ;0
L 1.15368002 -2.18461004 1.15971004 -2.18363996 0 P 0 ;0
L 1.15971004 -2.18363996 1.16521004 -2.18248002 0 P 0 ;0
L 1.16521004 -2.18248002 1.17063996 -2.18103002 0 P 0 ;0
L 1.17063996 -2.18103002 1.17528996 -2.17946998 0 P 0 ;0
L 1.17528996 -2.17946998 1.17978002 -2.17753996 0 P 0 ;0
L 1.17978002 -2.17753996 1.18216998 -2.1763 0 P 0 ;0
L 1.18216998 -2.1763 1.18446004 -2.17488996 0 P 0 ;0
L 1.18446004 -2.17488996 1.18663996 -2.17331004 0 P 0 ;0
L 1.18663996 -2.17331004 1.18871004 -2.17156004 0 P 0 ;0
L 1.18871004 -2.17156004 1.19161004 -2.16871998 0 P 0 ;0
L 1.19161004 -2.16871998 1.19431004 -2.16568996 0 P 0 ;0
L 1.19431004 -2.16568996 1.19678996 -2.16246998 0 P 0 ;0
L 1.19678996 -2.16246998 1.19908996 -2.15901998 0 P 0 ;0
L 1.19908996 -2.15901998 1.20113996 -2.15543996 0 P 0 ;0
L 1.20113996 -2.15543996 1.20295 -2.15171004 0 P 0 ;0
L 1.20295 -2.15171004 1.20435 -2.14815 0 P 0 ;0
L 1.20435 -2.14815 1.20543996 -2.14448996 0 P 0 ;0
L 1.20543996 -2.14448996 1.20621004 -2.14073996 0 P 0 ;0
L 1.20621004 -2.14073996 1.20651998 -2.13855 0 P 0 ;0
L 1.20651998 -2.13855 1.20671998 -2.13633996 0 P 0 ;0
L 1.20671998 -2.13633996 1.20761998 -2.12321004 0 P 0 ;0
L 1.20761998 -2.12321004 1.20858002 -2.10753996 0 P 0 ;0
L 1.20858002 -2.10753996 1.20951004 -2.09021998 0 P 0 ;0
L 1.20951004 -2.09021998 1.21048002 -2.07166004 0 P 0 ;0
L 1.21048002 -2.07166004 1.21156004 -2.05228002 0 P 0 ;0
L 1.21156004 -2.05228002 1.21258002 -2.03478996 0 P 0 ;0
L 1.21258002 -2.03478996 1.21333002 -2.02286004 0 P 0 ;0
L 1.21333002 -2.02286004 1.21393996 -2.01373996 0 P 0 ;0
L 1.21393996 -2.01373996 1.21443996 -2.00568996 0 P 0 ;0
L 1.21443996 -2.00568996 1.21485 -1.99883996 0 P 0 ;0
L 1.21485 -1.99883996 1.2149 -1.99721004 0 P 0 ;0
L 1.2149 -1.99721004 1.21488996 -1.99703996 0 P 0 ;0
L 1.21488996 -1.99703996 1.21486998 -1.99686004 0 P 0 ;0
L 1.21486998 -1.99686004 1.21483996 -1.99668996 0 P 0 ;0
L 1.21483996 -1.99668996 1.21478996 -1.99653002 0 P 0 ;0
L 1.21478996 -1.99653002 1.21473002 -1.99636998 0 P 0 ;0
L 1.21473002 -1.99636998 1.21466004 -1.99621004 0 P 0 ;0
L 1.21466004 -1.99621004 1.21458002 -1.99606004 0 P 0 ;0
L 1.21458002 -1.99606004 1.21448002 -1.99591004 0 P 0 ;0
L 1.21448002 -1.99591004 1.21433002 -1.99571998 0 P 0 ;0
L 1.21433002 -1.99571998 1.21416998 -1.99553996 0 P 0 ;0
L 1.21416998 -1.99553996 1.21398996 -1.99538002 0 P 0 ;0
L 1.21398996 -1.99538002 1.21378996 -1.99523996 0 P 0 ;0
L 1.21378996 -1.99523996 1.21358002 -1.99511004 0 P 0 ;0
L 1.21358002 -1.99511004 1.21336004 -1.995 0 P 0 ;0
L 1.21336004 -1.995 1.21261004 -1.99468996 0 P 0 ;0
L 1.21261004 -1.99468996 1.21183996 -1.99443996 0 P 0 ;0
L 1.21183996 -1.99443996 1.21105 -1.99423002 0 P 0 ;0
L 1.21105 -1.99423002 1.20593996 -1.99318002 0 P 0 ;0
L 1.20593996 -1.99318002 1.18996998 -1.99065 0 P 0 ;0
L 1.18996998 -1.99065 1.17318996 -1.98908002 0 P 0 ;0
L 1.17318996 -1.98908002 1.15718996 -1.98858002 0 P 0 ;0
L 1.15718996 -1.98858002 1.1504 -1.98876004 0 P 0 ;0
L 1.1504 -1.98876004 1.14356998 -1.98926998 0 P 0 ;0
L 1.04503996 -2.19061998 1.05141998 -2.19061998 0 P 0 ;0
L 1.04893002 -2.18961998 1.05323002 -2.18961998 0 P 0 ;0
L 1.05263002 -2.18861998 1.05503996 -2.18861998 0 P 0 ;0
L 1.05628996 -2.18761998 1.05676004 -2.18761998 0 P 0 ;0
L 1.09645 -2.17983002 1.16738002 -2.17983002 0 P 0 ;0
L 1.09126004 -2.17883002 1.17091004 -2.17883002 0 P 0 ;0
L 1.0868 -2.17783002 1.17386998 -2.17783002 0 P 0 ;0
L 1.08368002 -2.17683002 1.17636004 -2.17683002 0 P 0 ;0
L 1.0836 -2.17583002 1.1787 -2.17583002 0 P 0 ;0
L 1.08351998 -2.17483002 1.18066998 -2.17483002 0 P 0 ;0
L 1.08345 -2.17383002 1.18236998 -2.17383002 0 P 0 ;0
L 1.08336998 -2.17283002 1.1839 -2.17283002 0 P 0 ;0
L 1.08328996 -2.17183002 1.18526998 -2.17183002 0 P 0 ;0
L 1.08321998 -2.17083002 1.18646998 -2.17083002 0 P 0 ;0
L 1.08313996 -2.16983002 1.18761998 -2.16983002 0 P 0 ;0
L 1.08306998 -2.16883002 1.18863996 -2.16883002 0 P 0 ;0
L 1.08298996 -2.16783002 1.18966004 -2.16783002 0 P 0 ;0
L 1.08291998 -2.16683002 1.19061004 -2.16683002 0 P 0 ;0
L 1.08283996 -2.16583002 1.1915 -2.16583002 0 P 0 ;0
L 1.08276004 -2.16483002 1.19238996 -2.16483002 0 P 0 ;0
L 1.08268996 -2.16383002 1.19321004 -2.16383002 0 P 0 ;0
L 1.08261004 -2.16283002 1.19398002 -2.16283002 0 P 0 ;0
L 1.08253002 -2.16183002 1.19476004 -2.16183002 0 P 0 ;0
L 1.08246004 -2.16083002 1.19548002 -2.16083002 0 P 0 ;0
L 1.08238002 -2.15983002 1.19613996 -2.15983002 0 P 0 ;0
L 1.08231004 -2.15883002 1.19681004 -2.15883002 0 P 0 ;0
L 1.08223996 -2.15783002 1.19746004 -2.15783002 0 P 0 ;0
L 1.13506998 -2.18383002 1.12553002 -2.18343996 0 P 0 ;0
L 1.12553002 -2.18343996 1.11266004 -2.18218002 0 P 0 ;0
L 1.11266004 -2.18218002 1.09983002 -2.18048002 0 P 0 ;0
L 1.09983002 -2.18048002 1.09036998 -2.17866004 0 P 0 ;0
L 1.09036998 -2.17866004 1.0837 -2.17711004 0 P 0 ;0
L 1.0837 -2.17711004 1.08245 -2.16066998 0 P 0 ;0
L 1.08245 -2.16066998 1.08193996 -2.15361998 0 P 0 ;0
L 1.08193996 -2.15361998 1.08156998 -2.14726004 0 P 0 ;0
L 1.08156998 -2.14726004 1.08131998 -2.14191004 0 P 0 ;0
L 1.08131998 -2.14191004 1.08131004 -2.14108996 0 P 0 ;0
L 1.08131004 -2.14108996 1.08136004 -2.14026004 0 P 0 ;0
L 1.08136004 -2.14026004 1.0814 -2.13986998 0 P 0 ;0
L 1.0814 -2.13986998 1.08996004 -2.14233002 0 P 0 ;0
L 1.08996004 -2.14233002 1.08996998 -2.14233996 0 P 0 ;0
L 1.08996998 -2.14233996 1.08998996 -2.14233996 0 P 0 ;0
L 1.08998996 -2.14233996 1.099 -2.14471998 0 P 0 ;0
L 1.099 -2.14471998 1.10806998 -2.14668002 0 P 0 ;0
L 1.10806998 -2.14668002 1.11598002 -2.14791998 0 P 0 ;0
L 1.11598002 -2.14791998 1.12395 -2.1486 0 P 0 ;0
L 1.12395 -2.1486 1.13048996 -2.14863996 0 P 0 ;0
L 1.13048996 -2.14863996 1.137 -2.14811998 0 P 0 ;0
L 1.137 -2.14811998 1.13903002 -2.14778996 0 P 0 ;0
L 1.13903002 -2.14778996 1.14103002 -2.14728996 0 P 0 ;0
L 1.14103002 -2.14728996 1.14298002 -2.14661998 0 P 0 ;0
L 1.14298002 -2.14661998 1.14486998 -2.14581004 0 P 0 ;0
L 1.14486998 -2.14581004 1.14668002 -2.14483996 0 P 0 ;0
L 1.14668002 -2.14483996 1.1484 -2.14373996 0 P 0 ;0
L 1.1484 -2.14373996 1.15003002 -2.1425 0 P 0 ;0
L 1.15003002 -2.1425 1.15155 -2.14115 0 P 0 ;0
L 1.15155 -2.14115 1.1526 -2.14006998 0 P 0 ;0
L 1.1526 -2.14006998 1.15263996 -2.14001998 0 P 0 ;0
L 1.15263996 -2.14001998 1.15356004 -2.13893002 0 P 0 ;0
L 1.15356004 -2.13893002 1.15443996 -2.13771998 0 P 0 ;0
L 1.15443996 -2.13771998 1.15523002 -2.13646004 0 P 0 ;0
L 1.15523002 -2.13646004 1.15593996 -2.13515 0 P 0 ;0
L 1.15593996 -2.13515 1.15655 -2.13381004 0 P 0 ;0
L 1.15655 -2.13381004 1.15706004 -2.13243002 0 P 0 ;0
L 1.15706004 -2.13243002 1.15748002 -2.13101004 0 P 0 ;0
L 1.15748002 -2.13101004 1.1579 -2.12905 0 P 0 ;0
L 1.1579 -2.12905 1.15816004 -2.12706004 0 P 0 ;0
L 1.15816004 -2.12706004 1.15825 -2.12506998 0 P 0 ;0
L 1.15825 -2.12506998 1.15818002 -2.12165 0 P 0 ;0
L 1.15818002 -2.12165 1.15813996 -2.12118002 0 P 0 ;0
L 1.15813996 -2.12118002 1.15813002 -2.1211 0 P 0 ;0
L 1.15813002 -2.1211 1.15806004 -2.12068002 0 P 0 ;0
L 1.15806004 -2.12068002 1.15793996 -2.12018996 0 P 0 ;0
L 1.15793996 -2.12018996 1.15778002 -2.11973002 0 P 0 ;0
L 1.15778002 -2.11973002 1.1577 -2.11953002 0 P 0 ;0
L 1.1577 -2.11953002 1.15758996 -2.11933002 0 P 0 ;0
L 1.15758996 -2.11933002 1.15746998 -2.11913996 0 P 0 ;0
L 1.15746998 -2.11913996 1.15733002 -2.11895 0 P 0 ;0
L 1.15733002 -2.11895 1.15716998 -2.11878002 0 P 0 ;0
L 1.15716998 -2.11878002 1.157 -2.11863002 0 P 0 ;0
L 1.157 -2.11863002 1.15681998 -2.11848996 0 P 0 ;0
L 1.15681998 -2.11848996 1.15663002 -2.11836004 0 P 0 ;0
L 1.15663002 -2.11836004 1.15641998 -2.11825 0 P 0 ;0
L 1.15641998 -2.11825 1.15621004 -2.11816004 0 P 0 ;0
L 1.15621004 -2.11816004 1.15598996 -2.11808996 0 P 0 ;0
L 1.15598996 -2.11808996 1.15576998 -2.11803996 0 P 0 ;0
L 1.15576998 -2.11803996 1.15553002 -2.118 0 P 0 ;0
L 1.15553002 -2.118 1.15518002 -2.11798002 0 P 0 ;0
L 1.15518002 -2.11798002 1.15483996 -2.11798996 0 P 0 ;0
L 1.15483996 -2.11798996 1.15451004 -2.11803002 0 P 0 ;0
L 1.15451004 -2.11803002 1.15418002 -2.1181 0 P 0 ;0
L 1.15418002 -2.1181 1.15386004 -2.1182 0 P 0 ;0
L 1.15386004 -2.1182 1.15361004 -2.11828996 0 P 0 ;0
L 1.15361004 -2.11828996 1.14705 -2.12083996 0 P 0 ;0
L 1.14705 -2.12083996 1.14038996 -2.12278996 0 P 0 ;0
L 1.14038996 -2.12278996 1.13356004 -2.12416004 0 P 0 ;0
L 1.13356004 -2.12416004 1.1285 -2.12476998 0 P 0 ;0
L 1.1285 -2.12476998 1.12341004 -2.12501998 0 P 0 ;0
L 1.12341004 -2.12501998 1.11831004 -2.12493002 0 P 0 ;0
L 1.11831004 -2.12493002 1.11323002 -2.12448996 0 P 0 ;0
L 1.11323002 -2.12448996 1.10848996 -2.12373002 0 P 0 ;0
L 1.10848996 -2.12373002 1.10383996 -2.12263002 0 P 0 ;0
L 1.10383996 -2.12263002 1.09926998 -2.12118996 0 P 0 ;0
L 1.09926998 -2.12118996 1.09481004 -2.11941004 0 P 0 ;0
L 1.09481004 -2.11941004 1.09168002 -2.11788002 0 P 0 ;0
L 1.09168002 -2.11788002 1.08866004 -2.11611998 0 P 0 ;0
L 1.08866004 -2.11611998 1.08578002 -2.11413002 0 P 0 ;0
L 1.08578002 -2.11413002 1.08306998 -2.11193996 0 P 0 ;0
L 1.08306998 -2.11193996 1.08051998 -2.10955 0 P 0 ;0
L 1.08051998 -2.10955 1.07793996 -2.10673002 0 P 0 ;0
L 1.07793996 -2.10673002 1.07561004 -2.10373996 0 P 0 ;0
L 1.07561004 -2.10373996 1.07351004 -2.10058002 0 P 0 ;0
L 1.07351004 -2.10058002 1.07171004 -2.09733996 0 P 0 ;0
L 1.07171004 -2.09733996 1.07018002 -2.09396998 0 P 0 ;0
L 1.07018002 -2.09396998 1.06893996 -2.09048002 0 P 0 ;0
L 1.06893996 -2.09048002 1.06786004 -2.0865 0 P 0 ;0
L 1.06786004 -2.0865 1.06706004 -2.08243996 0 P 0 ;0
L 1.06706004 -2.08243996 1.06656004 -2.07833002 0 P 0 ;0
L 1.06656004 -2.07833002 1.06615 -2.07071004 0 P 0 ;0
L 1.06615 -2.07071004 1.06621004 -2.06313996 0 P 0 ;0
L 1.06621004 -2.06313996 1.06675 -2.0556 0 P 0 ;0
L 1.06675 -2.0556 1.0678 -2.04813002 0 P 0 ;0
L 1.0678 -2.04813002 1.06868996 -2.04391998 0 P 0 ;0
L 1.06868996 -2.04391998 1.06985 -2.03981004 0 P 0 ;0
L 1.06985 -2.03981004 1.0713 -2.03578996 0 P 0 ;0
L 1.0713 -2.03578996 1.07296004 -2.03206998 0 P 0 ;0
L 1.07296004 -2.03206998 1.07486998 -2.02848996 0 P 0 ;0
L 1.07486998 -2.02848996 1.07705 -2.02506004 0 P 0 ;0
L 1.07705 -2.02506004 1.07966004 -2.0215 0 P 0 ;0
L 1.07966004 -2.0215 1.08246998 -2.01811004 0 P 0 ;0
L 1.08246998 -2.01811004 1.08546998 -2.01491004 0 P 0 ;0
L 1.08546998 -2.01491004 1.0897 -2.01091004 0 P 0 ;0
L 1.0897 -2.01091004 1.09153002 -2.00936998 0 P 0 ;0
L 1.09153002 -2.00936998 1.09341998 -2.00793996 0 P 0 ;0
L 1.09341998 -2.00793996 1.09545 -2.00658002 0 P 0 ;0
L 1.09545 -2.00658002 1.09751004 -2.00533996 0 P 0 ;0
L 1.09751004 -2.00533996 1.10288002 -2.0025 0 P 0 ;0
L 1.10288002 -2.0025 1.10736998 -2.00043002 0 P 0 ;0
L 1.10736998 -2.00043002 1.11193002 -1.99861004 0 P 0 ;0
L 1.11193002 -1.99861004 1.12218002 -1.99533002 0 P 0 ;0
L 1.12218002 -1.99533002 1.13298002 -1.99281998 0 P 0 ;0
L 1.13298002 -1.99281998 1.14378996 -1.99126004 0 P 0 ;0
L 1.14378996 -1.99126004 1.1505 -1.99075 0 P 0 ;0
L 1.1505 -1.99075 1.15718002 -1.99058996 0 P 0 ;0
L 1.15718002 -1.99058996 1.17306998 -1.99108002 0 P 0 ;0
L 1.17306998 -1.99108002 1.18971998 -1.99263002 0 P 0 ;0
L 1.18971998 -1.99263002 1.20558002 -1.99515 0 P 0 ;0
L 1.20558002 -1.99515 1.21058996 -1.99618002 0 P 0 ;0
L 1.21058996 -1.99618002 1.21126998 -1.99636004 0 P 0 ;0
L 1.21126998 -1.99636004 1.21191998 -1.99656998 0 P 0 ;0
L 1.21191998 -1.99656998 1.21253002 -1.99681998 0 P 0 ;0
L 1.21253002 -1.99681998 1.21261004 -1.99686004 0 P 0 ;0
L 1.21261004 -1.99686004 1.21266004 -1.99688996 0 P 0 ;0
L 1.21266004 -1.99688996 1.21271998 -1.99693002 0 P 0 ;0
L 1.21271998 -1.99693002 1.21281998 -1.99703002 0 P 0 ;0
L 1.21281998 -1.99703002 1.21286004 -1.99708996 0 P 0 ;0
L 1.21286004 -1.99708996 1.21288002 -1.99711004 0 P 0 ;0
L 1.21288002 -1.99711004 1.21288002 -1.99711998 0 P 0 ;0
L 1.21288002 -1.99711998 1.21288996 -1.99715 0 P 0 ;0
L 1.21288996 -1.99715 1.2129 -1.99716998 0 P 0 ;0
L 1.2129 -1.99716998 1.2129 -1.99721998 0 P 0 ;0
L 1.2129 -1.99721998 1.21285 -1.99875 0 P 0 ;0
L 1.21285 -1.99875 1.21243996 -2.00556998 0 P 0 ;0
L 1.21243996 -2.00556998 1.21193996 -2.01361004 0 P 0 ;0
L 1.21193996 -2.01361004 1.21133996 -2.02273002 0 P 0 ;0
L 1.21133996 -2.02273002 1.21133996 -2.02273996 0 P 0 ;0
L 1.21133996 -2.02273996 1.21058996 -2.03468002 0 P 0 ;0
L 1.21058996 -2.03468002 1.20956004 -2.05216998 0 P 0 ;0
L 1.20956004 -2.05216998 1.20848996 -2.07156004 0 P 0 ;0
L 1.20848996 -2.07156004 1.20848996 -2.07156998 0 P 0 ;0
L 1.20848996 -2.07156998 1.20751004 -2.09011004 0 P 0 ;0
L 1.20751004 -2.09011004 1.20658996 -2.10743996 0 P 0 ;0
L 1.20658996 -2.10743996 1.20561998 -2.12308996 0 P 0 ;0
L 1.20561998 -2.12308996 1.20473002 -2.13618996 0 P 0 ;0
L 1.20473002 -2.13618996 1.20453002 -2.13831998 0 P 0 ;0
L 1.20453002 -2.13831998 1.20423996 -2.14041004 0 P 0 ;0
L 1.20423996 -2.14041004 1.2035 -2.144 0 P 0 ;0
L 1.2035 -2.144 1.20246004 -2.1475 0 P 0 ;0
L 1.20246004 -2.1475 1.20111998 -2.1509 0 P 0 ;0
L 1.20111998 -2.1509 1.19936998 -2.1545 0 P 0 ;0
L 1.19936998 -2.1545 1.19738002 -2.15796998 0 P 0 ;0
L 1.19738002 -2.15796998 1.19516004 -2.1613 0 P 0 ;0
L 1.19516004 -2.1613 1.19276998 -2.16441004 0 P 0 ;0
L 1.19276998 -2.16441004 1.19016004 -2.16733996 0 P 0 ;0
L 1.19016004 -2.16733996 1.18736004 -2.17008002 0 P 0 ;0
L 1.18736004 -2.17008002 1.1854 -2.17173996 0 P 0 ;0
L 1.1854 -2.17173996 1.18335 -2.17323002 0 P 0 ;0
L 1.18335 -2.17323002 1.18118002 -2.17456004 0 P 0 ;0
L 1.18118002 -2.17456004 1.17893002 -2.17573002 0 P 0 ;0
L 1.17893002 -2.17573002 1.17456998 -2.1776 0 P 0 ;0
L 1.17456998 -2.1776 1.17006998 -2.17911998 0 P 0 ;0
L 1.17006998 -2.17911998 1.16473996 -2.18053002 0 P 0 ;0
L 1.16473996 -2.18053002 1.15935 -2.18166998 0 P 0 ;0
L 1.15935 -2.18166998 1.15341998 -2.18263002 0 P 0 ;0
L 1.15341998 -2.18263002 1.1475 -2.18328996 0 P 0 ;0
L 1.1475 -2.18328996 1.13506998 -2.18383002 0 P 0 ;0
L 0.90491998 -2.21461998 1.00131004 -2.21461998 0 P 0 ;0
L 0.92235 -2.21361998 1.00355 -2.21361998 0 P 0 ;0
L 0.76925 -1.8965 0.85586998 -1.8965 0 P 0 ;0
L 0.76958996 -1.8955 0.85556004 -1.8955 0 P 0 ;0
L 0.76995 -1.8945 0.85521004 -1.8945 0 P 0 ;0
L 0.77031004 -1.8935 0.85486004 -1.8935 0 P 0 ;0
L 0.77071004 -1.8925 0.85443996 -1.8925 0 P 0 ;0
L 0.77115 -1.8915 0.85401004 -1.8915 0 P 0 ;0
L 0.7716 -1.8905 0.85355 -1.8905 0 P 0 ;0
L 0.77206004 -1.8895 0.85303002 -1.8895 0 P 0 ;0
L 0.7726 -1.8885 0.85251004 -1.8885 0 P 0 ;0
L 0.77313996 -1.8875 0.85198996 -1.8875 0 P 0 ;0
L 0.77368996 -1.8865 0.85138002 -1.8865 0 P 0 ;0
L 0.77433002 -1.8855 0.85073996 -1.8855 0 P 0 ;0
L 0.77496004 -1.8845 0.85011004 -1.8845 0 P 0 ;0
L 0.77561998 -1.8835 0.84943002 -1.8835 0 P 0 ;0
L 0.77636004 -1.8825 0.84866998 -1.8825 0 P 0 ;0
L 0.77711004 -1.8815 0.84791004 -1.8815 0 P 0 ;0
L 0.7779 -1.8805 0.84713002 -1.8805 0 P 0 ;0
L 0.77876998 -1.8795 0.84623002 -1.8795 0 P 0 ;0
L 0.77963996 -1.8785 0.84533002 -1.8785 0 P 0 ;0
L 0.7806 -1.8775 0.8444 -1.8775 0 P 0 ;0
L 0.78161004 -1.8765 0.84335 -1.8765 0 P 0 ;0
L 0.78265 -1.8755 0.84228996 -1.8755 0 P 0 ;0
L 0.78381998 -1.8745 0.84108996 -1.8745 0 P 0 ;0
L 0.78498996 -1.8735 0.83986998 -1.8735 0 P 0 ;0
L 0.78635 -1.8725 0.83848002 -1.8725 0 P 0 ;0
L 0.78773002 -1.8715 0.83706004 -1.8715 0 P 0 ;0
L 0.78933002 -1.8705 0.83541998 -1.8705 0 P 0 ;0
L 0.791 -1.8695 0.83366004 -1.8695 0 P 0 ;0
L 0.793 -1.8685 0.83171998 -1.8685 0 P 0 ;0
L 0.79525 -1.8675 0.82941998 -1.8675 0 P 0 ;0
L 0.79791998 -1.8665 0.82671004 -1.8665 0 P 0 ;0
L 0.80143996 -1.8655 0.82328996 -1.8655 0 P 0 ;0
L 0.80705 -1.8645 0.81776004 -1.8645 0 P 0 ;0
L 0.74543002 -1.89661998 0.75033002 -1.89661998 0 P 0 ;0
L 0.74751004 -1.89561998 0.75058996 -1.89561998 0 P 0 ;0
L 0.74958996 -1.89461998 0.75086004 -1.89461998 0 P 0 ;0
L 0.76733996 -1.9125 0.85751998 -1.9125 0 P 0 ;0
L 0.76728996 -1.9115 0.85756004 -1.9115 0 P 0 ;0
L 0.76723996 -1.9105 0.85758996 -1.9105 0 P 0 ;0
L 0.76721998 -1.9095 0.85763002 -1.9095 0 P 0 ;0
L 0.76725 -1.9085 0.85761004 -1.9085 0 P 0 ;0
L 0.76728002 -1.9075 0.85756998 -1.9075 0 P 0 ;0
L 0.76731004 -1.9065 0.85753002 -1.9065 0 P 0 ;0
L 0.76741998 -1.9055 0.85748996 -1.9055 0 P 0 ;0
L 0.76753996 -1.9045 0.85738002 -1.9045 0 P 0 ;0
L 0.76766004 -1.9035 0.85726004 -1.9035 0 P 0 ;0
L 0.76781998 -1.9025 0.85713996 -1.9025 0 P 0 ;0
L 0.76801998 -1.9015 0.85701004 -1.9015 0 P 0 ;0
L 0.76821004 -1.9005 0.85683002 -1.9005 0 P 0 ;0
L 0.76841998 -1.8995 0.85661998 -1.8995 0 P 0 ;0
L 0.7687 -1.8985 0.85641004 -1.8985 0 P 0 ;0
L 0.76896998 -1.8975 0.85613996 -1.8975 0 P 0 ;0
L 0.76751004 -2.08325 0.8416 -2.08325 0 P 0 ;0
L 0.76761998 -2.08225 0.84161998 -2.08225 0 P 0 ;0
L 0.76773996 -2.08125 0.84166998 -2.08125 0 P 0 ;0
L 0.76786004 -2.08025 0.84171998 -2.08025 0 P 0 ;0
L 0.76796998 -2.07925 0.84176998 -2.07925 0 P 0 ;0
L 0.76808002 -2.07825 0.84181004 -2.07825 0 P 0 ;0
L 0.76818002 -2.07725 0.84186004 -2.07725 0 P 0 ;0
L 0.76828996 -2.07625 0.8419 -2.07625 0 P 0 ;0
L 0.76838996 -2.07525 0.84195 -2.07525 0 P 0 ;0
L 0.76848996 -2.07425 0.842 -2.07425 0 P 0 ;0
L 0.7686 -2.07325 0.84205 -2.07325 0 P 0 ;0
L 0.7687 -2.07225 0.84208996 -2.07225 0 P 0 ;0
L 0.7688 -2.07125 0.84213996 -2.07125 0 P 0 ;0
L 0.7689 -2.07025 0.84218002 -2.07025 0 P 0 ;0
L 0.76901004 -2.06925 0.84223002 -2.06925 0 P 0 ;0
L 0.76911004 -2.06825 0.84228002 -2.06825 0 P 0 ;0
L 0.76921004 -2.06725 0.84233002 -2.06725 0 P 0 ;0
L 0.76931998 -2.06625 0.84236998 -2.06625 0 P 0 ;0
L 0.76941998 -2.06525 0.84241998 -2.06525 0 P 0 ;0
L 0.76948996 -2.06425 0.84246004 -2.06425 0 P 0 ;0
L 0.76956004 -2.06325 0.84251004 -2.06325 0 P 0 ;0
L 0.76963002 -2.06225 0.84256004 -2.06225 0 P 0 ;0
L 0.7697 -2.06125 0.8426 -2.06125 0 P 0 ;0
L 0.76976998 -2.06025 0.84265 -2.06025 0 P 0 ;0
L 0.76983996 -2.05925 0.8427 -2.05925 0 P 0 ;0
L 0.76991004 -2.05825 0.84273996 -2.05825 0 P 0 ;0
L 0.76996998 -2.05725 0.84278996 -2.05725 0 P 0 ;0
L 0.77001004 -2.05625 0.84283996 -2.05625 0 P 0 ;0
L 0.77003996 -2.05525 0.84288002 -2.05525 0 P 0 ;0
L 0.77008002 -2.05425 0.84295 -2.05425 0 P 0 ;0
L 0.77011998 -2.05325 0.84303996 -2.05325 0 P 0 ;0
L 0.77016004 -2.05225 0.84311998 -2.05225 0 P 0 ;0
L 0.77018996 -2.05125 0.84321004 -2.05125 0 P 0 ;0
L 0.77023002 -2.05025 0.8433 -2.05025 0 P 0 ;0
L 0.77026998 -2.04925 0.84338002 -2.04925 0 P 0 ;0
L 0.77031004 -2.04825 0.84346998 -2.04825 0 P 0 ;0
L 0.77033996 -2.04725 0.84356004 -2.04725 0 P 0 ;0
L 0.77038002 -2.04625 0.84363996 -2.04625 0 P 0 ;0
L 0.77041004 -2.04525 0.84373002 -2.04525 0 P 0 ;0
L 0.77043996 -2.04425 0.84381004 -2.04425 0 P 0 ;0
L 0.77046004 -2.04325 0.8439 -2.04325 0 P 0 ;0
L 0.77048002 -2.04225 0.84398996 -2.04225 0 P 0 ;0
L 0.77051004 -2.04125 0.84406998 -2.04125 0 P 0 ;0
L 0.77053002 -2.04025 0.84416004 -2.04025 0 P 0 ;0
L 0.77055 -2.03925 0.84425 -2.03925 0 P 0 ;0
L 0.77058002 -2.03825 0.84433002 -2.03825 0 P 0 ;0
L 0.7706 -2.03725 0.84441998 -2.03725 0 P 0 ;0
L 0.77061998 -2.03625 0.84451004 -2.03625 0 P 0 ;0
L 0.77065 -2.03525 0.84458996 -2.03525 0 P 0 ;0
L 0.77066998 -2.03425 0.84468002 -2.03425 0 P 0 ;0
L 0.7707 -2.03325 0.84476998 -2.03325 0 P 0 ;0
L 0.77071998 -2.03225 0.84485 -2.03225 0 P 0 ;0
L 0.77073002 -2.03125 0.84493996 -2.03125 0 P 0 ;0
L 0.77073996 -2.03025 0.84503002 -2.03025 0 P 0 ;0
L 0.79986004 -1.8638 0.79643996 -1.86486998 0 P 0 ;0
L 0.79643996 -1.86486998 0.79311998 -1.86621004 0 P 0 ;0
L 0.79311998 -1.86621004 0.78991004 -1.86781004 0 P 0 ;0
L 0.78991004 -1.86781004 0.78683996 -1.86966998 0 P 0 ;0
L 0.78683996 -1.86966998 0.78391998 -1.87178002 0 P 0 ;0
L 0.78391998 -1.87178002 0.78111998 -1.87416998 0 P 0 ;0
L 0.78111998 -1.87416998 0.7785 -1.87676004 0 P 0 ;0
L 0.7785 -1.87676004 0.77608002 -1.87953996 0 P 0 ;0
L 0.77608002 -1.87953996 0.77386998 -1.8825 0 P 0 ;0
L 0.77386998 -1.8825 0.77188002 -1.88561998 0 P 0 ;0
L 0.77188002 -1.88561998 0.77013996 -1.88886004 0 P 0 ;0
L 0.77013996 -1.88886004 0.76863996 -1.89221004 0 P 0 ;0
L 0.76863996 -1.89221004 0.7674 -1.89566998 0 P 0 ;0
L 0.7674 -1.89566998 0.76643002 -1.89921004 0 P 0 ;0
L 0.76643002 -1.89921004 0.76571004 -1.90283996 0 P 0 ;0
L 0.76571004 -1.90283996 0.76531004 -1.90636004 0 P 0 ;0
L 0.76531004 -1.90636004 0.7652 -1.90991004 0 P 0 ;0
L 0.7652 -1.90991004 0.76538996 -1.91345 0 P 0 ;0
L 0.76538996 -1.91345 0.76586998 -1.91696998 0 P 0 ;0
L 0.76586998 -1.91696998 0.76663996 -1.92046004 0 P 0 ;0
L 0.76663996 -1.92046004 0.76803002 -1.92493996 0 P 0 ;0
L 0.76803002 -1.92493996 0.76978002 -1.9293 0 P 0 ;0
L 0.76978002 -1.9293 0.77106998 -1.93193996 0 P 0 ;0
L 0.77106998 -1.93193996 0.77253002 -1.93448002 0 P 0 ;0
L 0.77253002 -1.93448002 0.77416004 -1.93693996 0 P 0 ;0
L 0.77416004 -1.93693996 0.77593002 -1.93923002 0 P 0 ;0
L 0.77593002 -1.93923002 0.77783996 -1.94141004 0 P 0 ;0
L 0.77783996 -1.94141004 0.77988996 -1.94345 0 P 0 ;0
L 0.77988996 -1.94345 0.78216004 -1.94545 0 P 0 ;0
L 0.78216004 -1.94545 0.78453996 -1.9473 0 P 0 ;0
L 0.78453996 -1.9473 0.78703002 -1.94901998 0 P 0 ;0
L 0.78703002 -1.94901998 0.79016998 -1.95088002 0 P 0 ;0
L 0.79016998 -1.95088002 0.79343996 -1.95248996 0 P 0 ;0
L 0.79343996 -1.95248996 0.79683002 -1.95383996 0 P 0 ;0
L 0.79683002 -1.95383996 0.80031998 -1.95491998 0 P 0 ;0
L 0.80031998 -1.95491998 0.80391004 -1.95573996 0 P 0 ;0
L 0.80391004 -1.95573996 0.80751998 -1.95626004 0 P 0 ;0
L 0.80751998 -1.95626004 0.81116004 -1.9565 0 P 0 ;0
L 0.81116004 -1.9565 0.81481004 -1.95646004 0 P 0 ;0
L 0.81481004 -1.95646004 0.81843996 -1.95613002 0 P 0 ;0
L 0.81843996 -1.95613002 0.82205 -1.95551004 0 P 0 ;0
L 0.82205 -1.95551004 0.82561998 -1.95461004 0 P 0 ;0
L 0.82561998 -1.95461004 0.82911004 -1.95345 0 P 0 ;0
L 0.82911004 -1.95345 0.83248996 -1.95201004 0 P 0 ;0
L 0.83248996 -1.95201004 0.83576004 -1.95031998 0 P 0 ;0
L 0.83576004 -1.95031998 0.83891998 -1.94836004 0 P 0 ;0
L 0.83891998 -1.94836004 0.84191998 -1.94616998 0 P 0 ;0
L 0.84191998 -1.94616998 0.84475 -1.94375 0 P 0 ;0
L 0.84475 -1.94375 0.84738996 -1.94113996 0 P 0 ;0
L 0.84738996 -1.94113996 0.84983002 -1.93833996 0 P 0 ;0
L 0.84983002 -1.93833996 0.85206998 -1.93533996 0 P 0 ;0
L 0.85206998 -1.93533996 0.8536 -1.93291998 0 P 0 ;0
L 0.8536 -1.93291998 0.85496004 -1.93041004 0 P 0 ;0
L 0.85496004 -1.93041004 0.85613996 -1.9278 0 P 0 ;0
L 0.85613996 -1.9278 0.85711998 -1.92511004 0 P 0 ;0
L 0.85711998 -1.92511004 0.85823002 -1.92123002 0 P 0 ;0
L 0.85823002 -1.92123002 0.85901998 -1.91726998 0 P 0 ;0
L 0.85901998 -1.91726998 0.85948996 -1.91323996 0 P 0 ;0
L 0.85948996 -1.91323996 0.85963996 -1.90918002 0 P 0 ;0
L 0.85963996 -1.90918002 0.85946998 -1.90513002 0 P 0 ;0
L 0.85946998 -1.90513002 0.85898002 -1.9011 0 P 0 ;0
L 0.85898002 -1.9011 0.85841998 -1.89826004 0 P 0 ;0
L 0.85841998 -1.89826004 0.85766004 -1.89546004 0 P 0 ;0
L 0.85766004 -1.89546004 0.85671004 -1.89273002 0 P 0 ;0
L 0.85671004 -1.89273002 0.85556998 -1.89006004 0 P 0 ;0
L 0.85556998 -1.89006004 0.85361998 -1.88631004 0 P 0 ;0
L 0.85361998 -1.88631004 0.85136004 -1.88273996 0 P 0 ;0
L 0.85136004 -1.88273996 0.84881004 -1.87938002 0 P 0 ;0
L 0.84881004 -1.87938002 0.84596998 -1.87623002 0 P 0 ;0
L 0.84596998 -1.87623002 0.84355 -1.87393996 0 P 0 ;0
L 0.84355 -1.87393996 0.84096998 -1.87181998 0 P 0 ;0
L 0.84096998 -1.87181998 0.83826004 -1.86988996 0 P 0 ;0
L 0.83826004 -1.86988996 0.83541004 -1.86815 0 P 0 ;0
L 0.83541004 -1.86815 0.83243996 -1.86661004 0 P 0 ;0
L 0.83243996 -1.86661004 0.82938996 -1.86531004 0 P 0 ;0
L 0.82938996 -1.86531004 0.82625 -1.86423002 0 P 0 ;0
L 0.82625 -1.86423002 0.82303996 -1.86336004 0 P 0 ;0
L 0.82303996 -1.86336004 0.81978002 -1.86273002 0 P 0 ;0
L 0.81978002 -1.86273002 0.81646998 -1.86233002 0 P 0 ;0
L 0.81646998 -1.86233002 0.81228996 -1.86215 0 P 0 ;0
L 0.81228996 -1.86215 0.80811004 -1.86233996 0 P 0 ;0
L 0.80811004 -1.86233996 0.80396004 -1.86288996 0 P 0 ;0
L 0.80396004 -1.86288996 0.79986004 -1.8638 0 P 0 ;0
L 0.80308996 -1.9535 0.82186004 -1.9535 0 P 0 ;0
L 0.79926004 -1.9525 0.82563996 -1.9525 0 P 0 ;0
L 0.79636004 -1.9515 0.82856998 -1.9515 0 P 0 ;0
L 0.79393002 -1.9505 0.83093996 -1.9505 0 P 0 ;0
L 0.7919 -1.9495 0.83298996 -1.9495 0 P 0 ;0
L 0.79008002 -1.9485 0.8349 -1.9485 0 P 0 ;0
L 0.78838996 -1.9475 0.83651004 -1.9475 0 P 0 ;0
L 0.7869 -1.9465 0.83806998 -1.9465 0 P 0 ;0
L 0.78548002 -1.9455 0.83943996 -1.9455 0 P 0 ;0
L 0.7842 -1.9445 0.84078996 -1.9445 0 P 0 ;0
L 0.78298002 -1.9435 0.84196998 -1.9435 0 P 0 ;0
L 0.78183996 -1.9425 0.84313996 -1.9425 0 P 0 ;0
L 0.78076998 -1.9415 0.84418996 -1.9415 0 P 0 ;0
L 0.77976004 -1.9405 0.8452 -1.9405 0 P 0 ;0
L 0.77883002 -1.9395 0.84616998 -1.9395 0 P 0 ;0
L 0.77793996 -1.9385 0.84703996 -1.9385 0 P 0 ;0
L 0.77711998 -1.9375 0.84791004 -1.9375 0 P 0 ;0
L 0.77635 -1.9365 0.84871004 -1.9365 0 P 0 ;0
L 0.77561004 -1.9355 0.84945 -1.9355 0 P 0 ;0
L 0.77493996 -1.9345 0.8502 -1.9345 0 P 0 ;0
L 0.77428002 -1.9335 0.85086998 -1.9335 0 P 0 ;0
L 0.7737 -1.9325 0.8515 -1.9325 0 P 0 ;0
L 0.77311998 -1.9315 0.8521 -1.9315 0 P 0 ;0
L 0.77258996 -1.9305 0.85263996 -1.9305 0 P 0 ;0
L 0.7721 -1.9295 0.85318002 -1.9295 0 P 0 ;0
L 0.77161004 -1.9285 0.85363002 -1.9285 0 P 0 ;0
L 0.77121004 -1.9275 0.85408002 -1.9275 0 P 0 ;0
L 0.77081004 -1.9265 0.85448002 -1.9265 0 P 0 ;0
L 0.77041004 -1.9255 0.85485 -1.9255 0 P 0 ;0
L 0.77001004 -1.9245 0.85521998 -1.9245 0 P 0 ;0
L 0.76968002 -1.9235 0.8555 -1.9235 0 P 0 ;0
L 0.76936998 -1.9225 0.85578996 -1.9225 0 P 0 ;0
L 0.76906004 -1.9215 0.85606998 -1.9215 0 P 0 ;0
L 0.76875 -1.9205 0.85633002 -1.9205 0 P 0 ;0
L 0.76848002 -1.9195 0.85653002 -1.9195 0 P 0 ;0
L 0.76826004 -1.9185 0.85673002 -1.9185 0 P 0 ;0
L 0.76803002 -1.9175 0.85693002 -1.9175 0 P 0 ;0
L 0.76783002 -1.9165 0.85708996 -1.9165 0 P 0 ;0
L 0.76768996 -1.9155 0.85721004 -1.9155 0 P 0 ;0
L 0.76755 -1.9145 0.85733002 -1.9145 0 P 0 ;0
L 0.76741998 -1.9135 0.85745 -1.9135 0 P 0 ;0
L 0.81121004 -1.9545 0.80773002 -1.95426998 0 P 0 ;0
L 0.80773002 -1.95426998 0.80426998 -1.95376998 0 P 0 ;0
L 0.80426998 -1.95376998 0.80083996 -1.95298996 0 P 0 ;0
L 0.80083996 -1.95298996 0.7975 -1.95195 0 P 0 ;0
L 0.7975 -1.95195 0.79426004 -1.95066004 0 P 0 ;0
L 0.79426004 -1.95066004 0.79111998 -1.94911998 0 P 0 ;0
L 0.79111998 -1.94911998 0.78811004 -1.94733002 0 P 0 ;0
L 0.78811004 -1.94733002 0.78573002 -1.94568996 0 P 0 ;0
L 0.78573002 -1.94568996 0.78343996 -1.9439 0 P 0 ;0
L 0.78343996 -1.9439 0.78126004 -1.94198996 0 P 0 ;0
L 0.78126004 -1.94198996 0.7793 -1.94003996 0 P 0 ;0
L 0.7793 -1.94003996 0.77746998 -1.93796004 0 P 0 ;0
L 0.77746998 -1.93796004 0.77578996 -1.93576998 0 P 0 ;0
L 0.77578996 -1.93576998 0.77423002 -1.93343002 0 P 0 ;0
L 0.77423002 -1.93343002 0.77283996 -1.931 0 P 0 ;0
L 0.77283996 -1.931 0.77161004 -1.92848996 0 P 0 ;0
L 0.77161004 -1.92848996 0.76991998 -1.92426998 0 P 0 ;0
L 0.76991998 -1.92426998 0.76858002 -1.91993996 0 P 0 ;0
L 0.76858002 -1.91993996 0.76783996 -1.91661998 0 P 0 ;0
L 0.76783996 -1.91661998 0.76738002 -1.91326998 0 P 0 ;0
L 0.76738002 -1.91326998 0.76721004 -1.90988996 0 P 0 ;0
L 0.76721004 -1.90988996 0.76731004 -1.90651004 0 P 0 ;0
L 0.76731004 -1.90651004 0.7677 -1.90315 0 P 0 ;0
L 0.7677 -1.90315 0.76838002 -1.89966998 0 P 0 ;0
L 0.76838002 -1.89966998 0.76931004 -1.89626998 0 P 0 ;0
L 0.76931004 -1.89626998 0.7705 -1.89296004 0 P 0 ;0
L 0.7705 -1.89296004 0.77193996 -1.88973996 0 P 0 ;0
L 0.77193996 -1.88973996 0.7736 -1.88663996 0 P 0 ;0
L 0.7736 -1.88663996 0.77551004 -1.88363996 0 P 0 ;0
L 0.77551004 -1.88363996 0.77763002 -1.8808 0 P 0 ;0
L 0.77763002 -1.8808 0.77996004 -1.87813002 0 P 0 ;0
L 0.77996004 -1.87813002 0.78246998 -1.87565 0 P 0 ;0
L 0.78246998 -1.87565 0.78516004 -1.87336004 0 P 0 ;0
L 0.78516004 -1.87336004 0.78795 -1.87133996 0 P 0 ;0
L 0.78795 -1.87133996 0.79088002 -1.86956004 0 P 0 ;0
L 0.79088002 -1.86956004 0.79393996 -1.86803002 0 P 0 ;0
L 0.79393996 -1.86803002 0.79711004 -1.86675 0 P 0 ;0
L 0.79711004 -1.86675 0.80038002 -1.86573002 0 P 0 ;0
L 0.80038002 -1.86573002 0.80431004 -1.86486004 0 P 0 ;0
L 0.80431004 -1.86486004 0.80828996 -1.86433996 0 P 0 ;0
L 0.80828996 -1.86433996 0.8123 -1.86416004 0 P 0 ;0
L 0.8123 -1.86416004 0.81631004 -1.86431998 0 P 0 ;0
L 0.81631004 -1.86431998 0.81946998 -1.86471004 0 P 0 ;0
L 0.81946998 -1.86471004 0.82258996 -1.86531004 0 P 0 ;0
L 0.82258996 -1.86531004 0.82566004 -1.86613996 0 P 0 ;0
L 0.82566004 -1.86613996 0.82866998 -1.86718002 0 P 0 ;0
L 0.82866998 -1.86718002 0.83158996 -1.86843002 0 P 0 ;0
L 0.83158996 -1.86843002 0.83443002 -1.86988996 0 P 0 ;0
L 0.83443002 -1.86988996 0.83716004 -1.87156004 0 P 0 ;0
L 0.83716004 -1.87156004 0.83976004 -1.87341004 0 P 0 ;0
L 0.83976004 -1.87341004 0.84223002 -1.87543996 0 P 0 ;0
L 0.84223002 -1.87543996 0.84453996 -1.87763002 0 P 0 ;0
L 0.84453996 -1.87763002 0.84726998 -1.88065 0 P 0 ;0
L 0.84726998 -1.88065 0.84971998 -1.88388002 0 P 0 ;0
L 0.84971998 -1.88388002 0.85188996 -1.88731004 0 P 0 ;0
L 0.85188996 -1.88731004 0.85376004 -1.89091004 0 P 0 ;0
L 0.85376004 -1.89091004 0.85483996 -1.89345 0 P 0 ;0
L 0.85483996 -1.89345 0.85575 -1.89605 0 P 0 ;0
L 0.85575 -1.89605 0.85646998 -1.89871004 0 P 0 ;0
L 0.85646998 -1.89871004 0.857 -1.90141004 0 P 0 ;0
L 0.857 -1.90141004 0.85748002 -1.9053 0 P 0 ;0
L 0.85748002 -1.9053 0.85763996 -1.90918996 0 P 0 ;0
L 0.85763996 -1.90918996 0.8575 -1.91308002 0 P 0 ;0
L 0.8575 -1.91308002 0.85703996 -1.91696004 0 P 0 ;0
L 0.85703996 -1.91696004 0.85628002 -1.92076004 0 P 0 ;0
L 0.85628002 -1.92076004 0.85521998 -1.92448996 0 P 0 ;0
L 0.85521998 -1.92448996 0.85428002 -1.92705 0 P 0 ;0
L 0.85428002 -1.92705 0.85316998 -1.92951998 0 P 0 ;0
L 0.85316998 -1.92951998 0.85188002 -1.93191004 0 P 0 ;0
L 0.85188002 -1.93191004 0.85041998 -1.9342 0 P 0 ;0
L 0.85041998 -1.9342 0.84826998 -1.93708002 0 P 0 ;0
L 0.84826998 -1.93708002 0.84593002 -1.93976998 0 P 0 ;0
L 0.84593002 -1.93976998 0.8434 -1.94228002 0 P 0 ;0
L 0.8434 -1.94228002 0.84068002 -1.9446 0 P 0 ;0
L 0.84068002 -1.9446 0.8378 -1.9467 0 P 0 ;0
L 0.8378 -1.9467 0.83476998 -1.94858002 0 P 0 ;0
L 0.83476998 -1.94858002 0.83163996 -1.9502 0 P 0 ;0
L 0.83163996 -1.9502 0.8284 -1.95158002 0 P 0 ;0
L 0.8284 -1.95158002 0.82506004 -1.95268996 0 P 0 ;0
L 0.82506004 -1.95268996 0.82163996 -1.95356004 0 P 0 ;0
L 0.82163996 -1.95356004 0.81818002 -1.95413996 0 P 0 ;0
L 0.81818002 -1.95413996 0.8147 -1.95446004 0 P 0 ;0
L 0.8147 -1.95446004 0.81121004 -1.9545 0 P 0 ;0
L 0.77075 -2.02925 0.84511004 -2.02925 0 P 0 ;0
L 0.77076004 -2.02825 0.8452 -2.02825 0 P 0 ;0
L 0.77076998 -2.02725 0.84528996 -2.02725 0 P 0 ;0
L 0.77078002 -2.02625 0.84536998 -2.02625 0 P 0 ;0
L 0.77078996 -2.02525 0.84548996 -2.02525 0 P 0 ;0
L 0.7708 -2.02425 0.84561998 -2.02425 0 P 0 ;0
L 0.77081004 -2.02325 0.84575 -2.02325 0 P 0 ;0
L 0.77081998 -2.02225 0.84588002 -2.02225 0 P 0 ;0
L 0.77083002 -2.02125 0.84601004 -2.02125 0 P 0 ;0
L 0.77083996 -2.02025 0.84613996 -2.02025 0 P 0 ;0
L 0.77085 -2.01925 0.84626004 -2.01925 0 P 0 ;0
L 0.77085 -2.01825 0.84638996 -2.01825 0 P 0 ;0
L 0.77085 -2.01725 0.84651998 -2.01725 0 P 0 ;0
L 0.77086004 -2.01625 0.84663996 -2.01625 0 P 0 ;0
L 0.77086004 -2.01525 0.84676998 -2.01525 0 P 0 ;0
L 0.77086004 -2.01425 0.8469 -2.01425 0 P 0 ;0
L 0.77086004 -2.01325 0.84703002 -2.01325 0 P 0 ;0
L 0.77086004 -2.01225 0.84716004 -2.01225 0 P 0 ;0
L 0.77086004 -2.01125 0.84728996 -2.01125 0 P 0 ;0
L 0.77086004 -2.01025 0.84741004 -2.01025 0 P 0 ;0
L 0.77086998 -2.00925 0.84753996 -2.00925 0 P 0 ;0
L 0.77086998 -2.00825 0.84766998 -2.00825 0 P 0 ;0
L 0.77086998 -2.00725 0.84778996 -2.00725 0 P 0 ;0
L 0.77086998 -2.00625 0.84791998 -2.00625 0 P 0 ;0
L 0.77086998 -2.00525 0.84805 -2.00525 0 P 0 ;0
L 0.77086998 -2.00425 0.84818002 -2.00425 0 P 0 ;0
L 0.77088002 -2.00325 0.84831004 -2.00325 0 P 0 ;0
L 0.77088002 -2.00225 0.84843996 -2.00225 0 P 0 ;0
L 0.77088002 -2.00125 0.84856004 -2.00125 0 P 0 ;0
L 0.77088002 -2.00025 0.84868996 -2.00025 0 P 0 ;0
L 0.77088002 -1.99925 0.84881998 -1.99925 0 P 0 ;0
L 0.77088002 -1.99825 0.84896004 -1.99825 0 P 0 ;0
L 0.77088002 -1.99725 0.84911004 -1.99725 0 P 0 ;0
L 0.77088996 -1.99625 0.84926998 -1.99625 0 P 0 ;0
L 0.77088996 -1.99525 0.84941998 -1.99525 0 P 0 ;0
L 0.77088996 -1.99425 0.84956998 -1.99425 0 P 0 ;0
L 0.77088996 -1.99325 0.84971998 -1.99325 0 P 0 ;0
L 0.77088996 -1.99225 0.84986998 -1.99225 0 P 0 ;0
L 0.77088996 -1.99125 0.85003002 -1.99125 0 P 0 ;0
L 0.7709 -1.99025 0.85018002 -1.99025 0 P 0 ;0
L 0.7709 -1.98925 0.85033002 -1.98925 0 P 0 ;0
L 0.76885 -2.01878002 0.76871998 -2.03201998 0 P 0 ;0
L 0.76871998 -2.03201998 0.7684 -2.04553996 0 P 0 ;0
L 0.7684 -2.04553996 0.76796004 -2.05751004 0 P 0 ;0
L 0.76796004 -2.05751004 0.76741004 -2.06523002 0 P 0 ;0
L 0.76741004 -2.06523002 0.76596004 -2.07933996 0 P 0 ;0
L 0.76596004 -2.07933996 0.7636 -2.09918002 0 P 0 ;0
L 0.7636 -2.09918002 0.76116004 -2.119 0 P 0 ;0
L 0.76116004 -2.119 0.76011998 -2.12526004 0 P 0 ;0
L 0.76011998 -2.12526004 0.75948996 -2.12825 0 P 0 ;0
L 0.75948996 -2.12825 0.84418002 -2.12825 0 P 0 ;0
L 0.84418002 -2.12825 0.84361998 -2.10788002 0 P 0 ;0
L 0.84361998 -2.10788002 0.8436 -2.08276004 0 P 0 ;0
L 0.8436 -2.08276004 0.8449 -2.05491998 0 P 0 ;0
L 0.8449 -2.05491998 0.84736004 -2.02641004 0 P 0 ;0
L 0.84736004 -2.02641004 0.85083996 -1.99923002 0 P 0 ;0
L 0.85083996 -1.99923002 0.85268996 -1.987 0 P 0 ;0
L 0.85268996 -1.987 0.7689 -1.987 0 P 0 ;0
L 0.7689 -1.987 0.76885 -2.01878002 0 P 0 ;0
L 0.76195 -2.12625 0.84211998 -2.12625 0 P 0 ;0
L 0.76213996 -2.12525 0.8421 -2.12525 0 P 0 ;0
L 0.76231004 -2.12425 0.84206998 -2.12425 0 P 0 ;0
L 0.76248002 -2.12325 0.84203996 -2.12325 0 P 0 ;0
L 0.76263996 -2.12225 0.84201004 -2.12225 0 P 0 ;0
L 0.76281004 -2.12125 0.84198996 -2.12125 0 P 0 ;0
L 0.76296998 -2.12025 0.84196004 -2.12025 0 P 0 ;0
L 0.76313996 -2.11925 0.84193002 -2.11925 0 P 0 ;0
L 0.76326998 -2.11825 0.8419 -2.11825 0 P 0 ;0
L 0.76338996 -2.11725 0.84188002 -2.11725 0 P 0 ;0
L 0.76351004 -2.11625 0.84185 -2.11625 0 P 0 ;0
L 0.76363996 -2.11525 0.84181998 -2.11525 0 P 0 ;0
L 0.76376004 -2.11425 0.84178996 -2.11425 0 P 0 ;0
L 0.76388002 -2.11325 0.84176998 -2.11325 0 P 0 ;0
L 0.76401004 -2.11225 0.84173996 -2.11225 0 P 0 ;0
L 0.76413002 -2.11125 0.84171004 -2.11125 0 P 0 ;0
L 0.76425 -2.11025 0.84168002 -2.11025 0 P 0 ;0
L 0.76438002 -2.10925 0.84166004 -2.10925 0 P 0 ;0
L 0.7645 -2.10825 0.84163002 -2.10825 0 P 0 ;0
L 0.76461998 -2.10725 0.84161998 -2.10725 0 P 0 ;0
L 0.76475 -2.10625 0.84161998 -2.10625 0 P 0 ;0
L 0.76486998 -2.10525 0.84161998 -2.10525 0 P 0 ;0
L 0.76498996 -2.10425 0.84161998 -2.10425 0 P 0 ;0
L 0.76511998 -2.10325 0.84161998 -2.10325 0 P 0 ;0
L 0.76523996 -2.10225 0.84161998 -2.10225 0 P 0 ;0
L 0.76536004 -2.10125 0.84161998 -2.10125 0 P 0 ;0
L 0.76548996 -2.10025 0.84161998 -2.10025 0 P 0 ;0
L 0.76561004 -2.09925 0.84161998 -2.09925 0 P 0 ;0
L 0.76573002 -2.09825 0.84161004 -2.09825 0 P 0 ;0
L 0.76583996 -2.09725 0.84161004 -2.09725 0 P 0 ;0
L 0.76596998 -2.09625 0.84161004 -2.09625 0 P 0 ;0
L 0.76608996 -2.09525 0.84161004 -2.09525 0 P 0 ;0
L 0.7662 -2.09425 0.84161004 -2.09425 0 P 0 ;0
L 0.76631998 -2.09325 0.84161004 -2.09325 0 P 0 ;0
L 0.76643996 -2.09225 0.84161004 -2.09225 0 P 0 ;0
L 0.76656004 -2.09125 0.84161004 -2.09125 0 P 0 ;0
L 0.76668002 -2.09025 0.84161004 -2.09025 0 P 0 ;0
L 0.76678996 -2.08925 0.84161004 -2.08925 0 P 0 ;0
L 0.76691998 -2.08825 0.84161004 -2.08825 0 P 0 ;0
L 0.76703002 -2.08725 0.84161004 -2.08725 0 P 0 ;0
L 0.76715 -2.08625 0.8416 -2.08625 0 P 0 ;0
L 0.76726998 -2.08525 0.8416 -2.08525 0 P 0 ;0
L 0.76738996 -2.08425 0.8416 -2.08425 0 P 0 ;0
L 0.76195 -2.12625 0.76208002 -2.12561998 0 P 0 ;0
L 0.76208002 -2.12561998 0.76313996 -2.11928996 0 P 0 ;0
L 0.76313996 -2.11928996 0.76558996 -2.09941998 0 P 0 ;0
L 0.76558996 -2.09941998 0.76558996 -2.09941004 0 P 0 ;0
L 0.76558996 -2.09941004 0.76793996 -2.07956004 0 P 0 ;0
L 0.76793996 -2.07956004 0.7694 -2.0654 0 P 0 ;0
L 0.7694 -2.0654 0.76941004 -2.06536004 0 P 0 ;0
L 0.76941004 -2.06536004 0.76996004 -2.05761998 0 P 0 ;0
L 0.76996004 -2.05761998 0.76996004 -2.05758996 0 P 0 ;0
L 0.76996004 -2.05758996 0.7704 -2.0456 0 P 0 ;0
L 0.7704 -2.0456 0.77071998 -2.03206004 0 P 0 ;0
L 0.77071998 -2.03206004 0.77085 -2.01878002 0 P 0 ;0
L 0.77085 -2.01878002 0.7709 -1.989 0 P 0 ;0
L 0.7709 -1.989 0.85036004 -1.989 0 P 0 ;0
L 0.85036004 -1.989 0.84886004 -1.99895 0 P 0 ;0
L 0.84886004 -1.99895 0.84538002 -2.02618996 0 P 0 ;0
L 0.84538002 -2.02618996 0.8429 -2.05478996 0 P 0 ;0
L 0.8429 -2.05478996 0.8416 -2.08271004 0 P 0 ;0
L 0.8416 -2.08271004 0.84161998 -2.10791004 0 P 0 ;0
L 0.84161998 -2.10791004 0.84211998 -2.12625 0 P 0 ;0
L 0.84211998 -2.12625 0.76195 -2.12625 0 P 0 ;0
L 0.71628996 -1.91261998 0.74938002 -1.91261998 0 P 0 ;0
L 0.71783002 -1.91161998 0.74933002 -1.91161998 0 P 0 ;0
L 0.71953002 -1.91061998 0.74931004 -1.91061998 0 P 0 ;0
L 0.72133002 -1.90961998 0.74928996 -1.90961998 0 P 0 ;0
L 0.72313996 -1.90861998 0.74926998 -1.90861998 0 P 0 ;0
L 0.72493996 -1.90761998 0.74928996 -1.90761998 0 P 0 ;0
L 0.72673996 -1.90661998 0.74931998 -1.90661998 0 P 0 ;0
L 0.72855 -1.90561998 0.74935 -1.90561998 0 P 0 ;0
L 0.73035 -1.90461998 0.74938996 -1.90461998 0 P 0 ;0
L 0.73215 -1.90361998 0.74946998 -1.90361998 0 P 0 ;0
L 0.73396004 -1.90261998 0.74953996 -1.90261998 0 P 0 ;0
L 0.73576004 -1.90161998 0.74961998 -1.90161998 0 P 0 ;0
L 0.73756998 -1.90061998 0.74973996 -1.90061998 0 P 0 ;0
L 0.73943002 -1.89961998 0.74986004 -1.89961998 0 P 0 ;0
L 0.74141998 -1.89861998 0.74998996 -1.89861998 0 P 0 ;0
L 0.74341004 -1.89761998 0.75015 -1.89761998 0 P 0 ;0
L 0.59843002 -2.08361998 0.6754 -2.08361998 0 P 0 ;0
L 0.59846004 -2.08261998 0.67538996 -2.08261998 0 P 0 ;0
L 0.59848002 -2.08161998 0.67538002 -2.08161998 0 P 0 ;0
L 0.59851004 -2.08061998 0.67538002 -2.08061998 0 P 0 ;0
L 0.59853002 -2.07961998 0.67546004 -2.07961998 0 P 0 ;0
L 0.59856004 -2.07861998 0.67553996 -2.07861998 0 P 0 ;0
L 0.59861998 -2.07761998 0.67561004 -2.07761998 0 P 0 ;0
L 0.5987 -2.07661998 0.67568996 -2.07661998 0 P 0 ;0
L 0.59878002 -2.07561998 0.67576004 -2.07561998 0 P 0 ;0
L 0.59885 -2.07461998 0.67583996 -2.07461998 0 P 0 ;0
L 0.59893002 -2.07361998 0.67591998 -2.07361998 0 P 0 ;0
L 0.59901004 -2.07261998 0.67598996 -2.07261998 0 P 0 ;0
L 0.59908002 -2.07161998 0.67606998 -2.07161998 0 P 0 ;0
L 0.59916004 -2.07061998 0.67613996 -2.07061998 0 P 0 ;0
L 0.59923002 -2.06961998 0.67621004 -2.06961998 0 P 0 ;0
L 0.59936004 -2.06861998 0.6763 -2.06861998 0 P 0 ;0
L 0.59948996 -2.06761998 0.67645 -2.06761998 0 P 0 ;0
L 0.59963002 -2.06661998 0.6766 -2.06661998 0 P 0 ;0
L 0.59976998 -2.06561998 0.67676004 -2.06561998 0 P 0 ;0
L 0.5999 -2.06461998 0.67691998 -2.06461998 0 P 0 ;0
L 0.60003002 -2.06361998 0.67706998 -2.06361998 0 P 0 ;0
L 0.60016998 -2.06261998 0.6773 -2.06261998 0 P 0 ;0
L 0.60031004 -2.06161998 0.67753002 -2.06161998 0 P 0 ;0
L 0.60051004 -2.06061998 0.67776004 -2.06061998 0 P 0 ;0
L 0.60071004 -2.05961998 0.67798996 -2.05961998 0 P 0 ;0
L 0.60091998 -2.05861998 0.67823002 -2.05861998 0 P 0 ;0
L 0.60111998 -2.05761998 0.67853002 -2.05761998 0 P 0 ;0
L 0.60133002 -2.05661998 0.67883996 -2.05661998 0 P 0 ;0
L 0.60153996 -2.05561998 0.67913996 -2.05561998 0 P 0 ;0
L 0.60173996 -2.05461998 0.67945 -2.05461998 0 P 0 ;0
L 0.60195 -2.05361998 0.67975 -2.05361998 0 P 0 ;0
L 0.60223002 -2.05261998 0.68006004 -2.05261998 0 P 0 ;0
L 0.60251004 -2.05161998 0.68036004 -2.05161998 0 P 0 ;0
L 0.60278996 -2.05061998 0.68066998 -2.05061998 0 P 0 ;0
L 0.60306004 -2.04961998 0.68096998 -2.04961998 0 P 0 ;0
L 0.60333996 -2.04861998 0.68135 -2.04861998 0 P 0 ;0
L 0.60361998 -2.04761998 0.68173002 -2.04761998 0 P 0 ;0
L 0.6039 -2.04661998 0.68211004 -2.04661998 0 P 0 ;0
L 0.60418002 -2.04561998 0.68248996 -2.04561998 0 P 0 ;0
L 0.60453002 -2.04461998 0.68288002 -2.04461998 0 P 0 ;0
L 0.60488002 -2.04361998 0.68326004 -2.04361998 0 P 0 ;0
L 0.60523002 -2.04261998 0.68363996 -2.04261998 0 P 0 ;0
L 0.60556998 -2.04161998 0.68401998 -2.04161998 0 P 0 ;0
L 0.60591998 -2.04061998 0.6844 -2.04061998 0 P 0 ;0
L 0.60626998 -2.03961998 0.68486004 -2.03961998 0 P 0 ;0
L 0.60661998 -2.03861998 0.68531998 -2.03861998 0 P 0 ;0
L 0.60698996 -2.03761998 0.68578002 -2.03761998 0 P 0 ;0
L 0.60743002 -2.03661998 0.68623996 -2.03661998 0 P 0 ;0
L 0.60786004 -2.03561998 0.6867 -2.03561998 0 P 0 ;0
L 0.60828996 -2.03461998 0.68716004 -2.03461998 0 P 0 ;0
L 0.60873002 -2.03361998 0.68761998 -2.03361998 0 P 0 ;0
L 0.60916004 -2.03261998 0.68808996 -2.03261998 0 P 0 ;0
L 0.60958996 -2.03161998 0.68856998 -2.03161998 0 P 0 ;0
L 0.61003002 -2.03061998 0.68911004 -2.03061998 0 P 0 ;0
L 0.61046004 -2.02961998 0.68965 -2.02961998 0 P 0 ;0
L 0.61088996 -2.02861998 0.69018996 -2.02861998 0 P 0 ;0
L 0.61133002 -2.02761998 0.69073002 -2.02761998 0 P 0 ;0
L 0.61176004 -2.02661998 0.69126998 -2.02661998 0 P 0 ;0
L 0.6122 -2.02561998 0.69181004 -2.02561998 0 P 0 ;0
L 0.61263002 -2.02461998 0.69235 -2.02461998 0 P 0 ;0
L 0.61306004 -2.02361998 0.69288002 -2.02361998 0 P 0 ;0
L 0.61348996 -2.02261998 0.69346998 -2.02261998 0 P 0 ;0
L 0.61393002 -2.02161998 0.69408996 -2.02161998 0 P 0 ;0
L 0.61436004 -2.02061998 0.6947 -2.02061998 0 P 0 ;0
L 0.61478996 -2.01961998 0.69531998 -2.01961998 0 P 0 ;0
L 0.61531004 -2.01861998 0.69593996 -2.01861998 0 P 0 ;0
L 0.61583996 -2.01761998 0.69656004 -2.01761998 0 P 0 ;0
L 0.61636004 -2.01661998 0.69718002 -2.01661998 0 P 0 ;0
L 0.61688002 -2.01561998 0.69778996 -2.01561998 0 P 0 ;0
L 0.6174 -2.01461998 0.69841998 -2.01461998 0 P 0 ;0
L 0.61791998 -2.01361998 0.69911998 -2.01361998 0 P 0 ;0
L 0.61843996 -2.01261998 0.69981998 -2.01261998 0 P 0 ;0
L 0.61896004 -2.01161998 0.70051998 -2.01161998 0 P 0 ;0
L 0.61948002 -2.01061998 0.70123002 -2.01061998 0 P 0 ;0
L 0.62 -2.00961998 0.70193002 -2.00961998 0 P 0 ;0
L 0.62051998 -2.00861998 0.70263002 -2.00861998 0 P 0 ;0
L 0.62103996 -2.00761998 0.70333002 -2.00761998 0 P 0 ;0
L 0.62163996 -2.00661998 0.70403996 -2.00661998 0 P 0 ;0
L 0.62225 -2.00561998 0.70483002 -2.00561998 0 P 0 ;0
L 0.62285 -2.00461998 0.70565 -2.00461998 0 P 0 ;0
L 0.62346004 -2.00361998 0.70646004 -2.00361998 0 P 0 ;0
L 0.62406004 -2.00261998 0.70726998 -2.00261998 0 P 0 ;0
L 0.62466004 -2.00161998 0.70808996 -2.00161998 0 P 0 ;0
L 0.62526998 -2.00061998 0.7089 -2.00061998 0 P 0 ;0
L 0.62586998 -1.99961998 0.70971004 -1.99961998 0 P 0 ;0
L 0.62648002 -1.99861998 0.71053002 -1.99861998 0 P 0 ;0
L 0.62708002 -1.99761998 0.71133996 -1.99761998 0 P 0 ;0
L 0.62768996 -1.99661998 0.71216004 -1.99661998 0 P 0 ;0
L 0.62831998 -1.99561998 0.71296998 -1.99561998 0 P 0 ;0
L 0.62901004 -1.99461998 0.71378996 -1.99461998 0 P 0 ;0
L 0.62971004 -1.99361998 0.71466004 -1.99361998 0 P 0 ;0
L 0.6304 -1.99261998 0.71561004 -1.99261998 0 P 0 ;0
L 0.6311 -1.99161998 0.71656998 -1.99161998 0 P 0 ;0
L 0.63178996 -1.99061998 0.71753002 -1.99061998 0 P 0 ;0
L 0.63248996 -1.98961998 0.71848996 -1.98961998 0 P 0 ;0
L 0.63318002 -1.98861998 0.71945 -1.98861998 0 P 0 ;0
L 0.63388002 -1.98761998 0.72041004 -1.98761998 0 P 0 ;0
L 0.63456998 -1.98661998 0.72136998 -1.98661998 0 P 0 ;0
L 0.63526998 -1.98561998 0.72233002 -1.98561998 0 P 0 ;0
L 0.63598002 -1.98461998 0.72328996 -1.98461998 0 P 0 ;0
L 0.63678996 -1.98361998 0.72425 -1.98361998 0 P 0 ;0
L 0.6376 -1.98261998 0.72521004 -1.98261998 0 P 0 ;0
L 0.63841004 -1.98161998 0.72628002 -1.98161998 0 P 0 ;0
L 0.63921998 -1.98061998 0.72738996 -1.98061998 0 P 0 ;0
L 0.64003002 -1.97961998 0.7285 -1.97961998 0 P 0 ;0
L 0.64083996 -1.97861998 0.72961004 -1.97861998 0 P 0 ;0
L 0.64165 -1.97761998 0.73071004 -1.97761998 0 P 0 ;0
L 0.64246004 -1.97661998 0.73181998 -1.97661998 0 P 0 ;0
L 0.64326998 -1.97561998 0.73293002 -1.97561998 0 P 0 ;0
L 0.64406998 -1.97461998 0.73403996 -1.97461998 0 P 0 ;0
L 0.64488002 -1.97361998 0.73515 -1.97361998 0 P 0 ;0
L 0.64568996 -1.97261998 0.73625 -1.97261998 0 P 0 ;0
L 0.6465 -1.97161998 0.73736004 -1.97161998 0 P 0 ;0
L 0.64731004 -1.97061998 0.73848002 -1.97061998 0 P 0 ;0
L 0.64811998 -1.96961998 0.73973002 -1.96961998 0 P 0 ;0
L 0.64893002 -1.96861998 0.74098996 -1.96861998 0 P 0 ;0
L 0.64981004 -1.96761998 0.74225 -1.96761998 0 P 0 ;0
L 0.65076004 -1.96661998 0.74351004 -1.96661998 0 P 0 ;0
L 0.65171004 -1.96561998 0.74476998 -1.96561998 0 P 0 ;0
L 0.65266998 -1.96461998 0.74603002 -1.96461998 0 P 0 ;0
L 0.65361998 -1.96361998 0.74728996 -1.96361998 0 P 0 ;0
L 0.65458002 -1.96261998 0.74855 -1.96261998 0 P 0 ;0
L 0.65553002 -1.96161998 0.74981004 -1.96161998 0 P 0 ;0
L 0.65648996 -1.96061998 0.75106004 -1.96061998 0 P 0 ;0
L 0.65743996 -1.95961998 0.75233996 -1.95961998 0 P 0 ;0
L 0.6584 -1.95861998 0.7537 -1.95861998 0 P 0 ;0
L 0.65935 -1.95761998 0.75506004 -1.95761998 0 P 0 ;0
L 0.66031004 -1.95661998 0.75641998 -1.95661998 0 P 0 ;0
L 0.66126004 -1.95561998 0.75778996 -1.95561998 0 P 0 ;0
L 0.66221004 -1.95461998 0.75916004 -1.95461998 0 P 0 ;0
L 0.66316998 -1.95361998 0.76053996 -1.95361998 0 P 0 ;0
L 0.66411998 -1.95261998 0.76193996 -1.95261998 0 P 0 ;0
L 0.66523002 -1.95161998 0.76333996 -1.95161998 0 P 0 ;0
L 0.66636004 -1.95061998 0.76406998 -1.95061998 0 P 0 ;0
L 0.66746998 -1.94961998 0.76355 -1.94961998 0 P 0 ;0
L 0.6686 -1.94861998 0.76291998 -1.94861998 0 P 0 ;0
L 0.66971004 -1.94761998 0.76226998 -1.94761998 0 P 0 ;0
L 0.67083996 -1.94661998 0.76161998 -1.94661998 0 P 0 ;0
L 0.67196004 -1.94561998 0.76096998 -1.94561998 0 P 0 ;0
L 0.67306998 -1.94461998 0.76033002 -1.94461998 0 P 0 ;0
L 0.6742 -1.94361998 0.75968996 -1.94361998 0 P 0 ;0
L 0.67531004 -1.94261998 0.75905 -1.94261998 0 P 0 ;0
L 0.67643996 -1.94161998 0.75846004 -1.94161998 0 P 0 ;0
L 0.67755 -1.94061998 0.75788996 -1.94061998 0 P 0 ;0
L 0.67868002 -1.93961998 0.75731998 -1.93961998 0 P 0 ;0
L 0.67978996 -1.93861998 0.75676998 -1.93861998 0 P 0 ;0
L 0.68091998 -1.93761998 0.75626998 -1.93761998 0 P 0 ;0
L 0.68221004 -1.93661998 0.75576998 -1.93661998 0 P 0 ;0
L 0.68353002 -1.93561998 0.75528002 -1.93561998 0 P 0 ;0
L 0.68483996 -1.93461998 0.75483996 -1.93461998 0 P 0 ;0
L 0.68616004 -1.93361998 0.75441004 -1.93361998 0 P 0 ;0
L 0.68746998 -1.93261998 0.75398002 -1.93261998 0 P 0 ;0
L 0.68878002 -1.93161998 0.7536 -1.93161998 0 P 0 ;0
L 0.6901 -1.93061998 0.75323996 -1.93061998 0 P 0 ;0
L 0.69141004 -1.92961998 0.75286998 -1.92961998 0 P 0 ;0
L 0.69271998 -1.92861998 0.75253996 -1.92861998 0 P 0 ;0
L 0.69403002 -1.92761998 0.75223002 -1.92761998 0 P 0 ;0
L 0.69535 -1.92661998 0.75193002 -1.92661998 0 P 0 ;0
L 0.69666004 -1.92561998 0.75163002 -1.92561998 0 P 0 ;0
L 0.69796998 -1.92461998 0.75138002 -1.92461998 0 P 0 ;0
L 0.69936998 -1.92361998 0.75113996 -1.92361998 0 P 0 ;0
L 0.70091004 -1.92261998 0.75088996 -1.92261998 0 P 0 ;0
L 0.70243996 -1.92161998 0.75066004 -1.92161998 0 P 0 ;0
L 0.70398002 -1.92061998 0.75046004 -1.92061998 0 P 0 ;0
L 0.70551998 -1.91961998 0.75026004 -1.91961998 0 P 0 ;0
L 0.70706004 -1.91861998 0.75006998 -1.91861998 0 P 0 ;0
L 0.7086 -1.91761998 0.7499 -1.91761998 0 P 0 ;0
L 0.71013996 -1.91661998 0.74976998 -1.91661998 0 P 0 ;0
L 0.71166998 -1.91561998 0.74961998 -1.91561998 0 P 0 ;0
L 0.71321004 -1.91461998 0.74951998 -1.91461998 0 P 0 ;0
L 0.71475 -1.91361998 0.74945 -1.91361998 0 P 0 ;0
L 0.61556998 -2.15661998 0.70655 -2.15661998 0 P 0 ;0
L 0.61503002 -2.15561998 0.7056 -2.15561998 0 P 0 ;0
L 0.61448996 -2.15461998 0.70465 -2.15461998 0 P 0 ;0
L 0.61395 -2.15361998 0.7037 -2.15361998 0 P 0 ;0
L 0.61341004 -2.15261998 0.70273996 -2.15261998 0 P 0 ;0
L 0.61286998 -2.15161998 0.70178996 -2.15161998 0 P 0 ;0
L 0.61233002 -2.15061998 0.70095 -2.15061998 0 P 0 ;0
L 0.61188002 -2.14961998 0.70015 -2.14961998 0 P 0 ;0
L 0.61143002 -2.14861998 0.69935 -2.14861998 0 P 0 ;0
L 0.61098002 -2.14761998 0.69855 -2.14761998 0 P 0 ;0
L 0.61053002 -2.14661998 0.69775 -2.14661998 0 P 0 ;0
L 0.61008002 -2.14561998 0.69695 -2.14561998 0 P 0 ;0
L 0.60963002 -2.14461998 0.69615 -2.14461998 0 P 0 ;0
L 0.60918002 -2.14361998 0.69535 -2.14361998 0 P 0 ;0
L 0.60873002 -2.14261998 0.69455 -2.14261998 0 P 0 ;0
L 0.60831004 -2.14161998 0.69381998 -2.14161998 0 P 0 ;0
L 0.60793996 -2.14061998 0.69315 -2.14061998 0 P 0 ;0
L 0.60756998 -2.13961998 0.69248002 -2.13961998 0 P 0 ;0
L 0.60721004 -2.13861998 0.69181004 -2.13861998 0 P 0 ;0
L 0.60683996 -2.13761998 0.69115 -2.13761998 0 P 0 ;0
L 0.60646998 -2.13661998 0.69048002 -2.13661998 0 P 0 ;0
L 0.60611004 -2.13561998 0.68981004 -2.13561998 0 P 0 ;0
L 0.60573996 -2.13461998 0.68918002 -2.13461998 0 P 0 ;0
L 0.60538002 -2.13361998 0.68863002 -2.13361998 0 P 0 ;0
L 0.60503996 -2.13261998 0.68808002 -2.13261998 0 P 0 ;0
L 0.60476004 -2.13161998 0.68753002 -2.13161998 0 P 0 ;0
L 0.60446998 -2.13061998 0.68698002 -2.13061998 0 P 0 ;0
L 0.60418002 -2.12961998 0.68643002 -2.12961998 0 P 0 ;0
L 0.6039 -2.12861998 0.68588002 -2.12861998 0 P 0 ;0
L 0.60361004 -2.12761998 0.68533002 -2.12761998 0 P 0 ;0
L 0.60331998 -2.12661998 0.68486004 -2.12661998 0 P 0 ;0
L 0.60303002 -2.12561998 0.68441998 -2.12561998 0 P 0 ;0
L 0.60275 -2.12461998 0.68396998 -2.12461998 0 P 0 ;0
L 0.60246004 -2.12361998 0.68353002 -2.12361998 0 P 0 ;0
L 0.60218002 -2.12261998 0.68308996 -2.12261998 0 P 0 ;0
L 0.60188996 -2.12161998 0.68263996 -2.12161998 0 P 0 ;0
L 0.60166998 -2.12061998 0.6822 -2.12061998 0 P 0 ;0
L 0.60145 -2.11961998 0.68176004 -2.11961998 0 P 0 ;0
L 0.60123002 -2.11861998 0.68138996 -2.11861998 0 P 0 ;0
L 0.60101004 -2.11761998 0.68105 -2.11761998 0 P 0 ;0
L 0.60078002 -2.11661998 0.68071004 -2.11661998 0 P 0 ;0
L 0.6006 -2.11561998 0.68036004 -2.11561998 0 P 0 ;0
L 0.60043002 -2.11461998 0.68001998 -2.11461998 0 P 0 ;0
L 0.60025 -2.11361998 0.67968002 -2.11361998 0 P 0 ;0
L 0.60008002 -2.11261998 0.67933002 -2.11261998 0 P 0 ;0
L 0.59991004 -2.11161998 0.67898996 -2.11161998 0 P 0 ;0
L 0.59976004 -2.11061998 0.6787 -2.11061998 0 P 0 ;0
L 0.59963996 -2.10961998 0.67845 -2.10961998 0 P 0 ;0
L 0.59951004 -2.10861998 0.6782 -2.10861998 0 P 0 ;0
L 0.59938002 -2.10761998 0.67795 -2.10761998 0 P 0 ;0
L 0.59925 -2.10661998 0.6777 -2.10661998 0 P 0 ;0
L 0.59913002 -2.10561998 0.67746004 -2.10561998 0 P 0 ;0
L 0.59905 -2.10461998 0.67721004 -2.10461998 0 P 0 ;0
L 0.59896998 -2.10361998 0.67696004 -2.10361998 0 P 0 ;0
L 0.59888002 -2.10261998 0.67671004 -2.10261998 0 P 0 ;0
L 0.5988 -2.10161998 0.67653996 -2.10161998 0 P 0 ;0
L 0.59871998 -2.10061998 0.67638002 -2.10061998 0 P 0 ;0
L 0.59866998 -2.09961998 0.67621004 -2.09961998 0 P 0 ;0
L 0.59863996 -2.09861998 0.67605 -2.09861998 0 P 0 ;0
L 0.59861004 -2.09761998 0.67588996 -2.09761998 0 P 0 ;0
L 0.59858996 -2.09661998 0.6758 -2.09661998 0 P 0 ;0
L 0.59856004 -2.09561998 0.67571004 -2.09561998 0 P 0 ;0
L 0.59853002 -2.09461998 0.67563002 -2.09461998 0 P 0 ;0
L 0.5985 -2.09361998 0.67553996 -2.09361998 0 P 0 ;0
L 0.59846998 -2.09261998 0.67546004 -2.09261998 0 P 0 ;0
L 0.59843996 -2.09161998 0.67546004 -2.09161998 0 P 0 ;0
L 0.59841998 -2.09061998 0.67545 -2.09061998 0 P 0 ;0
L 0.59838002 -2.08961998 0.67543996 -2.08961998 0 P 0 ;0
L 0.59836004 -2.08861998 0.67543002 -2.08861998 0 P 0 ;0
L 0.59833002 -2.08761998 0.67543002 -2.08761998 0 P 0 ;0
L 0.59835 -2.08661998 0.67541998 -2.08661998 0 P 0 ;0
L 0.59836998 -2.08561998 0.67541004 -2.08561998 0 P 0 ;0
L 0.5984 -2.08461998 0.67541004 -2.08461998 0 P 0 ;0
L 0.80005 -2.25161998 0.85543996 -2.25161998 0 P 0 ;0
L 0.78651998 -2.25061998 0.86596004 -2.25061998 0 P 0 ;0
L 0.77878996 -2.24961998 0.87636004 -2.24961998 0 P 0 ;0
L 0.77106004 -2.24861998 0.88285 -2.24861998 0 P 0 ;0
L 0.76398996 -2.24761998 0.88933996 -2.24761998 0 P 0 ;0
L 0.75891998 -2.24661998 0.89583996 -2.24661998 0 P 0 ;0
L 0.73781004 -1.8982 0.71738996 -1.90951998 0 P 0 ;0
L 0.71738996 -1.90951998 0.69766998 -1.92233996 0 P 0 ;0
L 0.69766998 -1.92233996 0.67971004 -1.93601998 0 P 0 ;0
L 0.67971004 -1.93601998 0.66278996 -1.95113002 0 P 0 ;0
L 0.66278996 -1.95113002 0.64786998 -1.96675 0 P 0 ;0
L 0.64786998 -1.96675 0.63423996 -1.98358996 0 P 0 ;0
L 0.63423996 -1.98358996 0.62643996 -1.99483002 0 P 0 ;0
L 0.62643996 -1.99483002 0.61933996 -2.00655 0 P 0 ;0
L 0.61933996 -2.00655 0.61298996 -2.01873996 0 P 0 ;0
L 0.61298996 -2.01873996 0.60503002 -2.03713002 0 P 0 ;0
L 0.60503002 -2.03713002 0.60225 -2.04506004 0 P 0 ;0
L 0.60225 -2.04506004 0.59998996 -2.05323002 0 P 0 ;0
L 0.59998996 -2.05323002 0.59833996 -2.0612 0 P 0 ;0
L 0.59833996 -2.0612 0.59725 -2.06928996 0 P 0 ;0
L 0.59725 -2.06928996 0.59656998 -2.07833996 0 P 0 ;0
L 0.59656998 -2.07833996 0.59633002 -2.0875 0 P 0 ;0
L 0.59633002 -2.0875 0.59668996 -2.10036998 0 P 0 ;0
L 0.59668996 -2.10036998 0.59715 -2.10596004 0 P 0 ;0
L 0.59715 -2.10596004 0.59786004 -2.11151004 0 P 0 ;0
L 0.59786004 -2.11151004 0.59878996 -2.11686998 0 P 0 ;0
L 0.59878996 -2.11686998 0.59996998 -2.1222 0 P 0 ;0
L 0.59996998 -2.1222 0.60326998 -2.13368996 0 P 0 ;0
L 0.60326998 -2.13368996 0.60656998 -2.1427 0 P 0 ;0
L 0.60656998 -2.1427 0.6105 -2.15143996 0 P 0 ;0
L 0.6105 -2.15143996 0.61505 -2.15988002 0 P 0 ;0
L 0.61505 -2.15988002 0.62023996 -2.16803996 0 P 0 ;0
L 0.62023996 -2.16803996 0.62828996 -2.17873002 0 P 0 ;0
L 0.62828996 -2.17873002 0.63718996 -2.18871004 0 P 0 ;0
L 0.63718996 -2.18871004 0.64693002 -2.19795 0 P 0 ;0
L 0.64693002 -2.19795 0.6582 -2.20701998 0 P 0 ;0
L 0.6582 -2.20701998 0.67011004 -2.21518996 0 P 0 ;0
L 0.67011004 -2.21518996 0.68261004 -2.22243002 0 P 0 ;0
L 0.68261004 -2.22243002 0.69673996 -2.22936004 0 P 0 ;0
L 0.69673996 -2.22936004 0.71123002 -2.23543996 0 P 0 ;0
L 0.71123002 -2.23543996 0.72611998 -2.24066998 0 P 0 ;0
L 0.72611998 -2.24066998 0.74536004 -2.24598996 0 P 0 ;0
L 0.74536004 -2.24598996 0.76493002 -2.24985 0 P 0 ;0
L 0.76493002 -2.24985 0.78671998 -2.25266998 0 P 0 ;0
L 0.78671998 -2.25266998 0.80863002 -2.25425 0 P 0 ;0
L 0.80863002 -2.25425 0.83146004 -2.25463002 0 P 0 ;0
L 0.83146004 -2.25463002 0.85418002 -2.25375 0 P 0 ;0
L 0.85418002 -2.25375 0.87641004 -2.25163996 0 P 0 ;0
L 0.87641004 -2.25163996 0.89853002 -2.24823002 0 P 0 ;0
L 0.89853002 -2.24823002 0.93045 -2.24101998 0 P 0 ;0
L 0.93045 -2.24101998 0.96466004 -2.23063002 0 P 0 ;0
L 0.96466004 -2.23063002 0.99911004 -2.2178 0 P 0 ;0
L 0.99911004 -2.2178 1.03183002 -2.20318002 0 P 0 ;0
L 1.03183002 -2.20318002 1.04391998 -2.19703002 0 P 0 ;0
L 1.04391998 -2.19703002 1.05581004 -2.19048996 0 P 0 ;0
L 1.05581004 -2.19048996 1.06676004 -2.18411998 0 P 0 ;0
L 1.06676004 -2.18411998 1.06681004 -2.18408996 0 P 0 ;0
L 1.06681004 -2.18408996 1.06685 -2.18405 0 P 0 ;0
L 1.06685 -2.18405 1.0669 -2.18401004 0 P 0 ;0
L 1.0669 -2.18401004 1.06693996 -2.18396998 0 P 0 ;0
L 1.06693996 -2.18396998 1.06696998 -2.18391998 0 P 0 ;0
L 1.06696998 -2.18391998 1.06701004 -2.18386998 0 P 0 ;0
L 1.06701004 -2.18386998 1.06703002 -2.18381998 0 P 0 ;0
L 1.06703002 -2.18381998 1.06706004 -2.18376004 0 P 0 ;0
L 1.06706004 -2.18376004 1.06706998 -2.18371004 0 P 0 ;0
L 1.06706998 -2.18371004 1.06708996 -2.18365 0 P 0 ;0
L 1.06708996 -2.18365 1.06708996 -2.18358996 0 P 0 ;0
L 1.06708996 -2.18358996 1.0671 -2.18353002 0 P 0 ;0
L 1.0671 -2.18353002 1.0671 -2.18346998 0 P 0 ;0
L 1.0671 -2.18346998 1.06708996 -2.18341004 0 P 0 ;0
L 1.06708996 -2.18341004 1.06706998 -2.18336004 0 P 0 ;0
L 1.06706998 -2.18336004 1.06706004 -2.1833 0 P 0 ;0
L 1.06706004 -2.1833 1.06703002 -2.18323996 0 P 0 ;0
L 1.06703002 -2.18323996 1.06701004 -2.18318996 0 P 0 ;0
L 1.06701004 -2.18318996 1.06696998 -2.18313996 0 P 0 ;0
L 1.06696998 -2.18313996 1.06693996 -2.18308996 0 P 0 ;0
L 1.06693996 -2.18308996 1.06688002 -2.18303002 0 P 0 ;0
L 1.06688002 -2.18303002 1.06678996 -2.18296998 0 P 0 ;0
L 1.06678996 -2.18296998 1.06673002 -2.18295 0 P 0 ;0
L 1.06673002 -2.18295 1.0667 -2.18295 0 P 0 ;0
L 1.0667 -2.18295 1.06666004 -2.18293996 0 P 0 ;0
L 1.06666004 -2.18293996 1.0666 -2.18293996 0 P 0 ;0
L 1.0666 -2.18293996 1.06656998 -2.18295 0 P 0 ;0
L 1.06656998 -2.18295 1.06653002 -2.18295 0 P 0 ;0
L 1.06653002 -2.18295 1.06153002 -2.1842 0 P 0 ;0
L 1.06153002 -2.1842 1.05583996 -2.18566998 0 P 0 ;0
L 1.05583996 -2.18566998 1.04916998 -2.1875 0 P 0 ;0
L 1.04916998 -2.1875 1.0153 -2.1962 0 P 0 ;0
L 1.0153 -2.1962 0.9814 -2.20333996 0 P 0 ;0
L 0.9814 -2.20333996 0.94881998 -2.2087 0 P 0 ;0
L 0.94881998 -2.2087 0.9189 -2.21198996 0 P 0 ;0
L 0.9189 -2.21198996 0.90113996 -2.21278996 0 P 0 ;0
L 0.90113996 -2.21278996 0.87738002 -2.21265 0 P 0 ;0
L 0.87738002 -2.21265 0.854 -2.21183002 0 P 0 ;0
L 0.854 -2.21183002 0.83788996 -2.21033996 0 P 0 ;0
L 0.83788996 -2.21033996 0.8174 -2.20693002 0 P 0 ;0
L 0.8174 -2.20693002 0.79708996 -2.2023 0 P 0 ;0
L 0.79708996 -2.2023 0.7769 -2.19641004 0 P 0 ;0
L 0.7769 -2.19641004 0.76433002 -2.19183996 0 P 0 ;0
L 0.76433002 -2.19183996 0.75208996 -2.18638002 0 P 0 ;0
L 0.75208996 -2.18638002 0.74026998 -2.18006998 0 P 0 ;0
L 0.74026998 -2.18006998 0.72886998 -2.17291004 0 P 0 ;0
L 0.72886998 -2.17291004 0.71961998 -2.16603002 0 P 0 ;0
L 0.71961998 -2.16603002 0.71098996 -2.15838996 0 P 0 ;0
L 0.71098996 -2.15838996 0.70303002 -2.15003002 0 P 0 ;0
L 0.70303002 -2.15003002 0.6958 -2.14098996 0 P 0 ;0
L 0.6958 -2.14098996 0.69106998 -2.1339 0 P 0 ;0
L 0.69106998 -2.1339 0.68696004 -2.12643002 0 P 0 ;0
L 0.68696004 -2.12643002 0.68351004 -2.11863002 0 P 0 ;0
L 0.68351004 -2.11863002 0.68073996 -2.11056004 0 P 0 ;0
L 0.68073996 -2.11056004 0.67866004 -2.10218996 0 P 0 ;0
L 0.67866004 -2.10218996 0.67788002 -2.09741998 0 P 0 ;0
L 0.67788002 -2.09741998 0.67746004 -2.0926 0 P 0 ;0
L 0.67746004 -2.0926 0.67738002 -2.08076004 0 P 0 ;0
L 0.67738002 -2.08076004 0.67828002 -2.06891004 0 P 0 ;0
L 0.67828002 -2.06891004 0.67903002 -2.06403996 0 P 0 ;0
L 0.67903002 -2.06403996 0.68013002 -2.05923996 0 P 0 ;0
L 0.68013002 -2.05923996 0.68288002 -2.05021998 0 P 0 ;0
L 0.68288002 -2.05021998 0.68623996 -2.04141004 0 P 0 ;0
L 0.68623996 -2.04141004 0.69018002 -2.03286004 0 P 0 ;0
L 0.69018002 -2.03286004 0.69486004 -2.02418002 0 P 0 ;0
L 0.69486004 -2.02418002 0.70003996 -2.0158 0 P 0 ;0
L 0.70003996 -2.0158 0.70573002 -2.00768996 0 P 0 ;0
L 0.70573002 -2.00768996 0.7158 -1.99531998 0 P 0 ;0
L 0.7158 -1.99531998 0.72681004 -1.98385 0 P 0 ;0
L 0.72681004 -1.98385 0.73971004 -1.9722 0 P 0 ;0
L 0.73971004 -1.9722 0.7533 -1.9614 0 P 0 ;0
L 0.7533 -1.9614 0.75753996 -1.95828002 0 P 0 ;0
L 0.75753996 -1.95828002 0.76138002 -1.95548002 0 P 0 ;0
L 0.76138002 -1.95548002 0.76463002 -1.95316004 0 P 0 ;0
L 0.76463002 -1.95316004 0.76516004 -1.95281004 0 P 0 ;0
L 0.76516004 -1.95281004 0.7657 -1.95248996 0 P 0 ;0
L 0.7657 -1.95248996 0.76578002 -1.95243996 0 P 0 ;0
L 0.76578002 -1.95243996 0.76586004 -1.95238002 0 P 0 ;0
L 0.76586004 -1.95238002 0.76593002 -1.95231998 0 P 0 ;0
L 0.76593002 -1.95231998 0.766 -1.95223996 0 P 0 ;0
L 0.766 -1.95223996 0.76606004 -1.95216998 0 P 0 ;0
L 0.76606004 -1.95216998 0.76616004 -1.95201004 0 P 0 ;0
L 0.76616004 -1.95201004 0.7662 -1.95191998 0 P 0 ;0
L 0.7662 -1.95191998 0.76626004 -1.95173996 0 P 0 ;0
L 0.76626004 -1.95173996 0.76628002 -1.95163996 0 P 0 ;0
L 0.76628002 -1.95163996 0.7663 -1.95143002 0 P 0 ;0
L 0.7663 -1.95143002 0.7663 -1.95121004 0 P 0 ;0
L 0.7663 -1.95121004 0.76628996 -1.951 0 P 0 ;0
L 0.76628996 -1.951 0.76625 -1.95078996 0 P 0 ;0
L 0.76625 -1.95078996 0.7662 -1.95058002 0 P 0 ;0
L 0.7662 -1.95058002 0.76613002 -1.95036998 0 P 0 ;0
L 0.76613002 -1.95036998 0.76583002 -1.94966998 0 P 0 ;0
L 0.76583002 -1.94966998 0.76548996 -1.94896998 0 P 0 ;0
L 0.76548996 -1.94896998 0.76508996 -1.9483 0 P 0 ;0
L 0.76508996 -1.9483 0.76253002 -1.94436004 0 P 0 ;0
L 0.76253002 -1.94436004 0.76056998 -1.94126998 0 P 0 ;0
L 0.76056998 -1.94126998 0.75871998 -1.93806004 0 P 0 ;0
L 0.75871998 -1.93806004 0.75716998 -1.93496998 0 P 0 ;0
L 0.75716998 -1.93496998 0.7558 -1.93178002 0 P 0 ;0
L 0.7558 -1.93178002 0.7546 -1.92853996 0 P 0 ;0
L 0.7546 -1.92853996 0.75358996 -1.92521004 0 P 0 ;0
L 0.75358996 -1.92521004 0.7527 -1.92161998 0 P 0 ;0
L 0.7527 -1.92161998 0.75196998 -1.91796004 0 P 0 ;0
L 0.75196998 -1.91796004 0.75155 -1.91496004 0 P 0 ;0
L 0.75155 -1.91496004 0.75133002 -1.91193002 0 P 0 ;0
L 0.75133002 -1.91193002 0.75126998 -1.9085 0 P 0 ;0
L 0.75126998 -1.9085 0.75136004 -1.90506004 0 P 0 ;0
L 0.75136004 -1.90506004 0.75161004 -1.90181998 0 P 0 ;0
L 0.75161004 -1.90181998 0.752 -1.8986 0 P 0 ;0
L 0.752 -1.8986 0.75228996 -1.89701998 0 P 0 ;0
L 0.75228996 -1.89701998 0.75268996 -1.89546998 0 P 0 ;0
L 0.75268996 -1.89546998 0.7532 -1.89395 0 P 0 ;0
L 0.7532 -1.89395 0.75358996 -1.89281998 0 P 0 ;0
L 0.75358996 -1.89281998 0.75373002 -1.89231998 0 P 0 ;0
L 0.75373002 -1.89231998 0.75383996 -1.8918 0 P 0 ;0
L 0.75383996 -1.8918 0.75391998 -1.89138996 0 P 0 ;0
L 0.75391998 -1.89138996 0.75396998 -1.89098996 0 P 0 ;0
L 0.75396998 -1.89098996 0.75396998 -1.89086004 0 P 0 ;0
L 0.75396998 -1.89086004 0.75393996 -1.89076998 0 P 0 ;0
L 0.75393996 -1.89076998 0.7539 -1.89071004 0 P 0 ;0
L 0.7539 -1.89071004 0.75386004 -1.89066998 0 P 0 ;0
L 0.75386004 -1.89066998 0.75381004 -1.89063002 0 P 0 ;0
L 0.75381004 -1.89063002 0.75378996 -1.89061004 0 P 0 ;0
L 0.75378996 -1.89061004 0.75373002 -1.89058996 0 P 0 ;0
L 0.75373002 -1.89058996 0.75368002 -1.89056998 0 P 0 ;0
L 0.75368002 -1.89056998 0.75356004 -1.89056998 0 P 0 ;0
L 0.75356004 -1.89056998 0.75346998 -1.8906 0 P 0 ;0
L 0.75346998 -1.8906 0.74898002 -1.8927 0 P 0 ;0
L 0.74898002 -1.8927 0.74383002 -1.89518002 0 P 0 ;0
L 0.74383002 -1.89518002 0.73781004 -1.8982 0 P 0 ;0
L 0.69776998 -2.22761998 0.96701004 -2.22761998 0 P 0 ;0
L 0.6957 -2.22661998 0.96968996 -2.22661998 0 P 0 ;0
L 0.69366998 -2.22561998 0.97238002 -2.22561998 0 P 0 ;0
L 0.69163002 -2.22461998 0.97506004 -2.22461998 0 P 0 ;0
L 0.68958996 -2.22361998 0.97775 -2.22361998 0 P 0 ;0
L 0.68756004 -2.22261998 0.98043002 -2.22261998 0 P 0 ;0
L 0.68551998 -2.22161998 0.98311004 -2.22161998 0 P 0 ;0
L 0.68348996 -2.22061998 0.9858 -2.22061998 0 P 0 ;0
L 0.68176998 -2.21961998 0.98848002 -2.21961998 0 P 0 ;0
L 0.68003996 -2.21861998 0.99116998 -2.21861998 0 P 0 ;0
L 0.67831004 -2.21761998 0.99385 -2.21761998 0 P 0 ;0
L 0.67658002 -2.21661998 0.99653996 -2.21661998 0 P 0 ;0
L 0.67485 -2.21561998 0.99908002 -2.21561998 0 P 0 ;0
L 0.67311998 -2.21461998 0.87665 -2.21461998 0 P 0 ;0
L 0.6714 -2.21361998 0.85166004 -2.21361998 0 P 0 ;0
L 0.6699 -2.21261998 0.84083002 -2.21261998 0 P 0 ;0
L 0.66845 -2.21161998 0.8334 -2.21161998 0 P 0 ;0
L 0.66698996 -2.21061998 0.8274 -2.21061998 0 P 0 ;0
L 0.66553002 -2.20961998 0.82138996 -2.20961998 0 P 0 ;0
L 0.66406998 -2.20861998 0.81583002 -2.20861998 0 P 0 ;0
L 0.66261998 -2.20761998 0.81143996 -2.20761998 0 P 0 ;0
L 0.66116004 -2.20661998 0.80706004 -2.20661998 0 P 0 ;0
L 0.6597 -2.20561998 0.80266998 -2.20561998 0 P 0 ;0
L 0.65841004 -2.20461998 0.79828996 -2.20461998 0 P 0 ;0
L 0.65716998 -2.20361998 0.79448996 -2.20361998 0 P 0 ;0
L 0.65593002 -2.20261998 0.79106004 -2.20261998 0 P 0 ;0
L 0.65468996 -2.20161998 0.78763996 -2.20161998 0 P 0 ;0
L 0.83143002 -2.25261998 0.80871998 -2.25225 0 P 0 ;0
L 0.80871998 -2.25225 0.78691998 -2.25066998 0 P 0 ;0
L 0.78691998 -2.25066998 0.76525 -2.24786998 0 P 0 ;0
L 0.76525 -2.24786998 0.74581998 -2.24403996 0 P 0 ;0
L 0.74581998 -2.24403996 0.72671004 -2.23876004 0 P 0 ;0
L 0.72671004 -2.23876004 0.71196004 -2.23356998 0 P 0 ;0
L 0.71196004 -2.23356998 0.69756998 -2.22753996 0 P 0 ;0
L 0.69756998 -2.22753996 0.68355 -2.22066004 0 P 0 ;0
L 0.68355 -2.22066004 0.67118002 -2.2135 0 P 0 ;0
L 0.67118002 -2.2135 0.65938996 -2.20541004 0 P 0 ;0
L 0.65938996 -2.20541004 0.64825 -2.19643996 0 P 0 ;0
L 0.64825 -2.19643996 0.63861998 -2.18731998 0 P 0 ;0
L 0.63861998 -2.18731998 0.62983002 -2.17746998 0 P 0 ;0
L 0.62983002 -2.17746998 0.62188996 -2.1669 0 P 0 ;0
L 0.62188996 -2.1669 0.61678002 -2.15886998 0 P 0 ;0
L 0.61678002 -2.15886998 0.6123 -2.15056004 0 P 0 ;0
L 0.6123 -2.15056004 0.60841998 -2.14193996 0 P 0 ;0
L 0.60841998 -2.14193996 0.60516998 -2.13306998 0 P 0 ;0
L 0.60516998 -2.13306998 0.60191004 -2.12171004 0 P 0 ;0
L 0.60191004 -2.12171004 0.60075 -2.11648002 0 P 0 ;0
L 0.60075 -2.11648002 0.59983996 -2.11121004 0 P 0 ;0
L 0.59983996 -2.11121004 0.59913996 -2.10576004 0 P 0 ;0
L 0.59913996 -2.10576004 0.59868996 -2.10026004 0 P 0 ;0
L 0.59868996 -2.10026004 0.59833002 -2.0875 0 P 0 ;0
L 0.59833002 -2.0875 0.59856998 -2.07843996 0 P 0 ;0
L 0.59856998 -2.07843996 0.59923996 -2.0695 0 P 0 ;0
L 0.59923996 -2.0695 0.60031998 -2.06153996 0 P 0 ;0
L 0.60031998 -2.06153996 0.60193002 -2.05368996 0 P 0 ;0
L 0.60193002 -2.05368996 0.60416004 -2.04566004 0 P 0 ;0
L 0.60416004 -2.04566004 0.60688996 -2.03786004 0 P 0 ;0
L 0.60688996 -2.03786004 0.6148 -2.01961004 0 P 0 ;0
L 0.6148 -2.01961004 0.62108996 -2.00753002 0 P 0 ;0
L 0.62108996 -2.00753002 0.62811998 -1.99591998 0 P 0 ;0
L 0.62811998 -1.99591998 0.63583996 -1.98478996 0 P 0 ;0
L 0.63583996 -1.98478996 0.64936998 -1.96808002 0 P 0 ;0
L 0.64936998 -1.96808002 0.66418002 -1.95256998 0 P 0 ;0
L 0.66418002 -1.95256998 0.68098002 -1.93756004 0 P 0 ;0
L 0.68098002 -1.93756004 0.69881998 -1.92398002 0 P 0 ;0
L 0.69881998 -1.92398002 0.71841998 -1.91123996 0 P 0 ;0
L 0.71841998 -1.91123996 0.73875 -1.89996998 0 P 0 ;0
L 0.73875 -1.89996998 0.74471004 -1.89696998 0 P 0 ;0
L 0.74471004 -1.89696998 0.74983002 -1.89451004 0 P 0 ;0
L 0.74983002 -1.89451004 0.7511 -1.89391004 0 P 0 ;0
L 0.7511 -1.89391004 0.75076998 -1.89488996 0 P 0 ;0
L 0.75076998 -1.89488996 0.75033996 -1.89658996 0 P 0 ;0
L 0.75033996 -1.89658996 0.75003002 -1.8983 0 P 0 ;0
L 0.75003002 -1.8983 0.74961998 -1.90161998 0 P 0 ;0
L 0.74961998 -1.90161998 0.74936004 -1.90496004 0 P 0 ;0
L 0.74936004 -1.90496004 0.74926998 -1.9085 0 P 0 ;0
L 0.74926998 -1.9085 0.74933002 -1.91201998 0 P 0 ;0
L 0.74933002 -1.91201998 0.74956004 -1.91516998 0 P 0 ;0
L 0.74956004 -1.91516998 0.75 -1.91828996 0 P 0 ;0
L 0.75 -1.91828996 0.75075 -1.92205 0 P 0 ;0
L 0.75075 -1.92205 0.75166004 -1.92573996 0 P 0 ;0
L 0.75166004 -1.92573996 0.7527 -1.92916998 0 P 0 ;0
L 0.7527 -1.92916998 0.75393996 -1.93253002 0 P 0 ;0
L 0.75393996 -1.93253002 0.75536004 -1.93581998 0 P 0 ;0
L 0.75536004 -1.93581998 0.75696004 -1.939 0 P 0 ;0
L 0.75696004 -1.939 0.75885 -1.94231004 0 P 0 ;0
L 0.75885 -1.94231004 0.76083996 -1.94543996 0 P 0 ;0
L 0.76083996 -1.94543996 0.76338996 -1.94933996 0 P 0 ;0
L 0.76338996 -1.94933996 0.76371998 -1.94991998 0 P 0 ;0
L 0.76371998 -1.94991998 0.76401004 -1.9505 0 P 0 ;0
L 0.76401004 -1.9505 0.76423996 -1.95103002 0 P 0 ;0
L 0.76423996 -1.95103002 0.76408996 -1.95111004 0 P 0 ;0
L 0.76408996 -1.95111004 0.76348996 -1.95151004 0 P 0 ;0
L 0.76348996 -1.95151004 0.76021004 -1.95386004 0 P 0 ;0
L 0.76021004 -1.95386004 0.7602 -1.95386998 0 P 0 ;0
L 0.7602 -1.95386998 0.75636998 -1.95666004 0 P 0 ;0
L 0.75636998 -1.95666004 0.75636004 -1.95666998 0 P 0 ;0
L 0.75636004 -1.95666998 0.75635 -1.95666998 0 P 0 ;0
L 0.75635 -1.95666998 0.75208996 -1.95981004 0 P 0 ;0
L 0.75208996 -1.95981004 0.73841004 -1.97066998 0 P 0 ;0
L 0.73841004 -1.97066998 0.72541004 -1.98241004 0 P 0 ;0
L 0.72541004 -1.98241004 0.7143 -1.994 0 P 0 ;0
L 0.7143 -1.994 0.71425 -1.99406004 0 P 0 ;0
L 0.71425 -1.99406004 0.70413996 -2.00648002 0 P 0 ;0
L 0.70413996 -2.00648002 0.69836998 -2.01468996 0 P 0 ;0
L 0.69836998 -2.01468996 0.69313002 -2.02318002 0 P 0 ;0
L 0.69313002 -2.02318002 0.68838996 -2.03196004 0 P 0 ;0
L 0.68838996 -2.03196004 0.68438996 -2.04063996 0 P 0 ;0
L 0.68438996 -2.04063996 0.68098996 -2.04958002 0 P 0 ;0
L 0.68098996 -2.04958002 0.6782 -2.05873002 0 P 0 ;0
L 0.6782 -2.05873002 0.67706004 -2.06366004 0 P 0 ;0
L 0.67706004 -2.06366004 0.67628996 -2.06866998 0 P 0 ;0
L 0.67628996 -2.06866998 0.67538002 -2.08068996 0 P 0 ;0
L 0.67538002 -2.08068996 0.67546004 -2.09268996 0 P 0 ;0
L 0.67546004 -2.09268996 0.67588996 -2.09766998 0 P 0 ;0
L 0.67588996 -2.09766998 0.6767 -2.10258996 0 P 0 ;0
L 0.6767 -2.10258996 0.67881998 -2.11111998 0 P 0 ;0
L 0.67881998 -2.11111998 0.68163996 -2.11936004 0 P 0 ;0
L 0.68163996 -2.11936004 0.68516004 -2.12731998 0 P 0 ;0
L 0.68516004 -2.12731998 0.68935 -2.13493996 0 P 0 ;0
L 0.68935 -2.13493996 0.69418002 -2.14216998 0 P 0 ;0
L 0.69418002 -2.14216998 0.70153002 -2.15135 0 P 0 ;0
L 0.70153002 -2.15135 0.7096 -2.15983002 0 P 0 ;0
L 0.7096 -2.15983002 0.71836004 -2.16758996 0 P 0 ;0
L 0.71836004 -2.16758996 0.71843002 -2.16763996 0 P 0 ;0
L 0.71843002 -2.16763996 0.72773996 -2.17456004 0 P 0 ;0
L 0.72773996 -2.17456004 0.73926998 -2.1818 0 P 0 ;0
L 0.73926998 -2.1818 0.75121004 -2.18818002 0 P 0 ;0
L 0.75121004 -2.18818002 0.75128002 -2.18821004 0 P 0 ;0
L 0.75128002 -2.18821004 0.76358002 -2.19368996 0 P 0 ;0
L 0.76358002 -2.19368996 0.77628002 -2.19831004 0 P 0 ;0
L 0.77628002 -2.19831004 0.79658996 -2.20423996 0 P 0 ;0
L 0.79658996 -2.20423996 0.81701004 -2.20888996 0 P 0 ;0
L 0.81701004 -2.20888996 0.83763996 -2.21233002 0 P 0 ;0
L 0.83763996 -2.21233002 0.85388002 -2.21383002 0 P 0 ;0
L 0.85388002 -2.21383002 0.87733996 -2.21465 0 P 0 ;0
L 0.87733996 -2.21465 0.90118002 -2.21478996 0 P 0 ;0
L 0.90118002 -2.21478996 0.91906004 -2.21398996 0 P 0 ;0
L 0.91906004 -2.21398996 0.94908996 -2.21068002 0 P 0 ;0
L 0.94908996 -2.21068002 0.98176998 -2.2053 0 P 0 ;0
L 0.98176998 -2.2053 1.01575 -2.19815 0 P 0 ;0
L 1.01575 -2.19815 1.04968002 -2.18943002 0 P 0 ;0
L 1.04968002 -2.18943002 1.05633996 -2.18761004 0 P 0 ;0
L 1.05633996 -2.18761004 1.05713996 -2.1874 0 P 0 ;0
L 1.05713996 -2.1874 1.05483002 -2.18875 0 P 0 ;0
L 1.05483002 -2.18875 1.04298996 -2.19526004 0 P 0 ;0
L 1.04298996 -2.19526004 1.03096998 -2.20136998 0 P 0 ;0
L 1.03096998 -2.20136998 0.99835 -2.21595 0 P 0 ;0
L 0.99835 -2.21595 0.96401998 -2.22873996 0 P 0 ;0
L 0.96401998 -2.22873996 0.92993996 -2.23908002 0 P 0 ;0
L 0.92993996 -2.23908002 0.89816004 -2.24626004 0 P 0 ;0
L 0.89816004 -2.24626004 0.87616004 -2.24965 0 P 0 ;0
L 0.87616004 -2.24965 0.85405 -2.25176004 0 P 0 ;0
L 0.85405 -2.25176004 0.83143002 -2.25261998 0 P 0 ;0
L 0.65345 -2.20061998 0.78421004 -2.20061998 0 P 0 ;0
L 0.65221004 -2.19961998 0.78078002 -2.19961998 0 P 0 ;0
L 0.65096004 -2.19861998 0.77735 -2.19861998 0 P 0 ;0
L 0.64971998 -2.19761998 0.77438996 -2.19761998 0 P 0 ;0
L 0.64848002 -2.19661998 0.77163996 -2.19661998 0 P 0 ;0
L 0.64738996 -2.19561998 0.76888996 -2.19561998 0 P 0 ;0
L 0.64633996 -2.19461998 0.76613996 -2.19461998 0 P 0 ;0
L 0.64528002 -2.19361998 0.76343002 -2.19361998 0 P 0 ;0
L 0.64421998 -2.19261998 0.76118996 -2.19261998 0 P 0 ;0
L 0.64316998 -2.19161998 0.75893996 -2.19161998 0 P 0 ;0
L 0.64211004 -2.19061998 0.7567 -2.19061998 0 P 0 ;0
L 0.64106004 -2.18961998 0.75446004 -2.18961998 0 P 0 ;0
L 0.64 -2.18861998 0.75221004 -2.18861998 0 P 0 ;0
L 0.63895 -2.18761998 0.75018002 -2.18761998 0 P 0 ;0
L 0.63801004 -2.18661998 0.74831004 -2.18661998 0 P 0 ;0
L 0.63711004 -2.18561998 0.74643002 -2.18561998 0 P 0 ;0
L 0.63621998 -2.18461998 0.74456004 -2.18461998 0 P 0 ;0
L 0.63533002 -2.18361998 0.74268002 -2.18361998 0 P 0 ;0
L 0.63443996 -2.18261998 0.74081004 -2.18261998 0 P 0 ;0
L 0.63353996 -2.18161998 0.73898996 -2.18161998 0 P 0 ;0
L 0.63265 -2.18061998 0.73738996 -2.18061998 0 P 0 ;0
L 0.63176004 -2.17961998 0.7358 -2.17961998 0 P 0 ;0
L 0.63086998 -2.17861998 0.73421004 -2.17861998 0 P 0 ;0
L 0.62996998 -2.17761998 0.73261998 -2.17761998 0 P 0 ;0
L 0.6292 -2.17661998 0.73103002 -2.17661998 0 P 0 ;0
L 0.62845 -2.17561998 0.72943996 -2.17561998 0 P 0 ;0
L 0.6277 -2.17461998 0.72783996 -2.17461998 0 P 0 ;0
L 0.62693996 -2.17361998 0.72648002 -2.17361998 0 P 0 ;0
L 0.62618996 -2.17261998 0.72513996 -2.17261998 0 P 0 ;0
L 0.62543996 -2.17161998 0.72378996 -2.17161998 0 P 0 ;0
L 0.62468996 -2.17061998 0.72245 -2.17061998 0 P 0 ;0
L 0.62393996 -2.16961998 0.7211 -2.16961998 0 P 0 ;0
L 0.62318002 -2.16861998 0.71976004 -2.16861998 0 P 0 ;0
L 0.62243996 -2.16761998 0.71841004 -2.16761998 0 P 0 ;0
L 0.62171004 -2.16661998 0.71726998 -2.16661998 0 P 0 ;0
L 0.62108002 -2.16561998 0.71613996 -2.16561998 0 P 0 ;0
L 0.62043996 -2.16461998 0.71501004 -2.16461998 0 P 0 ;0
L 0.61981004 -2.16361998 0.71388002 -2.16361998 0 P 0 ;0
L 0.61916998 -2.16261998 0.71276004 -2.16261998 0 P 0 ;0
L 0.61853002 -2.16161998 0.71163002 -2.16161998 0 P 0 ;0
L 0.6179 -2.16061998 0.7105 -2.16061998 0 P 0 ;0
L 0.61726004 -2.15961998 0.7094 -2.15961998 0 P 0 ;0
L 0.61665 -2.15861998 0.70845 -2.15861998 0 P 0 ;0
L 0.61611004 -2.15761998 0.7075 -2.15761998 0 P 0 ;0
L 0.75383996 -2.24561998 0.901 -2.24561998 0 P 0 ;0
L 0.74876998 -2.24461998 0.90541998 -2.24461998 0 P 0 ;0
L 0.74431004 -2.24361998 0.90985 -2.24361998 0 P 0 ;0
L 0.7407 -2.24261998 0.91426998 -2.24261998 0 P 0 ;0
L 0.73708002 -2.24161998 0.9187 -2.24161998 0 P 0 ;0
L 0.73346998 -2.24061998 0.92311998 -2.24061998 0 P 0 ;0
L 0.72986004 -2.23961998 0.92753996 -2.23961998 0 P 0 ;0
L 0.72633996 -2.23861998 0.93145 -2.23861998 0 P 0 ;0
L 0.72348996 -2.23761998 0.93473996 -2.23761998 0 P 0 ;0
L 0.72063996 -2.23661998 0.93803996 -2.23661998 0 P 0 ;0
L 0.7178 -2.23561998 0.94133002 -2.23561998 0 P 0 ;0
L 0.71495 -2.23461998 0.94461998 -2.23461998 0 P 0 ;0
L 0.7121 -2.23361998 0.94791998 -2.23361998 0 P 0 ;0
L 0.70968996 -2.23261998 0.95121004 -2.23261998 0 P 0 ;0
L 0.70731004 -2.23161998 0.95451004 -2.23161998 0 P 0 ;0
L 0.70491998 -2.23061998 0.9578 -2.23061998 0 P 0 ;0
L 0.70253996 -2.22961998 0.9611 -2.22961998 0 P 0 ;0
L 0.70015 -2.22861998 0.96431998 -2.22861998 0 P 0 ;0
L 9.44266998 5.22001998 9.42358002 5.20093002 1 P 0 
L 9.42358002 5.20093002 9.40448996 5.22001998 1 P 0 
L 9.41438996 5.21506998 9.42853002 5.22921004 3 P 0 
L 9.41933996 5.21011998 9.43348002 5.22426004 3 P 0 
L 9.42358002 5.23911004 9.44266998 5.22001998 1 P 0 
L 9.42358002 5.20588002 9.43771998 5.22001998 3 P 0 
L 9.41013996 5.21931004 9.42428996 5.23346004 3 P 0 
L 9.40448996 5.22001998 9.42358002 5.23911004 1 P 0 
L 9.4152 4.998 9.4152 4.962 4 P 0 
L 9.4092 4.998 9.4092 4.962 4 P 0 
L 9.55693002 4.998 9.55693002 4.962 4 P 0 
L 9.55093002 4.998 9.55093002 4.962 4 P 0 
L 9.54193002 4.998 9.54193002 4.962 4 P 0 
L 9.53293002 4.998 9.53293002 4.962 4 P 0 
L 9.55993002 5.004 9.56193002 5.004 1 P 0 
L 9.56193002 5.004 9.56293002 5.003 1 P 0 
L 9.56293002 5.003 9.56293002 4.956 1 P 0 
L 9.56293002 4.956 9.56193002 4.955 1 P 0 
L 9.56193002 4.955 9.52793002 4.955 1 P 0 
L 9.52793002 4.955 9.52693002 4.956 1 P 0 
L 9.52693002 4.956 9.52693002 5.003 1 P 0 
L 9.52693002 5.003 9.52793002 5.004 1 P 0 
L 9.52793002 5.004 9.55993002 5.004 1 P 0 
L 9.51186998 5.13928996 9.52601998 5.15343996 3 P 0 
L 9.51611998 5.13505 9.53026004 5.14918996 3 P 0 
L 9.52106998 5.1301 9.53521004 5.14423996 3 P 0 
L 9.50621998 5.14 9.52531004 5.15908996 1 P 0 
L 9.52531004 5.15908996 9.5444 5.14 1 P 0 
L 9.52531004 5.12586004 9.53945 5.14 3 P 0 
L 9.5444 5.14 9.52531004 5.12091004 1 P 0 
L 9.52531004 5.12091004 9.50621998 5.14 1 P 0 
L 9.54621998 5.14 9.56531004 5.15908996 1 P 0 
L 9.55186998 5.13928996 9.56601998 5.15343996 3 P 0 
L 9.56531004 5.12586004 9.57945 5.14 3 P 0 
L 9.56531004 5.15908996 9.5844 5.14 1 P 0 
L 9.56106998 5.1301 9.57521004 5.14423996 3 P 0 
L 9.55611998 5.13505 9.57026004 5.14918996 3 P 0 
L 9.56531004 5.12091004 9.54621998 5.14 1 P 0 
L 9.5844 5.14 9.56531004 5.12091004 1 P 0 
L 9.44266998 4.78291998 9.42358002 4.76383002 1 P 0 
L 9.42358002 4.76383002 9.40448996 4.78291998 1 P 0 
L 9.41438996 4.77796998 9.42853002 4.79211004 3 P 0 
L 9.41933996 4.77301998 9.43348002 4.78716004 3 P 0 
L 9.42358002 4.80201004 9.44266998 4.78291998 1 P 0 
L 9.42358002 4.76878002 9.43771998 4.78291998 3 P 0 
L 9.41013996 4.78221004 9.42428996 4.79636004 3 P 0 
L 9.40448996 4.78291998 9.42358002 4.80201004 1 P 0 
L 9.4152 4.87673996 9.4152 4.84073996 4 P 0 
L 9.4092 4.87673996 9.4092 4.84073996 4 P 0 
L 9.48606998 4.87673996 9.48606998 4.84073996 4 P 0 
L 9.48006998 4.87673996 9.48006998 4.84073996 4 P 0 
L 9.47106998 4.87673996 9.47106998 4.84073996 4 P 0 
L 9.46206998 4.87673996 9.46206998 4.84073996 4 P 0 
L 9.48906998 4.88273996 9.49106998 4.88273996 1 P 0 
L 9.49106998 4.88273996 9.49206998 4.88173996 1 P 0 
L 9.49206998 4.88173996 9.49206998 4.83473996 1 P 0 
L 9.49206998 4.83473996 9.49106998 4.83373996 1 P 0 
L 9.49106998 4.83373996 9.45706998 4.83373996 1 P 0 
L 9.45706998 4.83373996 9.45606998 4.83473996 1 P 0 
L 9.45606998 4.83473996 9.45606998 4.88173996 1 P 0 
L 9.45606998 4.88173996 9.45706998 4.88273996 1 P 0 
L 9.45706998 4.88273996 9.48906998 4.88273996 1 P 0 
L 9.55693002 4.87673996 9.55693002 4.84073996 4 P 0 
L 9.55093002 4.87673996 9.55093002 4.84073996 4 P 0 
L 9.54193002 4.87673996 9.54193002 4.84073996 4 P 0 
L 9.53293002 4.87673996 9.53293002 4.84073996 4 P 0 
L 9.55993002 4.88273996 9.56193002 4.88273996 1 P 0 
L 9.56193002 4.88273996 9.56293002 4.88173996 1 P 0 
L 9.56293002 4.88173996 9.56293002 4.83473996 1 P 0 
L 9.56293002 4.83473996 9.56193002 4.83373996 1 P 0 
L 9.56193002 4.83373996 9.52793002 4.83373996 1 P 0 
L 9.52793002 4.83373996 9.52693002 4.83473996 1 P 0 
L 9.52693002 4.83473996 9.52693002 4.88173996 1 P 0 
L 9.52693002 4.88173996 9.52793002 4.88273996 1 P 0 
L 9.52793002 4.88273996 9.55993002 4.88273996 1 P 0 
L 9.51186998 4.71901998 9.52601998 4.73316998 3 P 0 
L 9.51611998 4.71478002 9.53026004 4.72891998 3 P 0 
L 9.52106998 4.70983002 9.53521004 4.72396998 3 P 0 
L 9.50621998 4.71973002 9.52531004 4.73881998 1 P 0 
L 9.52531004 4.73881998 9.5444 4.71973002 1 P 0 
L 9.54621998 4.71973002 9.56531004 4.73881998 1 P 0 
L 9.55186998 4.71901998 9.56601998 4.73316998 3 P 0 
L 9.56531004 4.70558996 9.57945 4.71973002 3 P 0 
L 9.56531004 4.73881998 9.5844 4.71973002 1 P 0 
L 9.56106998 4.70983002 9.57521004 4.72396998 3 P 0 
L 9.55611998 4.71478002 9.57026004 4.72891998 3 P 0 
L 9.52531004 4.70558996 9.53945 4.71973002 3 P 0 
L 9.5444 4.71973002 9.52531004 4.70063996 1 P 0 
L 9.52531004 4.70063996 9.50621998 4.71973002 1 P 0 
L 9.56531004 4.70063996 9.54621998 4.71973002 1 P 0 
L 9.5844 4.71973002 9.56531004 4.70063996 1 P 0 
L 9.51353996 4.587 9.49445 4.56791004 1 P 0 
L 9.49445 4.56791004 9.47536004 4.587 1 P 0 
L 9.45445 4.56791004 9.43536004 4.587 1 P 0 
L 9.47353996 4.587 9.45445 4.56791004 1 P 0 
L 9.45445 4.57286004 9.46858996 4.587 3 P 0 
L 9.48526004 4.58205 9.4994 4.59618996 3 P 0 
L 9.49021004 4.5771 9.50435 4.59123996 3 P 0 
L 9.49445 4.60608996 9.51353996 4.587 1 P 0 
L 9.49445 4.57286004 9.50858996 4.587 3 P 0 
L 9.48101004 4.58628996 9.49516004 4.60043996 3 P 0 
L 9.47536004 4.587 9.49445 4.60608996 1 P 0 
L 9.45445 4.60608996 9.47353996 4.587 1 P 0 
L 9.43536004 4.587 9.45445 4.60608996 1 P 0 
L 9.45021004 4.5771 9.46435 4.59123996 3 P 0 
L 9.44526004 4.58205 9.4594 4.59618996 3 P 0 
L 9.44101004 4.58628996 9.45516004 4.60043996 3 P 0 
L 9.38358002 5.20093002 9.36448996 5.22001998 1 P 0 
L 9.40266998 5.22001998 9.38358002 5.20093002 1 P 0 
L 9.38358002 5.20588002 9.39771998 5.22001998 3 P 0 
L 9.38358002 5.23911004 9.40266998 5.22001998 1 P 0 
L 9.36448996 5.22001998 9.38358002 5.23911004 1 P 0 
L 9.37933996 5.21011998 9.39348002 5.22426004 3 P 0 
L 9.37438996 5.21506998 9.38853002 5.22921004 3 P 0 
L 9.37013996 5.21931004 9.38428996 5.23346004 3 P 0 
L 9.22841004 5.21931004 9.24256004 5.23346004 3 P 0 
L 9.23266004 5.21506998 9.2468 5.22921004 3 P 0 
L 9.23761004 5.21011998 9.25175 5.22426004 3 P 0 
L 9.22276004 5.22001998 9.24185 5.23911004 1 P 0 
L 9.24185 5.23911004 9.26093996 5.22001998 1 P 0 
L 9.26276004 5.22001998 9.28185 5.23911004 1 P 0 
L 9.26841004 5.21931004 9.28256004 5.23346004 3 P 0 
L 9.28185 5.20588002 9.29598996 5.22001998 3 P 0 
L 9.28185 5.23911004 9.30093996 5.22001998 1 P 0 
L 9.27761004 5.21011998 9.29175 5.22426004 3 P 0 
L 9.27266004 5.21506998 9.2868 5.22921004 3 P 0 
L 9.24185 5.20588002 9.25598996 5.22001998 3 P 0 
L 9.26093996 5.22001998 9.24185 5.20093002 1 P 0 
L 9.24185 5.20093002 9.22276004 5.22001998 1 P 0 
L 9.28185 5.20093002 9.26276004 5.22001998 1 P 0 
L 9.30093996 5.22001998 9.28185 5.20093002 1 P 0 
L 9.3718 5.1035 9.35271004 5.08441004 1 P 0 
L 9.35271004 5.08441004 9.33361998 5.1035 1 P 0 
L 9.31271004 5.08441004 9.29361998 5.1035 1 P 0 
L 9.3318 5.1035 9.31271004 5.08441004 1 P 0 
L 9.31271004 5.08936004 9.32685 5.1035 3 P 0 
L 9.34351998 5.09855 9.35766004 5.11268996 3 P 0 
L 9.34846998 5.0936 9.36261004 5.10773996 3 P 0 
L 9.35271004 5.12258996 9.3718 5.1035 1 P 0 
L 9.35271004 5.08936004 9.36685 5.1035 3 P 0 
L 9.33926998 5.10278996 9.35341998 5.11693996 3 P 0 
L 9.33361998 5.1035 9.35271004 5.12258996 1 P 0 
L 9.31271004 5.12258996 9.3318 5.1035 1 P 0 
L 9.29361998 5.1035 9.31271004 5.12258996 1 P 0 
L 9.30846998 5.0936 9.32261004 5.10773996 3 P 0 
L 9.30351998 5.09855 9.31766004 5.11268996 3 P 0 
L 9.29926998 5.10278996 9.31341998 5.11693996 3 P 0 
L 9.4002 4.998 9.4002 4.962 4 P 0 
L 9.3912 4.998 9.3912 4.962 4 P 0 
L 9.4182 5.004 9.4202 5.004 1 P 0 
L 9.4202 5.004 9.4212 5.003 1 P 0 
L 9.4212 5.003 9.4212 4.956 1 P 0 
L 9.4212 4.956 9.4202 4.955 1 P 0 
L 9.4202 4.955 9.3862 4.955 1 P 0 
L 9.3862 4.955 9.3852 4.956 1 P 0 
L 9.3852 4.956 9.3852 5.003 1 P 0 
L 9.3852 5.003 9.3862 5.004 1 P 0 
L 9.3862 5.004 9.4182 5.004 1 P 0 
L 9.34433996 4.998 9.34433996 4.962 4 P 0 
L 9.33833996 4.998 9.33833996 4.962 4 P 0 
L 9.32933996 4.998 9.32933996 4.962 4 P 0 
L 9.27346998 4.998 9.27346998 4.962 4 P 0 
L 9.26746998 4.998 9.26746998 4.962 4 P 0 
L 9.25846998 4.998 9.25846998 4.962 4 P 0 
L 9.24946998 4.998 9.24946998 4.962 4 P 0 
L 9.27646998 5.004 9.27846998 5.004 1 P 0 
L 9.27846998 5.004 9.27946998 5.003 1 P 0 
L 9.27946998 5.003 9.27946998 4.956 1 P 0 
L 9.27946998 4.956 9.27846998 4.955 1 P 0 
L 9.27846998 4.955 9.24446998 4.955 1 P 0 
L 9.24446998 4.955 9.24346998 4.956 1 P 0 
L 9.24346998 4.956 9.24346998 5.003 1 P 0 
L 9.24346998 5.003 9.24446998 5.004 1 P 0 
L 9.24446998 5.004 9.27646998 5.004 1 P 0 
L 9.32033996 4.998 9.32033996 4.962 4 P 0 
L 9.34733996 5.004 9.34933996 5.004 1 P 0 
L 9.34933996 5.004 9.35033996 5.003 1 P 0 
L 9.35033996 5.003 9.35033996 4.956 1 P 0 
L 9.35033996 4.956 9.34933996 4.955 1 P 0 
L 9.34933996 4.955 9.31533996 4.955 1 P 0 
L 9.31533996 4.955 9.31433996 4.956 1 P 0 
L 9.31433996 4.956 9.31433996 5.003 1 P 0 
L 9.31433996 5.003 9.31533996 5.004 1 P 0 
L 9.31533996 5.004 9.34733996 5.004 1 P 0 
L 9.38358002 4.76383002 9.36448996 4.78291998 1 P 0 
L 9.40266998 4.78291998 9.38358002 4.76383002 1 P 0 
L 9.38358002 4.76878002 9.39771998 4.78291998 3 P 0 
L 9.38358002 4.80201004 9.40266998 4.78291998 1 P 0 
L 9.36448996 4.78291998 9.38358002 4.80201004 1 P 0 
L 9.37933996 4.77301998 9.39348002 4.78716004 3 P 0 
L 9.37438996 4.77796998 9.38853002 4.79211004 3 P 0 
L 9.37013996 4.78221004 9.38428996 4.79636004 3 P 0 
L 9.23006998 4.78291998 9.21098002 4.76383002 1 P 0 
L 9.21098002 4.76383002 9.19188996 4.78291998 1 P 0 
L 9.17098002 4.76383002 9.15188996 4.78291998 1 P 0 
L 9.19006998 4.78291998 9.17098002 4.76383002 1 P 0 
L 9.17098002 4.76878002 9.18511998 4.78291998 3 P 0 
L 9.20178996 4.77796998 9.21593002 4.79211004 3 P 0 
L 9.20673996 4.77301998 9.22088002 4.78716004 3 P 0 
L 9.21098002 4.80201004 9.23006998 4.78291998 1 P 0 
L 9.21098002 4.76878002 9.22511998 4.78291998 3 P 0 
L 9.19753996 4.78221004 9.21168996 4.79636004 3 P 0 
L 9.19188996 4.78291998 9.21098002 4.80201004 1 P 0 
L 9.17098002 4.80201004 9.19006998 4.78291998 1 P 0 
L 9.15188996 4.78291998 9.17098002 4.80201004 1 P 0 
L 9.16673996 4.77301998 9.18088002 4.78716004 3 P 0 
L 9.16178996 4.77796998 9.17593002 4.79211004 3 P 0 
L 9.15753996 4.78221004 9.17168996 4.79636004 3 P 0 
L 9.4002 4.87673996 9.4002 4.84073996 4 P 0 
L 9.3912 4.87673996 9.3912 4.84073996 4 P 0 
L 9.4182 4.88273996 9.4202 4.88273996 1 P 0 
L 9.4202 4.88273996 9.4212 4.88173996 1 P 0 
L 9.4212 4.88173996 9.4212 4.83473996 1 P 0 
L 9.4212 4.83473996 9.4202 4.83373996 1 P 0 
L 9.4202 4.83373996 9.3862 4.83373996 1 P 0 
L 9.3862 4.83373996 9.3852 4.83473996 1 P 0 
L 9.3852 4.83473996 9.3852 4.88173996 1 P 0 
L 9.3852 4.88173996 9.3862 4.88273996 1 P 0 
L 9.3862 4.88273996 9.4182 4.88273996 1 P 0 
L 9.2026 4.87673996 9.2026 4.84073996 4 P 0 
L 9.1966 4.87673996 9.1966 4.84073996 4 P 0 
L 9.1876 4.87673996 9.1876 4.84073996 4 P 0 
L 9.1786 4.87673996 9.1786 4.84073996 4 P 0 
L 9.2056 4.88273996 9.2076 4.88273996 1 P 0 
L 9.2076 4.88273996 9.2086 4.88173996 1 P 0 
L 9.2086 4.88173996 9.2086 4.83473996 1 P 0 
L 9.2086 4.83473996 9.2076 4.83373996 1 P 0 
L 9.2076 4.83373996 9.1736 4.83373996 1 P 0 
L 9.1736 4.83373996 9.1726 4.83473996 1 P 0 
L 9.1726 4.83473996 9.1726 4.88173996 1 P 0 
L 9.1726 4.88173996 9.1736 4.88273996 1 P 0 
L 9.1736 4.88273996 9.2056 4.88273996 1 P 0 
L 9.27346998 4.87673996 9.27346998 4.84073996 4 P 0 
L 9.26746998 4.87673996 9.26746998 4.84073996 4 P 0 
L 9.25846998 4.87673996 9.25846998 4.84073996 4 P 0 
L 9.24946998 4.87673996 9.24946998 4.84073996 4 P 0 
L 9.27646998 4.88273996 9.27846998 4.88273996 1 P 0 
L 9.27846998 4.88273996 9.27946998 4.88173996 1 P 0 
L 9.27946998 4.88173996 9.27946998 4.83473996 1 P 0 
L 9.27946998 4.83473996 9.27846998 4.83373996 1 P 0 
L 9.27846998 4.83373996 9.24446998 4.83373996 1 P 0 
L 9.24446998 4.83373996 9.24346998 4.83473996 1 P 0 
L 9.24346998 4.83473996 9.24346998 4.88173996 1 P 0 
L 9.24346998 4.88173996 9.24446998 4.88273996 1 P 0 
L 9.24446998 4.88273996 9.27646998 4.88273996 1 P 0 
L 9.22841004 4.64128996 9.24256004 4.65543996 3 P 0 
L 9.23266004 4.63705 9.2468 4.65118996 3 P 0 
L 9.23761004 4.6321 9.25175 4.64623996 3 P 0 
L 9.22276004 4.642 9.24185 4.66108996 1 P 0 
L 9.24185 4.66108996 9.26093996 4.642 1 P 0 
L 9.26276004 4.642 9.28185 4.66108996 1 P 0 
L 9.26841004 4.64128996 9.28256004 4.65543996 3 P 0 
L 9.28185 4.62786004 9.29598996 4.642 3 P 0 
L 9.28185 4.66108996 9.30093996 4.642 1 P 0 
L 9.27761004 4.6321 9.29175 4.64623996 3 P 0 
L 9.27266004 4.63705 9.2868 4.65118996 3 P 0 
L 9.24185 4.62786004 9.25598996 4.642 3 P 0 
L 9.26093996 4.642 9.24185 4.62291004 1 P 0 
L 9.24185 4.62291004 9.22276004 4.642 1 P 0 
L 9.28185 4.62291004 9.26276004 4.642 1 P 0 
L 9.30093996 4.642 9.28185 4.62291004 1 P 0 
L 8.9435 5.17001998 8.92441004 5.15093002 1 P 0 
L 8.92441004 5.15093002 8.90531998 5.17001998 1 P 0 
L 8.91521998 5.16506998 8.92936004 5.17921004 3 P 0 
L 8.92016998 5.16011998 8.93431004 5.17426004 3 P 0 
L 8.92441004 5.18911004 8.9435 5.17001998 1 P 0 
L 8.92441004 5.15588002 8.93855 5.17001998 3 P 0 
L 8.91096998 5.16931004 8.92511998 5.18346004 3 P 0 
L 8.90531998 5.17001998 8.92441004 5.18911004 1 P 0 
L 9.01581004 5.16428996 9.02996004 5.17843996 3 P 0 
L 9.02006004 5.16005 9.0342 5.17418996 3 P 0 
L 9.02501004 5.1551 9.03915 5.16923996 3 P 0 
L 9.01016004 5.165 9.02925 5.18408996 1 P 0 
L 9.02925 5.18408996 9.04833996 5.165 1 P 0 
L 9.05016004 5.165 9.06925 5.18408996 1 P 0 
L 9.05581004 5.16428996 9.06996004 5.17843996 3 P 0 
L 9.06925 5.15086004 9.08338996 5.165 3 P 0 
L 9.06925 5.18408996 9.08833996 5.165 1 P 0 
L 9.06501004 5.1551 9.07915 5.16923996 3 P 0 
L 9.06006004 5.16005 9.0742 5.17418996 3 P 0 
L 9.02925 5.15086004 9.04338996 5.165 3 P 0 
L 9.04833996 5.165 9.02925 5.14591004 1 P 0 
L 9.02925 5.14591004 9.01016004 5.165 1 P 0 
L 9.06925 5.14591004 9.05016004 5.165 1 P 0 
L 9.08833996 5.165 9.06925 5.14591004 1 P 0 
L 9.1592 5.0535 9.14011004 5.03441004 1 P 0 
L 9.14011004 5.03441004 9.12101998 5.0535 1 P 0 
L 9.10011004 5.03441004 9.08101998 5.0535 1 P 0 
L 9.1192 5.0535 9.10011004 5.03441004 1 P 0 
L 9.10011004 5.03936004 9.11425 5.0535 3 P 0 
L 9.13091998 5.04855 9.14506004 5.06268996 3 P 0 
L 9.13586998 5.0436 9.15001004 5.05773996 3 P 0 
L 9.14011004 5.07258996 9.1592 5.0535 1 P 0 
L 9.14011004 5.03936004 9.15425 5.0535 3 P 0 
L 9.12666998 5.05278996 9.14081998 5.06693996 3 P 0 
L 9.12101998 5.0535 9.14011004 5.07258996 1 P 0 
L 9.10011004 5.07258996 9.1192 5.0535 1 P 0 
L 9.08101998 5.0535 9.10011004 5.07258996 1 P 0 
L 9.09586998 5.0436 9.11001004 5.05773996 3 P 0 
L 9.09091998 5.04855 9.10506004 5.06268996 3 P 0 
L 9.08666998 5.05278996 9.10081998 5.06693996 3 P 0 
L 9.13173996 4.998 9.13173996 4.962 4 P 0 
L 9.12573996 4.998 9.12573996 4.962 4 P 0 
L 9.11673996 4.998 9.11673996 4.962 4 P 0 
L 9.10773996 4.998 9.10773996 4.962 4 P 0 
L 9.13473996 5.004 9.13673996 5.004 1 P 0 
L 9.13673996 5.004 9.13773996 5.003 1 P 0 
L 9.13773996 5.003 9.13773996 4.956 1 P 0 
L 9.13773996 4.956 9.13673996 4.955 1 P 0 
L 9.13673996 4.955 9.10273996 4.955 1 P 0 
L 9.10273996 4.955 9.10173996 4.956 1 P 0 
L 9.10173996 4.956 9.10173996 5.003 1 P 0 
L 9.10173996 5.003 9.10273996 5.004 1 P 0 
L 9.10273996 5.004 9.13473996 5.004 1 P 0 
L 9.06086998 4.998 9.06086998 4.962 4 P 0 
L 9.05486998 4.998 9.05486998 4.962 4 P 0 
L 9.04586998 4.998 9.04586998 4.962 4 P 0 
L 9.03686998 4.998 9.03686998 4.962 4 P 0 
L 9.06386998 5.004 9.06586998 5.004 1 P 0 
L 9.06586998 5.004 9.06686998 5.003 1 P 0 
L 9.06686998 5.003 9.06686998 4.956 1 P 0 
L 9.06686998 4.956 9.06586998 4.955 1 P 0 
L 9.06586998 4.955 9.03186998 4.955 1 P 0 
L 9.03186998 4.955 9.03086998 4.956 1 P 0 
L 9.03086998 4.956 9.03086998 5.003 1 P 0 
L 9.03086998 5.003 9.03186998 5.004 1 P 0 
L 9.03186998 5.004 9.06386998 5.004 1 P 0 
L 9.08833996 4.667 9.06925 4.64791004 1 P 0 
L 9.06925 4.64791004 9.05016004 4.667 1 P 0 
L 9.02925 4.64791004 9.01016004 4.667 1 P 0 
L 9.04833996 4.667 9.02925 4.64791004 1 P 0 
L 9.02925 4.65286004 9.04338996 4.667 3 P 0 
L 9.06006004 4.66205 9.0742 4.67618996 3 P 0 
L 9.06501004 4.6571 9.07915 4.67123996 3 P 0 
L 9.06925 4.68608996 9.08833996 4.667 1 P 0 
L 9.06925 4.65286004 9.08338996 4.667 3 P 0 
L 9.05581004 4.66628996 9.06996004 4.68043996 3 P 0 
L 9.05016004 4.667 9.06925 4.68608996 1 P 0 
L 9.02925 4.68608996 9.04833996 4.667 1 P 0 
L 9.01016004 4.667 9.02925 4.68608996 1 P 0 
L 9.02501004 4.6571 9.03915 4.67123996 3 P 0 
L 9.02006004 4.66205 9.0342 4.67618996 3 P 0 
L 9.01581004 4.66628996 9.02996004 4.68043996 3 P 0 
L 8.94971004 4.667 8.93061998 4.64791004 1 P 0 
L 8.93061998 4.64791004 8.91153002 4.667 1 P 0 
L 8.92143002 4.66205 8.93556998 4.67618996 3 P 0 
L 8.92638002 4.6571 8.94051998 4.67123996 3 P 0 
L 8.93061998 4.68608996 8.94971004 4.667 1 P 0 
L 8.93061998 4.65286004 8.94476004 4.667 3 P 0 
L 8.91718002 4.66628996 8.93133002 4.68043996 3 P 0 
L 8.91153002 4.667 8.93061998 4.68608996 1 P 0 
L 8.99001004 4.87673996 8.99001004 4.84073996 4 P 0 
L 8.98401004 4.87673996 8.98401004 4.84073996 4 P 0 
L 8.97501004 4.87673996 8.97501004 4.84073996 4 P 0 
L 8.96601004 4.87673996 8.96601004 4.84073996 4 P 0 
L 8.99301004 4.88273996 8.99501004 4.88273996 1 P 0 
L 8.99501004 4.88273996 8.99601004 4.88173996 1 P 0 
L 8.99601004 4.88173996 8.99601004 4.83473996 1 P 0 
L 8.99601004 4.83473996 8.99501004 4.83373996 1 P 0 
L 8.99501004 4.83373996 8.96101004 4.83373996 1 P 0 
L 8.96101004 4.83373996 8.96001004 4.83473996 1 P 0 
L 8.96001004 4.83473996 8.96001004 4.88173996 1 P 0 
L 8.96001004 4.88173996 8.96101004 4.88273996 1 P 0 
L 8.96101004 4.88273996 8.99301004 4.88273996 1 P 0 
L 9.06086998 4.87673996 9.06086998 4.84073996 4 P 0 
L 9.05486998 4.87673996 9.05486998 4.84073996 4 P 0 
L 9.04586998 4.87673996 9.04586998 4.84073996 4 P 0 
L 9.03686998 4.87673996 9.03686998 4.84073996 4 P 0 
L 9.06386998 4.88273996 9.06586998 4.88273996 1 P 0 
L 9.06586998 4.88273996 9.06686998 4.88173996 1 P 0 
L 9.06686998 4.88173996 9.06686998 4.83473996 1 P 0 
L 9.06686998 4.83473996 9.06586998 4.83373996 1 P 0 
L 9.06586998 4.83373996 9.03186998 4.83373996 1 P 0 
L 9.03186998 4.83373996 9.03086998 4.83473996 1 P 0 
L 9.03086998 4.83473996 9.03086998 4.88173996 1 P 0 
L 9.03086998 4.88173996 9.03186998 4.88273996 1 P 0 
L 9.03186998 4.88273996 9.06386998 4.88273996 1 P 0 
L 8.88441004 5.15093002 8.86531998 5.17001998 1 P 0 
L 8.9035 5.17001998 8.88441004 5.15093002 1 P 0 
L 8.88441004 5.15588002 8.89855 5.17001998 3 P 0 
L 8.88441004 5.18911004 8.9035 5.17001998 1 P 0 
L 8.86531998 5.17001998 8.88441004 5.18911004 1 P 0 
L 8.88016998 5.16011998 8.89431004 5.17426004 3 P 0 
L 8.87521998 5.16506998 8.88936004 5.17921004 3 P 0 
L 8.87096998 5.16931004 8.88511998 5.18346004 3 P 0 
L 8.84826998 4.998 8.84826998 4.962 4 P 0 
L 8.84226998 4.998 8.84226998 4.962 4 P 0 
L 8.83326998 4.998 8.83326998 4.962 4 P 0 
L 8.82426998 4.998 8.82426998 4.962 4 P 0 
L 8.85126998 5.004 8.85326998 5.004 1 P 0 
L 8.85326998 5.004 8.85426998 5.003 1 P 0 
L 8.85426998 5.003 8.85426998 4.956 1 P 0 
L 8.85426998 4.956 8.85326998 4.955 1 P 0 
L 8.85326998 4.955 8.81926998 4.955 1 P 0 
L 8.81926998 4.955 8.81826998 4.956 1 P 0 
L 8.81826998 4.956 8.81826998 5.003 1 P 0 
L 8.81826998 5.003 8.81926998 5.004 1 P 0 
L 8.81926998 5.004 8.85126998 5.004 1 P 0 
L 8.77741004 4.998 8.77741004 4.962 4 P 0 
L 8.77141004 4.998 8.77141004 4.962 4 P 0 
L 8.76241004 4.998 8.76241004 4.962 4 P 0 
L 8.75341004 4.998 8.75341004 4.962 4 P 0 
L 8.78041004 5.004 8.78241004 5.004 1 P 0 
L 8.78241004 5.004 8.78341004 5.003 1 P 0 
L 8.78341004 5.003 8.78341004 4.956 1 P 0 
L 8.78341004 4.956 8.78241004 4.955 1 P 0 
L 8.78241004 4.955 8.74841004 4.955 1 P 0 
L 8.74841004 4.955 8.74741004 4.956 1 P 0 
L 8.74741004 4.956 8.74741004 5.003 1 P 0 
L 8.74741004 5.003 8.74841004 5.004 1 P 0 
L 8.74841004 5.004 8.78041004 5.004 1 P 0 
L 8.73235 5.13928996 8.7465 5.15343996 3 P 0 
L 8.7366 5.13505 8.75073996 5.14918996 3 P 0 
L 8.74155 5.1301 8.75568996 5.14423996 3 P 0 
L 8.7267 5.14 8.74578996 5.15908996 1 P 0 
L 8.74578996 5.15908996 8.76488002 5.14 1 P 0 
L 8.74578996 5.12586004 8.75993002 5.14 3 P 0 
L 8.76488002 5.14 8.74578996 5.12091004 1 P 0 
L 8.74578996 5.12091004 8.7267 5.14 1 P 0 
L 8.7667 5.14 8.78578996 5.15908996 1 P 0 
L 8.77235 5.13928996 8.7865 5.15343996 3 P 0 
L 8.78578996 5.12586004 8.79993002 5.14 3 P 0 
L 8.78578996 5.15908996 8.80488002 5.14 1 P 0 
L 8.78155 5.1301 8.79568996 5.14423996 3 P 0 
L 8.7766 5.13505 8.79073996 5.14918996 3 P 0 
L 8.78578996 5.12091004 8.7667 5.14 1 P 0 
L 8.80488002 5.14 8.78578996 5.12091004 1 P 0 
L 8.89061998 4.64791004 8.87153002 4.667 1 P 0 
L 8.90971004 4.667 8.89061998 4.64791004 1 P 0 
L 8.89061998 4.65286004 8.90476004 4.667 3 P 0 
L 8.89061998 4.68608996 8.90971004 4.667 1 P 0 
L 8.87153002 4.667 8.89061998 4.68608996 1 P 0 
L 8.88638002 4.6571 8.90051998 4.67123996 3 P 0 
L 8.88143002 4.66205 8.89556998 4.67618996 3 P 0 
L 8.87718002 4.66628996 8.89133002 4.68043996 3 P 0 
L 8.87573996 4.78291998 8.85665 4.76383002 1 P 0 
L 8.85665 4.76383002 8.83756004 4.78291998 1 P 0 
L 8.81665 4.76383002 8.79756004 4.78291998 1 P 0 
L 8.83573996 4.78291998 8.81665 4.76383002 1 P 0 
L 8.81665 4.76878002 8.83078996 4.78291998 3 P 0 
L 8.84746004 4.77796998 8.8616 4.79211004 3 P 0 
L 8.85241004 4.77301998 8.86655 4.78716004 3 P 0 
L 8.85665 4.80201004 8.87573996 4.78291998 1 P 0 
L 8.85665 4.76878002 8.87078996 4.78291998 3 P 0 
L 8.84321004 4.78221004 8.85736004 4.79636004 3 P 0 
L 8.83756004 4.78291998 8.85665 4.80201004 1 P 0 
L 8.81665 4.80201004 8.83573996 4.78291998 1 P 0 
L 8.79756004 4.78291998 8.81665 4.80201004 1 P 0 
L 8.81241004 4.77301998 8.82655 4.78716004 3 P 0 
L 8.80746004 4.77796998 8.8216 4.79211004 3 P 0 
L 8.80321004 4.78221004 8.81736004 4.79636004 3 P 0 
L 8.84226998 4.87673996 8.84226998 4.84073996 4 P 0 
L 8.84826998 4.87673996 8.84826998 4.84073996 4 P 0 
L 8.85126998 4.88273996 8.85326998 4.88273996 1 P 0 
L 8.85326998 4.88273996 8.85426998 4.88173996 1 P 0 
L 8.85426998 4.88173996 8.85426998 4.83473996 1 P 0 
L 8.85426998 4.83473996 8.85326998 4.83373996 1 P 0 
L 8.85326998 4.83373996 8.81926998 4.83373996 1 P 0 
L 8.81926998 4.83373996 8.81826998 4.83473996 1 P 0 
L 8.81826998 4.83473996 8.81826998 4.88173996 1 P 0 
L 8.81826998 4.88173996 8.81926998 4.88273996 1 P 0 
L 8.81926998 4.88273996 8.85126998 4.88273996 1 P 0 
L 8.82426998 4.87673996 8.82426998 4.84073996 4 P 0 
L 8.83326998 4.87673996 8.83326998 4.84073996 4 P 0 
L 8.77741004 4.87673996 8.77741004 4.84073996 4 P 0 
L 8.77141004 4.87673996 8.77141004 4.84073996 4 P 0 
L 8.76241004 4.87673996 8.76241004 4.84073996 4 P 0 
L 8.75341004 4.87673996 8.75341004 4.84073996 4 P 0 
L 8.78041004 4.88273996 8.78241004 4.88273996 1 P 0 
L 8.78241004 4.88273996 8.78341004 4.88173996 1 P 0 
L 8.78341004 4.88173996 8.78341004 4.83473996 1 P 0 
L 8.78341004 4.83473996 8.78241004 4.83373996 1 P 0 
L 8.78241004 4.83373996 8.74841004 4.83373996 1 P 0 
L 8.74841004 4.83373996 8.74741004 4.83473996 1 P 0 
L 8.74741004 4.83473996 8.74741004 4.88173996 1 P 0 
L 8.74741004 4.88173996 8.74841004 4.88273996 1 P 0 
L 8.74841004 4.88273996 8.78041004 4.88273996 1 P 0 
L 8.73235 4.66628996 8.7465 4.68043996 3 P 0 
L 8.7366 4.66205 8.75073996 4.67618996 3 P 0 
L 8.74155 4.6571 8.75568996 4.67123996 3 P 0 
L 8.7267 4.667 8.74578996 4.68608996 1 P 0 
L 8.74578996 4.68608996 8.76488002 4.667 1 P 0 
L 8.7667 4.667 8.78578996 4.68608996 1 P 0 
L 8.77235 4.66628996 8.7865 4.68043996 3 P 0 
L 8.78578996 4.65286004 8.79993002 4.667 3 P 0 
L 8.78578996 4.68608996 8.80488002 4.667 1 P 0 
L 8.78155 4.6571 8.79568996 4.67123996 3 P 0 
L 8.7766 4.66205 8.79073996 4.67618996 3 P 0 
L 8.74578996 4.65286004 8.75993002 4.667 3 P 0 
L 8.76488002 4.667 8.74578996 4.64791004 1 P 0 
L 8.74578996 4.64791004 8.7267 4.667 1 P 0 
L 8.78578996 4.64791004 8.7667 4.667 1 P 0 
L 8.80488002 4.667 8.78578996 4.64791004 1 P 0 
L 8.34726998 5.11428996 8.36141998 5.12843996 3 P 0 
L 8.35151998 5.11005 8.36566004 5.12418996 3 P 0 
L 8.35646998 5.1051 8.37061004 5.11923996 3 P 0 
L 8.34161998 5.115 8.36071004 5.13408996 1 P 0 
L 8.36071004 5.13408996 8.3798 5.115 1 P 0 
L 8.38161998 5.115 8.40071004 5.13408996 1 P 0 
L 8.38726998 5.11428996 8.40141998 5.12843996 3 P 0 
L 8.40071004 5.10086004 8.41485 5.115 3 P 0 
L 8.40071004 5.13408996 8.4198 5.115 1 P 0 
L 8.39646998 5.1051 8.41061004 5.11923996 3 P 0 
L 8.39151998 5.11005 8.40566004 5.12418996 3 P 0 
L 8.36071004 5.10086004 8.37485 5.115 3 P 0 
L 8.3798 5.115 8.36071004 5.09591004 1 P 0 
L 8.36071004 5.09591004 8.34161998 5.115 1 P 0 
L 8.40071004 5.09591004 8.38161998 5.115 1 P 0 
L 8.4198 5.115 8.40071004 5.09591004 1 P 0 
L 8.18811004 5.03441004 8.16901998 5.0535 1 P 0 
L 8.16901998 5.0535 8.18811004 5.07258996 1 P 0 
L 8.17466998 5.05278996 8.18881998 5.06693996 3 P 0 
L 8.2072 5.0535 8.18811004 5.03441004 1 P 0 
L 8.18811004 5.03936004 8.20225 5.0535 3 P 0 
L 8.18811004 5.07258996 8.2072 5.0535 1 P 0 
L 8.18386998 5.0436 8.19801004 5.05773996 3 P 0 
L 8.17891998 5.04855 8.19306004 5.06268996 3 P 0 
L 8.39533002 5.004 8.39733002 5.004 1 P 0 
L 8.39733002 5.004 8.39833002 5.003 1 P 0 
L 8.39833002 5.003 8.39833002 4.956 1 P 0 
L 8.39833002 4.956 8.39733002 4.955 1 P 0 
L 8.39733002 4.955 8.36333002 4.955 1 P 0 
L 8.36333002 4.955 8.36233002 4.956 1 P 0 
L 8.36233002 4.956 8.36233002 5.003 1 P 0 
L 8.36233002 5.003 8.36333002 5.004 1 P 0 
L 8.36333002 5.004 8.39533002 5.004 1 P 0 
L 8.36833002 4.998 8.36833002 4.962 4 P 0 
L 8.37733002 4.998 8.37733002 4.962 4 P 0 
L 8.38633002 4.998 8.38633002 4.962 4 P 0 
L 8.39233002 4.998 8.39233002 4.962 4 P 0 
L 8.16473996 4.998 8.16473996 4.962 4 P 0 
L 8.17373996 4.998 8.17373996 4.962 4 P 0 
L 8.17973996 4.998 8.17973996 4.962 4 P 0 
L 8.20553996 4.78221004 8.21968996 4.79636004 3 P 0 
L 8.20978996 4.77796998 8.22393002 4.79211004 3 P 0 
L 8.21473996 4.77301998 8.22888002 4.78716004 3 P 0 
L 8.19988996 4.78291998 8.21898002 4.80201004 1 P 0 
L 8.21898002 4.80201004 8.23806998 4.78291998 1 P 0 
L 8.23988996 4.78291998 8.25898002 4.80201004 1 P 0 
L 8.24553996 4.78221004 8.25968996 4.79636004 3 P 0 
L 8.25898002 4.76878002 8.27311998 4.78291998 3 P 0 
L 8.25898002 4.80201004 8.27806998 4.78291998 1 P 0 
L 8.25473996 4.77301998 8.26888002 4.78716004 3 P 0 
L 8.24978996 4.77796998 8.26393002 4.79211004 3 P 0 
L 8.21898002 4.76878002 8.23311998 4.78291998 3 P 0 
L 8.23806998 4.78291998 8.21898002 4.76383002 1 P 0 
L 8.21898002 4.76383002 8.19988996 4.78291998 1 P 0 
L 8.25898002 4.76383002 8.23988996 4.78291998 1 P 0 
L 8.27806998 4.78291998 8.25898002 4.76383002 1 P 0 
L 8.20865 4.66628996 8.2228 4.68043996 3 P 0 
L 8.2129 4.66205 8.22703996 4.67618996 3 P 0 
L 8.21785 4.6571 8.23198996 4.67123996 3 P 0 
L 8.203 4.667 8.22208996 4.68608996 1 P 0 
L 8.22208996 4.68608996 8.24118002 4.667 1 P 0 
L 8.243 4.667 8.26208996 4.68608996 1 P 0 
L 8.24865 4.66628996 8.2628 4.68043996 3 P 0 
L 8.26208996 4.68608996 8.28118002 4.667 1 P 0 
L 8.25785 4.6571 8.27198996 4.67123996 3 P 0 
L 8.2529 4.66205 8.26703996 4.67618996 3 P 0 
L 8.26208996 4.65286004 8.27623002 4.667 3 P 0 
L 8.22208996 4.65286004 8.23623002 4.667 3 P 0 
L 8.24118002 4.667 8.22208996 4.64791004 1 P 0 
L 8.22208996 4.64791004 8.203 4.667 1 P 0 
L 8.26208996 4.64791004 8.243 4.667 1 P 0 
L 8.28118002 4.667 8.26208996 4.64791004 1 P 0 
L 8.2536 4.88273996 8.2556 4.88273996 1 P 0 
L 8.2556 4.88273996 8.2566 4.88173996 1 P 0 
L 8.2566 4.88173996 8.2566 4.83473996 1 P 0 
L 8.2566 4.83473996 8.2556 4.83373996 1 P 0 
L 8.2556 4.83373996 8.2216 4.83373996 1 P 0 
L 8.2216 4.83373996 8.2206 4.83473996 1 P 0 
L 8.2206 4.83473996 8.2206 4.88173996 1 P 0 
L 8.2206 4.88173996 8.2216 4.88273996 1 P 0 
L 8.2216 4.88273996 8.2536 4.88273996 1 P 0 
L 8.2266 4.87673996 8.2266 4.84073996 4 P 0 
L 8.2356 4.87673996 8.2356 4.84073996 4 P 0 
L 8.2446 4.87673996 8.2446 4.84073996 4 P 0 
L 8.2506 4.87673996 8.2506 4.84073996 4 P 0 
L 8.39533002 4.88273996 8.39733002 4.88273996 1 P 0 
L 8.39733002 4.88273996 8.39833002 4.88173996 1 P 0 
L 8.39833002 4.88173996 8.39833002 4.83473996 1 P 0 
L 8.39833002 4.83473996 8.39733002 4.83373996 1 P 0 
L 8.39733002 4.83373996 8.36333002 4.83373996 1 P 0 
L 8.36333002 4.83373996 8.36233002 4.83473996 1 P 0 
L 8.36233002 4.83473996 8.36233002 4.88173996 1 P 0 
L 8.36233002 4.88173996 8.36333002 4.88273996 1 P 0 
L 8.36333002 4.88273996 8.39533002 4.88273996 1 P 0 
L 8.36833002 4.87673996 8.36833002 4.84073996 4 P 0 
L 8.37733002 4.87673996 8.37733002 4.84073996 4 P 0 
L 8.38633002 4.87673996 8.38633002 4.84073996 4 P 0 
L 8.39233002 4.87673996 8.39233002 4.84073996 4 P 0 
L 8.32446998 4.88273996 8.32646998 4.88273996 1 P 0 
L 8.32646998 4.88273996 8.32746998 4.88173996 1 P 0 
L 8.32746998 4.88173996 8.32746998 4.83473996 1 P 0 
L 8.32746998 4.83473996 8.32646998 4.83373996 1 P 0 
L 8.32646998 4.83373996 8.29246998 4.83373996 1 P 0 
L 8.29246998 4.83373996 8.29146998 4.83473996 1 P 0 
L 8.29146998 4.83473996 8.29146998 4.88173996 1 P 0 
L 8.29146998 4.88173996 8.29246998 4.88273996 1 P 0 
L 8.29246998 4.88273996 8.32446998 4.88273996 1 P 0 
L 8.29746998 4.87673996 8.29746998 4.84073996 4 P 0 
L 8.30646998 4.87673996 8.30646998 4.84073996 4 P 0 
L 8.31546998 4.87673996 8.31546998 4.84073996 4 P 0 
L 8.32146998 4.87673996 8.32146998 4.84073996 4 P 0 
L 8.4198 4.742 8.40071004 4.72291004 1 P 0 
L 8.40071004 4.72291004 8.38161998 4.742 1 P 0 
L 8.36071004 4.72291004 8.34161998 4.742 1 P 0 
L 8.3798 4.742 8.36071004 4.72291004 1 P 0 
L 8.36071004 4.72786004 8.37485 4.742 3 P 0 
L 8.39151998 4.73705 8.40566004 4.75118996 3 P 0 
L 8.39646998 4.7321 8.41061004 4.74623996 3 P 0 
L 8.40071004 4.76108996 8.4198 4.742 1 P 0 
L 8.40071004 4.72786004 8.41485 4.742 3 P 0 
L 8.38726998 4.74128996 8.40141998 4.75543996 3 P 0 
L 8.38161998 4.742 8.40071004 4.76108996 1 P 0 
L 8.36071004 4.76108996 8.3798 4.742 1 P 0 
L 8.34161998 4.742 8.36071004 4.76108996 1 P 0 
L 8.35646998 4.7321 8.37061004 4.74623996 3 P 0 
L 8.35151998 4.73705 8.36566004 4.75118996 3 P 0 
L 8.34726998 4.74128996 8.36141998 4.75543996 3 P 0 
L 8.13633996 5.169 8.11725 5.14991004 1 P 0 
L 8.11725 5.14991004 8.09816004 5.169 1 P 0 
L 8.07725 5.14991004 8.05816004 5.169 1 P 0 
L 8.09633996 5.169 8.07725 5.14991004 1 P 0 
L 8.07725 5.15486004 8.09138996 5.169 3 P 0 
L 8.10806004 5.16405 8.1222 5.17818996 3 P 0 
L 8.11301004 5.1591 8.12715 5.17323996 3 P 0 
L 8.11725 5.18808996 8.13633996 5.169 1 P 0 
L 8.11725 5.15486004 8.13138996 5.169 3 P 0 
L 8.10381004 5.16828996 8.11796004 5.18243996 3 P 0 
L 8.09816004 5.169 8.11725 5.18808996 1 P 0 
L 8.07725 5.18808996 8.09633996 5.169 1 P 0 
L 8.05816004 5.169 8.07725 5.18808996 1 P 0 
L 8.07301004 5.1591 8.08715 5.17323996 3 P 0 
L 8.06806004 5.16405 8.0822 5.17818996 3 P 0 
L 8.06381004 5.16828996 8.07796004 5.18243996 3 P 0 
L 7.92373996 5.169 7.90465 5.14991004 1 P 0 
L 7.90465 5.18808996 7.92373996 5.169 1 P 0 
L 8.14811004 5.03936004 8.16225 5.0535 3 P 0 
L 8.1672 5.0535 8.14811004 5.03441004 1 P 0 
L 8.14811004 5.03441004 8.12901998 5.0535 1 P 0 
L 8.13466998 5.05278996 8.14881998 5.06693996 3 P 0 
L 8.13891998 5.04855 8.15306004 5.06268996 3 P 0 
L 8.14386998 5.0436 8.15801004 5.05773996 3 P 0 
L 8.12901998 5.0535 8.14811004 5.07258996 1 P 0 
L 8.14811004 5.07258996 8.1672 5.0535 1 P 0 
L 7.96631998 5.04855 7.98046004 5.06268996 3 P 0 
L 7.97126998 5.0436 7.98541004 5.05773996 3 P 0 
L 7.97551004 5.07258996 7.9946 5.0535 1 P 0 
L 7.97551004 5.03936004 7.98965 5.0535 3 P 0 
L 7.9946 5.0535 7.97551004 5.03441004 1 P 0 
L 7.96206998 5.05278996 7.97621998 5.06693996 3 P 0 
L 7.95641998 5.0535 7.97551004 5.07258996 1 P 0 
L 7.93551004 5.07258996 7.9546 5.0535 1 P 0 
L 7.91641998 5.0535 7.93551004 5.07258996 1 P 0 
L 7.93126998 5.0436 7.94541004 5.05773996 3 P 0 
L 7.92631998 5.04855 7.94046004 5.06268996 3 P 0 
L 7.92206998 5.05278996 7.93621998 5.06693996 3 P 0 
L 7.97551004 5.03441004 7.95641998 5.0535 1 P 0 
L 7.93551004 5.03441004 7.91641998 5.0535 1 P 0 
L 7.9546 5.0535 7.93551004 5.03441004 1 P 0 
L 7.93551004 5.03936004 7.94965 5.0535 3 P 0 
L 8.18273996 5.004 8.18473996 5.004 1 P 0 
L 8.18473996 5.004 8.18573996 5.003 1 P 0 
L 8.18573996 5.003 8.18573996 4.956 1 P 0 
L 8.18573996 4.956 8.18473996 4.955 1 P 0 
L 8.18473996 4.955 8.15073996 4.955 1 P 0 
L 8.15073996 4.955 8.14973996 4.956 1 P 0 
L 8.14973996 4.956 8.14973996 5.003 1 P 0 
L 8.14973996 5.003 8.15073996 5.004 1 P 0 
L 8.15073996 5.004 8.18273996 5.004 1 P 0 
L 8.15573996 4.998 8.15573996 4.962 4 P 0 
L 8.11186998 5.004 8.11386998 5.004 1 P 0 
L 8.11386998 5.004 8.11486998 5.003 1 P 0 
L 8.11486998 5.003 8.11486998 4.956 1 P 0 
L 8.11486998 4.956 8.11386998 4.955 1 P 0 
L 8.11386998 4.955 8.07986998 4.955 1 P 0 
L 8.07986998 4.955 8.07886998 4.956 1 P 0 
L 8.07886998 4.956 8.07886998 5.003 1 P 0 
L 8.07886998 5.003 8.07986998 5.004 1 P 0 
L 8.07986998 5.004 8.11186998 5.004 1 P 0 
L 8.08486998 4.998 8.08486998 4.962 4 P 0 
L 8.09386998 4.998 8.09386998 4.962 4 P 0 
L 8.10286998 4.998 8.10286998 4.962 4 P 0 
L 8.10886998 4.998 8.10886998 4.962 4 P 0 
L 7.97013996 5.004 7.97213996 5.004 1 P 0 
L 7.97213996 5.004 7.97313996 5.003 1 P 0 
L 7.97313996 5.003 7.97313996 4.956 1 P 0 
L 7.97313996 4.956 7.97213996 4.955 1 P 0 
L 7.97213996 4.955 7.93813996 4.955 1 P 0 
L 7.93813996 4.955 7.93713996 4.956 1 P 0 
L 7.93713996 4.956 7.93713996 5.003 1 P 0 
L 7.93713996 5.003 7.93813996 5.004 1 P 0 
L 7.93813996 5.004 7.97013996 5.004 1 P 0 
L 7.94313996 4.998 7.94313996 4.962 4 P 0 
L 7.95213996 4.998 7.95213996 4.962 4 P 0 
L 7.96113996 4.998 7.96113996 4.962 4 P 0 
L 7.96713996 4.998 7.96713996 4.962 4 P 0 
L 8.03206998 4.65275 8.04621004 4.66688996 3 P 0 
L 8.05116004 4.66688996 8.03206998 4.6478 1 P 0 
L 8.03206998 4.6478 8.01298002 4.66688996 1 P 0 
L 8.07206998 4.6478 8.05298002 4.66688996 1 P 0 
L 8.01863002 4.66618002 8.03278002 4.68033002 3 P 0 
L 8.02288002 4.66193996 8.03701998 4.67608002 3 P 0 
L 8.02783002 4.65698996 8.04196998 4.67113002 3 P 0 
L 8.01298002 4.66688996 8.03206998 4.68598002 1 P 0 
L 8.03206998 4.68598002 8.05116004 4.66688996 1 P 0 
L 8.05298002 4.66688996 8.07206998 4.68598002 1 P 0 
L 8.05863002 4.66618002 8.07278002 4.68033002 3 P 0 
L 8.09116004 4.66688996 8.07206998 4.6478 1 P 0 
L 8.07206998 4.65275 8.08621004 4.66688996 3 P 0 
L 8.07206998 4.68598002 8.09116004 4.66688996 1 P 0 
L 8.06783002 4.65698996 8.08196998 4.67113002 3 P 0 
L 8.06288002 4.66193996 8.07701998 4.67608002 3 P 0 
L 8.06381004 4.78221004 8.07796004 4.79636004 3 P 0 
L 8.06806004 4.77796998 8.0822 4.79211004 3 P 0 
L 8.07301004 4.77301998 8.08715 4.78716004 3 P 0 
L 8.05816004 4.78291998 8.07725 4.80201004 1 P 0 
L 8.07725 4.80201004 8.09633996 4.78291998 1 P 0 
L 8.09816004 4.78291998 8.11725 4.80201004 1 P 0 
L 8.10381004 4.78221004 8.11796004 4.79636004 3 P 0 
L 8.11725 4.76878002 8.13138996 4.78291998 3 P 0 
L 8.11725 4.80201004 8.13633996 4.78291998 1 P 0 
L 8.11301004 4.77301998 8.12715 4.78716004 3 P 0 
L 8.10806004 4.77796998 8.1222 4.79211004 3 P 0 
L 8.07725 4.76878002 8.09138996 4.78291998 3 P 0 
L 8.09633996 4.78291998 8.07725 4.76383002 1 P 0 
L 8.07725 4.76383002 8.05816004 4.78291998 1 P 0 
L 8.11725 4.76383002 8.09816004 4.78291998 1 P 0 
L 8.13633996 4.78291998 8.11725 4.76383002 1 P 0 
L 8.11186998 4.88273996 8.11386998 4.88273996 1 P 0 
L 8.11386998 4.88273996 8.11486998 4.88173996 1 P 0 
L 8.11486998 4.88173996 8.11486998 4.83473996 1 P 0 
L 8.11486998 4.83473996 8.11386998 4.83373996 1 P 0 
L 8.11386998 4.83373996 8.07986998 4.83373996 1 P 0 
L 8.07986998 4.83373996 8.07886998 4.83473996 1 P 0 
L 8.07886998 4.83473996 8.07886998 4.88173996 1 P 0 
L 8.07886998 4.88173996 8.07986998 4.88273996 1 P 0 
L 8.07986998 4.88273996 8.11186998 4.88273996 1 P 0 
L 8.08486998 4.87673996 8.08486998 4.84073996 4 P 0 
L 8.09386998 4.87673996 8.09386998 4.84073996 4 P 0 
L 8.10286998 4.87673996 8.10286998 4.84073996 4 P 0 
L 8.10886998 4.87673996 8.10886998 4.84073996 4 P 0 
L 8.041 4.88273996 8.043 4.88273996 1 P 0 
L 8.043 4.88273996 8.044 4.88173996 1 P 0 
L 8.044 4.88173996 8.044 4.83473996 1 P 0 
L 8.044 4.83473996 8.043 4.83373996 1 P 0 
L 8.043 4.83373996 8.009 4.83373996 1 P 0 
L 8.009 4.83373996 8.008 4.83473996 1 P 0 
L 8.008 4.83473996 8.008 4.88173996 1 P 0 
L 8.008 4.88173996 8.009 4.88273996 1 P 0 
L 8.009 4.88273996 8.041 4.88273996 1 P 0 
L 8.014 4.87673996 8.014 4.84073996 4 P 0 
L 8.023 4.87673996 8.023 4.84073996 4 P 0 
L 8.032 4.87673996 8.032 4.84073996 4 P 0 
L 8.038 4.87673996 8.038 4.84073996 4 P 0 
L 7.90465 4.67608996 7.92373996 4.657 1 P 0 
L 7.92373996 4.657 7.90465 4.63791004 1 P 0 
L 7.90465 5.14991004 7.88556004 5.169 1 P 0 
L 7.86465 5.14991004 7.84556004 5.169 1 P 0 
L 7.88373996 5.169 7.86465 5.14991004 1 P 0 
L 7.86465 5.15486004 7.87878996 5.169 3 P 0 
L 7.89546004 5.16405 7.9096 5.17818996 3 P 0 
L 7.90041004 5.1591 7.91455 5.17323996 3 P 0 
L 7.90465 5.15486004 7.91878996 5.169 3 P 0 
L 7.89121004 5.16828996 7.90536004 5.18243996 3 P 0 
L 7.88556004 5.169 7.90465 5.18808996 1 P 0 
L 7.86465 5.18808996 7.88373996 5.169 1 P 0 
L 7.84556004 5.169 7.86465 5.18808996 1 P 0 
L 7.86041004 5.1591 7.87455 5.17323996 3 P 0 
L 7.85546004 5.16405 7.8696 5.17818996 3 P 0 
L 7.85121004 5.16828996 7.86536004 5.18243996 3 P 0 
L 7.68285 5.04855 7.69698996 5.06268996 3 P 0 
L 7.6878 5.0436 7.70193996 5.05773996 3 P 0 
L 7.69203996 5.07258996 7.71113002 5.0535 1 P 0 
L 7.69203996 5.03936004 7.70618002 5.0535 3 P 0 
L 7.71113002 5.0535 7.69203996 5.03441004 1 P 0 
L 7.6786 5.05278996 7.69275 5.06693996 3 P 0 
L 7.67295 5.0535 7.69203996 5.07258996 1 P 0 
L 7.69203996 5.03441004 7.67295 5.0535 1 P 0 
L 7.89926998 5.004 7.90126998 5.004 1 P 0 
L 7.90126998 5.004 7.90226998 5.003 1 P 0 
L 7.90226998 5.003 7.90226998 4.956 1 P 0 
L 7.90226998 4.956 7.90126998 4.955 1 P 0 
L 7.90126998 4.955 7.86726998 4.955 1 P 0 
L 7.86726998 4.955 7.86626998 4.956 1 P 0 
L 7.86626998 4.956 7.86626998 5.003 1 P 0 
L 7.86626998 5.003 7.86726998 5.004 1 P 0 
L 7.86726998 5.004 7.89926998 5.004 1 P 0 
L 7.87226998 4.998 7.87226998 4.962 4 P 0 
L 7.88126998 4.998 7.88126998 4.962 4 P 0 
L 7.89026998 4.998 7.89026998 4.962 4 P 0 
L 7.89626998 4.998 7.89626998 4.962 4 P 0 
L 7.65966998 4.998 7.65966998 4.962 4 P 0 
L 7.66866998 4.998 7.66866998 4.962 4 P 0 
L 7.67766998 4.998 7.67766998 4.962 4 P 0 
L 7.68366998 4.998 7.68366998 4.962 4 P 0 
L 7.8246 4.77796998 7.83873996 4.79211004 3 P 0 
L 7.82955 4.77301998 7.84368996 4.78716004 3 P 0 
L 7.83378996 4.80201004 7.85288002 4.78291998 1 P 0 
L 7.83378996 4.76878002 7.84793002 4.78291998 3 P 0 
L 7.85288002 4.78291998 7.83378996 4.76383002 1 P 0 
L 7.82035 4.78221004 7.8345 4.79636004 3 P 0 
L 7.8147 4.78291998 7.83378996 4.80201004 1 P 0 
L 7.79378996 4.80201004 7.81288002 4.78291998 1 P 0 
L 7.7747 4.78291998 7.79378996 4.80201004 1 P 0 
L 7.78955 4.77301998 7.80368996 4.78716004 3 P 0 
L 7.7846 4.77796998 7.79873996 4.79211004 3 P 0 
L 7.78035 4.78221004 7.7945 4.79636004 3 P 0 
L 7.83378996 4.76383002 7.8147 4.78291998 1 P 0 
L 7.79378996 4.76383002 7.7747 4.78291998 1 P 0 
L 7.81288002 4.78291998 7.79378996 4.76383002 1 P 0 
L 7.79378996 4.76878002 7.80793002 4.78291998 3 P 0 
L 7.68286004 4.77796998 7.697 4.79211004 3 P 0 
L 7.68781004 4.77301998 7.70195 4.78716004 3 P 0 
L 7.69205 4.80201004 7.71113996 4.78291998 1 P 0 
L 7.69205 4.76878002 7.70618996 4.78291998 3 P 0 
L 7.71113996 4.78291998 7.69205 4.76383002 1 P 0 
L 7.67861004 4.78221004 7.69276004 4.79636004 3 P 0 
L 7.67296004 4.78291998 7.69205 4.80201004 1 P 0 
L 7.69205 4.76383002 7.67296004 4.78291998 1 P 0 
L 7.65966998 4.87673996 7.65966998 4.84073996 4 P 0 
L 7.66866998 4.87673996 7.66866998 4.84073996 4 P 0 
L 7.67766998 4.87673996 7.67766998 4.84073996 4 P 0 
L 7.68366998 4.87673996 7.68366998 4.84073996 4 P 0 
L 7.89926998 4.88273996 7.90126998 4.88273996 1 P 0 
L 7.90126998 4.88273996 7.90226998 4.88173996 1 P 0 
L 7.90226998 4.88173996 7.90226998 4.83473996 1 P 0 
L 7.90226998 4.83473996 7.90126998 4.83373996 1 P 0 
L 7.90126998 4.83373996 7.86726998 4.83373996 1 P 0 
L 7.86726998 4.83373996 7.86626998 4.83473996 1 P 0 
L 7.86626998 4.83473996 7.86626998 4.88173996 1 P 0 
L 7.86626998 4.88173996 7.86726998 4.88273996 1 P 0 
L 7.86726998 4.88273996 7.89926998 4.88273996 1 P 0 
L 7.87226998 4.87673996 7.87226998 4.84073996 4 P 0 
L 7.88126998 4.87673996 7.88126998 4.84073996 4 P 0 
L 7.89026998 4.87673996 7.89026998 4.84073996 4 P 0 
L 7.89626998 4.87673996 7.89626998 4.84073996 4 P 0 
L 7.82841004 4.88273996 7.83041004 4.88273996 1 P 0 
L 7.83041004 4.88273996 7.83141004 4.88173996 1 P 0 
L 7.83141004 4.88173996 7.83141004 4.83473996 1 P 0 
L 7.83141004 4.83473996 7.83041004 4.83373996 1 P 0 
L 7.83041004 4.83373996 7.79641004 4.83373996 1 P 0 
L 7.79641004 4.83373996 7.79541004 4.83473996 1 P 0 
L 7.79541004 4.83473996 7.79541004 4.88173996 1 P 0 
L 7.79541004 4.88173996 7.79641004 4.88273996 1 P 0 
L 7.79641004 4.88273996 7.82841004 4.88273996 1 P 0 
L 7.80141004 4.87673996 7.80141004 4.84073996 4 P 0 
L 7.81041004 4.87673996 7.81041004 4.84073996 4 P 0 
L 7.81941004 4.87673996 7.81941004 4.84073996 4 P 0 
L 7.82541004 4.87673996 7.82541004 4.84073996 4 P 0 
L 7.89546004 4.65205 7.9096 4.66618996 3 P 0 
L 7.89121004 4.65628996 7.90536004 4.67043996 3 P 0 
L 7.88556004 4.657 7.90465 4.67608996 1 P 0 
L 7.86465 4.67608996 7.88373996 4.657 1 P 0 
L 7.84556004 4.657 7.86465 4.67608996 1 P 0 
L 7.85546004 4.65205 7.8696 4.66618996 3 P 0 
L 7.85121004 4.65628996 7.86536004 4.67043996 3 P 0 
L 7.90465 4.63791004 7.88556004 4.657 1 P 0 
L 7.86465 4.63791004 7.84556004 4.657 1 P 0 
L 7.88373996 4.657 7.86465 4.63791004 1 P 0 
L 7.86465 4.64286004 7.87878996 4.657 3 P 0 
L 7.90041004 4.6471 7.91455 4.66123996 3 P 0 
L 7.90465 4.64286004 7.91878996 4.657 3 P 0 
L 7.86041004 4.6471 7.87455 4.66123996 3 P 0 
L 7.64028002 5.169 7.62118996 5.14991004 1 P 0 
L 7.62118996 5.14991004 7.6021 5.169 1 P 0 
L 7.58118996 5.14991004 7.5621 5.169 1 P 0 
L 7.60028002 5.169 7.58118996 5.14991004 1 P 0 
L 7.58118996 5.15486004 7.59533002 5.169 3 P 0 
L 7.612 5.16405 7.62613996 5.17818996 3 P 0 
L 7.61695 5.1591 7.63108996 5.17323996 3 P 0 
L 7.62118996 5.18808996 7.64028002 5.169 1 P 0 
L 7.62118996 5.15486004 7.63533002 5.169 3 P 0 
L 7.60775 5.16828996 7.6219 5.18243996 3 P 0 
L 7.6021 5.169 7.62118996 5.18808996 1 P 0 
L 7.58118996 5.18808996 7.60028002 5.169 1 P 0 
L 7.5621 5.169 7.58118996 5.18808996 1 P 0 
L 7.57695 5.1591 7.59108996 5.17323996 3 P 0 
L 7.572 5.16405 7.58613996 5.17818996 3 P 0 
L 7.56775 5.16828996 7.5819 5.18243996 3 P 0 
L 7.65203996 5.07258996 7.67113002 5.0535 1 P 0 
L 7.63295 5.0535 7.65203996 5.07258996 1 P 0 
L 7.6478 5.0436 7.66193996 5.05773996 3 P 0 
L 7.64285 5.04855 7.65698996 5.06268996 3 P 0 
L 7.6386 5.05278996 7.65275 5.06693996 3 P 0 
L 7.65203996 5.03441004 7.63295 5.0535 1 P 0 
L 7.67113002 5.0535 7.65203996 5.03441004 1 P 0 
L 7.65203996 5.03936004 7.66618002 5.0535 3 P 0 
L 7.61581004 5.004 7.61781004 5.004 1 P 0 
L 7.61781004 5.004 7.61881004 5.003 1 P 0 
L 7.61881004 5.003 7.61881004 4.956 1 P 0 
L 7.61881004 4.956 7.61781004 4.955 1 P 0 
L 7.61781004 4.955 7.58381004 4.955 1 P 0 
L 7.58381004 4.955 7.58281004 4.956 1 P 0 
L 7.58281004 4.956 7.58281004 5.003 1 P 0 
L 7.58281004 5.003 7.58381004 5.004 1 P 0 
L 7.58381004 5.004 7.61581004 5.004 1 P 0 
L 7.58881004 4.998 7.58881004 4.962 4 P 0 
L 7.59781004 4.998 7.59781004 4.962 4 P 0 
L 7.60681004 4.998 7.60681004 4.962 4 P 0 
L 7.61281004 4.998 7.61281004 4.962 4 P 0 
L 7.68666998 5.004 7.68866998 5.004 1 P 0 
L 7.68866998 5.004 7.68966998 5.003 1 P 0 
L 7.68966998 5.003 7.68966998 4.956 1 P 0 
L 7.68966998 4.956 7.68866998 4.955 1 P 0 
L 7.68866998 4.955 7.65466998 4.955 1 P 0 
L 7.65466998 4.955 7.65366998 4.956 1 P 0 
L 7.65366998 4.956 7.65366998 5.003 1 P 0 
L 7.65366998 5.003 7.65466998 5.004 1 P 0 
L 7.65466998 5.004 7.68666998 5.004 1 P 0 
L 7.65205 4.80201004 7.67113996 4.78291998 1 P 0 
L 7.63296004 4.78291998 7.65205 4.80201004 1 P 0 
L 7.64781004 4.77301998 7.66195 4.78716004 3 P 0 
L 7.64286004 4.77796998 7.657 4.79211004 3 P 0 
L 7.63861004 4.78221004 7.65276004 4.79636004 3 P 0 
L 7.65205 4.76383002 7.63296004 4.78291998 1 P 0 
L 7.67113996 4.78291998 7.65205 4.76383002 1 P 0 
L 7.65205 4.76878002 7.66618996 4.78291998 3 P 0 
L 7.68666998 4.88273996 7.68866998 4.88273996 1 P 0 
L 7.68866998 4.88273996 7.68966998 4.88173996 1 P 0 
L 7.68966998 4.88173996 7.68966998 4.83473996 1 P 0 
L 7.68966998 4.83473996 7.68866998 4.83373996 1 P 0 
L 7.68866998 4.83373996 7.65466998 4.83373996 1 P 0 
L 7.65466998 4.83373996 7.65366998 4.83473996 1 P 0 
L 7.65366998 4.83473996 7.65366998 4.88173996 1 P 0 
L 7.65366998 4.88173996 7.65466998 4.88273996 1 P 0 
L 7.65466998 4.88273996 7.68666998 4.88273996 1 P 0 
L 7.61581004 4.88273996 7.61781004 4.88273996 1 P 0 
L 7.61781004 4.88273996 7.61881004 4.88173996 1 P 0 
L 7.61881004 4.88173996 7.61881004 4.83473996 1 P 0 
L 7.61881004 4.83473996 7.61781004 4.83373996 1 P 0 
L 7.61781004 4.83373996 7.58381004 4.83373996 1 P 0 
L 7.58381004 4.83373996 7.58281004 4.83473996 1 P 0 
L 7.58281004 4.83473996 7.58281004 4.88173996 1 P 0 
L 7.58281004 4.88173996 7.58381004 4.88273996 1 P 0 
L 7.58381004 4.88273996 7.61581004 4.88273996 1 P 0 
L 7.58881004 4.87673996 7.58881004 4.84073996 4 P 0 
L 7.59781004 4.87673996 7.59781004 4.84073996 4 P 0 
L 7.60681004 4.87673996 7.60681004 4.84073996 4 P 0 
L 7.61281004 4.87673996 7.61281004 4.84073996 4 P 0 
L 7.64028002 4.707 7.62118996 4.68791004 1 P 0 
L 7.62118996 4.68791004 7.6021 4.707 1 P 0 
L 7.58118996 4.68791004 7.5621 4.707 1 P 0 
L 7.60028002 4.707 7.58118996 4.68791004 1 P 0 
L 7.58118996 4.69286004 7.59533002 4.707 3 P 0 
L 7.612 4.70205 7.62613996 4.71618996 3 P 0 
L 7.61695 4.6971 7.63108996 4.71123996 3 P 0 
L 7.62118996 4.72608996 7.64028002 4.707 1 P 0 
L 7.62118996 4.69286004 7.63533002 4.707 3 P 0 
L 7.60775 4.70628996 7.6219 4.72043996 3 P 0 
L 7.6021 4.707 7.62118996 4.72608996 1 P 0 
L 7.58118996 4.72608996 7.60028002 4.707 1 P 0 
L 7.5621 4.707 7.58118996 4.72608996 1 P 0 
L 7.57695 4.6971 7.59108996 4.71123996 3 P 0 
L 7.572 4.70205 7.58613996 4.71618996 3 P 0 
L 7.56775 4.70628996 7.5819 4.72043996 3 P 0 
L 2.80133996 5.14 2.78225 5.12091004 1 P 0 
L 2.78225 5.12091004 2.76316004 5.14 1 P 0 
L 2.77306004 5.13505 2.7872 5.14918996 3 P 0 
L 2.77801004 5.1301 2.79215 5.14423996 3 P 0 
L 2.78225 5.15908996 2.80133996 5.14 1 P 0 
L 2.78225 5.12586004 2.79638996 5.14 3 P 0 
L 2.76881004 5.13928996 2.78296004 5.15343996 3 P 0 
L 2.76316004 5.14 2.78225 5.15908996 1 P 0 
L 2.74225 5.12091004 2.72316004 5.14 1 P 0 
L 2.76133996 5.14 2.74225 5.12091004 1 P 0 
L 2.74225 5.12586004 2.75638996 5.14 3 P 0 
L 2.74225 5.15908996 2.76133996 5.14 1 P 0 
L 2.72316004 5.14 2.74225 5.15908996 1 P 0 
L 2.73801004 5.1301 2.75215 5.14423996 3 P 0 
L 2.73306004 5.13505 2.7472 5.14918996 3 P 0 
L 2.72881004 5.13928996 2.74296004 5.15343996 3 P 0 
L 3.43746998 4.58628996 3.45161998 4.60043996 3 P 0 
L 3.44171998 4.58205 3.45586004 4.59618996 3 P 0 
L 3.44666998 4.5771 3.46081004 4.59123996 3 P 0 
L 3.43181998 4.587 3.45091004 4.60608996 1 P 0 
L 3.45091004 4.60608996 3.47 4.587 1 P 0 
L 3.47181998 4.587 3.49091004 4.60608996 1 P 0 
L 3.47746998 4.58628996 3.49161998 4.60043996 3 P 0 
L 3.49091004 4.57286004 3.50505 4.587 3 P 0 
L 3.49091004 4.60608996 3.51 4.587 1 P 0 
L 3.48666998 4.5771 3.50081004 4.59123996 3 P 0 
L 3.48171998 4.58205 3.49586004 4.59618996 3 P 0 
L 3.45091004 4.57286004 3.46505 4.587 3 P 0 
L 3.47 4.587 3.45091004 4.56791004 1 P 0 
L 3.45091004 4.56791004 3.43181998 4.587 1 P 0 
L 3.49091004 4.56791004 3.47181998 4.587 1 P 0 
L 3.51 4.587 3.49091004 4.56791004 1 P 0 
L 2.80133996 4.667 2.78225 4.64791004 1 P 0 
L 2.78225 4.64791004 2.76316004 4.667 1 P 0 
L 2.74225 4.64791004 2.72316004 4.667 1 P 0 
L 2.76133996 4.667 2.74225 4.64791004 1 P 0 
L 2.74225 4.65286004 2.75638996 4.667 3 P 0 
L 2.77306004 4.66205 2.7872 4.67618996 3 P 0 
L 2.77801004 4.6571 2.79215 4.67123996 3 P 0 
L 2.78225 4.68608996 2.80133996 4.667 1 P 0 
L 2.78225 4.65286004 2.79638996 4.667 3 P 0 
L 2.76881004 4.66628996 2.78296004 4.68043996 3 P 0 
L 2.76316004 4.667 2.78225 4.68608996 1 P 0 
L 2.74225 4.68608996 2.76133996 4.667 1 P 0 
L 2.72316004 4.667 2.74225 4.68608996 1 P 0 
L 2.73801004 4.6571 2.75215 4.67123996 3 P 0 
L 2.73306004 4.66205 2.7472 4.67618996 3 P 0 
L 2.72881004 4.66628996 2.74296004 4.68043996 3 P 0 
L 3.2974 4.642 3.27831004 4.62291004 1 P 0 
L 3.27831004 4.62291004 3.25921998 4.642 1 P 0 
L 3.23831004 4.62291004 3.21921998 4.642 1 P 0 
L 3.2574 4.642 3.23831004 4.62291004 1 P 0 
L 3.23831004 4.62786004 3.25245 4.642 3 P 0 
L 3.26911998 4.63705 3.28326004 4.65118996 3 P 0 
L 3.27406998 4.6321 3.28821004 4.64623996 3 P 0 
L 3.27831004 4.66108996 3.2974 4.642 1 P 0 
L 3.27831004 4.62786004 3.29245 4.642 3 P 0 
L 3.26486998 4.64128996 3.27901998 4.65543996 3 P 0 
L 3.25921998 4.642 3.27831004 4.66108996 1 P 0 
L 3.23831004 4.66108996 3.2574 4.642 1 P 0 
L 3.21921998 4.642 3.23831004 4.66108996 1 P 0 
L 3.23406998 4.6321 3.24821004 4.64623996 3 P 0 
L 3.22911998 4.63705 3.24326004 4.65118996 3 P 0 
L 3.22486998 4.64128996 3.23901998 4.65543996 3 P 0 
L 3.58086004 4.71973002 3.56176998 4.70063996 1 P 0 
L 3.56176998 4.70063996 3.54268002 4.71973002 1 P 0 
L 3.52176998 4.70063996 3.50268002 4.71973002 1 P 0 
L 3.54086004 4.71973002 3.52176998 4.70063996 1 P 0 
L 3.52176998 4.70558996 3.53591004 4.71973002 3 P 0 
L 3.55258002 4.71478002 3.56671998 4.72891998 3 P 0 
L 3.55753002 4.70983002 3.57166998 4.72396998 3 P 0 
L 3.56176998 4.73881998 3.58086004 4.71973002 1 P 0 
L 3.56176998 4.70558996 3.57591004 4.71973002 3 P 0 
L 3.54833002 4.71901998 3.56248002 4.73316998 3 P 0 
L 3.54268002 4.71973002 3.56176998 4.73881998 1 P 0 
L 3.52176998 4.73881998 3.54086004 4.71973002 1 P 0 
L 3.50268002 4.71973002 3.52176998 4.73881998 1 P 0 
L 3.51753002 4.70983002 3.53166998 4.72396998 3 P 0 
L 3.51258002 4.71478002 3.52671998 4.72891998 3 P 0 
L 3.50833002 4.71901998 3.52248002 4.73316998 3 P 0 
L 3.2974 5.22001998 3.27831004 5.20093002 1 P 0 
L 3.27831004 5.20093002 3.25921998 5.22001998 1 P 0 
L 3.23831004 5.20093002 3.21921998 5.22001998 1 P 0 
L 3.2574 5.22001998 3.23831004 5.20093002 1 P 0 
L 3.23831004 5.20588002 3.25245 5.22001998 3 P 0 
L 3.26911998 5.21506998 3.28326004 5.22921004 3 P 0 
L 3.27406998 5.21011998 3.28821004 5.22426004 3 P 0 
L 3.27831004 5.23911004 3.2974 5.22001998 1 P 0 
L 3.27831004 5.20588002 3.29245 5.22001998 3 P 0 
L 3.26486998 5.21931004 3.27901998 5.23346004 3 P 0 
L 3.25921998 5.22001998 3.27831004 5.23911004 1 P 0 
L 3.23831004 5.23911004 3.2574 5.22001998 1 P 0 
L 3.21921998 5.22001998 3.23831004 5.23911004 1 P 0 
L 3.23406998 5.21011998 3.24821004 5.22426004 3 P 0 
L 3.22911998 5.21506998 3.24326004 5.22921004 3 P 0 
L 3.22486998 5.21931004 3.23901998 5.23346004 3 P 0 
L 3.0848 5.165 3.06571004 5.14591004 1 P 0 
L 3.06571004 5.14591004 3.04661998 5.165 1 P 0 
L 3.02571004 5.14591004 3.00661998 5.165 1 P 0 
L 3.0448 5.165 3.02571004 5.14591004 1 P 0 
L 3.02571004 5.15086004 3.03985 5.165 3 P 0 
L 3.05651998 5.16005 3.07066004 5.17418996 3 P 0 
L 3.06146998 5.1551 3.07561004 5.16923996 3 P 0 
L 3.06571004 5.18408996 3.0848 5.165 1 P 0 
L 3.06571004 5.15086004 3.07985 5.165 3 P 0 
L 3.05226998 5.16428996 3.06641998 5.17843996 3 P 0 
L 3.04661998 5.165 3.06571004 5.18408996 1 P 0 
L 3.02571004 5.18408996 3.0448 5.165 1 P 0 
L 3.00661998 5.165 3.02571004 5.18408996 1 P 0 
L 3.02146998 5.1551 3.03561004 5.16923996 3 P 0 
L 3.01651998 5.16005 3.03066004 5.17418996 3 P 0 
L 3.01226998 5.16428996 3.02641998 5.17843996 3 P 0 
L 3.58086004 5.14 3.56176998 5.12091004 1 P 0 
L 3.56176998 5.12091004 3.54268002 5.14 1 P 0 
L 3.55258002 5.13505 3.56671998 5.14918996 3 P 0 
L 3.55753002 5.1301 3.57166998 5.14423996 3 P 0 
L 3.56176998 5.15908996 3.58086004 5.14 1 P 0 
L 3.56176998 5.12586004 3.57591004 5.14 3 P 0 
L 3.54833002 5.13928996 3.56248002 5.15343996 3 P 0 
L 3.54268002 5.14 3.56176998 5.15908996 1 P 0 
L 3.52176998 5.12091004 3.50268002 5.14 1 P 0 
L 3.54086004 5.14 3.52176998 5.12091004 1 P 0 
L 3.52176998 5.12586004 3.53591004 5.14 3 P 0 
L 3.52176998 5.15908996 3.54086004 5.14 1 P 0 
L 3.50268002 5.14 3.52176998 5.15908996 1 P 0 
L 3.51753002 5.1301 3.53166998 5.14423996 3 P 0 
L 3.51258002 5.13505 3.52671998 5.14918996 3 P 0 
L 3.50833002 5.13928996 3.52248002 5.15343996 3 P 0 
L 1.56421004 4.70628996 1.57836004 4.72043996 3 P 0 
L 1.56846004 4.70205 1.5826 4.71618996 3 P 0 
L 1.57341004 4.6971 1.58755 4.71123996 3 P 0 
L 1.55856004 4.707 1.57765 4.72608996 1 P 0 
L 1.57765 4.72608996 1.59673996 4.707 1 P 0 
L 1.59856004 4.707 1.61765 4.72608996 1 P 0 
L 1.60421004 4.70628996 1.61836004 4.72043996 3 P 0 
L 1.61765 4.69286004 1.63178996 4.707 3 P 0 
L 1.61765 4.72608996 1.63673996 4.707 1 P 0 
L 1.61341004 4.6971 1.62755 4.71123996 3 P 0 
L 1.60846004 4.70205 1.6226 4.71618996 3 P 0 
L 1.57765 4.69286004 1.59178996 4.707 3 P 0 
L 1.59673996 4.707 1.57765 4.68791004 1 P 0 
L 1.57765 4.68791004 1.55856004 4.707 1 P 0 
L 1.61765 4.68791004 1.59856004 4.707 1 P 0 
L 1.63673996 4.707 1.61765 4.68791004 1 P 0 
L 1.84766998 4.65628996 1.86181998 4.67043996 3 P 0 
L 1.85191998 4.65205 1.86606004 4.66618996 3 P 0 
L 1.85686998 4.6471 1.87101004 4.66123996 3 P 0 
L 1.84201998 4.657 1.86111004 4.67608996 1 P 0 
L 1.86111004 4.67608996 1.8802 4.657 1 P 0 
L 1.88201998 4.657 1.90111004 4.67608996 1 P 0 
L 1.88766998 4.65628996 1.90181998 4.67043996 3 P 0 
L 1.90111004 4.64286004 1.91525 4.657 3 P 0 
L 1.90111004 4.67608996 1.9202 4.657 1 P 0 
L 1.89686998 4.6471 1.91101004 4.66123996 3 P 0 
L 1.89191998 4.65205 1.90606004 4.66618996 3 P 0 
L 1.86111004 4.64286004 1.87525 4.657 3 P 0 
L 1.8802 4.657 1.86111004 4.63791004 1 P 0 
L 1.86111004 4.63791004 1.84201998 4.657 1 P 0 
L 1.90111004 4.63791004 1.88201998 4.657 1 P 0 
L 1.9202 4.657 1.90111004 4.63791004 1 P 0 
L 2.34373002 4.74128996 2.35788002 4.75543996 3 P 0 
L 2.34798002 4.73705 2.36211998 4.75118996 3 P 0 
L 2.35293002 4.7321 2.36706998 4.74623996 3 P 0 
L 2.33808002 4.742 2.35716998 4.76108996 1 P 0 
L 2.35716998 4.76108996 2.37626004 4.742 1 P 0 
L 2.37808002 4.742 2.39716998 4.76108996 1 P 0 
L 2.38373002 4.74128996 2.39788002 4.75543996 3 P 0 
L 2.39716998 4.72786004 2.41131004 4.742 3 P 0 
L 2.39716998 4.76108996 2.41626004 4.742 1 P 0 
L 2.39293002 4.7321 2.40706998 4.74623996 3 P 0 
L 2.38798002 4.73705 2.40211998 4.75118996 3 P 0 
L 2.35716998 4.72786004 2.37131004 4.742 3 P 0 
L 2.37626004 4.742 2.35716998 4.72291004 1 P 0 
L 2.35716998 4.72291004 2.33808002 4.742 1 P 0 
L 2.39716998 4.72291004 2.37808002 4.742 1 P 0 
L 2.41626004 4.742 2.39716998 4.72291004 1 P 0 
L 1.56421004 5.16828996 1.57836004 5.18243996 3 P 0 
L 1.56846004 5.16405 1.5826 5.17818996 3 P 0 
L 1.57341004 5.1591 1.58755 5.17323996 3 P 0 
L 1.55856004 5.169 1.57765 5.18808996 1 P 0 
L 1.57765 5.18808996 1.59673996 5.169 1 P 0 
L 1.59856004 5.169 1.61765 5.18808996 1 P 0 
L 1.60421004 5.16828996 1.61836004 5.18243996 3 P 0 
L 1.61765 5.15486004 1.63178996 5.169 3 P 0 
L 1.61765 5.18808996 1.63673996 5.169 1 P 0 
L 1.61341004 5.1591 1.62755 5.17323996 3 P 0 
L 1.60846004 5.16405 1.6226 5.17818996 3 P 0 
L 1.57765 5.15486004 1.59178996 5.169 3 P 0 
L 1.59673996 5.169 1.57765 5.14991004 1 P 0 
L 1.57765 5.14991004 1.55856004 5.169 1 P 0 
L 1.61765 5.14991004 1.59856004 5.169 1 P 0 
L 1.63673996 5.169 1.61765 5.14991004 1 P 0 
L 1.84766998 5.16828996 1.86181998 5.18243996 3 P 0 
L 1.85191998 5.16405 1.86606004 5.17818996 3 P 0 
L 1.85686998 5.1591 1.87101004 5.17323996 3 P 0 
L 1.84201998 5.169 1.86111004 5.18808996 1 P 0 
L 1.86111004 5.18808996 1.8802 5.169 1 P 0 
L 1.88201998 5.169 1.90111004 5.18808996 1 P 0 
L 1.88766998 5.16828996 1.90181998 5.18243996 3 P 0 
L 1.90111004 5.15486004 1.91525 5.169 3 P 0 
L 1.90111004 5.18808996 1.9202 5.169 1 P 0 
L 1.89686998 5.1591 1.91101004 5.17323996 3 P 0 
L 1.89191998 5.16405 1.90606004 5.17818996 3 P 0 
L 1.86111004 5.15486004 1.87525 5.169 3 P 0 
L 1.8802 5.169 1.86111004 5.14991004 1 P 0 
L 1.86111004 5.14991004 1.84201998 5.169 1 P 0 
L 1.90111004 5.14991004 1.88201998 5.169 1 P 0 
L 1.9202 5.169 1.90111004 5.14991004 1 P 0 
L 2.06026998 5.16828996 2.07441998 5.18243996 3 P 0 
L 2.06451998 5.16405 2.07866004 5.17818996 3 P 0 
L 2.06946998 5.1591 2.08361004 5.17323996 3 P 0 
L 2.05461998 5.169 2.07371004 5.18808996 1 P 0 
L 2.07371004 5.18808996 2.0928 5.169 1 P 0 
L 2.09461998 5.169 2.11371004 5.18808996 1 P 0 
L 2.10026998 5.16828996 2.11441998 5.18243996 3 P 0 
L 2.11371004 5.15486004 2.12785 5.169 3 P 0 
L 2.11371004 5.18808996 2.1328 5.169 1 P 0 
L 2.10946998 5.1591 2.12361004 5.17323996 3 P 0 
L 2.10451998 5.16405 2.11866004 5.17818996 3 P 0 
L 2.07371004 5.15486004 2.08785 5.169 3 P 0 
L 2.0928 5.169 2.07371004 5.14991004 1 P 0 
L 2.07371004 5.14991004 2.05461998 5.169 1 P 0 
L 2.11371004 5.14991004 2.09461998 5.169 1 P 0 
L 2.1328 5.169 2.11371004 5.14991004 1 P 0 
L 8.45 3.66615 8.45 3.71615 8 P 0 
L 8.5 3.76615 8.5 3.81615 8 P 0 
L 8.45 3.81615 8.45 3.86615 8 P 0 
L 8.5 3.46615 8.5 3.51615 8 P 0 
L 8.45 3.41615 8.45 3.46615 8 P 0 
L 8.5 3.61615 8.5 3.66615 8 P 0 
L 8.45 3.26615 8.45 3.31615 8 P 0 
L 8.5 3.31615 8.5 3.36615 8 P 0 
L 8.2 3.66615 8.2 3.71615 8 P 0 
L 8.35 3.66615 8.35 3.71615 8 P 0 
L 8.4 3.76615 8.4 3.81615 8 P 0 
L 8.35 3.81615 8.35 3.86615 8 P 0 
L 8.2 3.81615 8.2 3.86615 8 P 0 
L 8.4 3.46615 8.4 3.51615 8 P 0 
L 8.35 3.41615 8.35 3.46615 8 P 0 
L 8.2 3.41615 8.2 3.46615 8 P 0 
L 8.4 3.61615 8.4 3.66615 8 P 0 
L 8.35 3.26615 8.35 3.31615 8 P 0 
L 8.4 3.31615 8.4 3.36615 8 P 0 
L 8.2 3.26615 8.2 3.31615 8 P 0 
L 8.25 2.86615 8.3 2.86615 8 P 0 
L 8.1 3.66615 8.1 3.71615 8 P 0 
L 8.15 3.76615 8.15 3.81615 8 P 0 
L 8.1 3.81615 8.1 3.86615 8 P 0 
L 8.05 3.76615 8.05 3.81615 8 P 0 
L 8.1 3.41615 8.1 3.46615 8 P 0 
L 8.15 3.46615 8.15 3.51615 8 P 0 
L 8 3.46615 8 3.51615 8 P 0 
L 8.05 3.61615 8.05 3.66615 8 P 0 
L 8.15 3.61615 8.15 3.66615 8 P 0 
L 8.1 3.26615 8.1 3.31615 8 P 0 
L 8.15 3.31615 8.15 3.36615 8 P 0 
L 8.05 3.31615 8.05 3.36615 8 P 0 
L 5.42048002 1.91835 5.42048002 1.87835 8 P 0 
L 5.57531004 1.8508 5.57531004 1.8108 8 P 0 
L 2.02853002 4.65275 2.04266998 4.66688996 3 P 0 
L 2.04761998 4.66688996 2.02853002 4.6478 1 P 0 
L 2.02853002 4.6478 2.00943996 4.66688996 1 P 0 
L 2.06853002 4.6478 2.04943996 4.66688996 1 P 0 
L 2.01508996 4.66618002 2.02923996 4.68033002 3 P 0 
L 2.01933996 4.66193996 2.03348002 4.67608002 3 P 0 
L 2.02428996 4.65698996 2.03843002 4.67113002 3 P 0 
L 2.00943996 4.66688996 2.02853002 4.68598002 1 P 0 
L 2.02853002 4.68598002 2.04761998 4.66688996 1 P 0 
L 2.04943996 4.66688996 2.06853002 4.68598002 1 P 0 
L 2.05508996 4.66618002 2.06923996 4.68033002 3 P 0 
L 2.08761998 4.66688996 2.06853002 4.6478 1 P 0 
L 2.06853002 4.65275 2.08266998 4.66688996 3 P 0 
L 2.06853002 4.68598002 2.08761998 4.66688996 1 P 0 
L 2.06428996 4.65698996 2.07843002 4.67113002 3 P 0 
L 2.05933996 4.66193996 2.07348002 4.67608002 3 P 0 
L 2.34606004 3.26615 2.34606004 3.31615 8 P 0 
L 2.39606004 3.31615 2.39606004 3.36615 8 P 0 
L 2.44606004 3.26615 2.44606004 3.31615 8 P 0 
L 2.49606004 3.31615 2.49606004 3.36615 8 P 0 
L 2.49606004 3.46615 2.49606004 3.51615 8 P 0 
L 2.44606004 3.41615 2.44606004 3.46615 8 P 0 
L 2.39606004 3.46615 2.39606004 3.51615 8 P 0 
L 2.34606004 3.41615 2.34606004 3.46615 8 P 0 
L 2.19606004 3.26615 2.19606004 3.31615 8 P 0 
L 2.09606004 3.26615 2.09606004 3.31615 8 P 0 
L 2.14606004 3.31615 2.14606004 3.36615 8 P 0 
L 2.19606004 3.41615 2.19606004 3.46615 8 P 0 
L 2.09606004 3.41615 2.09606004 3.46615 8 P 0 
L 2.04606004 3.31615 2.04606004 3.36615 8 P 0 
L 2.14606004 3.46615 2.14606004 3.51615 8 P 0 
L 1.99606004 3.46615 1.99606004 3.51615 8 P 0 
L 2.04606004 3.61615 2.04606004 3.66615 8 P 0 
L 2.09606004 3.66615 2.09606004 3.71615 8 P 0 
L 2.14606004 3.61615 2.14606004 3.66615 8 P 0 
L 2.19606004 3.66615 2.19606004 3.71615 8 P 0 
L 2.49606004 3.61615 2.49606004 3.66615 8 P 0 
L 2.34606004 3.66615 2.34606004 3.71615 8 P 0 
L 2.39606004 3.61615 2.39606004 3.66615 8 P 0 
L 2.44606004 3.66615 2.44606004 3.71615 8 P 0 
L 2.49606004 3.76615 2.49606004 3.81615 8 P 0 
L 2.44606004 3.81615 2.44606004 3.86615 8 P 0 
L 2.39606004 3.76615 2.39606004 3.81615 8 P 0 
L 2.34606004 3.81615 2.34606004 3.86615 8 P 0 
L 2.14606004 3.76615 2.14606004 3.81615 8 P 0 
L 2.19606004 3.81615 2.19606004 3.86615 8 P 0 
L 2.09606004 3.81615 2.09606004 3.86615 8 P 0 
L 2.04606004 3.76615 2.04606004 3.81615 8 P 0 
L 2.24606004 2.86615 2.29606004 2.86615 8 P 0 
L 3.0848 4.667 3.06571004 4.64791004 1 P 0 
L 3.06571004 4.64791004 3.04661998 4.667 1 P 0 
L 3.02571004 4.64791004 3.00661998 4.667 1 P 0 
L 3.0448 4.667 3.02571004 4.64791004 1 P 0 
L 3.02571004 4.65286004 3.03985 4.667 3 P 0 
L 3.05651998 4.66205 3.07066004 4.67618996 3 P 0 
L 3.06146998 4.6571 3.07561004 4.67123996 3 P 0 
L 3.06571004 4.68608996 3.0848 4.667 1 P 0 
L 3.06571004 4.65286004 3.07985 4.667 3 P 0 
L 3.05226998 4.66628996 3.06641998 4.68043996 3 P 0 
L 3.04661998 4.667 3.06571004 4.68608996 1 P 0 
L 3.02571004 4.68608996 3.0448 4.667 1 P 0 
L 3.00661998 4.667 3.02571004 4.68608996 1 P 0 
L 3.02146998 4.6571 3.03561004 4.67123996 3 P 0 
L 3.01651998 4.66205 3.03066004 4.67618996 3 P 0 
L 3.01226998 4.66628996 3.02641998 4.68043996 3 P 0 
L 2.94616998 4.667 2.92708002 4.64791004 1 P 0 
L 2.92708002 4.64791004 2.90798996 4.667 1 P 0 
L 2.88708002 4.64791004 2.86798996 4.667 1 P 0 
L 2.90616998 4.667 2.88708002 4.64791004 1 P 0 
L 2.88708002 4.65286004 2.90121998 4.667 3 P 0 
L 2.91788996 4.66205 2.93203002 4.67618996 3 P 0 
L 2.92283996 4.6571 2.93698002 4.67123996 3 P 0 
L 2.92708002 4.68608996 2.94616998 4.667 1 P 0 
L 2.92708002 4.65286004 2.94121998 4.667 3 P 0 
L 2.91363996 4.66628996 2.92778996 4.68043996 3 P 0 
L 2.90798996 4.667 2.92708002 4.68608996 1 P 0 
L 2.88708002 4.68608996 2.90616998 4.667 1 P 0 
L 2.86798996 4.667 2.88708002 4.68608996 1 P 0 
L 2.88283996 4.6571 2.89698002 4.67123996 3 P 0 
L 2.87788996 4.66205 2.89203002 4.67618996 3 P 0 
L 2.87363996 4.66628996 2.88778996 4.68043996 3 P 0 
L 2.8722 4.78291998 2.85311004 4.76383002 1 P 0 
L 2.85311004 4.76383002 2.83401998 4.78291998 1 P 0 
L 2.81311004 4.76383002 2.79401998 4.78291998 1 P 0 
L 2.8322 4.78291998 2.81311004 4.76383002 1 P 0 
L 2.81311004 4.76878002 2.82725 4.78291998 3 P 0 
L 2.84391998 4.77796998 2.85806004 4.79211004 3 P 0 
L 2.84886998 4.77301998 2.86301004 4.78716004 3 P 0 
L 2.85311004 4.80201004 2.8722 4.78291998 1 P 0 
L 2.85311004 4.76878002 2.86725 4.78291998 3 P 0 
L 2.83966998 4.78221004 2.85381998 4.79636004 3 P 0 
L 2.83401998 4.78291998 2.85311004 4.80201004 1 P 0 
L 2.81311004 4.80201004 2.8322 4.78291998 1 P 0 
L 2.79401998 4.78291998 2.81311004 4.80201004 1 P 0 
L 2.80886998 4.77301998 2.82301004 4.78716004 3 P 0 
L 2.80391998 4.77796998 2.81806004 4.79211004 3 P 0 
L 2.79966998 4.78221004 2.81381998 4.79636004 3 P 0 
L 3.43913002 4.78291998 3.42003996 4.76383002 1 P 0 
L 3.42003996 4.76383002 3.40095 4.78291998 1 P 0 
L 3.38003996 4.76383002 3.36095 4.78291998 1 P 0 
L 3.39913002 4.78291998 3.38003996 4.76383002 1 P 0 
L 3.38003996 4.76878002 3.39418002 4.78291998 3 P 0 
L 3.41085 4.77796998 3.42498996 4.79211004 3 P 0 
L 3.4158 4.77301998 3.42993996 4.78716004 3 P 0 
L 3.42003996 4.80201004 3.43913002 4.78291998 1 P 0 
L 3.42003996 4.76878002 3.43418002 4.78291998 3 P 0 
L 3.4066 4.78221004 3.42075 4.79636004 3 P 0 
L 3.40095 4.78291998 3.42003996 4.80201004 1 P 0 
L 3.38003996 4.80201004 3.39913002 4.78291998 1 P 0 
L 3.36095 4.78291998 3.38003996 4.80201004 1 P 0 
L 3.3758 4.77301998 3.38993996 4.78716004 3 P 0 
L 3.37085 4.77796998 3.38498996 4.79211004 3 P 0 
L 3.3666 4.78221004 3.38075 4.79636004 3 P 0 
L 3.22653002 4.78291998 3.20743996 4.76383002 1 P 0 
L 3.20743996 4.76383002 3.18835 4.78291998 1 P 0 
L 3.16743996 4.76383002 3.14835 4.78291998 1 P 0 
L 3.18653002 4.78291998 3.16743996 4.76383002 1 P 0 
L 3.16743996 4.76878002 3.18158002 4.78291998 3 P 0 
L 3.19825 4.77796998 3.21238996 4.79211004 3 P 0 
L 3.2032 4.77301998 3.21733996 4.78716004 3 P 0 
L 3.20743996 4.80201004 3.22653002 4.78291998 1 P 0 
L 3.20743996 4.76878002 3.22158002 4.78291998 3 P 0 
L 3.194 4.78221004 3.20815 4.79636004 3 P 0 
L 3.18835 4.78291998 3.20743996 4.80201004 1 P 0 
L 3.16743996 4.80201004 3.18653002 4.78291998 1 P 0 
L 3.14835 4.78291998 3.16743996 4.80201004 1 P 0 
L 3.1632 4.77301998 3.17733996 4.78716004 3 P 0 
L 3.15825 4.77796998 3.17238996 4.79211004 3 P 0 
L 3.154 4.78221004 3.16815 4.79636004 3 P 0 
L 3.15566004 5.0535 3.13656998 5.03441004 1 P 0 
L 3.13656998 5.03441004 3.11748002 5.0535 1 P 0 
L 3.09656998 5.03441004 3.07748002 5.0535 1 P 0 
L 3.11566004 5.0535 3.09656998 5.03441004 1 P 0 
L 3.09656998 5.03936004 3.11071004 5.0535 3 P 0 
L 3.12738002 5.04855 3.14151998 5.06268996 3 P 0 
L 3.13233002 5.0436 3.14646998 5.05773996 3 P 0 
L 3.13656998 5.07258996 3.15566004 5.0535 1 P 0 
L 3.13656998 5.03936004 3.15071004 5.0535 3 P 0 
L 3.12313002 5.05278996 3.13728002 5.06693996 3 P 0 
L 3.11748002 5.0535 3.13656998 5.07258996 1 P 0 
L 3.09656998 5.07258996 3.11566004 5.0535 1 P 0 
L 3.07748002 5.0535 3.09656998 5.07258996 1 P 0 
L 3.09233002 5.0436 3.10646998 5.05773996 3 P 0 
L 3.08738002 5.04855 3.10151998 5.06268996 3 P 0 
L 3.08313002 5.05278996 3.09728002 5.06693996 3 P 0 
L 3.36826004 5.1035 3.34916998 5.08441004 1 P 0 
L 3.34916998 5.08441004 3.33008002 5.1035 1 P 0 
L 3.30916998 5.08441004 3.29008002 5.1035 1 P 0 
L 3.32826004 5.1035 3.30916998 5.08441004 1 P 0 
L 3.30916998 5.08936004 3.32331004 5.1035 3 P 0 
L 3.33998002 5.09855 3.35411998 5.11268996 3 P 0 
L 3.34493002 5.0936 3.35906998 5.10773996 3 P 0 
L 3.34916998 5.12258996 3.36826004 5.1035 1 P 0 
L 3.34916998 5.08936004 3.36331004 5.1035 3 P 0 
L 3.33573002 5.10278996 3.34988002 5.11693996 3 P 0 
L 3.33008002 5.1035 3.34916998 5.12258996 1 P 0 
L 3.30916998 5.12258996 3.32826004 5.1035 1 P 0 
L 3.29008002 5.1035 3.30916998 5.12258996 1 P 0 
L 3.30493002 5.0936 3.31906998 5.10773996 3 P 0 
L 3.29998002 5.09855 3.31411998 5.11268996 3 P 0 
L 3.29573002 5.10278996 3.30988002 5.11693996 3 P 0 
L 3.43913002 5.22001998 3.42003996 5.20093002 1 P 0 
L 3.42003996 5.20093002 3.40095 5.22001998 1 P 0 
L 3.38003996 5.20093002 3.36095 5.22001998 1 P 0 
L 3.39913002 5.22001998 3.38003996 5.20093002 1 P 0 
L 3.38003996 5.20588002 3.39418002 5.22001998 3 P 0 
L 3.41085 5.21506998 3.42498996 5.22921004 3 P 0 
L 3.4158 5.21011998 3.42993996 5.22426004 3 P 0 
L 3.42003996 5.23911004 3.43913002 5.22001998 1 P 0 
L 3.42003996 5.20588002 3.43418002 5.22001998 3 P 0 
L 3.4066 5.21931004 3.42075 5.23346004 3 P 0 
L 3.40095 5.22001998 3.42003996 5.23911004 1 P 0 
L 3.38003996 5.23911004 3.39913002 5.22001998 1 P 0 
L 3.36095 5.22001998 3.38003996 5.23911004 1 P 0 
L 3.3758 5.21011998 3.38993996 5.22426004 3 P 0 
L 3.37085 5.21506998 3.38498996 5.22921004 3 P 0 
L 3.3666 5.21931004 3.38075 5.23346004 3 P 0 
L 2.93996004 5.17001998 2.92086998 5.15093002 1 P 0 
L 2.92086998 5.15093002 2.90178002 5.17001998 1 P 0 
L 2.88086998 5.15093002 2.86178002 5.17001998 1 P 0 
L 2.89996004 5.17001998 2.88086998 5.15093002 1 P 0 
L 2.88086998 5.15588002 2.89501004 5.17001998 3 P 0 
L 2.91168002 5.16506998 2.92581998 5.17921004 3 P 0 
L 2.91663002 5.16011998 2.93076998 5.17426004 3 P 0 
L 2.92086998 5.18911004 2.93996004 5.17001998 1 P 0 
L 2.92086998 5.15588002 2.93501004 5.17001998 3 P 0 
L 2.90743002 5.16931004 2.92158002 5.18346004 3 P 0 
L 2.90178002 5.17001998 2.92086998 5.18911004 1 P 0 
L 2.88086998 5.18911004 2.89996004 5.17001998 1 P 0 
L 2.86178002 5.17001998 2.88086998 5.18911004 1 P 0 
L 2.87663002 5.16011998 2.89076998 5.17426004 3 P 0 
L 2.87168002 5.16506998 2.88581998 5.17921004 3 P 0 
L 2.86743002 5.16931004 2.88158002 5.18346004 3 P 0 
L 2.34373002 5.11428996 2.35788002 5.12843996 3 P 0 
L 2.34798002 5.11005 2.36211998 5.12418996 3 P 0 
L 2.35293002 5.1051 2.36706998 5.11923996 3 P 0 
L 2.33808002 5.115 2.35716998 5.13408996 1 P 0 
L 2.35716998 5.13408996 2.37626004 5.115 1 P 0 
L 2.37808002 5.115 2.39716998 5.13408996 1 P 0 
L 2.38373002 5.11428996 2.39788002 5.12843996 3 P 0 
L 2.39716998 5.10086004 2.41131004 5.115 3 P 0 
L 2.39716998 5.13408996 2.41626004 5.115 1 P 0 
L 2.39293002 5.1051 2.40706998 5.11923996 3 P 0 
L 2.38798002 5.11005 2.40211998 5.12418996 3 P 0 
L 2.35716998 5.10086004 2.37131004 5.115 3 P 0 
L 2.37626004 5.115 2.35716998 5.09591004 1 P 0 
L 2.35716998 5.09591004 2.33808002 5.115 1 P 0 
L 2.39716998 5.09591004 2.37808002 5.115 1 P 0 
L 2.41626004 5.115 2.39716998 5.09591004 1 P 0 
L 2.18456998 5.03441004 2.16548002 5.0535 1 P 0 
L 2.16548002 5.0535 2.18456998 5.07258996 1 P 0 
L 2.17113002 5.05278996 2.18528002 5.06693996 3 P 0 
L 2.20366004 5.0535 2.18456998 5.03441004 1 P 0 
L 2.18456998 5.03936004 2.19871004 5.0535 3 P 0 
L 2.18456998 5.07258996 2.20366004 5.0535 1 P 0 
L 2.18033002 5.0436 2.19446998 5.05773996 3 P 0 
L 2.17538002 5.04855 2.18951998 5.06268996 3 P 0 
L 2.202 4.78221004 2.21615 4.79636004 3 P 0 
L 2.20625 4.77796998 2.22038996 4.79211004 3 P 0 
L 2.2112 4.77301998 2.22533996 4.78716004 3 P 0 
L 2.19635 4.78291998 2.21543996 4.80201004 1 P 0 
L 2.21543996 4.80201004 2.23453002 4.78291998 1 P 0 
L 2.23635 4.78291998 2.25543996 4.80201004 1 P 0 
L 2.242 4.78221004 2.25615 4.79636004 3 P 0 
L 2.25543996 4.76878002 2.26958002 4.78291998 3 P 0 
L 2.25543996 4.80201004 2.27453002 4.78291998 1 P 0 
L 2.2512 4.77301998 2.26533996 4.78716004 3 P 0 
L 2.24625 4.77796998 2.26038996 4.79211004 3 P 0 
L 2.21543996 4.76878002 2.22958002 4.78291998 3 P 0 
L 2.23453002 4.78291998 2.21543996 4.76383002 1 P 0 
L 2.21543996 4.76383002 2.19635 4.78291998 1 P 0 
L 2.25543996 4.76383002 2.23635 4.78291998 1 P 0 
L 2.27453002 4.78291998 2.25543996 4.76383002 1 P 0 
L 2.20511004 4.66628996 2.21926004 4.68043996 3 P 0 
L 2.20936004 4.66205 2.2235 4.67618996 3 P 0 
L 2.21431004 4.6571 2.22845 4.67123996 3 P 0 
L 2.19946004 4.667 2.21855 4.68608996 1 P 0 
L 2.21855 4.68608996 2.23763996 4.667 1 P 0 
L 2.23946004 4.667 2.25855 4.68608996 1 P 0 
L 2.24511004 4.66628996 2.25926004 4.68043996 3 P 0 
L 2.25855 4.68608996 2.27763996 4.667 1 P 0 
L 2.25431004 4.6571 2.26845 4.67123996 3 P 0 
L 2.24936004 4.66205 2.2635 4.67618996 3 P 0 
L 2.25855 4.65286004 2.27268996 4.667 3 P 0 
L 2.21855 4.65286004 2.23268996 4.667 3 P 0 
L 2.23763996 4.667 2.21855 4.64791004 1 P 0 
L 2.21855 4.64791004 2.19946004 4.667 1 P 0 
L 2.25855 4.64791004 2.23946004 4.667 1 P 0 
L 2.27763996 4.667 2.25855 4.64791004 1 P 0 
L 2.14456998 5.03936004 2.15871004 5.0535 3 P 0 
L 2.16366004 5.0535 2.14456998 5.03441004 1 P 0 
L 2.14456998 5.03441004 2.12548002 5.0535 1 P 0 
L 2.13113002 5.05278996 2.14528002 5.06693996 3 P 0 
L 2.13538002 5.04855 2.14951998 5.06268996 3 P 0 
L 2.14033002 5.0436 2.15446998 5.05773996 3 P 0 
L 2.12548002 5.0535 2.14456998 5.07258996 1 P 0 
L 2.14456998 5.07258996 2.16366004 5.0535 1 P 0 
L 1.96278002 5.04855 1.97691998 5.06268996 3 P 0 
L 1.96773002 5.0436 1.98186998 5.05773996 3 P 0 
L 1.97196998 5.07258996 1.99106004 5.0535 1 P 0 
L 1.97196998 5.03936004 1.98611004 5.0535 3 P 0 
L 1.99106004 5.0535 1.97196998 5.03441004 1 P 0 
L 1.95853002 5.05278996 1.97268002 5.06693996 3 P 0 
L 1.95288002 5.0535 1.97196998 5.07258996 1 P 0 
L 1.93196998 5.07258996 1.95106004 5.0535 1 P 0 
L 1.91288002 5.0535 1.93196998 5.07258996 1 P 0 
L 1.92773002 5.0436 1.94186998 5.05773996 3 P 0 
L 1.92278002 5.04855 1.93691998 5.06268996 3 P 0 
L 1.91853002 5.05278996 1.93268002 5.06693996 3 P 0 
L 1.97196998 5.03441004 1.95288002 5.0535 1 P 0 
L 1.93196998 5.03441004 1.91288002 5.0535 1 P 0 
L 1.95106004 5.0535 1.93196998 5.03441004 1 P 0 
L 1.93196998 5.03936004 1.94611004 5.0535 3 P 0 
L 2.06026998 4.78221004 2.07441998 4.79636004 3 P 0 
L 2.06451998 4.77796998 2.07866004 4.79211004 3 P 0 
L 2.06946998 4.77301998 2.08361004 4.78716004 3 P 0 
L 2.05461998 4.78291998 2.07371004 4.80201004 1 P 0 
L 2.07371004 4.80201004 2.0928 4.78291998 1 P 0 
L 2.09461998 4.78291998 2.11371004 4.80201004 1 P 0 
L 2.10026998 4.78221004 2.11441998 4.79636004 3 P 0 
L 2.11371004 4.76878002 2.12785 4.78291998 3 P 0 
L 2.11371004 4.80201004 2.1328 4.78291998 1 P 0 
L 2.10946998 4.77301998 2.12361004 4.78716004 3 P 0 
L 2.10451998 4.77796998 2.11866004 4.79211004 3 P 0 
L 2.07371004 4.76878002 2.08785 4.78291998 3 P 0 
L 2.0928 4.78291998 2.07371004 4.76383002 1 P 0 
L 2.07371004 4.76383002 2.05461998 4.78291998 1 P 0 
L 2.11371004 4.76383002 2.09461998 4.78291998 1 P 0 
L 2.1328 4.78291998 2.11371004 4.76383002 1 P 0 
L 1.67931004 5.04855 1.69345 5.06268996 3 P 0 
L 1.68426004 5.0436 1.6984 5.05773996 3 P 0 
L 1.6885 5.07258996 1.70758996 5.0535 1 P 0 
L 1.6885 5.03936004 1.70263996 5.0535 3 P 0 
L 1.70758996 5.0535 1.6885 5.03441004 1 P 0 
L 1.67506004 5.05278996 1.68921004 5.06693996 3 P 0 
L 1.66941004 5.0535 1.6885 5.07258996 1 P 0 
L 1.6885 5.03441004 1.66941004 5.0535 1 P 0 
L 1.82106004 4.77796998 1.8352 4.79211004 3 P 0 
L 1.82601004 4.77301998 1.84015 4.78716004 3 P 0 
L 1.83025 4.80201004 1.84933996 4.78291998 1 P 0 
L 1.83025 4.76878002 1.84438996 4.78291998 3 P 0 
L 1.84933996 4.78291998 1.83025 4.76383002 1 P 0 
L 1.81681004 4.78221004 1.83096004 4.79636004 3 P 0 
L 1.81116004 4.78291998 1.83025 4.80201004 1 P 0 
L 1.79025 4.80201004 1.80933996 4.78291998 1 P 0 
L 1.77116004 4.78291998 1.79025 4.80201004 1 P 0 
L 1.78601004 4.77301998 1.80015 4.78716004 3 P 0 
L 1.78106004 4.77796998 1.7952 4.79211004 3 P 0 
L 1.77681004 4.78221004 1.79096004 4.79636004 3 P 0 
L 1.83025 4.76383002 1.81116004 4.78291998 1 P 0 
L 1.79025 4.76383002 1.77116004 4.78291998 1 P 0 
L 1.80933996 4.78291998 1.79025 4.76383002 1 P 0 
L 1.79025 4.76878002 1.80438996 4.78291998 3 P 0 
L 1.67931998 4.77796998 1.69346004 4.79211004 3 P 0 
L 1.68426998 4.77301998 1.69841004 4.78716004 3 P 0 
L 1.68851004 4.80201004 1.7076 4.78291998 1 P 0 
L 1.68851004 4.76878002 1.70265 4.78291998 3 P 0 
L 1.7076 4.78291998 1.68851004 4.76383002 1 P 0 
L 1.67506998 4.78221004 1.68921998 4.79636004 3 P 0 
L 1.66941998 4.78291998 1.68851004 4.80201004 1 P 0 
L 1.68851004 4.76383002 1.66941998 4.78291998 1 P 0 
L 1.6485 5.07258996 1.66758996 5.0535 1 P 0 
L 1.62941004 5.0535 1.6485 5.07258996 1 P 0 
L 1.64426004 5.0436 1.6584 5.05773996 3 P 0 
L 1.63931004 5.04855 1.65345 5.06268996 3 P 0 
L 1.63506004 5.05278996 1.64921004 5.06693996 3 P 0 
L 1.6485 5.03441004 1.62941004 5.0535 1 P 0 
L 1.66758996 5.0535 1.6485 5.03441004 1 P 0 
L 1.6485 5.03936004 1.66263996 5.0535 3 P 0 
L 1.64851004 4.80201004 1.6676 4.78291998 1 P 0 
L 1.62941998 4.78291998 1.64851004 4.80201004 1 P 0 
L 1.64426998 4.77301998 1.65841004 4.78716004 3 P 0 
L 1.63931998 4.77796998 1.65346004 4.79211004 3 P 0 
L 1.63506998 4.78221004 1.64921998 4.79636004 3 P 0 
L 1.64851004 4.76383002 1.62941998 4.78291998 1 P 0 
L 1.6676 4.78291998 1.64851004 4.76383002 1 P 0 
L 1.64851004 4.76878002 1.66265 4.78291998 3 P 0 
L 5.42048002 1.6433 5.42048002 1.6033 8 P 0 
L 5.57531004 1.7118 5.57531004 1.6718 8 P 0 
L 5.42048002 1.7796 5.42048002 1.7396 8 P 0 
L 5.57531004 1.9869 5.57531004 1.9469 8 P 0 
L 5.42048002 2.0547 5.42048002 2.0147 8 P 0 
L 5.57531004 2.1278 5.57531004 2.0878 8 P 0 
L 5.42048002 2.1954 5.42048002 2.1554 8 P 0 
L 5.57531004 2.2632 5.57531004 2.2232 8 P 0 
L 5.42048002 2.3308 5.42048002 2.2908 8 P 0 
L 5.57531004 2.3986 5.57531004 2.3586 8 P 0 
L 5.42048002 2.4662 5.42048002 2.4262 8 P 0 
L 5.57531004 2.5378 5.57531004 2.4978 8 P 0 
L 5.57531004 2.673 5.57531004 2.633 8 P 0 
L 5.42048002 2.6054 5.42048002 2.5654 8 P 0 
L 10.09 2.73655 10.09 2.69655 8 P 0 
L 9.975 2.66445 9.975 2.62445 8 P 0 
L 9.975 2.5109 9.975 2.4709 8 P 0 
L 10.09 2.57845 10.09 2.53845 8 P 0 
L 10.09 2.44335 10.09 2.40335 8 P 0 
L 9.975 2.3758 9.975 2.3358 8 P 0 
L 10.09 2.30825 10.09 2.26825 8 P 0 
L 9.975 2.23955 9.975 2.19955 8 P 0 
L 10.09 2.17095 10.09 2.13095 8 P 0 
L 10.09 2.05655 10.09 2.01655 8 P 0 
L 10.225 1.96645 10.225 1.92645 8 P 0 
L 10.26025 1.86845 10.26025 1.82845 8 P 0 
L 10.26 1.70445 10.26 1.66445 8 P 0 
L 10.35543996 1.52156004 10.38371998 1.49328002 9 P 0 
L 10.46445 1.395 10.42445 1.395 8 P 0 
L 10.395 1.28555 10.395 1.32555 8 P 0 
L 11.53316004 1.412 11.53316004 1.452 8 P 0 
L 11.73316004 1.492 11.73316004 1.532 8 P 0 
L 11.53316004 1.572 11.53316004 1.612 8 P 0 
L 11.78316004 1.652 11.78316004 1.692 8 P 0 
L 11.53316004 1.732 11.53316004 1.772 8 P 0 
L 11.73316004 1.812 11.73316004 1.852 8 P 0 
L 11.53316004 1.892 11.53316004 1.932 8 P 0 
L 11.53316004 2.052 11.53316004 2.092 8 P 0 
L 11.73316004 1.972 11.73316004 2.012 8 P 0 
L 11.73316004 2.132 11.73316004 2.172 8 P 0 
L 11.83316004 2.212 11.83316004 2.252 8 P 0 
L 11.73316004 2.292 11.73316004 2.332 8 P 0 
L 11.53316004 2.372 11.53316004 2.412 8 P 0 
L 11.53316004 2.532 11.53316004 2.572 8 P 0 
L 11.73316004 2.452 11.73316004 2.492 8 P 0 
L 11.73316004 2.612 11.73316004 2.652 8 P 0 
L 1.68313002 4.88273996 1.68513002 4.88273996 1 P 0 
L 1.68513002 4.88273996 1.68613002 4.88173996 1 P 0 
L 1.68613002 4.88173996 1.68613002 4.83473996 1 P 0 
L 1.68613002 4.83473996 1.68513002 4.83373996 1 P 0 
L 1.68513002 4.83373996 1.65113002 4.83373996 1 P 0 
L 1.65113002 4.83373996 1.65013002 4.83473996 1 P 0 
L 1.65013002 4.83473996 1.65013002 4.88173996 1 P 0 
L 1.65013002 4.88173996 1.65113002 4.88273996 1 P 0 
L 1.65113002 4.88273996 1.68313002 4.88273996 1 P 0 
L 1.65613002 4.87673996 1.65613002 4.84073996 4 P 0 
L 1.66513002 4.87673996 1.66513002 4.84073996 4 P 0 
L 1.67413002 4.87673996 1.67413002 4.84073996 4 P 0 
L 1.68013002 4.87673996 1.68013002 4.84073996 4 P 0 
L 2.25006004 4.88273996 2.25206004 4.88273996 1 P 0 
L 2.25206004 4.88273996 2.25306004 4.88173996 1 P 0 
L 2.25306004 4.88173996 2.25306004 4.83473996 1 P 0 
L 2.25306004 4.83473996 2.25206004 4.83373996 1 P 0 
L 2.25206004 4.83373996 2.21806004 4.83373996 1 P 0 
L 2.21806004 4.83373996 2.21706004 4.83473996 1 P 0 
L 2.21706004 4.83473996 2.21706004 4.88173996 1 P 0 
L 2.21706004 4.88173996 2.21806004 4.88273996 1 P 0 
L 2.21806004 4.88273996 2.25006004 4.88273996 1 P 0 
L 2.22306004 4.87673996 2.22306004 4.84073996 4 P 0 
L 2.23206004 4.87673996 2.23206004 4.84073996 4 P 0 
L 2.24106004 4.87673996 2.24106004 4.84073996 4 P 0 
L 2.24706004 4.87673996 2.24706004 4.84073996 4 P 0 
L 3.41166004 4.87673996 3.41166004 4.84073996 4 P 0 
L 3.40566004 4.87673996 3.40566004 4.84073996 4 P 0 
L 3.39666004 4.87673996 3.39666004 4.84073996 4 P 0 
L 3.38766004 4.87673996 3.38766004 4.84073996 4 P 0 
L 3.41466004 4.88273996 3.41666004 4.88273996 1 P 0 
L 3.41666004 4.88273996 3.41766004 4.88173996 1 P 0 
L 3.41766004 4.88173996 3.41766004 4.83473996 1 P 0 
L 3.41766004 4.83473996 3.41666004 4.83373996 1 P 0 
L 3.41666004 4.83373996 3.38266004 4.83373996 1 P 0 
L 3.38266004 4.83373996 3.38166004 4.83473996 1 P 0 
L 3.38166004 4.83473996 3.38166004 4.88173996 1 P 0 
L 3.38166004 4.88173996 3.38266004 4.88273996 1 P 0 
L 3.38266004 4.88273996 3.41466004 4.88273996 1 P 0 
L 3.41166004 4.998 3.41166004 4.962 4 P 0 
L 3.40566004 4.998 3.40566004 4.962 4 P 0 
L 3.39666004 4.998 3.39666004 4.962 4 P 0 
L 3.38766004 4.998 3.38766004 4.962 4 P 0 
L 3.41466004 5.004 3.41666004 5.004 1 P 0 
L 3.41666004 5.004 3.41766004 5.003 1 P 0 
L 3.41766004 5.003 3.41766004 4.956 1 P 0 
L 3.41766004 4.956 3.41666004 4.955 1 P 0 
L 3.41666004 4.955 3.38266004 4.955 1 P 0 
L 3.38266004 4.955 3.38166004 4.956 1 P 0 
L 3.38166004 4.956 3.38166004 5.003 1 P 0 
L 3.38166004 5.003 3.38266004 5.004 1 P 0 
L 3.38266004 5.004 3.41466004 5.004 1 P 0 
L 2.83873002 4.87673996 2.83873002 4.84073996 4 P 0 
L 2.84473002 4.87673996 2.84473002 4.84073996 4 P 0 
L 2.84773002 4.88273996 2.84973002 4.88273996 1 P 0 
L 2.84973002 4.88273996 2.85073002 4.88173996 1 P 0 
L 2.85073002 4.88173996 2.85073002 4.83473996 1 P 0 
L 2.85073002 4.83473996 2.84973002 4.83373996 1 P 0 
L 2.84973002 4.83373996 2.81573002 4.83373996 1 P 0 
L 2.81573002 4.83373996 2.81473002 4.83473996 1 P 0 
L 2.81473002 4.83473996 2.81473002 4.88173996 1 P 0 
L 2.81473002 4.88173996 2.81573002 4.88273996 1 P 0 
L 2.81573002 4.88273996 2.84773002 4.88273996 1 P 0 
L 2.82073002 4.87673996 2.82073002 4.84073996 4 P 0 
L 2.82973002 4.87673996 2.82973002 4.84073996 4 P 0 
L 8.98115 2.825 8.98115 2.865 8 P 0 
L 2.97721004 2.825 2.97721004 2.865 8 P 0 
L 11.03661004 2.46615 11.03661004 2.51615 8 P 0 
L 11.08661004 2.21615 11.08661004 2.26615 8 P 0 
L 10.98661004 2.21615 10.98661004 2.26615 8 P 0 
L 11.03661004 2.26615 11.03661004 2.31615 8 P 0 
L 10.93661004 2.26615 10.93661004 2.31615 8 P 0 
L 10.98661004 2.36615 10.98661004 2.41615 8 P 0 
L 10.93661004 2.41615 10.93661004 2.46615 8 P 0 
L 11.08661004 2.36615 11.08661004 2.41615 8 P 0 
L 10.93661004 2.01615 10.93661004 2.06615 8 P 0 
L 10.98661004 2.06615 10.98661004 2.11615 8 P 0 
L 11.03661004 2.01615 11.03661004 2.06615 8 P 0 
L 11.08661004 2.06615 11.08661004 2.11615 8 P 0 
L 10.93661004 1.86615 10.93661004 1.91615 8 P 0 
L 11.03661004 1.86615 11.03661004 1.91615 8 P 0 
L 10.98661004 1.91615 10.98661004 1.96615 8 P 0 
L 11.08661004 1.91615 11.08661004 1.96615 8 P 0 
L 10.73661004 2.46615 10.73661004 2.41615 8 P 0 
L 10.68661004 2.41615 10.68661004 2.36615 8 P 0 
L 10.68661004 2.26615 10.68661004 2.21615 8 P 0 
L 10.73661004 2.31615 10.73661004 2.26615 8 P 0 
L 10.68661004 2.11615 10.68661004 2.06615 8 P 0 
L 10.83661004 2.16615 10.88661004 2.16615 8 P 0 
L 10.73661004 2.01615 10.73661004 2.06615 8 P 0 
L 10.68661004 1.91615 10.68661004 1.96615 8 P 0 
L 10.73661004 1.86615 10.73661004 1.91615 8 P 0 
L 10.63661004 2.46615 10.63661004 2.41615 8 P 0 
L 10.58661004 2.41615 10.58661004 2.36615 8 P 0 
L 10.63661004 2.31615 10.63661004 2.26615 8 P 0 
L 10.58661004 2.26615 10.58661004 2.21615 8 P 0 
L 10.58661004 2.11615 10.58661004 2.06615 8 P 0 
L 10.63661004 2.01615 10.63661004 2.06615 8 P 0 
L 10.58661004 1.91615 10.58661004 1.96615 8 P 0 
L 10.63661004 1.86615 10.63661004 1.91615 8 P 0 
L 0.69348996 1.86611998 0.69348996 1.90611998 8 P 0 
L 5.03268002 2.46615 5.03268002 2.51615 8 P 0 
L 5.08268002 2.36615 5.08268002 2.41615 8 P 0 
L 4.93268002 2.41615 4.93268002 2.46615 8 P 0 
L 4.98268002 2.36615 4.98268002 2.41615 8 P 0 
L 4.93268002 2.26615 4.93268002 2.31615 8 P 0 
L 5.03268002 2.26615 5.03268002 2.31615 8 P 0 
L 4.98268002 2.21615 4.98268002 2.26615 8 P 0 
L 5.08268002 2.21615 5.08268002 2.26615 8 P 0 
L 5.08268002 2.06615 5.08268002 2.11615 8 P 0 
L 5.03268002 2.01615 5.03268002 2.06615 8 P 0 
L 4.98268002 2.06615 4.98268002 2.11615 8 P 0 
L 4.93268002 2.01615 4.93268002 2.06615 8 P 0 
L 5.08268002 1.91615 5.08268002 1.96615 8 P 0 
L 4.98268002 1.91615 4.98268002 1.96615 8 P 0 
L 5.03268002 1.86615 5.03268002 1.91615 8 P 0 
L 4.93268002 1.86615 4.93268002 1.91615 8 P 0 
L 4.73268002 1.86615 4.73268002 1.91615 8 P 0 
L 4.63268002 1.86615 4.63268002 1.91615 8 P 0 
L 4.68268002 1.91615 4.68268002 1.96615 8 P 0 
L 4.58268002 1.91615 4.58268002 1.96615 8 P 0 
L 4.63268002 2.01615 4.63268002 2.06615 8 P 0 
L 4.73268002 2.01615 4.73268002 2.06615 8 P 0 
L 4.83268002 2.16615 4.88268002 2.16615 8 P 0 
L 4.58268002 2.11615 4.58268002 2.06615 8 P 0 
L 4.68268002 2.11615 4.68268002 2.06615 8 P 0 
L 4.73268002 2.31615 4.73268002 2.26615 8 P 0 
L 4.68268002 2.26615 4.68268002 2.21615 8 P 0 
L 4.58268002 2.26615 4.58268002 2.21615 8 P 0 
L 4.63268002 2.31615 4.63268002 2.26615 8 P 0 
L 4.58268002 2.41615 4.58268002 2.36615 8 P 0 
L 4.68268002 2.41615 4.68268002 2.36615 8 P 0 
L 4.63268002 2.46615 4.63268002 2.41615 8 P 0 
L 4.73268002 2.46615 4.73268002 2.41615 8 P 0 
A 12.75476004 4.52361998 12.75476004 4.52361998 12.73621004 4.52361998 5 P 0 N
A 12.8335 4.48425 12.8335 4.48425 12.81495 4.48425 5 P 0 N
L 12.73621004 4.52361998 12.81495 4.48425 11 P 0 
L 12.73621004 4.36613996 12.81495 4.32676998 11 P 0 
A 12.8335 4.32676998 12.8335 4.32676998 12.81495 4.32676998 5 P 0 N
A 12.75476004 4.36613996 12.75476004 4.36613996 12.73621004 4.36613996 5 P 0 N
L 12.73621004 4.20866004 12.81495 4.16928996 11 P 0 
A 12.8335 4.16928996 12.8335 4.16928996 12.81495 4.16928996 5 P 0 N
A 12.75476004 4.20866004 12.75476004 4.20866004 12.73621004 4.20866004 5 P 0 N
L 12.73621004 4.05118002 12.81495 4.01181004 11 P 0 
A 12.8335 4.01181004 12.8335 4.01181004 12.81495 4.01181004 5 P 0 N
A 12.75476004 4.05118002 12.75476004 4.05118002 12.73621004 4.05118002 5 P 0 N
L 12.73621004 3.8937 12.81495 3.85433002 11 P 0 
A 12.8335 3.85433002 12.8335 3.85433002 12.81495 3.85433002 5 P 0 N
A 12.75476004 3.8937 12.75476004 3.8937 12.73621004 3.8937 5 P 0 N
A 12.75476004 3.73621998 12.75476004 3.73621998 12.73621004 3.73621998 5 P 0 N
L 12.73621004 3.73621998 12.81495 3.69685 11 P 0 
A 12.8335 3.69685 12.8335 3.69685 12.81495 3.69685 5 P 0 N
L 12.73621004 3.57873996 12.81495 3.53936998 11 P 0 
A 12.8335 3.53936998 12.8335 3.53936998 12.81495 3.53936998 5 P 0 N
A 12.75476004 3.57873996 12.75476004 3.57873996 12.73621004 3.57873996 5 P 0 N
L 12.73621004 3.42126004 12.81495 3.38188996 11 P 0 
A 12.8335 3.38188996 12.8335 3.38188996 12.81495 3.38188996 5 P 0 N
A 12.75476004 3.42126004 12.75476004 3.42126004 12.73621004 3.42126004 5 P 0 N
A 12.8335 3.22441004 12.8335 3.22441004 12.81495 3.22441004 5 P 0 N
L 12.73621004 3.02756004 12.81495 3.06693002 11 P 0 
A 12.8335 3.06693002 12.8335 3.06693002 12.81495 3.06693002 5 P 0 N
A 12.75476004 3.02756004 12.75476004 3.02756004 12.73621004 3.02756004 5 P 0 N
L 12.73621004 3.18503996 12.81495 3.22441004 11 P 0 
A 12.75476004 3.18503996 12.75476004 3.18503996 12.73621004 3.18503996 5 P 0 N
A 12.8335 2.75196998 12.8335 2.75196998 12.81495 2.75196998 5 P 0 N
L 12.73621004 2.87008002 12.81495 2.90945 11 P 0 
A 12.8335 2.90945 12.8335 2.90945 12.81495 2.90945 5 P 0 N
A 12.75476004 2.87008002 12.75476004 2.87008002 12.73621004 2.87008002 5 P 0 N
A 12.8335 2.51575 12.8335 2.51575 12.81495 2.51575 5 P 0 N
A 12.75476004 2.47638002 12.75476004 2.47638002 12.73621004 2.47638002 5 P 0 N
L 12.73621004 2.7126 12.81495 2.75196998 11 P 0 
A 12.75476004 2.7126 12.75476004 2.7126 12.73621004 2.7126 5 P 0 N
L 12.73621004 2.3189 12.81495 2.35826998 11 P 0 
A 12.8335 2.35826998 12.8335 2.35826998 12.81495 2.35826998 5 P 0 N
A 12.75476004 2.3189 12.75476004 2.3189 12.73621004 2.3189 5 P 0 N
L 12.73621004 2.47638002 12.81495 2.51575 11 P 0 
A 12.75476004 2.00393996 12.75476004 2.00393996 12.73621004 2.00393996 5 P 0 N
L 12.73621004 2.16141998 12.81495 2.20078996 11 P 0 
A 12.8335 2.20078996 12.8335 2.20078996 12.81495 2.20078996 5 P 0 N
A 12.75476004 2.16141998 12.75476004 2.16141998 12.73621004 2.16141998 5 P 0 N
L 12.73621004 2.00393996 12.81495 1.96456998 11 P 0 
A 12.8335 1.96456998 12.8335 1.96456998 12.81495 1.96456998 5 P 0 N
L 12.55905 4.563 12.63778996 4.60236998 11 P 0 
A 12.65633996 4.60236998 12.65633996 4.60236998 12.63778996 4.60236998 5 P 0 N
A 12.5776 4.563 12.5776 4.563 12.55905 4.563 5 P 0 N
L 12.55905 4.24803002 12.63778996 4.2874 11 P 0 
A 12.65633996 4.2874 12.65633996 4.2874 12.63778996 4.2874 5 P 0 N
A 12.5776 4.24803002 12.5776 4.24803002 12.55905 4.24803002 5 P 0 N
L 12.55905 4.40551004 12.63778996 4.44488002 11 P 0 
A 12.65633996 4.44488002 12.65633996 4.44488002 12.63778996 4.44488002 5 P 0 N
A 12.5776 4.40551004 12.5776 4.40551004 12.55905 4.40551004 5 P 0 N
A 12.65633996 3.97243996 12.65633996 3.97243996 12.63778996 3.97243996 5 P 0 N
L 12.55905 4.09055 12.63778996 4.12991998 11 P 0 
A 12.65633996 4.12991998 12.65633996 4.12991998 12.63778996 4.12991998 5 P 0 N
A 12.5776 4.09055 12.5776 4.09055 12.55905 4.09055 5 P 0 N
L 12.55905 3.77558996 12.63778996 3.81496004 11 P 0 
A 12.65633996 3.81496004 12.65633996 3.81496004 12.63778996 3.81496004 5 P 0 N
A 12.5776 3.77558996 12.5776 3.77558996 12.55905 3.77558996 5 P 0 N
L 12.55905 3.93306998 12.63778996 3.97243996 11 P 0 
A 12.5776 3.93306998 12.5776 3.93306998 12.55905 3.93306998 5 P 0 N
A 12.65633996 3.5 12.65633996 3.5 12.63778996 3.5 5 P 0 N
L 12.55905 3.61811004 12.63778996 3.65748002 11 P 0 
A 12.65633996 3.65748002 12.65633996 3.65748002 12.63778996 3.65748002 5 P 0 N
A 12.5776 3.61811004 12.5776 3.61811004 12.55905 3.61811004 5 P 0 N
L 12.55905 3.30315 12.63778996 3.26378002 11 P 0 
A 12.65633996 3.26378002 12.65633996 3.26378002 12.63778996 3.26378002 5 P 0 N
A 12.5776 3.30315 12.5776 3.30315 12.55905 3.30315 5 P 0 N
L 12.55905 3.46063002 12.63778996 3.5 11 P 0 
A 12.5776 3.46063002 12.5776 3.46063002 12.55905 3.46063002 5 P 0 N
L 12.55905 3.14566998 12.63778996 3.1063 11 P 0 
A 12.65633996 3.1063 12.65633996 3.1063 12.63778996 3.1063 5 P 0 N
A 12.5776 3.14566998 12.5776 3.14566998 12.55905 3.14566998 5 P 0 N
A 12.5776 2.98818996 12.5776 2.98818996 12.55905 2.98818996 5 P 0 N
L 12.55905 2.98818996 12.63778996 2.94881998 11 P 0 
A 12.65633996 2.94881998 12.65633996 2.94881998 12.63778996 2.94881998 5 P 0 N
L 12.55905 2.83071004 12.63778996 2.79133996 11 P 0 
A 12.65633996 2.79133996 12.65633996 2.79133996 12.63778996 2.79133996 5 P 0 N
A 12.5776 2.83071004 12.5776 2.83071004 12.55905 2.83071004 5 P 0 N
L 12.55905 2.59448996 12.63778996 2.55511998 11 P 0 
A 12.65633996 2.55511998 12.65633996 2.55511998 12.63778996 2.55511998 5 P 0 N
A 12.5776 2.59448996 12.5776 2.59448996 12.55905 2.59448996 5 P 0 N
L 12.55905 2.43701004 12.63778996 2.39763996 11 P 0 
A 12.65633996 2.39763996 12.65633996 2.39763996 12.63778996 2.39763996 5 P 0 N
A 12.5776 2.43701004 12.5776 2.43701004 12.55905 2.43701004 5 P 0 N
L 12.55905 2.27953002 12.63778996 2.24016004 11 P 0 
A 12.65633996 2.24016004 12.65633996 2.24016004 12.63778996 2.24016004 5 P 0 N
A 12.5776 2.27953002 12.5776 2.27953002 12.55905 2.27953002 5 P 0 N
A 12.5776 2.04331004 12.5776 2.04331004 12.55905 2.04331004 5 P 0 N
A 12.65633996 2.08268002 12.65633996 2.08268002 12.63778996 2.08268002 5 P 0 N
L 12.55905 2.04331004 12.63778996 2.08268002 11 P 0 
L 12.55905 1.96456998 12.63778996 1.9252 11 P 0 
A 12.65633996 1.9252 12.65633996 1.9252 12.63778996 1.9252 5 P 0 N
A 12.5776 1.96456998 12.5776 1.96456998 12.55905 1.96456998 5 P 0 N
A 0.11303996 4.52363002 0.11303996 4.52363002 0.09448996 4.52363002 5 P 0 N
A 0.19178002 4.563 0.19178002 4.563 0.17323002 4.563 5 P 0 N
L 0.09448996 4.52363002 0.17323002 4.563 11 P 0 
A 0.11303996 4.36613996 0.11303996 4.36613996 0.09448996 4.36613996 5 P 0 N
A 0.19178002 4.40551004 0.19178002 4.40551004 0.17323002 4.40551004 5 P 0 N
L 0.09448996 4.36613996 0.17323002 4.40551004 11 P 0 
A 0.11303996 4.20866004 0.11303996 4.20866004 0.09448996 4.20866004 5 P 0 N
A 0.19178002 4.24803002 0.19178002 4.24803002 0.17323002 4.24803002 5 P 0 N
L 0.09448996 4.20866004 0.17323002 4.24803002 11 P 0 
A 0.11303996 4.05118002 0.11303996 4.05118002 0.09448996 4.05118002 5 P 0 N
A 0.19178002 4.09055 0.19178002 4.09055 0.17323002 4.09055 5 P 0 N
L 0.09448996 4.05118002 0.17323002 4.09055 11 P 0 
A 0.11303996 3.8937 0.11303996 3.8937 0.09448996 3.8937 5 P 0 N
A 0.19178002 3.93306998 0.19178002 3.93306998 0.17323002 3.93306998 5 P 0 N
L 0.09448996 3.8937 0.17323002 3.93306998 11 P 0 
A 0.11303996 3.73621998 0.11303996 3.73621998 0.09448996 3.73621998 5 P 0 N
A 0.19178002 3.77558996 0.19178002 3.77558996 0.17323002 3.77558996 5 P 0 N
L 0.09448996 3.73621998 0.17323002 3.77558996 11 P 0 
A 0.11303996 3.57873996 0.11303996 3.57873996 0.09448996 3.57873996 5 P 0 N
A 0.19178002 3.61811004 0.19178002 3.61811004 0.17323002 3.61811004 5 P 0 N
L 0.09448996 3.57873996 0.17323002 3.61811004 11 P 0 
A 0.11303996 3.42126004 0.11303996 3.42126004 0.09448996 3.42126004 5 P 0 N
A 0.19178002 3.46063002 0.19178002 3.46063002 0.17323002 3.46063002 5 P 0 N
L 0.09448996 3.42126004 0.17323002 3.46063002 11 P 0 
A 0.2902 3.14566998 0.2902 3.14566998 0.27165 3.14566998 5 P 0 N
A 0.36893996 3.18503996 0.36893996 3.18503996 0.35038996 3.18503996 5 P 0 N
L 0.27165 3.14566998 0.35038996 3.18503996 11 P 0 
A 0.2902 2.98818996 0.2902 2.98818996 0.27165 2.98818996 5 P 0 N
A 0.36893996 3.02756004 0.36893996 3.02756004 0.35038996 3.02756004 5 P 0 N
L 0.27165 2.98818996 0.35038996 3.02756004 11 P 0 
A 0.2902 2.83071004 0.2902 2.83071004 0.27165 2.83071004 5 P 0 N
A 0.36893996 2.87008002 0.36893996 2.87008002 0.35038996 2.87008002 5 P 0 N
L 0.27165 2.83071004 0.35038996 2.87008002 11 P 0 
A 0.2902 2.67323002 0.2902 2.67323002 0.27165 2.67323002 5 P 0 N
A 0.36893996 2.7126 0.36893996 2.7126 0.35038996 2.7126 5 P 0 N
L 0.27165 2.67323002 0.35038996 2.7126 11 P 0 
A 0.2902 2.43701004 0.2902 2.43701004 0.27165 2.43701004 5 P 0 N
A 0.36893996 2.47638002 0.36893996 2.47638002 0.35038996 2.47638002 5 P 0 N
L 0.27165 2.43701004 0.35038996 2.47638002 11 P 0 
A 0.2902 2.27953002 0.2902 2.27953002 0.27165 2.27953002 5 P 0 N
A 0.36893996 2.3189 0.36893996 2.3189 0.35038996 2.3189 5 P 0 N
L 0.27165 2.27953002 0.35038996 2.3189 11 P 0 
A 0.2902 2.12205 0.2902 2.12205 0.27165 2.12205 5 P 0 N
A 0.36893996 2.16141998 0.36893996 2.16141998 0.35038996 2.16141998 5 P 0 N
L 0.27165 2.12205 0.35038996 2.16141998 11 P 0 
L 0.09448996 2.00393996 0.17323002 2.04331004 11 P 0 
A 0.19178002 2.04331004 0.19178002 2.04331004 0.17323002 2.04331004 5 P 0 N
A 0.11303996 2.00393996 0.11303996 2.00393996 0.09448996 2.00393996 5 P 0 N
A 0.2902 1.96456998 0.2902 1.96456998 0.27165 1.96456998 5 P 0 N
A 0.36893996 1.9252 0.36893996 1.9252 0.35038996 1.9252 5 P 0 N
L 0.27165 1.96456998 0.35038996 1.9252 10 P 0 
A 0.11303996 1.9252 0.11303996 1.9252 0.09448996 1.9252 5 P 0 N
A 0.19178002 1.88583002 0.19178002 1.88583002 0.17323002 1.88583002 5 P 0 N
L 0.09448996 1.9252 0.17323002 1.88583002 11 P 0 
A 0.11303996 2.24016004 0.11303996 2.24016004 0.09448996 2.24016004 5 P 0 N
A 0.19178002 2.20078996 0.19178002 2.20078996 0.17323002 2.20078996 5 P 0 N
L 0.09448996 2.24016004 0.17323002 2.20078996 11 P 0 
A 0.11303996 2.39763996 0.11303996 2.39763996 0.09448996 2.39763996 5 P 0 N
A 0.19178002 2.35826998 0.19178002 2.35826998 0.17323002 2.35826998 5 P 0 N
L 0.09448996 2.39763996 0.17323002 2.35826998 11 P 0 
A 0.11303996 2.55511998 0.11303996 2.55511998 0.09448996 2.55511998 5 P 0 N
A 0.19178002 2.51575 0.19178002 2.51575 0.17323002 2.51575 5 P 0 N
L 0.09448996 2.55511998 0.17323002 2.51575 11 P 0 
A 0.11303996 2.79133996 0.11303996 2.79133996 0.09448996 2.79133996 5 P 0 N
A 0.19178002 2.75196998 0.19178002 2.75196998 0.17323002 2.75196998 5 P 0 N
L 0.09448996 2.79133996 0.17323002 2.75196998 11 P 0 
A 0.11303996 2.94881998 0.11303996 2.94881998 0.09448996 2.94881998 5 P 0 N
A 0.19178002 2.90945 0.19178002 2.90945 0.17323002 2.90945 5 P 0 N
L 0.09448996 2.94881998 0.17323002 2.90945 11 P 0 
A 0.11303996 3.1063 0.11303996 3.1063 0.09448996 3.1063 5 P 0 N
A 0.19178002 3.06693002 0.19178002 3.06693002 0.17323002 3.06693002 5 P 0 N
L 0.09448996 3.1063 0.17323002 3.06693002 11 P 0 
A 0.11303996 3.26378002 0.11303996 3.26378002 0.09448996 3.26378002 5 P 0 N
A 0.19178002 3.22441004 0.19178002 3.22441004 0.17323002 3.22441004 5 P 0 N
L 0.09448996 3.26378002 0.17323002 3.22441004 11 P 0 
A 0.2902 3.38188996 0.2902 3.38188996 0.27165 3.38188996 5 P 0 N
A 0.36893996 3.34251998 0.36893996 3.34251998 0.35038996 3.34251998 5 P 0 N
L 0.27165 3.38188996 0.35038996 3.34251998 11 P 0 
A 0.2902 3.53936998 0.2902 3.53936998 0.27165 3.53936998 5 P 0 N
A 0.36893996 3.5 0.36893996 3.5 0.35038996 3.5 5 P 0 N
L 0.27165 3.53936998 0.35038996 3.5 11 P 0 
A 0.2902 3.69685 0.2902 3.69685 0.27165 3.69685 5 P 0 N
A 0.36893996 3.65748002 0.36893996 3.65748002 0.35038996 3.65748002 5 P 0 N
L 0.27165 3.69685 0.35038996 3.65748002 11 P 0 
A 0.2902 3.85433002 0.2902 3.85433002 0.27165 3.85433002 5 P 0 N
A 0.36893996 3.81496004 0.36893996 3.81496004 0.35038996 3.81496004 5 P 0 N
L 0.27165 3.85433002 0.35038996 3.81496004 11 P 0 
A 0.2902 4.01181004 0.2902 4.01181004 0.27165 4.01181004 5 P 0 N
A 0.36893996 3.97243996 0.36893996 3.97243996 0.35038996 3.97243996 5 P 0 N
L 0.27165 4.01181004 0.35038996 3.97243996 11 P 0 
A 0.2902 4.16928996 0.2902 4.16928996 0.27165 4.16928996 5 P 0 N
A 0.36893996 4.12991998 0.36893996 4.12991998 0.35038996 4.12991998 5 P 0 N
L 0.27165 4.16928996 0.35038996 4.12991998 11 P 0 
A 0.2902 4.32676998 0.2902 4.32676998 0.27165 4.32676998 5 P 0 N
A 0.36893996 4.2874 0.36893996 4.2874 0.35038996 4.2874 5 P 0 N
L 0.27165 4.32676998 0.35038996 4.2874 11 P 0 
L 0.27165 4.48425 0.35038996 4.44488002 11 P 0 
A 0.36893996 4.44488002 0.36893996 4.44488002 0.35038996 4.44488002 5 P 0 N
A 0.2902 4.48425 0.2902 4.48425 0.27165 4.48425 5 P 0 N
L 3.3408 4.998 3.3408 4.962 4 P 0 
L 3.3348 4.998 3.3348 4.962 4 P 0 
L 3.3258 4.998 3.3258 4.962 4 P 0 
L 3.55338996 4.998 3.55338996 4.962 4 P 0 
L 3.54738996 4.998 3.54738996 4.962 4 P 0 
L 3.53838996 4.998 3.53838996 4.962 4 P 0 
L 3.52938996 4.998 3.52938996 4.962 4 P 0 
L 3.55638996 5.004 3.55838996 5.004 1 P 0 
L 3.55838996 5.004 3.55938996 5.003 1 P 0 
L 3.55938996 5.003 3.55938996 4.956 1 P 0 
L 3.55938996 4.956 3.55838996 4.955 1 P 0 
L 3.55838996 4.955 3.52438996 4.955 1 P 0 
L 3.52438996 4.955 3.52338996 4.956 1 P 0 
L 3.52338996 4.956 3.52338996 5.003 1 P 0 
L 3.52338996 5.003 3.52438996 5.004 1 P 0 
L 3.52438996 5.004 3.55638996 5.004 1 P 0 
L 3.48253002 4.87673996 3.48253002 4.84073996 4 P 0 
L 3.47653002 4.87673996 3.47653002 4.84073996 4 P 0 
L 3.46753002 4.87673996 3.46753002 4.84073996 4 P 0 
L 3.45853002 4.87673996 3.45853002 4.84073996 4 P 0 
L 3.48553002 4.88273996 3.48753002 4.88273996 1 P 0 
L 3.48753002 4.88273996 3.48853002 4.88173996 1 P 0 
L 3.48853002 4.88173996 3.48853002 4.83473996 1 P 0 
L 3.48853002 4.83473996 3.48753002 4.83373996 1 P 0 
L 3.48753002 4.83373996 3.45353002 4.83373996 1 P 0 
L 3.45353002 4.83373996 3.45253002 4.83473996 1 P 0 
L 3.45253002 4.83473996 3.45253002 4.88173996 1 P 0 
L 3.45253002 4.88173996 3.45353002 4.88273996 1 P 0 
L 3.45353002 4.88273996 3.48553002 4.88273996 1 P 0 
L 3.55338996 4.87673996 3.55338996 4.84073996 4 P 0 
L 3.54738996 4.87673996 3.54738996 4.84073996 4 P 0 
L 3.53838996 4.87673996 3.53838996 4.84073996 4 P 0 
L 3.52938996 4.87673996 3.52938996 4.84073996 4 P 0 
L 3.55638996 4.88273996 3.55838996 4.88273996 1 P 0 
L 3.55838996 4.88273996 3.55938996 4.88173996 1 P 0 
L 3.55938996 4.88173996 3.55938996 4.83473996 1 P 0 
L 3.55938996 4.83473996 3.55838996 4.83373996 1 P 0 
L 3.55838996 4.83373996 3.52438996 4.83373996 1 P 0 
L 3.52438996 4.83373996 3.52338996 4.83473996 1 P 0 
L 3.52338996 4.83473996 3.52338996 4.88173996 1 P 0 
L 3.52338996 4.88173996 3.52438996 4.88273996 1 P 0 
L 3.52438996 4.88273996 3.55638996 4.88273996 1 P 0 
L 3.1282 4.998 3.1282 4.962 4 P 0 
L 3.1222 4.998 3.1222 4.962 4 P 0 
L 3.1132 4.998 3.1132 4.962 4 P 0 
L 3.1042 4.998 3.1042 4.962 4 P 0 
L 3.1312 5.004 3.1332 5.004 1 P 0 
L 3.1332 5.004 3.1342 5.003 1 P 0 
L 3.1342 5.003 3.1342 4.956 1 P 0 
L 3.1342 4.956 3.1332 4.955 1 P 0 
L 3.1332 4.955 3.0992 4.955 1 P 0 
L 3.0992 4.955 3.0982 4.956 1 P 0 
L 3.0982 4.956 3.0982 5.003 1 P 0 
L 3.0982 5.003 3.0992 5.004 1 P 0 
L 3.0992 5.004 3.1312 5.004 1 P 0 
L 3.26993002 4.998 3.26993002 4.962 4 P 0 
L 3.26393002 4.998 3.26393002 4.962 4 P 0 
L 3.25493002 4.998 3.25493002 4.962 4 P 0 
L 3.24593002 4.998 3.24593002 4.962 4 P 0 
L 3.27293002 5.004 3.27493002 5.004 1 P 0 
L 3.27493002 5.004 3.27593002 5.003 1 P 0 
L 3.27593002 5.003 3.27593002 4.956 1 P 0 
L 3.27593002 4.956 3.27493002 4.955 1 P 0 
L 3.27493002 4.955 3.24093002 4.955 1 P 0 
L 3.24093002 4.955 3.23993002 4.956 1 P 0 
L 3.23993002 4.956 3.23993002 5.003 1 P 0 
L 3.23993002 5.003 3.24093002 5.004 1 P 0 
L 3.24093002 5.004 3.27293002 5.004 1 P 0 
L 3.3168 4.998 3.3168 4.962 4 P 0 
L 3.3438 5.004 3.3458 5.004 1 P 0 
L 3.3458 5.004 3.3468 5.003 1 P 0 
L 3.3468 5.003 3.3468 4.956 1 P 0 
L 3.3468 4.956 3.3458 4.955 1 P 0 
L 3.3458 4.955 3.3118 4.955 1 P 0 
L 3.3118 4.955 3.3108 4.956 1 P 0 
L 3.3108 4.956 3.3108 5.003 1 P 0 
L 3.3108 5.003 3.3118 5.004 1 P 0 
L 3.3118 5.004 3.3438 5.004 1 P 0 
L 3.19906004 4.87673996 3.19906004 4.84073996 4 P 0 
L 3.19306004 4.87673996 3.19306004 4.84073996 4 P 0 
L 3.18406004 4.87673996 3.18406004 4.84073996 4 P 0 
L 3.17506004 4.87673996 3.17506004 4.84073996 4 P 0 
L 3.20206004 4.88273996 3.20406004 4.88273996 1 P 0 
L 3.20406004 4.88273996 3.20506004 4.88173996 1 P 0 
L 3.20506004 4.88173996 3.20506004 4.83473996 1 P 0 
L 3.20506004 4.83473996 3.20406004 4.83373996 1 P 0 
L 3.20406004 4.83373996 3.17006004 4.83373996 1 P 0 
L 3.17006004 4.83373996 3.16906004 4.83473996 1 P 0 
L 3.16906004 4.83473996 3.16906004 4.88173996 1 P 0 
L 3.16906004 4.88173996 3.17006004 4.88273996 1 P 0 
L 3.17006004 4.88273996 3.20206004 4.88273996 1 P 0 
L 3.26993002 4.87673996 3.26993002 4.84073996 4 P 0 
L 3.26393002 4.87673996 3.26393002 4.84073996 4 P 0 
L 3.25493002 4.87673996 3.25493002 4.84073996 4 P 0 
L 3.24593002 4.87673996 3.24593002 4.84073996 4 P 0 
L 3.27293002 4.88273996 3.27493002 4.88273996 1 P 0 
L 3.27493002 4.88273996 3.27593002 4.88173996 1 P 0 
L 3.27593002 4.88173996 3.27593002 4.83473996 1 P 0 
L 3.27593002 4.83473996 3.27493002 4.83373996 1 P 0 
L 3.27493002 4.83373996 3.24093002 4.83373996 1 P 0 
L 3.24093002 4.83373996 3.23993002 4.83473996 1 P 0 
L 3.23993002 4.83473996 3.23993002 4.88173996 1 P 0 
L 3.23993002 4.88173996 3.24093002 4.88273996 1 P 0 
L 3.24093002 4.88273996 3.27293002 4.88273996 1 P 0 
L 2.84473002 4.998 2.84473002 4.962 4 P 0 
L 2.83873002 4.998 2.83873002 4.962 4 P 0 
L 2.82973002 4.998 2.82973002 4.962 4 P 0 
L 3.05733002 4.998 3.05733002 4.962 4 P 0 
L 3.05133002 4.998 3.05133002 4.962 4 P 0 
L 3.04233002 4.998 3.04233002 4.962 4 P 0 
L 3.03333002 4.998 3.03333002 4.962 4 P 0 
L 3.06033002 5.004 3.06233002 5.004 1 P 0 
L 3.06233002 5.004 3.06333002 5.003 1 P 0 
L 3.06333002 5.003 3.06333002 4.956 1 P 0 
L 3.06333002 4.956 3.06233002 4.955 1 P 0 
L 3.06233002 4.955 3.02833002 4.955 1 P 0 
L 3.02833002 4.955 3.02733002 4.956 1 P 0 
L 3.02733002 4.956 3.02733002 5.003 1 P 0 
L 3.02733002 5.003 3.02833002 5.004 1 P 0 
L 3.02833002 5.004 3.06033002 5.004 1 P 0 
L 2.98646998 4.87673996 2.98646998 4.84073996 4 P 0 
L 2.98046998 4.87673996 2.98046998 4.84073996 4 P 0 
L 2.97146998 4.87673996 2.97146998 4.84073996 4 P 0 
L 2.96246998 4.87673996 2.96246998 4.84073996 4 P 0 
L 2.98946998 4.88273996 2.99146998 4.88273996 1 P 0 
L 2.99146998 4.88273996 2.99246998 4.88173996 1 P 0 
L 2.99246998 4.88173996 2.99246998 4.83473996 1 P 0 
L 2.99246998 4.83473996 2.99146998 4.83373996 1 P 0 
L 2.99146998 4.83373996 2.95746998 4.83373996 1 P 0 
L 2.95746998 4.83373996 2.95646998 4.83473996 1 P 0 
L 2.95646998 4.83473996 2.95646998 4.88173996 1 P 0 
L 2.95646998 4.88173996 2.95746998 4.88273996 1 P 0 
L 2.95746998 4.88273996 2.98946998 4.88273996 1 P 0 
L 3.05733002 4.87673996 3.05733002 4.84073996 4 P 0 
L 3.05133002 4.87673996 3.05133002 4.84073996 4 P 0 
L 3.04233002 4.87673996 3.04233002 4.84073996 4 P 0 
L 3.03333002 4.87673996 3.03333002 4.84073996 4 P 0 
L 3.06033002 4.88273996 3.06233002 4.88273996 1 P 0 
L 3.06233002 4.88273996 3.06333002 4.88173996 1 P 0 
L 3.06333002 4.88173996 3.06333002 4.83473996 1 P 0 
L 3.06333002 4.83473996 3.06233002 4.83373996 1 P 0 
L 3.06233002 4.83373996 3.02833002 4.83373996 1 P 0 
L 3.02833002 4.83373996 3.02733002 4.83473996 1 P 0 
L 3.02733002 4.83473996 3.02733002 4.88173996 1 P 0 
L 3.02733002 4.88173996 3.02833002 4.88273996 1 P 0 
L 3.02833002 4.88273996 3.06033002 4.88273996 1 P 0 
L 2.82073002 4.998 2.82073002 4.962 4 P 0 
L 2.84773002 5.004 2.84973002 5.004 1 P 0 
L 2.84973002 5.004 2.85073002 5.003 1 P 0 
L 2.85073002 5.003 2.85073002 4.956 1 P 0 
L 2.85073002 4.956 2.84973002 4.955 1 P 0 
L 2.84973002 4.955 2.81573002 4.955 1 P 0 
L 2.81573002 4.955 2.81473002 4.956 1 P 0 
L 2.81473002 4.956 2.81473002 5.003 1 P 0 
L 2.81473002 5.003 2.81573002 5.004 1 P 0 
L 2.81573002 5.004 2.84773002 5.004 1 P 0 
L 2.77386998 4.998 2.77386998 4.962 4 P 0 
L 2.76786998 4.998 2.76786998 4.962 4 P 0 
L 2.75886998 4.998 2.75886998 4.962 4 P 0 
L 2.74986998 4.998 2.74986998 4.962 4 P 0 
L 2.77686998 5.004 2.77886998 5.004 1 P 0 
L 2.77886998 5.004 2.77986998 5.003 1 P 0 
L 2.77986998 5.003 2.77986998 4.956 1 P 0 
L 2.77986998 4.956 2.77886998 4.955 1 P 0 
L 2.77886998 4.955 2.74486998 4.955 1 P 0 
L 2.74486998 4.955 2.74386998 4.956 1 P 0 
L 2.74386998 4.956 2.74386998 5.003 1 P 0 
L 2.74386998 5.003 2.74486998 5.004 1 P 0 
L 2.74486998 5.004 2.77686998 5.004 1 P 0 
L 2.77386998 4.87673996 2.77386998 4.84073996 4 P 0 
L 2.76786998 4.87673996 2.76786998 4.84073996 4 P 0 
L 2.75886998 4.87673996 2.75886998 4.84073996 4 P 0 
L 2.74986998 4.87673996 2.74986998 4.84073996 4 P 0 
L 2.77686998 4.88273996 2.77886998 4.88273996 1 P 0 
L 2.77886998 4.88273996 2.77986998 4.88173996 1 P 0 
L 2.77986998 4.88173996 2.77986998 4.83473996 1 P 0 
L 2.77986998 4.83473996 2.77886998 4.83373996 1 P 0 
L 2.77886998 4.83373996 2.74486998 4.83373996 1 P 0 
L 2.74486998 4.83373996 2.74386998 4.83473996 1 P 0 
L 2.74386998 4.83473996 2.74386998 4.88173996 1 P 0 
L 2.74386998 4.88173996 2.74486998 4.88273996 1 P 0 
L 2.74486998 4.88273996 2.77686998 4.88273996 1 P 0 
L 2.39178996 4.88273996 2.39378996 4.88273996 1 P 0 
L 2.39378996 4.88273996 2.39478996 4.88173996 1 P 0 
L 2.39478996 4.88173996 2.39478996 4.83473996 1 P 0 
L 2.39478996 4.83473996 2.39378996 4.83373996 1 P 0 
L 2.39378996 4.83373996 2.35978996 4.83373996 1 P 0 
L 2.35978996 4.83373996 2.35878996 4.83473996 1 P 0 
L 2.35878996 4.83473996 2.35878996 4.88173996 1 P 0 
L 2.35878996 4.88173996 2.35978996 4.88273996 1 P 0 
L 2.35978996 4.88273996 2.39178996 4.88273996 1 P 0 
L 2.36478996 4.87673996 2.36478996 4.84073996 4 P 0 
L 2.37378996 4.87673996 2.37378996 4.84073996 4 P 0 
L 2.38278996 4.87673996 2.38278996 4.84073996 4 P 0 
L 2.38878996 4.87673996 2.38878996 4.84073996 4 P 0 
L 2.32093002 4.88273996 2.32293002 4.88273996 1 P 0 
L 2.32293002 4.88273996 2.32393002 4.88173996 1 P 0 
L 2.32393002 4.88173996 2.32393002 4.83473996 1 P 0 
L 2.32393002 4.83473996 2.32293002 4.83373996 1 P 0 
L 2.32293002 4.83373996 2.28893002 4.83373996 1 P 0 
L 2.28893002 4.83373996 2.28793002 4.83473996 1 P 0 
L 2.28793002 4.83473996 2.28793002 4.88173996 1 P 0 
L 2.28793002 4.88173996 2.28893002 4.88273996 1 P 0 
L 2.28893002 4.88273996 2.32093002 4.88273996 1 P 0 
L 2.29393002 4.87673996 2.29393002 4.84073996 4 P 0 
L 2.30293002 4.87673996 2.30293002 4.84073996 4 P 0 
L 2.31193002 4.87673996 2.31193002 4.84073996 4 P 0 
L 2.31793002 4.87673996 2.31793002 4.84073996 4 P 0 
L 2.39178996 5.004 2.39378996 5.004 1 P 0 
L 2.39378996 5.004 2.39478996 5.003 1 P 0 
L 2.39478996 5.003 2.39478996 4.956 1 P 0 
L 2.39478996 4.956 2.39378996 4.955 1 P 0 
L 2.39378996 4.955 2.35978996 4.955 1 P 0 
L 2.35978996 4.955 2.35878996 4.956 1 P 0 
L 2.35878996 4.956 2.35878996 5.003 1 P 0 
L 2.35878996 5.003 2.35978996 5.004 1 P 0 
L 2.35978996 5.004 2.39178996 5.004 1 P 0 
L 2.36478996 4.998 2.36478996 4.962 4 P 0 
L 2.37378996 4.998 2.37378996 4.962 4 P 0 
L 2.38278996 4.998 2.38278996 4.962 4 P 0 
L 2.38878996 4.998 2.38878996 4.962 4 P 0 
L 2.1792 5.004 2.1812 5.004 1 P 0 
L 2.1812 5.004 2.1822 5.003 1 P 0 
L 2.1822 5.003 2.1822 4.956 1 P 0 
L 2.1822 4.956 2.1812 4.955 1 P 0 
L 2.1812 4.955 2.1472 4.955 1 P 0 
L 2.1472 4.955 2.1462 4.956 1 P 0 
L 2.1462 4.956 2.1462 5.003 1 P 0 
L 2.1462 5.003 2.1472 5.004 1 P 0 
L 2.1472 5.004 2.1792 5.004 1 P 0 
L 2.1522 4.998 2.1522 4.962 4 P 0 
L 2.1612 4.998 2.1612 4.962 4 P 0 
L 2.1702 4.998 2.1702 4.962 4 P 0 
L 2.1762 4.998 2.1762 4.962 4 P 0 
L 2.10833002 5.004 2.11033002 5.004 1 P 0 
L 2.11033002 5.004 2.11133002 5.003 1 P 0 
L 2.11133002 5.003 2.11133002 4.956 1 P 0 
L 2.11133002 4.956 2.11033002 4.955 1 P 0 
L 2.11033002 4.955 2.07633002 4.955 1 P 0 
L 2.07633002 4.955 2.07533002 4.956 1 P 0 
L 2.07533002 4.956 2.07533002 5.003 1 P 0 
L 2.07533002 5.003 2.07633002 5.004 1 P 0 
L 2.07633002 5.004 2.10833002 5.004 1 P 0 
L 2.08133002 4.998 2.08133002 4.962 4 P 0 
L 2.09033002 4.998 2.09033002 4.962 4 P 0 
L 2.09933002 4.998 2.09933002 4.962 4 P 0 
L 2.10533002 4.998 2.10533002 4.962 4 P 0 
L 1.9666 5.004 1.9686 5.004 1 P 0 
L 1.9686 5.004 1.9696 5.003 1 P 0 
L 1.9696 5.003 1.9696 4.956 1 P 0 
L 1.9696 4.956 1.9686 4.955 1 P 0 
L 1.9686 4.955 1.9346 4.955 1 P 0 
L 1.9346 4.955 1.9336 4.956 1 P 0 
L 1.9336 4.956 1.9336 5.003 1 P 0 
L 1.9336 5.003 1.9346 5.004 1 P 0 
L 1.9346 5.004 1.9666 5.004 1 P 0 
L 1.9396 4.998 1.9396 4.962 4 P 0 
L 1.9486 4.998 1.9486 4.962 4 P 0 
L 1.9576 4.998 1.9576 4.962 4 P 0 
L 1.9636 4.998 1.9636 4.962 4 P 0 
L 1.89573002 5.004 1.89773002 5.004 1 P 0 
L 1.89773002 5.004 1.89873002 5.003 1 P 0 
L 1.89873002 5.003 1.89873002 4.956 1 P 0 
L 1.89873002 4.956 1.89773002 4.955 1 P 0 
L 1.89773002 4.955 1.86373002 4.955 1 P 0 
L 1.86373002 4.955 1.86273002 4.956 1 P 0 
L 1.86273002 4.956 1.86273002 5.003 1 P 0 
L 1.86273002 5.003 1.86373002 5.004 1 P 0 
L 1.86373002 5.004 1.89573002 5.004 1 P 0 
L 1.86873002 4.998 1.86873002 4.962 4 P 0 
L 1.87773002 4.998 1.87773002 4.962 4 P 0 
L 1.88673002 4.998 1.88673002 4.962 4 P 0 
L 1.89273002 4.998 1.89273002 4.962 4 P 0 
L 2.10833002 4.88273996 2.11033002 4.88273996 1 P 0 
L 2.11033002 4.88273996 2.11133002 4.88173996 1 P 0 
L 2.11133002 4.88173996 2.11133002 4.83473996 1 P 0 
L 2.11133002 4.83473996 2.11033002 4.83373996 1 P 0 
L 2.11033002 4.83373996 2.07633002 4.83373996 1 P 0 
L 2.07633002 4.83373996 2.07533002 4.83473996 1 P 0 
L 2.07533002 4.83473996 2.07533002 4.88173996 1 P 0 
L 2.07533002 4.88173996 2.07633002 4.88273996 1 P 0 
L 2.07633002 4.88273996 2.10833002 4.88273996 1 P 0 
L 2.08133002 4.87673996 2.08133002 4.84073996 4 P 0 
L 2.09033002 4.87673996 2.09033002 4.84073996 4 P 0 
L 2.09933002 4.87673996 2.09933002 4.84073996 4 P 0 
L 2.10533002 4.87673996 2.10533002 4.84073996 4 P 0 
L 2.03746004 4.88273996 2.03946004 4.88273996 1 P 0 
L 2.03946004 4.88273996 2.04046004 4.88173996 1 P 0 
L 2.04046004 4.88173996 2.04046004 4.83473996 1 P 0 
L 2.04046004 4.83473996 2.03946004 4.83373996 1 P 0 
L 2.03946004 4.83373996 2.00546004 4.83373996 1 P 0 
L 2.00546004 4.83373996 2.00446004 4.83473996 1 P 0 
L 2.00446004 4.83473996 2.00446004 4.88173996 1 P 0 
L 2.00446004 4.88173996 2.00546004 4.88273996 1 P 0 
L 2.00546004 4.88273996 2.03746004 4.88273996 1 P 0 
L 2.01046004 4.87673996 2.01046004 4.84073996 4 P 0 
L 2.01946004 4.87673996 2.01946004 4.84073996 4 P 0 
L 2.02846004 4.87673996 2.02846004 4.84073996 4 P 0 
L 2.03446004 4.87673996 2.03446004 4.84073996 4 P 0 
L 1.89573002 4.88273996 1.89773002 4.88273996 1 P 0 
L 1.89773002 4.88273996 1.89873002 4.88173996 1 P 0 
L 1.89873002 4.88173996 1.89873002 4.83473996 1 P 0 
L 1.89873002 4.83473996 1.89773002 4.83373996 1 P 0 
L 1.89773002 4.83373996 1.86373002 4.83373996 1 P 0 
L 1.86373002 4.83373996 1.86273002 4.83473996 1 P 0 
L 1.86273002 4.83473996 1.86273002 4.88173996 1 P 0 
L 1.86273002 4.88173996 1.86373002 4.88273996 1 P 0 
L 1.86373002 4.88273996 1.89573002 4.88273996 1 P 0 
L 1.86873002 4.87673996 1.86873002 4.84073996 4 P 0 
L 1.87773002 4.87673996 1.87773002 4.84073996 4 P 0 
L 1.88673002 4.87673996 1.88673002 4.84073996 4 P 0 
L 1.89273002 4.87673996 1.89273002 4.84073996 4 P 0 
L 1.82486998 4.88273996 1.82686998 4.88273996 1 P 0 
L 1.82686998 4.88273996 1.82786998 4.88173996 1 P 0 
L 1.82786998 4.88173996 1.82786998 4.83473996 1 P 0 
L 1.82786998 4.83473996 1.82686998 4.83373996 1 P 0 
L 1.82686998 4.83373996 1.79286998 4.83373996 1 P 0 
L 1.79286998 4.83373996 1.79186998 4.83473996 1 P 0 
L 1.79186998 4.83473996 1.79186998 4.88173996 1 P 0 
L 1.79186998 4.88173996 1.79286998 4.88273996 1 P 0 
L 1.79286998 4.88273996 1.82486998 4.88273996 1 P 0 
L 1.79786998 4.87673996 1.79786998 4.84073996 4 P 0 
L 1.80686998 4.87673996 1.80686998 4.84073996 4 P 0 
L 1.81586998 4.87673996 1.81586998 4.84073996 4 P 0 
L 1.82186998 4.87673996 1.82186998 4.84073996 4 P 0 
L 1.61226998 4.88273996 1.61426998 4.88273996 1 P 0 
L 1.61426998 4.88273996 1.61526998 4.88173996 1 P 0 
L 1.61526998 4.88173996 1.61526998 4.83473996 1 P 0 
L 1.61526998 4.83473996 1.61426998 4.83373996 1 P 0 
L 1.61426998 4.83373996 1.58026998 4.83373996 1 P 0 
L 1.58026998 4.83373996 1.57926998 4.83473996 1 P 0 
L 1.57926998 4.83473996 1.57926998 4.88173996 1 P 0 
L 1.57926998 4.88173996 1.58026998 4.88273996 1 P 0 
L 1.58026998 4.88273996 1.61226998 4.88273996 1 P 0 
L 1.58526998 4.87673996 1.58526998 4.84073996 4 P 0 
L 1.59426998 4.87673996 1.59426998 4.84073996 4 P 0 
L 1.60326998 4.87673996 1.60326998 4.84073996 4 P 0 
L 1.60926998 4.87673996 1.60926998 4.84073996 4 P 0 
L 1.61226998 5.004 1.61426998 5.004 1 P 0 
L 1.61426998 5.004 1.61526998 5.003 1 P 0 
L 1.61526998 5.003 1.61526998 4.956 1 P 0 
L 1.61526998 4.956 1.61426998 4.955 1 P 0 
L 1.61426998 4.955 1.58026998 4.955 1 P 0 
L 1.58026998 4.955 1.57926998 4.956 1 P 0 
L 1.57926998 4.956 1.57926998 5.003 1 P 0 
L 1.57926998 5.003 1.58026998 5.004 1 P 0 
L 1.58026998 5.004 1.61226998 5.004 1 P 0 
L 1.58526998 4.998 1.58526998 4.962 4 P 0 
L 1.59426998 4.998 1.59426998 4.962 4 P 0 
L 1.60326998 4.998 1.60326998 4.962 4 P 0 
L 1.60926998 4.998 1.60926998 4.962 4 P 0 
L 1.68313002 5.004 1.68513002 5.004 1 P 0 
L 1.68513002 5.004 1.68613002 5.003 1 P 0 
L 1.68613002 5.003 1.68613002 4.956 1 P 0 
L 1.68613002 4.956 1.68513002 4.955 1 P 0 
L 1.68513002 4.955 1.65113002 4.955 1 P 0 
L 1.65113002 4.955 1.65013002 4.956 1 P 0 
L 1.65013002 4.956 1.65013002 5.003 1 P 0 
L 1.65013002 5.003 1.65113002 5.004 1 P 0 
L 1.65113002 5.004 1.68313002 5.004 1 P 0 
L 1.65613002 4.998 1.65613002 4.962 4 P 0 
L 1.66513002 4.998 1.66513002 4.962 4 P 0 
L 1.67413002 4.998 1.67413002 4.962 4 P 0 
L 1.68013002 4.998 1.68013002 4.962 4 P 0 
L 4.87 0.025 6.565 0.025 16 P 0 
L 4.885 0.085 6.53 0.085 16 P 0 
L 4.895 0.15 6.54 0.15 16 P 0 
L 4.89 0.215 6.555 0.215 16 P 0 
L 4.89 0.3 6.535 0.3 16 P 0 
L 4.895 0.37 6.54 0.37 16 P 0 
A 12.84646004 6.02361998 12.9252 5.94488002 12.84646004 5.94488002 11 P 0 Y
A 12.9252 0.07873996 12.84646004 0 12.84646004 0.07873996 11 P 0 Y
L 12.9252 5.94488002 12.9252 0.07873996 11 P 0 
L 12.84646004 0 6.66536004 0 11 P 0 
A 6.58661998 0.35433002 6.50788002 0.43306998 6.50788002 0.35433002 11 P 0 N
A 6.66536004 0 6.58661998 0.07873996 6.66535994 0.07873996 11 P 0 Y
L 6.58661998 0.07873996 6.58661998 0.35433002 11 P 0 
A 4.93308002 0.43306998 4.85433996 0.35433002 4.93307992 0.35433002 11 P 0 N
L 6.50788002 0.43306998 4.93308002 0.43306998 11 P 0 
L 4.85433996 0.35433002 4.85433996 0.07873996 11 P 0 
A 4.85433996 0.07873996 4.77558996 0 4.7755999 0.07873996 11 P 0 Y
A 0.07873996 0 0 0.07873996 0.07873996 0.07873996 11 P 0 Y
L 4.77558996 0 0.07873996 0 11 P 0 
L 0.07873996 6.02361998 12.84646004 6.02361998 11 P 0 
A 0 5.94488002 0.07873996 6.02361998 0.07873996 5.94488002 11 P 0 Y
L 0 0.07873996 0 5.94488002 11 P 0 
L 0 6.07011998 12.89 6.07011998 16 P 0 
L 0 -0.0465 12.89 -0.0465 16 P 0 
L 0.005 6.16 0.035 6.13 5 P 0 
L 12.91 6.15 12.88 6.12 5 P 0 
L 12.91 -0.13 12.88 -0.1 5 P 0 
L 0.005 -0.135 0.035 -0.105 5 P 0 
L 0 -0.41426004 0 -0.093 11 P 0 
A 0.07873996 -0.493 0 -0.41426004 0.07873996 -0.41426004 11 P 0 Y
L 12.84646004 -0.493 0.07873996 -0.493 11 P 0 
A 12.9252 -0.41426004 12.84646004 -0.493 12.84646004 -0.41426004 11 P 0 Y
L 12.9252 -0.093 12.9252 -0.41426004 11 P 0 
L 0 -0.093 12.9252 -0.093 11 P 0 
L 0 6.11661998 12.9252 6.11661998 11 P 0 
L 0 6.43788002 0 6.11661998 11 P 0 
A 0.07873996 6.51661998 0 6.43788002 0.07873996 6.43788002 11 P 0 N
L 12.84646004 6.51661998 0.07873996 6.51661998 11 P 0 
A 12.9252 6.43788002 12.84646004 6.51661998 12.84646004 6.43788002 11 P 0 N
L 12.9252 6.11661998 12.9252 6.43788002 11 P 0 
L 0.0349 -2.3038 0.0349 -1.0038 4 P 0 ;0
L 0.0349 -1.0038 4.5349 -1.0038 4 P 0 ;0
L 4.5349 -1.0038 4.5349 -2.3038 4 P 0 ;0
L 4.5349 -2.3038 0.0349 -2.3038 4 P 0 ;0
L 0.0349 -1.6038 4.5349 -1.6038 4 P 0 ;0
L 0.0349 -1.8038 4.5349 -1.8038 4 P 0 ;0
L 2.4349 -2.1038 4.0349 -2.1038 4 P 0 ;0
L 2.4349 -2.3038 2.4349 -1.8038 4 P 0 ;0
L 3.2349 -2.1038 3.2349 -1.8038 4 P 0 ;0
L 4.0349 -2.3038 4.0349 -1.8038 4 P 0 ;0
L 0.0723999 -1.6844687 0.07906663 -1.69030079 2 P 0 ;0
L 0.07906663 -1.69030079 0.08656654 -1.6938 2 P 0 ;0
L 0.08656654 -1.6938 0.09323337 -1.6938 2 P 0 ;0
L 0.09323337 -1.6938 0.0999001 -1.69030079 2 P 0 ;0
L 0.0999001 -1.69030079 0.10490059 -1.6844687 2 P 0 ;0
L 0.10490059 -1.6844687 0.1074 -1.67629951 2 P 0 ;0
L 0.1074 -1.67629951 0.10573376 -1.66813455 2 P 0 ;0
L 0.10573376 -1.66813455 0.10156644 -1.66113396 2 P 0 ;0
L 0.10156644 -1.66113396 0.09406654 -1.65646614 2 P 0 ;0
L 0.09406654 -1.65646614 0.08406713 -1.65413327 2 P 0 ;0
L 0.08406713 -1.65413327 0.07823346 -1.64946762 2 P 0 ;0
L 0.07823346 -1.64946762 0.07573248 -1.64130059 2 P 0 ;0
L 0.07573248 -1.64130059 0.0774003 -1.63313356 2 P 0 ;0
L 0.0774003 -1.63313356 0.08156614 -1.62730148 2 P 0 ;0
L 0.08156614 -1.62730148 0.0873997 -1.6238 2 P 0 ;0
L 0.0873997 -1.6238 0.09323337 -1.6238 2 P 8191 ;0
L 0.09323337 -1.6238 0.09906693 -1.62613287 2 P 0 ;0
L 0.09906693 -1.62613287 0.10406742 -1.63196713 2 P 0 ;0
L 0.1383999 -1.6938 0.1383999 -1.6238 2 P 0 ;0
L 0.1734 -1.6238 0.1734 -1.6938 2 P 0 ;0
L 0.1734 -1.65880108 0.1383999 -1.65880108 2 P 0 ;0
L 0.23856683 -1.6938 0.20523307 -1.6938 2 P 0 ;0
L 0.20523307 -1.6938 0.20523307 -1.6238 2 P 0 ;0
L 0.20523307 -1.6238 0.23856683 -1.6238 2 P 0 ;0
L 0.22523337 -1.65763258 0.20523307 -1.65763258 2 P 0 ;0
L 0.30456683 -1.6938 0.27123307 -1.6938 2 P 0 ;0
L 0.27123307 -1.6938 0.27123307 -1.6238 2 P 0 ;0
L 0.27123307 -1.6238 0.30456683 -1.6238 2 P 0 ;0
L 0.29123337 -1.65763258 0.27123307 -1.65763258 2 P 0 ;0
L 0.35389921 -1.6238 0.35389921 -1.6938 2 P 0 ;0
L 0.33473356 -1.6238 0.37306634 -1.6238 2 P 0 ;0
L 0.09489921 -1.7188 0.09489921 -1.7888 2 P 0 ;0
L 0.07573356 -1.7188 0.11406634 -1.7188 2 P 0 ;0
L 0.1508998 -1.7188 0.17089862 -1.7188 2 P 0 ;0
L 0.16089921 -1.7188 0.16089921 -1.7888 2 P 0 ;0
L 0.1508998 -1.7888 0.17089862 -1.7888 2 P 0 ;0
L 0.22689921 -1.7188 0.22689921 -1.7888 2 P 0 ;0
L 0.20773356 -1.7188 0.24606634 -1.7188 2 P 0 ;0
L 0.27623307 -1.7188 0.27623307 -1.7888 2 P 0 ;0
L 0.27623307 -1.7888 0.30956683 -1.7888 2 P 0 ;0
L 0.37556683 -1.7888 0.34223307 -1.7888 2 P 0 ;0
L 0.34223307 -1.7888 0.34223307 -1.7188 2 P 0 ;0
L 0.34223307 -1.7188 0.37556683 -1.7188 2 P 0 ;0
L 0.36223337 -1.75263258 0.34223307 -1.75263258 2 P 0 ;0
L 2.5438999 -1.96813563 2.5519 -1.97480089 2 P 0 ;0
L 2.5519 -1.97480089 2.5608999 -1.9788 2 P 0 ;0
L 2.5608999 -1.9788 2.5689 -1.9788 2 P 0 ;0
L 2.5689 -1.9788 2.5769001 -1.97480089 2 P 0 ;0
L 2.5769001 -1.97480089 2.58290069 -1.96813563 2 P 0 ;0
L 2.58290069 -1.96813563 2.5859 -1.95879941 2 P 0 ;0
L 2.5859 -1.95879941 2.58390049 -1.94946811 2 P 0 ;0
L 2.58390049 -1.94946811 2.5788997 -1.94146732 2 P 0 ;0
L 2.5788997 -1.94146732 2.5698998 -1.93613278 2 P 0 ;0
L 2.5698998 -1.93613278 2.55790049 -1.93346663 2 P 0 ;0
L 2.55790049 -1.93346663 2.5509002 -1.92813445 2 P 0 ;0
L 2.5509002 -1.92813445 2.54789902 -1.91880069 2 P 0 ;0
L 2.54789902 -1.91880069 2.54990039 -1.90946683 2 P 0 ;0
L 2.54990039 -1.90946683 2.55489931 -1.90280167 2 P 0 ;0
L 2.55489931 -1.90280167 2.5618997 -1.8988 2 P 0 ;0
L 2.5618997 -1.8988 2.5689 -1.8988 2 P 0 ;0
L 2.5689 -1.8988 2.57590039 -1.90146614 2 P 0 ;0
L 2.57590039 -1.90146614 2.58190089 -1.90813386 2 P 0 ;0
L 2.6648998 -1.90546772 2.65889931 -1.90146614 2 P 0 ;0
L 2.65889931 -1.90146614 2.65190079 -1.8988 2 P 0 ;0
L 2.65190079 -1.8988 2.64390069 -1.8988 2 P 0 ;0
L 2.64390069 -1.8988 2.63489892 -1.90280167 2 P 0 ;0
L 2.63489892 -1.90280167 2.62790039 -1.90946683 2 P 0 ;0
L 2.62790039 -1.90946683 2.62289961 -1.91746762 2 P 0 ;0
L 2.62289961 -1.91746762 2.61889862 -1.93080049 2 P 0 ;0
L 2.61889862 -1.93080049 2.61789892 -1.94280039 2 P 0 ;0
L 2.61789892 -1.94280039 2.6199003 -1.9548003 2 P 0 ;0
L 2.6199003 -1.9548003 2.62289961 -1.96280098 2 P 0 ;0
L 2.62289961 -1.96280098 2.6289002 -1.97080177 2 P 0 ;0
L 2.6289002 -1.97080177 2.63590049 -1.97613396 2 P 0 ;0
L 2.63590049 -1.97613396 2.64289902 -1.9788 2 P 0 ;0
L 2.64289902 -1.9788 2.64989941 -1.9788 2 P 0 ;0
L 2.64989941 -1.9788 2.6568997 -1.97613396 2 P 0 ;0
L 2.6568997 -1.97613396 2.6629003 -1.97213484 2 P 0 ;0
L 2.6629003 -1.97213484 2.66790098 -1.96680266 2 P 0 ;0
L 2.69589892 -1.9788 2.72089902 -1.8988 2 P 0 ;0
L 2.72089902 -1.8988 2.74590098 -1.9788 2 P 0 ;0
L 2.73689931 -1.95080118 2.70489882 -1.95080118 2 P 0 ;0
L 2.77889961 -1.8988 2.77889961 -1.9788 2 P 0 ;0
L 2.77889961 -1.9788 2.8189003 -1.9788 2 P 0 ;0
L 2.8969003 -1.9788 2.85689961 -1.9788 2 P 0 ;0
L 2.85689961 -1.9788 2.85689961 -1.8988 2 P 0 ;0
L 2.85689961 -1.8988 2.8969003 -1.8988 2 P 0 ;0
L 2.8809 -1.93746575 2.85689961 -1.93746575 2 P 0 ;0
L 3.03289902 -1.9788 3.03289902 -1.8988 2 P 0 ;0
L 3.03289902 -1.8988 3.0208998 -1.91479911 2 P 0 ;0
L 3.0208998 -1.9788 3.04489833 -1.9788 2 P 0 ;0
L 3.11089902 -1.98146604 3.10889951 -1.98013297 2 P 8191 ;0
L 3.10889951 -1.98013297 3.10889951 -1.97746703 2 P 8191 ;0
L 3.10889951 -1.97746703 3.11089902 -1.97613396 2 P 8191 ;0
L 3.11089902 -1.97613396 3.11290039 -1.97746703 2 P 8191 ;0
L 3.11290039 -1.97746703 3.11290039 -1.98013297 2 P 8191 ;0
L 3.11290039 -1.98013297 3.11089902 -1.98146604 2 P 8191 ;0
L 3.11089902 -1.945469 3.10889951 -1.94413346 2 P 8191 ;0
L 3.10889951 -1.94413346 3.10889951 -1.94146732 2 P 8191 ;0
L 3.10889951 -1.94146732 3.11089902 -1.94013435 2 P 8191 ;0
L 3.11089902 -1.94013435 3.11290039 -1.94146732 2 P 8191 ;0
L 3.11290039 -1.94146732 3.11290039 -1.94413346 2 P 8191 ;0
L 3.11290039 -1.94413346 3.11089902 -1.945469 2 P 8191 ;0
L 3.18889902 -1.9788 3.18889902 -1.8988 2 P 0 ;0
L 3.18889902 -1.8988 3.1768998 -1.91479911 2 P 0 ;0
L 3.1768998 -1.9788 3.20089833 -1.9788 2 P 0 ;0
L 2.5138999 -2.23313563 2.5219 -2.23980089 2 P 0 ;0
L 2.5219 -2.23980089 2.5308999 -2.2438 2 P 0 ;0
L 2.5308999 -2.2438 2.5389 -2.2438 2 P 0 ;0
L 2.5389 -2.2438 2.5469001 -2.23980089 2 P 0 ;0
L 2.5469001 -2.23980089 2.55290069 -2.23313563 2 P 0 ;0
L 2.55290069 -2.23313563 2.5559 -2.22379941 2 P 0 ;0
L 2.5559 -2.22379941 2.55390049 -2.21446811 2 P 0 ;0
L 2.55390049 -2.21446811 2.5488997 -2.20646732 2 P 0 ;0
L 2.5488997 -2.20646732 2.5398998 -2.20113278 2 P 0 ;0
L 2.5398998 -2.20113278 2.52790049 -2.19846663 2 P 0 ;0
L 2.52790049 -2.19846663 2.5209002 -2.19313445 2 P 0 ;0
L 2.5209002 -2.19313445 2.51789902 -2.18380069 2 P 0 ;0
L 2.51789902 -2.18380069 2.51990039 -2.17446683 2 P 0 ;0
L 2.51990039 -2.17446683 2.52489931 -2.16780167 2 P 0 ;0
L 2.52489931 -2.16780167 2.5318997 -2.1638 2 P 0 ;0
L 2.5318997 -2.1638 2.5389 -2.1638 2 P 0 ;0
L 2.5389 -2.1638 2.54590039 -2.16646614 2 P 0 ;0
L 2.54590039 -2.16646614 2.55190089 -2.17313386 2 P 0 ;0
L 2.5918999 -2.2438 2.5918999 -2.1638 2 P 0 ;0
L 2.6339 -2.1638 2.6339 -2.2438 2 P 0 ;0
L 2.6339 -2.20380128 2.5918999 -2.20380128 2 P 0 ;0
L 2.7109003 -2.2438 2.67089961 -2.2438 2 P 0 ;0
L 2.67089961 -2.2438 2.67089961 -2.1638 2 P 0 ;0
L 2.67089961 -2.1638 2.7109003 -2.1638 2 P 0 ;0
L 2.6949 -2.20246575 2.67089961 -2.20246575 2 P 0 ;0
L 2.7889003 -2.2438 2.74889961 -2.2438 2 P 0 ;0
L 2.74889961 -2.2438 2.74889961 -2.1638 2 P 0 ;0
L 2.74889961 -2.1638 2.7889003 -2.1638 2 P 0 ;0
L 2.7729 -2.20246575 2.74889961 -2.20246575 2 P 0 ;0
L 2.84689902 -2.1638 2.84689902 -2.2438 2 P 0 ;0
L 2.8239003 -2.1638 2.86989961 -2.1638 2 P 0 ;0
L 3.29489961 -1.9238 3.29489961 -2.0038 2 P 0 ;0
L 3.29489961 -2.0038 3.3349003 -2.0038 2 P 0 ;0
L 3.36789892 -2.0038 3.39289902 -1.9238 2 P 0 ;0
L 3.39289902 -1.9238 3.41790098 -2.0038 2 P 0 ;0
L 3.40889931 -1.97580118 3.37689882 -1.97580118 2 P 0 ;0
L 3.47089902 -2.0038 3.47089902 -1.96780039 2 P 0 ;0
L 3.47089902 -1.96780039 3.45089961 -1.9238 2 P 0 ;0
L 3.4909003 -1.9238 3.47089902 -1.96780039 2 P 0 ;0
L 3.5689003 -2.0038 3.52889961 -2.0038 2 P 0 ;0
L 3.52889961 -2.0038 3.52889961 -1.9238 2 P 0 ;0
L 3.52889961 -1.9238 3.5689003 -1.9238 2 P 0 ;0
L 3.5529 -1.96246575 3.52889961 -1.96246575 2 P 0 ;0
L 3.60689961 -2.0038 3.60689961 -1.9238 2 P 0 ;0
L 3.60689961 -1.9238 3.6318998 -1.9238 2 P 0 ;0
L 3.6318998 -1.9238 3.6398999 -1.92780167 2 P 0 ;0
L 3.6398999 -1.92780167 3.64490069 -1.93313386 2 P 0 ;0
L 3.64490069 -1.93313386 3.6469003 -1.94380069 2 P 0 ;0
L 3.6469003 -1.94380069 3.64490069 -1.95446752 2 P 0 ;0
L 3.64490069 -1.95446752 3.6389001 -1.96113278 2 P 0 ;0
L 3.6389001 -1.96113278 3.6318998 -1.96513435 2 P 0 ;0
L 3.6318998 -1.96513435 3.60689961 -1.96513435 2 P 0 ;0
L 3.6318998 -1.96513435 3.6469003 -2.0038 2 P 0 ;0
L 3.33989902 -2.2538 3.33189892 -2.25246703 2 P 0 ;0
L 3.33189892 -2.25246703 3.32490039 -2.24713484 2 P 0 ;0
L 3.32490039 -2.24713484 3.3188999 -2.23913406 2 P 0 ;0
L 3.3188999 -2.23913406 3.31489892 -2.2298003 2 P 0 ;0
L 3.31489892 -2.2298003 3.31289931 -2.21913346 2 P 0 ;0
L 3.31289931 -2.21913346 3.31289931 -2.20846663 2 P 0 ;0
L 3.31289931 -2.20846663 3.31489892 -2.1977998 2 P 0 ;0
L 3.31489892 -2.1977998 3.3188999 -2.18846604 2 P 0 ;0
L 3.3188999 -2.18846604 3.32490039 -2.18046772 2 P 0 ;0
L 3.32490039 -2.18046772 3.33189892 -2.17513307 2 P 0 ;0
L 3.33189892 -2.17513307 3.33989902 -2.1738 2 P 0 ;0
L 3.33989902 -2.1738 3.34789911 -2.17513307 2 P 0 ;0
L 3.34789911 -2.17513307 3.35489951 -2.18046772 2 P 0 ;0
L 3.35489951 -2.18046772 3.3609 -2.18846604 2 P 0 ;0
L 3.3609 -2.18846604 3.36490098 -2.1977998 2 P 0 ;0
L 3.36490098 -2.1977998 3.36690059 -2.20846663 2 P 0 ;0
L 3.36690059 -2.20846663 3.36690059 -2.21913346 2 P 0 ;0
L 3.36690059 -2.21913346 3.36490098 -2.2298003 2 P 0 ;0
L 3.36490098 -2.2298003 3.3609 -2.23913406 2 P 0 ;0
L 3.3609 -2.23913406 3.35489951 -2.24713484 2 P 0 ;0
L 3.35489951 -2.24713484 3.34789911 -2.25246703 2 P 0 ;0
L 3.34789911 -2.25246703 3.33989902 -2.2538 2 P 0 ;0
L 3.39889941 -2.2538 3.39889941 -2.1738 2 P 0 ;0
L 3.39889941 -2.1738 3.43690049 -2.1738 2 P 0 ;0
L 3.4228998 -2.21246575 3.39889941 -2.21246575 2 P 0 ;0
L 0.16489872 -1.0538 0.16489872 -1.1538 2 P 0 ;0
L 0.13423376 -1.0538 0.19556614 -1.0538 2 P 0 ;0
L 0.2588997 -1.0538 0.29089774 -1.0538 2 P 0 ;0
L 0.27489872 -1.0538 0.27489872 -1.1538 2 P 0 ;0
L 0.2588997 -1.1538 0.29089774 -1.1538 2 P 0 ;0
L 0.38489872 -1.0538 0.38489872 -1.1538 2 P 0 ;0
L 0.35423376 -1.0538 0.41556614 -1.0538 2 P 0 ;0
L 0.46823287 -1.0538 0.46823287 -1.1538 2 P 0 ;0
L 0.46823287 -1.1538 0.52156703 -1.1538 2 P 0 ;0
L 0.63156703 -1.1538 0.57823287 -1.1538 2 P 0 ;0
L 0.57823287 -1.1538 0.57823287 -1.0538 2 P 0 ;0
L 0.57823287 -1.0538 0.63156703 -1.0538 2 P 0 ;0
L 0.61023337 -1.10213219 0.57823287 -1.10213219 2 P 0 ;0
L 4.18989892 -1.9538 4.21489902 -1.8738 2 P 0 ;0
L 4.21489902 -1.8738 4.23990098 -1.9538 2 P 0 ;0
L 4.23089931 -1.92580118 4.19889882 -1.92580118 2 P 0 ;0
L 4.27289961 -1.9538 4.27289961 -1.8738 2 P 0 ;0
L 4.27289961 -1.8738 4.2978998 -1.8738 2 P 0 ;0
L 4.2978998 -1.8738 4.3058999 -1.87780167 2 P 0 ;0
L 4.3058999 -1.87780167 4.31090069 -1.88313386 2 P 0 ;0
L 4.31090069 -1.88313386 4.3129003 -1.89380069 2 P 0 ;0
L 4.3129003 -1.89380069 4.31090069 -1.90446752 2 P 0 ;0
L 4.31090069 -1.90446752 4.3049001 -1.91113278 2 P 0 ;0
L 4.3049001 -1.91113278 4.2978998 -1.91513435 2 P 0 ;0
L 4.2978998 -1.91513435 4.27289961 -1.91513435 2 P 0 ;0
L 4.2978998 -1.91513435 4.3129003 -1.9538 2 P 0 ;0
L 4.37089902 -1.8738 4.37089902 -1.9538 2 P 0 ;0
L 4.3479003 -1.8738 4.39389961 -1.8738 2 P 0 ;0
L 3.61989892 -2.2538 3.61989892 -2.1638 2 P 0 ;0
L 3.61989892 -2.1638 3.6058997 -2.18179892 2 P 0 ;0
L 3.6058997 -2.2538 3.63389803 -2.2538 2 P 0 ;0
L 3.68773268 -2.17879961 3.69473337 -2.16980148 2 P 0 ;0
L 3.69473337 -2.16980148 3.70290039 -2.1652997 2 P 0 ;0
L 3.70290039 -2.1652997 3.71223386 -2.1638 2 P 0 ;0
L 3.71223386 -2.1638 3.7239002 -2.16679941 2 P 0 ;0
L 3.7239002 -2.16679941 3.73206722 -2.17430059 2 P 0 ;0
L 3.73206722 -2.17430059 3.7344001 -2.18329862 2 P 0 ;0
L 3.7344001 -2.18329862 3.73323366 -2.19230217 2 P 0 ;0
L 3.73323366 -2.19230217 3.72856585 -2.19980059 2 P 0 ;0
L 3.72856585 -2.19980059 3.70523317 -2.2148001 2 P 0 ;0
L 3.70523317 -2.2148001 3.69473337 -2.22530069 2 P 0 ;0
L 3.69473337 -2.22530069 3.68773268 -2.24030295 2 P 0 ;0
L 3.68773268 -2.24030295 3.6853998 -2.2538 2 P 0 ;0
L 3.6853998 -2.2538 3.7344001 -2.2538 2 P 0 ;0
L 0.5058997 -1.6638 0.53389803 -1.6638 2 P 0 ;0
L 0.51989892 -1.6638 0.51989892 -1.7538 2 P 0 ;0
L 0.5058997 -1.7538 0.53389803 -1.7538 2 P 0 ;0
L 0.58306703 -1.7538 0.58306703 -1.6638 2 P 0 ;0
L 0.58306703 -1.6638 0.63673287 -1.7538 2 P 0 ;0
L 0.63673287 -1.7538 0.63673287 -1.6638 2 P 0 ;0
L 0.69989892 -1.6638 0.69989892 -1.7538 2 P 0 ;0
L 0.67306703 -1.6638 0.72673287 -1.6638 2 P 0 ;0
L 0.81323366 -1.7538 0.76656624 -1.7538 2 P 0 ;0
L 0.76656624 -1.7538 0.76656624 -1.6638 2 P 0 ;0
L 0.76656624 -1.6638 0.81323366 -1.6638 2 P 0 ;0
L 0.79456673 -1.70729902 0.76656624 -1.70729902 2 P 0 ;0
L 0.85656624 -1.7538 0.85656624 -1.6638 2 P 0 ;0
L 0.85656624 -1.6638 0.88573307 -1.6638 2 P 0 ;0
L 0.88573307 -1.6638 0.89506654 -1.66830187 2 P 0 ;0
L 0.89506654 -1.66830187 0.90090079 -1.67430059 2 P 0 ;0
L 0.90090079 -1.67430059 0.90323366 -1.68630069 2 P 0 ;0
L 0.90323366 -1.68630069 0.90090079 -1.69830089 2 P 0 ;0
L 0.90090079 -1.69830089 0.8939002 -1.70579931 2 P 0 ;0
L 0.8939002 -1.70579931 0.88573307 -1.71030108 2 P 0 ;0
L 0.88573307 -1.71030108 0.85656624 -1.71030108 2 P 0 ;0
L 0.88573307 -1.71030108 0.90323366 -1.7538 2 P 0 ;0
L 0.94306703 -1.7538 0.94306703 -1.6638 2 P 0 ;0
L 0.94306703 -1.6638 0.99673287 -1.7538 2 P 0 ;0
L 0.99673287 -1.7538 0.99673287 -1.6638 2 P 0 ;0
L 1.03073209 -1.7538 1.05989892 -1.6638 2 P 0 ;0
L 1.05989892 -1.6638 1.08906782 -1.7538 2 P 0 ;0
L 1.07856585 -1.72230128 1.04123189 -1.72230128 2 P 0 ;0
L 1.12656624 -1.6638 1.12656624 -1.7538 2 P 0 ;0
L 1.12656624 -1.7538 1.17323366 -1.7538 2 P 0 ;0
L 1.30656624 -1.6638 1.30656624 -1.7538 2 P 0 ;0
L 1.30656624 -1.7538 1.35323366 -1.7538 2 P 0 ;0
L 1.39073209 -1.7538 1.41989892 -1.6638 2 P 0 ;0
L 1.41989892 -1.6638 1.44906782 -1.7538 2 P 0 ;0
L 1.43856585 -1.72230128 1.40123189 -1.72230128 2 P 0 ;0
L 1.50989892 -1.7538 1.50989892 -1.71330049 2 P 0 ;0
L 1.50989892 -1.71330049 1.48656624 -1.6638 2 P 0 ;0
L 1.53323366 -1.6638 1.50989892 -1.71330049 2 P 0 ;0
L 1.62323366 -1.7538 1.57656624 -1.7538 2 P 0 ;0
L 1.57656624 -1.7538 1.57656624 -1.6638 2 P 0 ;0
L 1.57656624 -1.6638 1.62323366 -1.6638 2 P 0 ;0
L 1.60456673 -1.70729902 1.57656624 -1.70729902 2 P 0 ;0
L 1.66656624 -1.7538 1.66656624 -1.6638 2 P 0 ;0
L 1.66656624 -1.6638 1.69573307 -1.6638 2 P 0 ;0
L 1.69573307 -1.6638 1.70506654 -1.66830187 2 P 0 ;0
L 1.70506654 -1.66830187 1.71090079 -1.67430059 2 P 0 ;0
L 1.71090079 -1.67430059 1.71323366 -1.68630069 2 P 0 ;0
L 1.71323366 -1.68630069 1.71090079 -1.69830089 2 P 0 ;0
L 1.71090079 -1.69830089 1.7039002 -1.70579931 2 P 0 ;0
L 1.7039002 -1.70579931 1.69573307 -1.71030108 2 P 0 ;0
L 1.69573307 -1.71030108 1.66656624 -1.71030108 2 P 0 ;0
L 1.69573307 -1.71030108 1.71323366 -1.7538 2 P 0 ;0
L 1.84773268 -1.67879961 1.85473337 -1.66980148 2 P 0 ;0
L 1.85473337 -1.66980148 1.86290039 -1.6652997 2 P 0 ;0
L 1.86290039 -1.6652997 1.87223386 -1.6638 2 P 0 ;0
L 1.87223386 -1.6638 1.8839002 -1.66679941 2 P 0 ;0
L 1.8839002 -1.66679941 1.89206722 -1.67430059 2 P 0 ;0
L 1.89206722 -1.67430059 1.8944001 -1.68329862 2 P 0 ;0
L 1.8944001 -1.68329862 1.89323366 -1.69230217 2 P 0 ;0
L 1.89323366 -1.69230217 1.88856585 -1.69980059 2 P 0 ;0
L 1.88856585 -1.69980059 1.86523317 -1.7148001 2 P 0 ;0
L 1.86523317 -1.7148001 1.85473337 -1.72530069 2 P 0 ;0
L 1.85473337 -1.72530069 1.84773268 -1.74030295 2 P 0 ;0
L 1.84773268 -1.74030295 1.8453998 -1.7538 2 P 0 ;0
L 1.8453998 -1.7538 1.8944001 -1.7538 2 P 0 ;0
L 3.79773268 -1.92879961 3.80473337 -1.91980148 2 P 0 ;0
L 3.80473337 -1.91980148 3.81290039 -1.9152997 2 P 0 ;0
L 3.81290039 -1.9152997 3.82223386 -1.9138 2 P 0 ;0
L 3.82223386 -1.9138 3.8339002 -1.91679941 2 P 0 ;0
L 3.8339002 -1.91679941 3.84206722 -1.92430059 2 P 0 ;0
L 3.84206722 -1.92430059 3.8444001 -1.93329862 2 P 0 ;0
L 3.8444001 -1.93329862 3.84323366 -1.94230217 2 P 0 ;0
L 3.84323366 -1.94230217 3.83856585 -1.94980059 2 P 0 ;0
L 3.83856585 -1.94980059 3.81523317 -1.9648001 2 P 0 ;0
L 3.81523317 -1.9648001 3.80473337 -1.97530069 2 P 0 ;0
L 3.80473337 -1.97530069 3.79773268 -1.99030295 2 P 0 ;0
L 3.79773268 -1.99030295 3.7953998 -2.0038 2 P 0 ;0
L 3.7953998 -2.0038 3.8444001 -2.0038 2 P 0 ;0
L 3.04773268 -2.17879961 3.05473337 -2.16980148 2 P 0 ;0
L 3.05473337 -2.16980148 3.06290039 -2.1652997 2 P 0 ;0
L 3.06290039 -2.1652997 3.07223386 -2.1638 2 P 0 ;0
L 3.07223386 -2.1638 3.0839002 -2.16679941 2 P 0 ;0
L 3.0839002 -2.16679941 3.09206722 -2.17430059 2 P 0 ;0
L 3.09206722 -2.17430059 3.0944001 -2.18329862 2 P 0 ;0
L 3.0944001 -2.18329862 3.09323366 -2.19230217 2 P 0 ;0
L 3.09323366 -2.19230217 3.08856585 -2.19980059 2 P 0 ;0
L 3.08856585 -2.19980059 3.06523317 -2.2148001 2 P 0 ;0
L 3.06523317 -2.2148001 3.05473337 -2.22530069 2 P 0 ;0
L 3.05473337 -2.22530069 3.04773268 -2.24030295 2 P 0 ;0
L 3.04773268 -2.24030295 3.0453998 -2.2538 2 P 0 ;0
L 3.0453998 -2.2538 3.0944001 -2.2538 2 P 0 ;0
L 0.59099833 -1.36499882 0.5990003 -1.35750039 2 P 0 ;0
L 0.5990003 -1.35750039 0.60499902 -1.34500315 2 P 0 ;0
L 0.60499902 -1.34500315 0.60900187 -1.32749764 2 P 0 ;0
L 0.60900187 -1.32749764 0.60499902 -1.31250089 2 P 0 ;0
L 0.60499902 -1.31250089 0.59700079 -1.30250305 2 P 0 ;0
L 0.59700079 -1.30250305 0.5830001 -1.295 2 P 0 ;0
L 0.5830001 -1.295 0.52900059 -1.295 2 P 0 ;0
L 0.52900059 -1.295 0.52900059 -1.445 2 P 0 ;0
L 0.52900059 -1.445 0.59500118 -1.445 2 P 0 ;0
L 0.59500118 -1.445 0.60900187 -1.43500217 2 P 0 ;0
L 0.60900187 -1.43500217 0.6170001 -1.42000079 2 P 0 ;0
L 0.6170001 -1.42000079 0.62099931 -1.4025 2 P 0 ;0
L 0.62099931 -1.4025 0.6170001 -1.38500374 2 P 0 ;0
L 0.6170001 -1.38500374 0.60499902 -1.37000236 2 P 0 ;0
L 0.60499902 -1.37000236 0.59099833 -1.36499882 2 P 0 ;0
L 0.59099833 -1.36499882 0.52900059 -1.36499882 2 P 0 ;0
L 0.77100138 -1.445 0.77100138 -1.34500315 2 P 0 ;0
L 0.77100138 -1.36249941 0.76299951 -1.35250148 2 P 0 ;0
L 0.76299951 -1.35250148 0.75099833 -1.34750256 2 P 0 ;0
L 0.75099833 -1.34750256 0.73700138 -1.34500315 2 P 0 ;0
L 0.73700138 -1.34500315 0.72300069 -1.35000207 2 P 0 ;0
L 0.72300069 -1.35000207 0.71099961 -1.3599999 2 P 0 ;0
L 0.71099961 -1.3599999 0.70299764 -1.37500128 2 P 0 ;0
L 0.70299764 -1.37500128 0.69899852 -1.39500157 2 P 0 ;0
L 0.69899852 -1.39500157 0.70299764 -1.41500187 2 P 0 ;0
L 0.70299764 -1.41500187 0.71099961 -1.43000325 2 P 0 ;0
L 0.71099961 -1.43000325 0.72300069 -1.44000108 2 P 0 ;0
L 0.72300069 -1.44000108 0.73700138 -1.445 2 P 0 ;0
L 0.73700138 -1.445 0.75099833 -1.44250059 2 P 0 ;0
L 0.75099833 -1.44250059 0.76299951 -1.43500217 2 P 0 ;0
L 0.76299951 -1.43500217 0.77100138 -1.42500433 2 P 0 ;0
L 0.86700039 -1.445 0.86700039 -1.34500315 2 P 0 ;0
L 0.86700039 -1.36499882 0.87699833 -1.35500098 2 P 0 ;0
L 0.87699833 -1.35500098 0.8869998 -1.34750256 2 P 0 ;0
L 0.8869998 -1.34750256 0.90100049 -1.34500315 2 P 0 ;0
L 0.90100049 -1.34500315 0.91099833 -1.34750256 2 P 0 ;0
L 0.91099833 -1.34750256 0.92299951 -1.35500098 2 P 0 ;0
L 1.02700039 -1.445 1.02700039 -1.34500315 2 P 0 ;0
L 1.02700039 -1.36499882 1.03699833 -1.35500098 2 P 0 ;0
L 1.03699833 -1.35500098 1.0469998 -1.34750256 2 P 0 ;0
L 1.0469998 -1.34750256 1.06100049 -1.34500315 2 P 0 ;0
L 1.06100049 -1.34500315 1.07099833 -1.34750256 2 P 0 ;0
L 1.07099833 -1.34750256 1.08299951 -1.35500098 2 P 0 ;0
L 1.18500089 -1.37750069 1.24900187 -1.37750069 2 P 0 ;0
L 1.24900187 -1.37750069 1.24299951 -1.3599999 2 P 0 ;0
L 1.24299951 -1.3599999 1.23300157 -1.35000207 2 P 0 ;0
L 1.23300157 -1.35000207 1.21900089 -1.34500315 2 P 0 ;0
L 1.21900089 -1.34500315 1.2050003 -1.34750256 2 P 0 ;0
L 1.2050003 -1.34750256 1.19299911 -1.35500098 2 P 0 ;0
L 1.19299911 -1.35500098 1.18500089 -1.37250177 2 P 0 ;0
L 1.18500089 -1.37250177 1.18099803 -1.38750315 2 P 0 ;0
L 1.18099803 -1.38750315 1.18099803 -1.4025 2 P 0 ;0
L 1.18099803 -1.4025 1.18500089 -1.41750138 2 P 0 ;0
L 1.18500089 -1.41750138 1.19499872 -1.43250276 2 P 0 ;0
L 1.19499872 -1.43250276 1.2069998 -1.44250059 2 P 0 ;0
L 1.2069998 -1.44250059 1.22100049 -1.445 2 P 0 ;0
L 1.22100049 -1.445 1.23500118 -1.44000108 2 P 0 ;0
L 1.23500118 -1.44000108 1.24900187 -1.42500433 2 P 0 ;0
L 1.37499813 -1.445 1.37499813 -1.295 2 P 0 ;0
L 1.50500089 -1.37750069 1.56900187 -1.37750069 2 P 0 ;0
L 1.56900187 -1.37750069 1.56299951 -1.3599999 2 P 0 ;0
L 1.56299951 -1.3599999 1.55300157 -1.35000207 2 P 0 ;0
L 1.55300157 -1.35000207 1.53900089 -1.34500315 2 P 0 ;0
L 1.53900089 -1.34500315 1.5250003 -1.34750256 2 P 0 ;0
L 1.5250003 -1.34750256 1.51299911 -1.35500098 2 P 0 ;0
L 1.51299911 -1.35500098 1.50500089 -1.37250177 2 P 0 ;0
L 1.50500089 -1.37250177 1.50099803 -1.38750315 2 P 0 ;0
L 1.50099803 -1.38750315 1.50099803 -1.4025 2 P 0 ;0
L 1.50099803 -1.4025 1.50500089 -1.41750138 2 P 0 ;0
L 1.50500089 -1.41750138 1.51499872 -1.43250276 2 P 0 ;0
L 1.51499872 -1.43250276 1.5269998 -1.44250059 2 P 0 ;0
L 1.5269998 -1.44250059 1.54100049 -1.445 2 P 0 ;0
L 1.54100049 -1.445 1.55500118 -1.44000108 2 P 0 ;0
L 1.55500118 -1.44000108 1.56900187 -1.42500433 2 P 0 ;0
L 1.6529998 -1.48999951 1.66500089 -1.49499843 2 P 0 ;0
L 1.66500089 -1.49499843 1.68100108 -1.48999951 2 P 0 ;0
L 1.68100108 -1.48999951 1.69099902 -1.48000167 2 P 0 ;0
L 1.69099902 -1.48000167 1.69900089 -1.4674997 2 P 0 ;0
L 1.69900089 -1.4674997 1.71099833 -1.42750374 2 P 0 ;0
L 1.71099833 -1.42750374 1.7370001 -1.34500315 2 P 0 ;0
L 1.67299911 -1.34500315 1.71099833 -1.42750374 2 P 0 ;0
L 1.82500089 -1.37750069 1.88900187 -1.37750069 2 P 0 ;0
L 1.88900187 -1.37750069 1.88299951 -1.3599999 2 P 0 ;0
L 1.88299951 -1.3599999 1.87300157 -1.35000207 2 P 0 ;0
L 1.87300157 -1.35000207 1.85900089 -1.34500315 2 P 0 ;0
L 1.85900089 -1.34500315 1.8450003 -1.34750256 2 P 0 ;0
L 1.8450003 -1.34750256 1.83299911 -1.35500098 2 P 0 ;0
L 1.83299911 -1.35500098 1.82500089 -1.37250177 2 P 0 ;0
L 1.82500089 -1.37250177 1.82099803 -1.38750315 2 P 0 ;0
L 1.82099803 -1.38750315 1.82099803 -1.4025 2 P 0 ;0
L 1.82099803 -1.4025 1.82500089 -1.41750138 2 P 0 ;0
L 1.82500089 -1.41750138 1.83499872 -1.43250276 2 P 0 ;0
L 1.83499872 -1.43250276 1.8469998 -1.44250059 2 P 0 ;0
L 1.8469998 -1.44250059 1.86100049 -1.445 2 P 0 ;0
L 1.86100049 -1.445 1.87500118 -1.44000108 2 P 0 ;0
L 1.87500118 -1.44000108 1.88900187 -1.42500433 2 P 0 ;0
L 2.18699921 -1.37000236 2.22700167 -1.37000236 2 P 0 ;0
L 2.22700167 -1.37000236 2.22700167 -1.41500187 2 P 0 ;0
L 2.22700167 -1.41500187 2.21500059 -1.43000325 2 P 0 ;0
L 2.21500059 -1.43000325 2.2009999 -1.44000108 2 P 0 ;0
L 2.2009999 -1.44000108 2.18100049 -1.445 2 P 0 ;0
L 2.18100049 -1.445 2.16100108 -1.44000108 2 P 0 ;0
L 2.16100108 -1.44000108 2.14700039 -1.43000325 2 P 0 ;0
L 2.14700039 -1.43000325 2.13499931 -1.41500187 2 P 0 ;0
L 2.13499931 -1.41500187 2.12699734 -1.39750108 2 P 0 ;0
L 2.12699734 -1.39750108 2.12299823 -1.37750069 2 P 0 ;0
L 2.12299823 -1.37750069 2.12299823 -1.3599999 2 P 0 ;0
L 2.12299823 -1.3599999 2.12699734 -1.34500315 2 P 0 ;0
L 2.12699734 -1.34500315 2.13499931 -1.32749764 2 P 0 ;0
L 2.13499931 -1.32749764 2.14700039 -1.31250089 2 P 0 ;0
L 2.14700039 -1.31250089 2.15899783 -1.30250305 2 P 0 ;0
L 2.15899783 -1.30250305 2.17499813 -1.295 2 P 0 ;0
L 2.17499813 -1.295 2.18899882 -1.295 2 P 0 ;0
L 2.18899882 -1.295 2.20499902 -1.29999902 2 P 0 ;0
L 2.20499902 -1.29999902 2.2170001 -1.31000138 2 P 0 ;0
L 2.29699892 -1.31999931 2.309 -1.30500246 2 P 0 ;0
L 2.309 -1.30500246 2.32300069 -1.29749951 2 P 0 ;0
L 2.32300069 -1.29749951 2.33900089 -1.295 2 P 0 ;0
L 2.33900089 -1.295 2.3590003 -1.29999902 2 P 0 ;0
L 2.3590003 -1.29999902 2.37300098 -1.31250089 2 P 0 ;0
L 2.37300098 -1.31250089 2.3770001 -1.32749764 2 P 0 ;0
L 2.3770001 -1.32749764 2.37500059 -1.34250364 2 P 0 ;0
L 2.37500059 -1.34250364 2.36699862 -1.35500098 2 P 0 ;0
L 2.36699862 -1.35500098 2.3269998 -1.3800002 2 P 0 ;0
L 2.3269998 -1.3800002 2.309 -1.39750108 2 P 0 ;0
L 2.309 -1.39750108 2.29699892 -1.42250482 2 P 0 ;0
L 2.29699892 -1.42250482 2.2929998 -1.445 2 P 0 ;0
L 2.2929998 -1.445 2.3770001 -1.445 2 P 0 ;0
L 2.6129998 -1.42500433 2.629 -1.43750167 2 P 0 ;0
L 2.629 -1.43750167 2.6469998 -1.445 2 P 0 ;0
L 2.6469998 -1.445 2.6630001 -1.445 2 P 0 ;0
L 2.6630001 -1.445 2.6790003 -1.43750167 2 P 0 ;0
L 2.6790003 -1.43750167 2.69100138 -1.42500433 2 P 0 ;0
L 2.69100138 -1.42500433 2.6970001 -1.40749892 2 P 0 ;0
L 2.6970001 -1.40749892 2.69300098 -1.39000266 2 P 0 ;0
L 2.69300098 -1.39000266 2.68299951 -1.37500128 2 P 0 ;0
L 2.68299951 -1.37500128 2.66499961 -1.36499882 2 P 0 ;0
L 2.66499961 -1.36499882 2.64100108 -1.3599999 2 P 0 ;0
L 2.64100108 -1.3599999 2.62700039 -1.35000207 2 P 0 ;0
L 2.62700039 -1.35000207 2.62099803 -1.33250118 2 P 0 ;0
L 2.62099803 -1.33250118 2.62500089 -1.31500039 2 P 0 ;0
L 2.62500089 -1.31500039 2.63499872 -1.30250305 2 P 0 ;0
L 2.63499872 -1.30250305 2.64899941 -1.295 2 P 0 ;0
L 2.64899941 -1.295 2.6630001 -1.295 2 P 0 ;0
L 2.6630001 -1.295 2.67700079 -1.29999902 2 P 0 ;0
L 2.67700079 -1.29999902 2.68900187 -1.31250089 2 P 0 ;0
L 2.7729998 -1.445 2.8570001 -1.295 2 P 0 ;0
L 2.7729998 -1.295 2.8570001 -1.445 2 P 0 ;0
L 2.92299823 -1.445 2.92299823 -1.295 2 P 0 ;0
L 2.92299823 -1.295 2.97499813 -1.42000079 2 P 0 ;0
L 2.97499813 -1.42000079 3.02700167 -1.295 2 P 0 ;0
L 3.02700167 -1.295 3.02700167 -1.445 2 P 0 ;0
L 3.09699892 -1.31999931 3.109 -1.30500246 2 P 0 ;0
L 3.109 -1.30500246 3.12300069 -1.29749951 2 P 0 ;0
L 3.12300069 -1.29749951 3.13900089 -1.295 2 P 0 ;0
L 3.13900089 -1.295 3.1590003 -1.29999902 2 P 0 ;0
L 3.1590003 -1.29999902 3.17300098 -1.31250089 2 P 0 ;0
L 3.17300098 -1.31250089 3.1770001 -1.32749764 2 P 0 ;0
L 3.1770001 -1.32749764 3.17500059 -1.34250364 2 P 0 ;0
L 3.17500059 -1.34250364 3.16699862 -1.35500098 2 P 0 ;0
L 3.16699862 -1.35500098 3.1269998 -1.3800002 2 P 0 ;0
L 3.1269998 -1.3800002 3.109 -1.39750108 2 P 0 ;0
L 3.109 -1.39750108 3.09699892 -1.42250482 2 P 0 ;0
L 3.09699892 -1.42250482 3.0929998 -1.445 2 P 0 ;0
L 3.0929998 -1.445 3.1770001 -1.445 2 P 0 ;0
L 3.269 -1.39500157 3.3209999 -1.39500157 2 P 0 ;0
L 3.41499931 -1.445 3.41499931 -1.295 2 P 0 ;0
L 3.41499931 -1.295 3.46499961 -1.295 2 P 0 ;0
L 3.46499961 -1.295 3.4809999 -1.30250305 2 P 0 ;0
L 3.4809999 -1.30250305 3.49100138 -1.31250089 2 P 0 ;0
L 3.49100138 -1.31250089 3.49500059 -1.33250118 2 P 0 ;0
L 3.49500059 -1.33250118 3.49100138 -1.35250148 2 P 0 ;0
L 3.49100138 -1.35250148 3.4790003 -1.36499882 2 P 0 ;0
L 3.4790003 -1.36499882 3.46499961 -1.37250177 2 P 0 ;0
L 3.46499961 -1.37250177 3.41499931 -1.37250177 2 P 0 ;0
L 3.46499961 -1.37250177 3.49500059 -1.445 2 P 0 ;0
L 3.61499813 -1.34500315 3.61499813 -1.445 2 P 0 ;0
L 3.61499813 -1.30500246 3.61099902 -1.30250305 2 P 8191 ;0
L 3.61099902 -1.30250305 3.61099902 -1.29749951 2 P 8191 ;0
L 3.61099902 -1.29749951 3.61499813 -1.295 2 P 8191 ;0
L 3.61499813 -1.295 3.61900089 -1.29749951 2 P 8191 ;0
L 3.61900089 -1.29749951 3.61900089 -1.30250305 2 P 8191 ;0
L 3.61900089 -1.30250305 3.61499813 -1.30500246 2 P 8191 ;0
L 3.74500089 -1.42750374 3.75499872 -1.43750167 2 P 0 ;0
L 3.75499872 -1.43750167 3.76899941 -1.445 2 P 0 ;0
L 3.76899941 -1.445 3.78100049 -1.445 2 P 0 ;0
L 3.78100049 -1.445 3.79300157 -1.44000108 2 P 0 ;0
L 3.79300157 -1.44000108 3.8009999 -1.43250276 2 P 0 ;0
L 3.8009999 -1.43250276 3.80499902 -1.42250482 2 P 0 ;0
L 3.80499902 -1.42250482 3.80299951 -1.40749892 2 P 0 ;0
L 3.80299951 -1.40749892 3.79500118 -1.40000049 2 P 0 ;0
L 3.79500118 -1.40000049 3.75899783 -1.38500374 2 P 0 ;0
L 3.75899783 -1.38500374 3.75099961 -1.36749833 2 P 0 ;0
L 3.75099961 -1.36749833 3.75499872 -1.35500098 2 P 0 ;0
L 3.75499872 -1.35500098 3.76300069 -1.34750256 2 P 0 ;0
L 3.76300069 -1.34750256 3.77499813 -1.34500315 2 P 0 ;0
L 3.77499813 -1.34500315 3.78699921 -1.34750256 2 P 0 ;0
L 3.78699921 -1.34750256 3.7990003 -1.35500098 2 P 0 ;0
L 3.90500089 -1.37750069 3.96900187 -1.37750069 2 P 0 ;0
L 3.96900187 -1.37750069 3.96299951 -1.3599999 2 P 0 ;0
L 3.96299951 -1.3599999 3.95300157 -1.35000207 2 P 0 ;0
L 3.95300157 -1.35000207 3.93900089 -1.34500315 2 P 0 ;0
L 3.93900089 -1.34500315 3.9250003 -1.34750256 2 P 0 ;0
L 3.9250003 -1.34750256 3.91299911 -1.35500098 2 P 0 ;0
L 3.91299911 -1.35500098 3.90500089 -1.37250177 2 P 0 ;0
L 3.90500089 -1.37250177 3.90099803 -1.38750315 2 P 0 ;0
L 3.90099803 -1.38750315 3.90099803 -1.4025 2 P 0 ;0
L 3.90099803 -1.4025 3.90500089 -1.41750138 2 P 0 ;0
L 3.90500089 -1.41750138 3.91499872 -1.43250276 2 P 0 ;0
L 3.91499872 -1.43250276 3.9269998 -1.44250059 2 P 0 ;0
L 3.9269998 -1.44250059 3.94100049 -1.445 2 P 0 ;0
L 3.94100049 -1.445 3.95500118 -1.44000108 2 P 0 ;0
L 3.95500118 -1.44000108 3.96900187 -1.42500433 2 P 0 ;0
L 4.06700039 -1.445 4.06700039 -1.34500315 2 P 0 ;0
L 4.06700039 -1.36499882 4.07699833 -1.35500098 2 P 0 ;0
L 4.07699833 -1.35500098 4.0869998 -1.34750256 2 P 0 ;0
L 4.0869998 -1.34750256 4.10100049 -1.34500315 2 P 0 ;0
L 4.10100049 -1.34500315 4.11099833 -1.34750256 2 P 0 ;0
L 4.11099833 -1.34750256 4.12299951 -1.35500098 2 P 0 ;0
L 4.16964783 -2.2038 4.21839813 -2.0478 2 P 0 ;0
L 4.21839813 -2.0478 4.26715207 -2.2038 2 P 0 ;0
L 4.24959862 -2.14920217 4.18719774 -2.14920217 2 P 0 ;0
L 4.37939813 -2.2038 4.37939813 -2.0478 2 P 0 ;0
L 4.37939813 -2.0478 4.35599961 -2.07899813 2 P 0 ;0
L 4.35599961 -2.2038 4.40279675 -2.2038 2 P 0 ;0
L 2.0009002 -0.9538 2.0009002 -0.8038 2 P 0 ;0
L 2.0009002 -0.8038 2.04089902 -0.8038 2 P 0 ;0
L 2.04089902 -0.8038 2.05689921 -0.81130305 2 P 0 ;0
L 2.05689921 -0.81130305 2.0689003 -0.82130089 2 P 0 ;0
L 2.0689003 -0.82130089 2.07890187 -0.83629764 2 P 0 ;0
L 2.07890187 -0.83629764 2.0869001 -0.85380315 2 P 0 ;0
L 2.0869001 -0.85380315 2.0888997 -0.87880236 2 P 0 ;0
L 2.0888997 -0.87880236 2.0869001 -0.90380157 2 P 0 ;0
L 2.0869001 -0.90380157 2.07890187 -0.92130246 2 P 0 ;0
L 2.07890187 -0.92130246 2.0689003 -0.93630374 2 P 0 ;0
L 2.0689003 -0.93630374 2.05689921 -0.94630167 2 P 0 ;0
L 2.05689921 -0.94630167 2.04089902 -0.9538 2 P 0 ;0
L 2.04089902 -0.9538 2.0009002 -0.9538 2 P 0 ;0
L 2.15489783 -0.9538 2.20489813 -0.8038 2 P 0 ;0
L 2.20489813 -0.8038 2.25490207 -0.9538 2 P 0 ;0
L 2.23689862 -0.90130207 2.17289764 -0.90130207 2 P 0 ;0
L 2.36489813 -0.8038 2.36489813 -0.9538 2 P 0 ;0
L 2.31890059 -0.8038 2.41089931 -0.8038 2 P 0 ;0
L 2.56490059 -0.9538 2.48489931 -0.9538 2 P 0 ;0
L 2.48489931 -0.9538 2.48489931 -0.8038 2 P 0 ;0
L 2.48489931 -0.8038 2.56490059 -0.8038 2 P 0 ;0
L 2.5329001 -0.87629833 2.48489931 -0.87629833 2 P 0 ;0
L 2.84489813 -0.9538 2.82889783 -0.95130059 2 P 0 ;0
L 2.82889783 -0.95130059 2.81490089 -0.94130276 2 P 0 ;0
L 2.81490089 -0.94130276 2.8028998 -0.92630138 2 P 0 ;0
L 2.8028998 -0.92630138 2.79489783 -0.90880049 2 P 0 ;0
L 2.79489783 -0.90880049 2.79089862 -0.8888002 2 P 0 ;0
L 2.79089862 -0.8888002 2.79089862 -0.8687999 2 P 0 ;0
L 2.79089862 -0.8687999 2.79489783 -0.84879961 2 P 0 ;0
L 2.79489783 -0.84879961 2.8028998 -0.83129872 2 P 0 ;0
L 2.8028998 -0.83129872 2.81490089 -0.81630197 2 P 0 ;0
L 2.81490089 -0.81630197 2.82889783 -0.80629951 2 P 0 ;0
L 2.82889783 -0.80629951 2.84489813 -0.8038 2 P 0 ;0
L 2.84489813 -0.8038 2.86089833 -0.80629951 2 P 0 ;0
L 2.86089833 -0.80629951 2.87489902 -0.81630197 2 P 0 ;0
L 2.87489902 -0.81630197 2.8869001 -0.83129872 2 P 0 ;0
L 2.8869001 -0.83129872 2.89490207 -0.84879961 2 P 0 ;0
L 2.89490207 -0.84879961 2.89890128 -0.8687999 2 P 0 ;0
L 2.89890128 -0.8687999 2.89890128 -0.8888002 2 P 0 ;0
L 2.89890128 -0.8888002 2.89490207 -0.90880049 2 P 0 ;0
L 2.89490207 -0.90880049 2.8869001 -0.92630138 2 P 0 ;0
L 2.8869001 -0.92630138 2.87489902 -0.94130276 2 P 0 ;0
L 2.87489902 -0.94130276 2.86089833 -0.95130059 2 P 0 ;0
L 2.86089833 -0.95130059 2.84489813 -0.9538 2 P 0 ;0
L 3.0488997 -0.81630197 3.03689862 -0.80879902 2 P 0 ;0
L 3.03689862 -0.80879902 3.02290157 -0.8038 2 P 0 ;0
L 3.02290157 -0.8038 3.00690138 -0.8038 2 P 0 ;0
L 3.00690138 -0.8038 2.98889783 -0.81130305 2 P 0 ;0
L 2.98889783 -0.81130305 2.97490089 -0.82380039 2 P 0 ;0
L 2.97490089 -0.82380039 2.96489931 -0.83880177 2 P 0 ;0
L 2.96489931 -0.83880177 2.95689734 -0.86380098 2 P 0 ;0
L 2.95689734 -0.86380098 2.95489783 -0.88630069 2 P 0 ;0
L 2.95489783 -0.88630069 2.95890059 -0.90880049 2 P 0 ;0
L 2.95890059 -0.90880049 2.96489931 -0.92380187 2 P 0 ;0
L 2.96489931 -0.92380187 2.97690039 -0.93880325 2 P 0 ;0
L 2.97690039 -0.93880325 2.99090108 -0.94880108 2 P 0 ;0
L 2.99090108 -0.94880108 3.00489813 -0.9538 2 P 0 ;0
L 3.00489813 -0.9538 3.01889882 -0.9538 2 P 0 ;0
L 3.01889882 -0.9538 3.03289951 -0.94880108 2 P 0 ;0
L 3.03289951 -0.94880108 3.04490059 -0.94130276 2 P 0 ;0
L 3.04490059 -0.94130276 3.05490207 -0.93130482 2 P 0 ;0
L 3.16489813 -0.8038 3.16489813 -0.9538 2 P 0 ;0
L 3.11890059 -0.8038 3.21089931 -0.8038 2 P 0 ;0
L 3.28889852 -0.95879892 3.36090138 -0.8038 2 P 0 ;0
L 3.44689892 -0.82879931 3.4589 -0.81380246 2 P 0 ;0
L 3.4589 -0.81380246 3.47290069 -0.80629951 2 P 0 ;0
L 3.47290069 -0.80629951 3.48890089 -0.8038 2 P 0 ;0
L 3.48890089 -0.8038 3.5089003 -0.80879902 2 P 0 ;0
L 3.5089003 -0.80879902 3.52290098 -0.82130089 2 P 0 ;0
L 3.52290098 -0.82130089 3.5269001 -0.83629764 2 P 0 ;0
L 3.5269001 -0.83629764 3.52490059 -0.85130364 2 P 0 ;0
L 3.52490059 -0.85130364 3.51689862 -0.86380098 2 P 0 ;0
L 3.51689862 -0.86380098 3.4768998 -0.8888002 2 P 0 ;0
L 3.4768998 -0.8888002 3.4589 -0.90630108 2 P 0 ;0
L 3.4589 -0.90630108 3.44689892 -0.93130482 2 P 0 ;0
L 3.44689892 -0.93130482 3.4428998 -0.9538 2 P 0 ;0
L 3.4428998 -0.9538 3.5269001 -0.9538 2 P 0 ;0
L 3.64089902 -0.9538 3.64489813 -0.92130246 2 P 0 ;0
L 3.64489813 -0.92130246 3.65090049 -0.89380374 2 P 0 ;0
L 3.65090049 -0.89380374 3.65889882 -0.8687999 2 P 0 ;0
L 3.65889882 -0.8687999 3.6689003 -0.84130118 2 P 0 ;0
L 3.6689003 -0.84130118 3.68490059 -0.8038 2 P 0 ;0
L 3.68490059 -0.8038 3.60489931 -0.8038 2 P 0 ;0
L 3.76889852 -0.95879892 3.84090138 -0.8038 2 P 0 ;0
L 3.92689892 -0.82879931 3.9389 -0.81380246 2 P 0 ;0
L 3.9389 -0.81380246 3.95290069 -0.80629951 2 P 0 ;0
L 3.95290069 -0.80629951 3.96890089 -0.8038 2 P 0 ;0
L 3.96890089 -0.8038 3.9889003 -0.80879902 2 P 0 ;0
L 3.9889003 -0.80879902 4.00290098 -0.82130089 2 P 0 ;0
L 4.00290098 -0.82130089 4.0069001 -0.83629764 2 P 0 ;0
L 4.0069001 -0.83629764 4.00490059 -0.85130364 2 P 0 ;0
L 4.00490059 -0.85130364 3.99689862 -0.86380098 2 P 0 ;0
L 3.99689862 -0.86380098 3.9568998 -0.8888002 2 P 0 ;0
L 3.9568998 -0.8888002 3.9389 -0.90630108 2 P 0 ;0
L 3.9389 -0.90630108 3.92689892 -0.93130482 2 P 0 ;0
L 3.92689892 -0.93130482 3.9228998 -0.9538 2 P 0 ;0
L 3.9228998 -0.9538 4.0069001 -0.9538 2 P 0 ;0
L 4.12489813 -0.8038 4.10889783 -0.80879902 2 P 0 ;0
L 4.10889783 -0.80879902 4.09690039 -0.82130089 2 P 0 ;0
L 4.09690039 -0.82130089 4.08889852 -0.83629764 2 P 0 ;0
L 4.08889852 -0.83629764 4.0828998 -0.85630256 2 P 0 ;0
L 4.0828998 -0.85630256 4.0809002 -0.87880236 2 P 0 ;0
L 4.0809002 -0.87880236 4.0828998 -0.90130207 2 P 0 ;0
L 4.0828998 -0.90130207 4.08889852 -0.92130246 2 P 0 ;0
L 4.08889852 -0.92130246 4.09690039 -0.93630374 2 P 0 ;0
L 4.09690039 -0.93630374 4.10889783 -0.94880108 2 P 0 ;0
L 4.10889783 -0.94880108 4.12489813 -0.9538 2 P 0 ;0
L 4.12489813 -0.9538 4.14089833 -0.94880108 2 P 0 ;0
L 4.14089833 -0.94880108 4.15289951 -0.93630374 2 P 0 ;0
L 4.15289951 -0.93630374 4.16090138 -0.92130246 2 P 0 ;0
L 4.16090138 -0.92130246 4.1669001 -0.90130207 2 P 0 ;0
L 4.1669001 -0.90130207 4.1688997 -0.87880236 2 P 0 ;0
L 4.1688997 -0.87880236 4.1669001 -0.85630256 2 P 0 ;0
L 4.1669001 -0.85630256 4.16090138 -0.83629764 2 P 0 ;0
L 4.16090138 -0.83629764 4.15289951 -0.82130089 2 P 0 ;0
L 4.15289951 -0.82130089 4.14089833 -0.80879902 2 P 0 ;0
L 4.14089833 -0.80879902 4.12489813 -0.8038 2 P 0 ;0
L 4.28489813 -0.9538 4.28489813 -0.8038 2 P 0 ;0
L 4.28489813 -0.8038 4.26089961 -0.83379823 2 P 0 ;0
L 4.26089961 -0.9538 4.30889665 -0.9538 2 P 0 ;0
L 4.44089902 -0.9538 4.44489813 -0.92130246 2 P 0 ;0
L 4.44489813 -0.92130246 4.45090049 -0.89380374 2 P 0 ;0
L 4.45090049 -0.89380374 4.45889882 -0.8687999 2 P 0 ;0
L 4.45889882 -0.8687999 4.4689003 -0.84130118 2 P 0 ;0
L 4.4689003 -0.84130118 4.48490059 -0.8038 2 P 0 ;0
L 4.48490059 -0.8038 4.40489931 -0.8038 2 P 0 ;0

### steps/drc/layers/l3/features
#
#Feature symbol names
#
$0 r2
$1 r3.7
$2 r4.5
$3 r6
$4 r15
$5 r17
$6 r20
$7 r43.7
$8 r74.8
$9 s15

#
#Feature attribute names
#
@0 .nomenclature
@1 .pattern_fill
@2 .geometry
@3 .string
@4 .pad_usage
@5 .string_angle

#
#Feature attribute text strings
#
&0 C1_11P0_7TP
&1 V20D10AT28SM14
&2 TPB30V20D10AT28BPM
&3 V17D8AT30SM11
&4 C1_9P1_4
&5 S1_9P1_4
&6 SHEET
&7 TITLE
&8 SCALE 1:1
&9 LAYER
&10 OF
&11 ART
&12 12
&13 INTERNAL LAYER 3
&14 3
&15 Barreleye G2 SXM2-Riser
&16 A1
&17 DATE OCT/27/2017

#
#Layer features
#
P 1.515 6.26 7 P 0 0;2=0,4=0
L 9.47125 6.30625 1.5187 6.30625 1 P 0 
L 1.5187 6.30625 1.515 6.30255 1 P 0 
L 1.515 6.30255 1.515 6.26 1 P 0 
P 1.515 6.36 7 P 0 0;2=0,4=0
L 9.47125 6.31375 1.5187 6.31375 1 P 0 
L 1.5187 6.31375 1.515 6.31745 1 P 0 
L 1.515 6.31745 1.515 6.36 1 P 0 
L 4.105 4.985 4.02525 4.90525 2 P 0 
L 4.02525 4.90525 4.02525 4.86831004 2 P 0 
L 4.02525 4.86831004 4.01315 4.85621004 2 P 0 
L 4.01315 4.85621004 4.01315 4.60315 2 P 0 
L 4.01315 4.60315 3.996 4.586 2 P 0 
L 3.996 4.586 3.996 4.38711998 2 P 0 
L 3.996 4.38711998 3.9658 4.35691998 2 P 0 
L 3.9658 4.35691998 3.9658 1.94226004 2 P 0 
L 3.9658 1.94226004 4.89306004 1.015 2 P 0 
L 4.89306004 1.015 5.99616998 1.015 2 P 0 
L 5.99616998 1.015 6.77261998 1.79145 2 P 0 
L 6.77261998 1.79145 9.72145 1.79145 2 P 0 
L 9.72145 1.79145 9.875 1.945 2 P 0 
L 9.875 1.945 9.875 2.715 2 P 0 
L 9.875 2.715 10.07 2.91 2 P 0 
L 10.07 2.91 10.07 2.928 2 P 0 
P 10.07 2.928 6 P 0 0;2=1,4=1
P 4.105 4.985 6 P 0 0;2=2,4=1
L 7.445 1.705 7.46 1.72 2 P 0 
L 7.46 1.72 9.76 1.72 2 P 0 
L 9.76 1.72 9.7872 1.7472 2 P 0 
L 9.7872 1.7472 11.0922 1.7472 2 P 0 
L 11.0922 1.7472 11.185 1.84 2 P 0 
L 11.185 1.84 11.185 2.795 2 P 0 
L 11.185 2.795 11.135 2.845 2 P 0 
P 7.445 1.705 6 P 0 0;2=1,4=1
P 11.135 2.845 6 P 0 0;2=1,4=1
P 11.03661004 2.16615 5 P 0 0;2=3,4=1
P 3.8899 4.765 6 P 0 0;2=2,4=1
L 3.8899 4.765 3.915 4.7399 2 P 0 
L 3.915 4.7399 3.915 4.625 2 P 0 
L 3.915 4.625 3.96325 4.57675 2 P 0 
L 3.96325 4.57675 3.96325 4.39825 2 P 0 
L 3.96325 4.39825 3.9348 4.3698 2 P 0 
L 3.9348 4.3698 3.9348 1.92403996 2 P 0 
L 3.9348 1.92403996 4.87483996 0.984 2 P 0 
L 4.87483996 0.984 6.01438996 0.984 2 P 0 
L 6.01438996 0.984 6.78703996 1.75665 2 P 0 
L 6.78703996 1.75665 9.74165 1.75665 2 P 0 
L 9.74165 1.75665 9.7632 1.7782 2 P 0 
L 9.7632 1.7782 11.0684 1.7782 2 P 0 
L 11.0684 1.7782 11.145 1.8548 2 P 0 
L 11.145 1.8548 11.145 2.125 2 P 0 
L 11.145 2.125 11.13 2.14 2 P 0 
L 11.13 2.14 11.06276004 2.14 2 P 0 
L 11.06276004 2.14 11.03661004 2.16615 2 P 0 
L 3.0531 -0.1945 3.0531 -0.4155 2 P 0 
L 3.0531 -0.4155 3.0486 -0.42 2 P 0 
L 3.0486 -0.42 2.9981 -0.42 2 P 0 
L 2.9981 -0.42 2.9936 -0.4155 2 P 0 
L 2.9936 -0.4155 2.9936 -0.1945 2 P 0 
L 2.9936 -0.1945 2.9891 -0.19 2 P 0 
L 2.9891 -0.19 2.9386 -0.19 2 P 0 
L 2.9386 -0.19 2.9341 -0.1945 2 P 0 
L 2.9341 -0.1945 2.9341 -0.4155 2 P 0 
L 2.9341 -0.4155 2.9296 -0.42 2 P 0 
L 2.9296 -0.42 2.8791 -0.42 2 P 0 
L 2.8791 -0.42 2.8746 -0.4155 2 P 0 
L 2.8746 -0.4155 2.8746 -0.1945 2 P 0 
L 2.8746 -0.1945 2.8701 -0.19 2 P 0 
L 2.8701 -0.19 2.8196 -0.19 2 P 0 
L 2.8196 -0.19 2.8151 -0.1945 2 P 0 
L 2.8151 -0.1945 2.8151 -0.4155 2 P 0 
L 2.8151 -0.4155 2.8106 -0.42 2 P 0 
L 2.8106 -0.42 2.7601 -0.42 2 P 0 
L 2.7601 -0.42 2.7556 -0.4155 2 P 0 
L 2.7556 -0.4155 2.7556 -0.1945 2 P 0 
L 2.7556 -0.1945 2.7511 -0.19 2 P 0 
L 2.7511 -0.19 2.7006 -0.19 2 P 0 
L 2.7006 -0.19 2.6961 -0.1945 2 P 0 
L 2.6961 -0.1945 2.6961 -0.4155 2 P 0 
L 2.6961 -0.4155 2.6916 -0.42 2 P 0 
L 2.6916 -0.42 2.6411 -0.42 2 P 0 
L 2.6411 -0.42 2.6366 -0.4155 2 P 0 
L 2.6366 -0.4155 2.6366 -0.1945 2 P 0 
L 2.6366 -0.1945 2.6321 -0.19 2 P 0 
L 2.6321 -0.19 2.5816 -0.19 2 P 0 
L 2.5816 -0.19 2.5771 -0.1945 2 P 0 
L 2.5771 -0.1945 2.5771 -0.4155 2 P 0 
L 2.5771 -0.4155 2.5726 -0.42 2 P 0 
L 2.5726 -0.42 2.5221 -0.42 2 P 0 
L 2.5221 -0.42 2.5176 -0.4155 2 P 0 
L 2.5176 -0.4155 2.5176 -0.1945 2 P 0 
L 2.5176 -0.1945 2.5131 -0.19 2 P 0 
L 2.5131 -0.19 2.4626 -0.19 2 P 0 
L 2.4626 -0.19 2.4581 -0.1945 2 P 0 
L 2.4581 -0.1945 2.4581 -0.4155 2 P 0 
L 2.4581 -0.4155 2.4536 -0.42 2 P 0 
L 2.4536 -0.42 2.4031 -0.42 2 P 0 
L 2.4031 -0.42 2.3986 -0.4155 2 P 0 
L 2.3986 -0.4155 2.3986 -0.1945 2 P 0 
L 2.3986 -0.1945 2.3941 -0.19 2 P 0 
L 2.3941 -0.19 2.3436 -0.19 2 P 0 
L 2.3436 -0.19 2.3391 -0.1945 2 P 0 
L 2.3391 -0.1945 2.3391 -0.4155 2 P 0 
L 2.3391 -0.4155 2.3346 -0.42 2 P 0 
L 2.3346 -0.42 2.2841 -0.42 2 P 0 
L 2.2841 -0.42 2.2796 -0.4155 2 P 0 
L 2.2796 -0.4155 2.2796 -0.1945 2 P 0 
L 2.2796 -0.1945 2.2751 -0.19 2 P 0 
L 2.2751 -0.19 2.2246 -0.19 2 P 0 
L 2.2246 -0.19 2.2201 -0.1945 2 P 0 
L 2.2201 -0.1945 2.2201 -0.4155 2 P 0 
L 2.2201 -0.4155 2.2156 -0.42 2 P 0 
L 2.2156 -0.42 2.1651 -0.42 2 P 0 
L 2.1651 -0.42 2.1606 -0.4155 2 P 0 
L 2.1606 -0.4155 2.1606 -0.1945 2 P 0 
L 2.1606 -0.1945 2.1561 -0.19 2 P 0 
L 2.1561 -0.19 2.1056 -0.19 2 P 0 
L 2.1056 -0.19 2.1011 -0.1945 2 P 0 
L 2.1011 -0.1945 2.1011 -0.4155 2 P 0 
L 2.1011 -0.4155 2.0966 -0.42 2 P 0 
L 2.0966 -0.42 2.0461 -0.42 2 P 0 
L 2.0461 -0.42 2.0416 -0.4155 2 P 0 
L 2.0416 -0.4155 2.0416 -0.1945 2 P 0 
L 2.0416 -0.1945 2.0371 -0.19 2 P 0 
L 2.0371 -0.19 1.9866 -0.19 2 P 0 
L 1.9866 -0.19 1.9821 -0.1945 2 P 0 
L 1.9821 -0.1945 1.9821 -0.4155 2 P 0 
L 1.9821 -0.4155 1.9776 -0.42 2 P 0 
L 1.9776 -0.42 1.9271 -0.42 2 P 0 
L 1.9271 -0.42 1.9226 -0.4155 2 P 0 
L 1.9226 -0.4155 1.9226 -0.1945 2 P 0 
L 1.9226 -0.1945 1.9181 -0.19 2 P 0 
L 1.9181 -0.19 1.8676 -0.19 2 P 0 
L 1.8676 -0.19 1.8631 -0.1945 2 P 0 
L 1.8631 -0.1945 1.8631 -0.4155 2 P 0 
L 1.8631 -0.4155 1.8586 -0.42 2 P 0 
L 1.8586 -0.42 1.8081 -0.42 2 P 0 
L 1.8081 -0.42 1.8036 -0.4155 2 P 0 
L 1.8036 -0.4155 1.8036 -0.1945 2 P 0 
L 1.8036 -0.1945 1.7991 -0.19 2 P 0 
L 1.7991 -0.19 1.7486 -0.19 2 P 0 
L 1.7486 -0.19 1.7441 -0.1945 2 P 0 
L 1.7441 -0.1945 1.7441 -0.4155 2 P 0 
L 1.7441 -0.4155 1.7396 -0.42 2 P 0 
L 1.7396 -0.42 1.6891 -0.42 2 P 0 
L 1.6891 -0.42 1.6846 -0.4155 2 P 0 
L 1.6846 -0.4155 1.6846 -0.1945 2 P 0 
L 1.6846 -0.1945 1.6801 -0.19 2 P 0 
L 1.6801 -0.19 1.6296 -0.19 2 P 0 
L 1.6296 -0.19 1.6251 -0.1945 2 P 0 
L 1.6251 -0.1945 1.6251 -0.4155 2 P 0 
L 1.6251 -0.4155 1.6206 -0.42 2 P 0 
L 1.6206 -0.42 1.5701 -0.42 2 P 0 
L 1.5701 -0.42 1.5656 -0.4155 2 P 0 
L 1.5656 -0.4155 1.5656 -0.1945 2 P 0 
L 1.5656 -0.1945 1.5611 -0.19 2 P 0 
L 1.5611 -0.19 1.5106 -0.19 2 P 0 
L 1.5106 -0.19 1.5061 -0.1945 2 P 0 
L 1.5061 -0.1945 1.5061 -0.4155 2 P 0 
L 1.5061 -0.4155 1.5016 -0.42 2 P 0 
L 1.5016 -0.42 1.46 -0.42 2 P 0 
L 1.46 -0.42 1.445 -0.405 2 P 0 
L 1.445 -0.405 1.445 -0.31 2 P 0 
L 1.445 -0.31 1.435 -0.3 2 P 0 
L 1.435 -0.3 1.225 -0.3 2 P 0 
L 1.225 -0.3 1.175 -0.25 2 P 0 
P 1.175 -0.25 7 P 0 0;2=0,4=0
P 11.03998996 4.8431 6 P 0 0;2=1,4=1
P 11.08498996 4.8431 6 P 0 0;2=1,4=1
P 11.13498996 4.8431 6 P 0 0;2=1,4=1
P 11.17998996 4.8431 6 P 0 0;2=1,4=1
P 11.17998996 4.8031 6 P 0 0;2=1,4=1
P 11.17998996 4.7581 6 P 0 0;2=1,4=1
P 11.17998996 4.7131 6 P 0 0;2=1,4=1
P 11.17998996 4.6731 6 P 0 0;2=1,4=1
P 11.03998996 4.6731 6 P 0 0;2=1,4=1
P 11.08498996 4.6731 6 P 0 0;2=1,4=1
P 11.13498996 4.6731 6 P 0 0;2=1,4=1
P 11.03998996 4.7131 6 P 0 0;2=1,4=1
P 11.03998996 4.8031 6 P 0 0;2=1,4=1
P 11.03998996 4.7581 6 P 0 0;2=1,4=1
P 10.81998996 4.6631 6 P 0 0;2=1,4=1
P 10.85998996 4.6631 6 P 0 0;2=1,4=1
P 10.65998996 4.6631 6 P 0 0;2=1,4=1
P 10.69998996 4.6631 6 P 0 0;2=1,4=1
P 10.81998996 4.7031 6 P 0 0;2=1,4=1
P 10.81998996 4.8381 6 P 0 0;2=1,4=1
P 10.81998996 4.7931 6 P 0 0;2=1,4=1
P 10.81998996 4.7481 6 P 0 0;2=1,4=1
P 10.85998996 4.7031 6 P 0 0;2=1,4=1
P 10.85998996 4.8381 6 P 0 0;2=1,4=1
P 10.85998996 4.7931 6 P 0 0;2=1,4=1
P 10.85998996 4.7481 6 P 0 0;2=1,4=1
P 10.65998996 4.7031 6 P 0 0;2=1,4=1
P 10.65998996 4.8381 6 P 0 0;2=1,4=1
P 10.65998996 4.7931 6 P 0 0;2=1,4=1
P 10.65998996 4.7481 6 P 0 0;2=1,4=1
P 10.69998996 4.7031 6 P 0 0;2=1,4=1
P 10.69998996 4.8381 6 P 0 0;2=1,4=1
P 10.69998996 4.7931 6 P 0 0;2=1,4=1
P 10.69998996 4.7481 6 P 0 0;2=1,4=1
P 10.77998996 4.6431 6 P 0 0;2=1,4=1
P 10.73498996 4.6431 6 P 0 0;2=1,4=1
P 10.73998996 4.8381 6 P 0 0;2=1,4=1
P 10.77998996 4.8381 6 P 0 0;2=1,4=1
P 10.30998996 4.6631 6 P 0 0;2=1,4=1
P 10.26998996 4.6631 6 P 0 0;2=1,4=1
P 10.34498996 4.6431 6 P 0 0;2=1,4=1
P 10.38998996 4.6431 6 P 0 0;2=1,4=1
P 10.42998996 4.6631 6 P 0 0;2=1,4=1
P 10.46998996 4.6631 6 P 0 0;2=1,4=1
P 10.30998996 4.7481 6 P 0 0;2=1,4=1
P 10.30998996 4.7931 6 P 0 0;2=1,4=1
P 10.30998996 4.7031 6 P 0 0;2=1,4=1
P 10.26998996 4.7481 6 P 0 0;2=1,4=1
P 10.26998996 4.7931 6 P 0 0;2=1,4=1
P 10.26998996 4.7031 6 P 0 0;2=1,4=1
P 10.26998996 4.8381 6 P 0 0;2=1,4=1
P 10.30998996 4.8381 6 P 0 0;2=1,4=1
P 10.38998996 4.8381 6 P 0 0;2=1,4=1
P 10.34998996 4.8381 6 P 0 0;2=1,4=1
P 10.46998996 4.8381 6 P 0 0;2=1,4=1
P 10.42998996 4.8381 6 P 0 0;2=1,4=1
P 10.42998996 4.7031 6 P 0 0;2=1,4=1
P 10.42998996 4.7931 6 P 0 0;2=1,4=1
P 10.42998996 4.7481 6 P 0 0;2=1,4=1
P 10.46998996 4.7031 6 P 0 0;2=1,4=1
P 10.46998996 4.7931 6 P 0 0;2=1,4=1
P 10.46998996 4.7481 6 P 0 0;2=1,4=1
P 10.58661004 3.16615 5 P 0 0;2=3,4=1
P 10.63661004 3.01615 5 P 0 0;2=3,4=1
P 10.58661004 3.11615 5 P 0 0;2=3,4=1
P 10.58661004 3.01615 5 P 0 0;2=3,4=1
P 10.63661004 3.11615 5 P 0 0;2=3,4=1
P 10.63661004 2.96615 5 P 0 0;2=3,4=1
P 10.58661004 2.96615 5 P 0 0;2=3,4=1
P 10.58661004 3.41615 5 P 0 0;2=3,4=1
P 10.63661004 3.16615 5 P 0 0;2=3,4=1
P 10.63661004 3.26615 5 P 0 0;2=3,4=1
P 10.58661004 3.31615 5 P 0 0;2=3,4=1
P 10.58661004 3.26615 5 P 0 0;2=3,4=1
P 10.63661004 3.31615 5 P 0 0;2=3,4=1
P 10.63661004 3.56615 5 P 0 0;2=3,4=1
P 10.63661004 3.61615 5 P 0 0;2=3,4=1
P 10.58661004 3.56615 5 P 0 0;2=3,4=1
P 10.58661004 3.61615 5 P 0 0;2=3,4=1
P 10.63661004 3.46615 5 P 0 0;2=3,4=1
P 10.63661004 3.41615 5 P 0 0;2=3,4=1
P 10.58661004 3.46615 5 P 0 0;2=3,4=1
P 10.63661004 3.86615 5 P 0 0;2=3,4=1
P 10.63661004 3.76615 5 P 0 0;2=3,4=1
P 10.58661004 3.86615 5 P 0 0;2=3,4=1
P 10.58661004 3.76615 5 P 0 0;2=3,4=1
P 10.63661004 3.71615 5 P 0 0;2=3,4=1
P 10.58661004 3.71615 5 P 0 0;2=3,4=1
P 10.88661004 2.96615 5 P 0 0;2=3,4=1
P 10.83661004 2.96615 5 P 0 0;2=3,4=1
P 10.88661004 3.01615 5 P 0 0;2=3,4=1
P 10.83661004 3.01615 5 P 0 0;2=3,4=1
P 10.88661004 3.11615 5 P 0 0;2=3,4=1
P 10.83661004 3.11615 5 P 0 0;2=3,4=1
P 10.83661004 3.16615 5 P 0 0;2=3,4=1
P 10.78661004 3.16615 5 P 0 0;2=3,4=1
P 10.68661004 3.16615 5 P 0 0;2=3,4=1
P 10.73661004 3.16615 5 P 0 0;2=3,4=1
P 10.78661004 3.01615 5 P 0 0;2=3,4=1
P 10.78661004 3.11615 5 P 0 0;2=3,4=1
P 10.73661004 3.01615 5 P 0 0;2=3,4=1
P 10.73661004 3.11615 5 P 0 0;2=3,4=1
P 10.68661004 3.01615 5 P 0 0;2=3,4=1
P 10.68661004 3.11615 5 P 0 0;2=3,4=1
P 10.78661004 2.96615 5 P 0 0;2=3,4=1
P 10.73661004 2.96615 5 P 0 0;2=3,4=1
P 10.68661004 2.96615 5 P 0 0;2=3,4=1
P 10.88661004 3.16615 5 P 0 0;2=3,4=1
P 10.88661004 3.26615 5 P 0 0;2=3,4=1
P 10.83661004 3.26615 5 P 0 0;2=3,4=1
P 10.83661004 3.31615 5 P 0 0;2=3,4=1
P 10.88661004 3.31615 5 P 0 0;2=3,4=1
P 10.83661004 3.41615 5 P 0 0;2=3,4=1
P 10.78661004 3.41615 5 P 0 0;2=3,4=1
P 10.68661004 3.41615 5 P 0 0;2=3,4=1
P 10.73661004 3.41615 5 P 0 0;2=3,4=1
P 10.78661004 3.31615 5 P 0 0;2=3,4=1
P 10.78661004 3.26615 5 P 0 0;2=3,4=1
P 10.68661004 3.31615 5 P 0 0;2=3,4=1
P 10.68661004 3.26615 5 P 0 0;2=3,4=1
P 10.73661004 3.26615 5 P 0 0;2=3,4=1
P 10.73661004 3.31615 5 P 0 0;2=3,4=1
P 10.88661004 3.41615 5 P 0 0;2=3,4=1
P 10.83661004 3.46615 5 P 0 0;2=3,4=1
P 10.88661004 3.46615 5 P 0 0;2=3,4=1
P 10.83661004 3.56615 5 P 0 0;2=3,4=1
P 10.88661004 3.56615 5 P 0 0;2=3,4=1
P 10.83661004 3.61615 5 P 0 0;2=3,4=1
P 10.88661004 3.61615 5 P 0 0;2=3,4=1
P 10.78661004 3.56615 5 P 0 0;2=3,4=1
P 10.78661004 3.61615 5 P 0 0;2=3,4=1
P 10.68661004 3.61615 5 P 0 0;2=3,4=1
P 10.68661004 3.56615 5 P 0 0;2=3,4=1
P 10.73661004 3.61615 5 P 0 0;2=3,4=1
P 10.73661004 3.56615 5 P 0 0;2=3,4=1
P 10.78661004 3.46615 5 P 0 0;2=3,4=1
P 10.73661004 3.46615 5 P 0 0;2=3,4=1
P 10.68661004 3.46615 5 P 0 0;2=3,4=1
P 10.83661004 3.71615 5 P 0 0;2=3,4=1
P 10.88661004 3.71615 5 P 0 0;2=3,4=1
P 10.83661004 3.76615 5 P 0 0;2=3,4=1
P 10.88661004 3.76615 5 P 0 0;2=3,4=1
P 10.83661004 3.86615 5 P 0 0;2=3,4=1
P 10.88661004 3.86615 5 P 0 0;2=3,4=1
P 10.78661004 3.86615 5 P 0 0;2=3,4=1
P 10.78661004 3.76615 5 P 0 0;2=3,4=1
P 10.68661004 3.86615 5 P 0 0;2=3,4=1
P 10.68661004 3.76615 5 P 0 0;2=3,4=1
P 10.73661004 3.86615 5 P 0 0;2=3,4=1
P 10.73661004 3.76615 5 P 0 0;2=3,4=1
P 10.78661004 3.71615 5 P 0 0;2=3,4=1
P 10.68661004 3.71615 5 P 0 0;2=3,4=1
P 10.73661004 3.71615 5 P 0 0;2=3,4=1
P 11.03661004 2.96615 5 P 0 0;2=3,4=1
P 10.93661004 2.96615 5 P 0 0;2=3,4=1
P 10.98661004 2.96615 5 P 0 0;2=3,4=1
P 11.03661004 3.01615 5 P 0 0;2=3,4=1
P 10.93661004 3.01615 5 P 0 0;2=3,4=1
P 10.98661004 3.01615 5 P 0 0;2=3,4=1
P 11.03661004 3.11615 5 P 0 0;2=3,4=1
P 10.93661004 3.11615 5 P 0 0;2=3,4=1
P 10.98661004 3.11615 5 P 0 0;2=3,4=1
P 11.03661004 3.16615 5 P 0 0;2=3,4=1
P 10.93661004 3.16615 5 P 0 0;2=3,4=1
P 10.98661004 3.16615 5 P 0 0;2=3,4=1
P 11.03661004 3.26615 5 P 0 0;2=3,4=1
P 10.93661004 3.26615 5 P 0 0;2=3,4=1
P 10.98661004 3.26615 5 P 0 0;2=3,4=1
P 10.98661004 3.31615 5 P 0 0;2=3,4=1
P 10.93661004 3.31615 5 P 0 0;2=3,4=1
P 11.03661004 3.31615 5 P 0 0;2=3,4=1
P 10.98661004 3.41615 5 P 0 0;2=3,4=1
P 10.93661004 3.41615 5 P 0 0;2=3,4=1
P 11.03661004 3.41615 5 P 0 0;2=3,4=1
P 10.98661004 3.46615 5 P 0 0;2=3,4=1
P 10.93661004 3.46615 5 P 0 0;2=3,4=1
P 11.03661004 3.46615 5 P 0 0;2=3,4=1
P 10.98661004 3.56615 5 P 0 0;2=3,4=1
P 10.93661004 3.56615 5 P 0 0;2=3,4=1
P 11.03661004 3.56615 5 P 0 0;2=3,4=1
P 10.98661004 3.61615 5 P 0 0;2=3,4=1
P 10.93661004 3.61615 5 P 0 0;2=3,4=1
P 11.03661004 3.61615 5 P 0 0;2=3,4=1
P 10.98661004 3.71615 5 P 0 0;2=3,4=1
P 10.93661004 3.71615 5 P 0 0;2=3,4=1
P 11.03661004 3.71615 5 P 0 0;2=3,4=1
P 10.98661004 3.76615 5 P 0 0;2=3,4=1
P 10.93661004 3.76615 5 P 0 0;2=3,4=1
P 11.03661004 3.76615 5 P 0 0;2=3,4=1
P 10.98661004 3.86615 5 P 0 0;2=3,4=1
P 10.93661004 3.86615 5 P 0 0;2=3,4=1
P 11.03661004 3.86615 5 P 0 0;2=3,4=1
S P 0
OB 11.173 2.943 I
OS 10.587 2.943
OS 10.25998996063 3.27001003937
OS 10.25998996063 4.84498996063
OS 10.27 4.855
OS 11.17808996063 4.855
OS 11.2 4.83308996063
OS 11.2 2.97
OS 11.173 2.943
OE
OB 11.044130019685 4.22441003937 H
OC 11.044130019685 4.22441003937 10.836619980315 4.22441003937 N
OE
OB 10.602630019685 3.06615 H
OC 10.602630019685 3.06615 10.58661003937 3.06615 N
OE
OB 10.602630019685 3.21615 H
OC 10.602630019685 3.21615 10.58661003937 3.21615 N
OE
OB 10.602630019685 3.36615 H
OC 10.602630019685 3.36615 10.58661003937 3.36615 N
OE
OB 10.602630019685 3.51615 H
OC 10.602630019685 3.51615 10.58661003937 3.51615 N
OE
OB 10.602630019685 3.81615 H
OC 10.602630019685 3.81615 10.58661003937 3.81615 N
OE
OB 10.602630019685 3.66615 H
OC 10.602630019685 3.66615 10.58661003937 3.66615 N
OE
OB 10.702630019685 3.06615 H
OC 10.702630019685 3.06615 10.68661003937 3.06615 N
OE
OB 10.752630019685 3.06615 H
OC 10.752630019685 3.06615 10.73661003937 3.06615 N
OE
OB 10.802630019685 3.06615 H
OC 10.802630019685 3.06615 10.78661003937 3.06615 N
OE
OB 10.852630019685 3.06615 H
OC 10.852630019685 3.06615 10.83661003937 3.06615 N
OE
OB 10.652630019685 3.06615 H
OC 10.652630019685 3.06615 10.63661003937 3.06615 N
OE
OB 10.702630019685 3.21615 H
OC 10.702630019685 3.21615 10.68661003937 3.21615 N
OE
OB 10.702630019685 3.36615 H
OC 10.702630019685 3.36615 10.68661003937 3.36615 N
OE
OB 10.752630019685 3.21615 H
OC 10.752630019685 3.21615 10.73661003937 3.21615 N
OE
OB 10.802630019685 3.21615 H
OC 10.802630019685 3.21615 10.78661003937 3.21615 N
OE
OB 10.752630019685 3.36615 H
OC 10.752630019685 3.36615 10.73661003937 3.36615 N
OE
OB 10.802630019685 3.36615 H
OC 10.802630019685 3.36615 10.78661003937 3.36615 N
OE
OB 10.852630019685 3.36615 H
OC 10.852630019685 3.36615 10.83661003937 3.36615 N
OE
OB 10.852630019685 3.21615 H
OC 10.852630019685 3.21615 10.83661003937 3.21615 N
OE
OB 10.652630019685 3.21615 H
OC 10.652630019685 3.21615 10.63661003937 3.21615 N
OE
OB 10.652630019685 3.36615 H
OC 10.652630019685 3.36615 10.63661003937 3.36615 N
OE
OB 10.702630019685 3.51615 H
OC 10.702630019685 3.51615 10.68661003937 3.51615 N
OE
OB 10.752630019685 3.51615 H
OC 10.752630019685 3.51615 10.73661003937 3.51615 N
OE
OB 10.802630019685 3.51615 H
OC 10.802630019685 3.51615 10.78661003937 3.51615 N
OE
OB 10.852630019685 3.51615 H
OC 10.852630019685 3.51615 10.83661003937 3.51615 N
OE
OB 10.652630019685 3.51615 H
OC 10.652630019685 3.51615 10.63661003937 3.51615 N
OE
OB 10.702630019685 3.81615 H
OC 10.702630019685 3.81615 10.68661003937 3.81615 N
OE
OB 10.752630019685 3.81615 H
OC 10.752630019685 3.81615 10.73661003937 3.81615 N
OE
OB 10.802630019685 3.81615 H
OC 10.802630019685 3.81615 10.78661003937 3.81615 N
OE
OB 10.852630019685 3.81615 H
OC 10.852630019685 3.81615 10.83661003937 3.81615 N
OE
OB 10.702630019685 3.66615 H
OC 10.702630019685 3.66615 10.68661003937 3.66615 N
OE
OB 10.752630019685 3.66615 H
OC 10.752630019685 3.66615 10.73661003937 3.66615 N
OE
OB 10.802630019685 3.66615 H
OC 10.802630019685 3.66615 10.78661003937 3.66615 N
OE
OB 10.852630019685 3.66615 H
OC 10.852630019685 3.66615 10.83661003937 3.66615 N
OE
OB 10.652630019685 3.66615 H
OC 10.652630019685 3.66615 10.63661003937 3.66615 N
OE
OB 10.652630019685 3.81615 H
OC 10.652630019685 3.81615 10.63661003937 3.81615 N
OE
OB 11.002630019685 3.06615 H
OC 11.002630019685 3.06615 10.98661003937 3.06615 N
OE
OB 10.952630019685 3.06615 H
OC 10.952630019685 3.06615 10.93661003937 3.06615 N
OE
OB 11.052630019685 3.06615 H
OC 11.052630019685 3.06615 11.03661003937 3.06615 N
OE
OB 10.902630019685 3.06615 H
OC 10.902630019685 3.06615 10.88661003937 3.06615 N
OE
OB 11.052630019685 3.36615 H
OC 11.052630019685 3.36615 11.03661003937 3.36615 N
OE
OB 10.952630019685 3.36615 H
OC 10.952630019685 3.36615 10.93661003937 3.36615 N
OE
OB 11.002630019685 3.36615 H
OC 11.002630019685 3.36615 10.98661003937 3.36615 N
OE
OB 11.002630019685 3.21615 H
OC 11.002630019685 3.21615 10.98661003937 3.21615 N
OE
OB 10.952630019685 3.21615 H
OC 10.952630019685 3.21615 10.93661003937 3.21615 N
OE
OB 11.052630019685 3.21615 H
OC 11.052630019685 3.21615 11.03661003937 3.21615 N
OE
OB 10.902630019685 3.36615 H
OC 10.902630019685 3.36615 10.88661003937 3.36615 N
OE
OB 10.902630019685 3.21615 H
OC 10.902630019685 3.21615 10.88661003937 3.21615 N
OE
OB 11.052630019685 3.51615 H
OC 11.052630019685 3.51615 11.03661003937 3.51615 N
OE
OB 10.952630019685 3.51615 H
OC 10.952630019685 3.51615 10.93661003937 3.51615 N
OE
OB 11.002630019685 3.51615 H
OC 11.002630019685 3.51615 10.98661003937 3.51615 N
OE
OB 10.902630019685 3.51615 H
OC 10.902630019685 3.51615 10.88661003937 3.51615 N
OE
OB 10.952630019685 3.81615 H
OC 10.952630019685 3.81615 10.93661003937 3.81615 N
OE
OB 11.002630019685 3.81615 H
OC 11.002630019685 3.81615 10.98661003937 3.81615 N
OE
OB 11.052630019685 3.66615 H
OC 11.052630019685 3.66615 11.03661003937 3.66615 N
OE
OB 10.952630019685 3.66615 H
OC 10.952630019685 3.66615 10.93661003937 3.66615 N
OE
OB 11.002630019685 3.66615 H
OC 11.002630019685 3.66615 10.98661003937 3.66615 N
OE
OB 10.902630019685 3.66615 H
OC 10.902630019685 3.66615 10.88661003937 3.66615 N
OE
OB 10.902630019685 3.81615 H
OC 10.902630019685 3.81615 10.88661003937 3.81615 N
OE
OB 11.052630019685 3.81615 H
OC 11.052630019685 3.81615 11.03661003937 3.81615 N
OE
SE
P 8.5 3.76615 5 P 0 0;2=3,4=1
P 9.35271004 5.1035 5 P 0 0;2=3,4=1
L 8.5 3.76615 8.5 3.7837 1 P 0 
A 8.5 3.7837 8.50093799 3.78616476 8.5037 3.78370276 1 P 0 Y
A 8.50093799 3.78616476 8.50328002 3.78738002 8.50370325 3.7837 1 P 0 Y
L 8.50328002 3.78738002 8.5037 3.7874 1 P 0 
L 8.5037 3.7874 8.55293002 3.7874 1 P 0 
A 8.55293002 3.7874 8.56251447 3.78592372 8.55293317 3.75556998 1 P 0 Y
A 8.56251447 3.78592372 8.57121004 3.78163002 8.55293425 3.75556998 1 P 0 Y
L 8.57121004 3.78163002 8.64058996 3.73303002 1 P 0 
L 8.64058996 3.73303002 8.70988996 3.6341 1 P 0 
L 8.70988996 3.6341 8.72531004 3.62328996 1 P 0 
L 8.72531004 3.62328996 8.74326998 3.62011998 1 P 0 
L 8.74326998 3.62011998 8.92911998 3.65288996 1 P 0 
L 8.92911998 3.65288996 9.0805 3.75888002 1 P 0 
L 9.0805 3.75888002 9.23158996 3.86466998 1 P 0 
L 9.23158996 3.86466998 9.38701998 4.08668996 1 P 0 
A 9.38701998 4.08668996 9.39381998 4.11208002 9.35553996 4.10872657 1 P 0 N
A 9.39381998 4.11208002 9.38271004 4.1359 9.35553996 4.10872657 1 P 0 N
L 9.38271004 4.1359 9.3827 4.13591004 1 P 0 
A 9.3827 4.13591004 9.37309636 4.14295118 9.35501535 4.10821998 1 P 0 N
A 9.37309636 4.14295118 9.36181998 4.14678002 9.35501535 4.10821998 1 P 0 N
L 9.36181998 4.14678002 9.31281998 4.15543002 1 P 0 
A 9.31281998 4.15543002 9.28996004 4.16733002 9.32026033 4.19763002 1 P 0 Y
L 9.28996004 4.16733002 9.28058002 4.17671004 1 P 0 
A 9.28058002 4.17671004 9.27481329 4.18457451 9.30323002 4.19936496 1 P 0 Y
A 9.27481329 4.18457451 9.27168002 4.19381004 9.30323002 4.19936447 1 P 0 Y
L 9.27168002 4.19381004 9.19633996 4.62115 1 P 0 
L 9.19633996 4.62115 9.20818996 4.68838002 1 P 0 
L 9.20818996 4.68838002 9.21668002 4.7005 1 P 0 
L 9.21668002 4.7005 9.23358996 4.71233002 1 P 0 
L 9.23358996 4.71233002 9.25556998 4.71621004 1 P 0 
L 9.25556998 4.71621004 9.29658002 4.74493002 1 P 0 
L 9.29658002 4.74493002 9.33016998 4.79291998 1 P 0 
L 9.33016998 4.79291998 9.34256004 4.86318002 1 P 0 
L 9.34256004 4.86318002 9.35593002 4.88226998 1 P 0 
L 9.35593002 4.88226998 9.37935 4.89866998 1 P 0 
L 9.37935 4.89866998 9.40506004 4.9032 1 P 0 
L 9.40506004 4.9032 9.43623002 4.8977 1 P 0 
L 9.43623002 4.8977 9.45056004 4.90023002 1 P 0 
L 9.45056004 4.90023002 9.46008996 4.90693002 1 P 0 
L 9.46008996 4.90693002 9.47578002 4.92928002 1 P 0 
L 9.47578002 4.92928002 9.48166004 4.96263996 1 P 0 
L 9.48166004 4.96263996 9.46953002 5.03138002 1 P 0 
L 9.46953002 5.03138002 9.45623996 5.05036998 1 P 0 
L 9.45623996 5.05036998 9.43538002 5.06498002 1 P 0 
L 9.43538002 5.06498002 9.42101004 5.0675 1 P 0 
L 9.42101004 5.0675 9.34603996 5.0675 1 P 0 
L 9.34603996 5.0675 9.33646004 5.07708002 1 P 0 
L 9.33646004 5.07708002 9.33646004 5.09941998 1 P 0 
A 9.33646004 5.09941998 9.34053996 5.1035 9.34053996 5.09942008 1 P 0 Y
L 9.34053996 5.1035 9.35271004 5.1035 1 P 0 
P 8.5 3.81615 5 P 0 0;2=3,4=1
P 9.31271004 5.1035 5 P 0 0;2=3,4=1
L 8.5 3.81615 8.5 3.7986 1 P 0 
A 8.5 3.7986 8.50093799 3.79613524 8.5037 3.79859724 1 P 0 N
A 8.50093799 3.79613524 8.50328002 3.79491998 8.50370325 3.7986 1 P 0 N
L 8.50328002 3.79491998 8.50346004 3.7949 1 P 0 
L 8.50346004 3.7949 8.55293002 3.7949 1 P 0 
A 8.55293002 3.7949 8.56477362 3.79308041 8.55294764 3.75556004 1 P 0 Y
A 8.56477362 3.79308041 8.57551998 3.78778002 8.55294783 3.75556004 1 P 0 Y
L 8.57551998 3.78778002 8.64598002 3.73841998 1 P 0 
L 8.64598002 3.73841998 8.71528002 3.63948996 1 P 0 
L 8.71528002 3.63948996 8.72825 3.63038996 1 P 0 
L 8.72825 3.63038996 8.74326998 3.62773996 1 P 0 
L 8.74326998 3.62773996 8.92618002 3.65998996 1 P 0 
L 8.92618002 3.65998996 9.2262 3.87006004 1 P 0 
L 9.2262 3.87006004 9.38086998 4.091 1 P 0 
A 9.38086998 4.091 9.38633868 4.11142707 9.35553996 4.10872687 1 P 0 N
A 9.38633868 4.11142707 9.3774 4.13058996 9.35553996 4.10872697 1 P 0 N
L 9.3774 4.13058996 9.37738996 4.1306 1 P 0 
A 9.37738996 4.1306 9.3696311 4.13629213 9.35500394 4.10821998 1 P 0 N
A 9.3696311 4.13629213 9.36051998 4.13938996 9.35500423 4.10821998 1 P 0 N
L 9.36051998 4.13938996 9.31151998 4.14803996 1 P 0 
A 9.31151998 4.14803996 9.28465 4.16201998 9.32024911 4.19763002 1 P 0 Y
L 9.28465 4.16201998 9.27526998 4.1714 1 P 0 
A 9.27526998 4.1714 9.26815423 4.18110925 9.30323002 4.19935354 1 P 0 Y
A 9.26815423 4.18110925 9.26428996 4.19251004 9.30323002 4.19935335 1 P 0 Y
L 9.26428996 4.19251004 9.18871998 4.62115 1 P 0 
L 9.18871998 4.62115 9.20108996 4.69131998 1 P 0 
L 9.20108996 4.69131998 9.21128996 4.70588996 1 P 0 
L 9.21128996 4.70588996 9.23065 4.71943002 1 P 0 
L 9.23065 4.71943002 9.25261998 4.72331004 1 P 0 
L 9.25261998 4.72331004 9.25263002 4.72331004 1 P 0 
L 9.25263002 4.72331004 9.26833002 4.73431004 1 P 0 
L 9.26833002 4.73431004 9.26835 4.73433002 1 P 0 
L 9.26835 4.73433002 9.29118996 4.75031998 1 P 0 
L 9.29118996 4.75031998 9.32306998 4.79586004 1 P 0 
L 9.32306998 4.79586004 9.33546004 4.86611998 1 P 0 
L 9.33546004 4.86611998 9.35053996 4.88766004 1 P 0 
L 9.35053996 4.88766004 9.37641004 4.90576998 1 P 0 
L 9.37641004 4.90576998 9.40506004 4.91081998 1 P 0 
L 9.40506004 4.91081998 9.43623002 4.90531998 1 P 0 
L 9.43623002 4.90531998 9.44761004 4.90733002 1 P 0 
L 9.44761004 4.90733002 9.4547 4.91231004 1 P 0 
L 9.4547 4.91231004 9.46868002 4.93221998 1 P 0 
L 9.46868002 4.93221998 9.47403996 4.96263996 1 P 0 
L 9.47403996 4.96263996 9.46243002 5.02843996 1 P 0 
L 9.46243002 5.02843996 9.45085 5.04498002 1 P 0 
L 9.45085 5.04498002 9.43586004 5.05548002 1 P 0 
L 9.43586004 5.05548002 9.43586998 5.05548002 1 P 0 
L 9.43586998 5.05548002 9.43243996 5.05788002 1 P 0 
L 9.43243996 5.05788002 9.42035 5.06 1 P 0 
L 9.42035 5.06 9.40516004 5.06 1 P 0 
L 9.40516004 5.06 9.40116004 5.056 1 P 0 
L 9.40116004 5.056 9.39006004 5.056 1 P 0 
L 9.39006004 5.056 9.38606004 5.06 1 P 0 
L 9.38606004 5.06 9.37496004 5.06 1 P 0 
L 9.37496004 5.06 9.37096004 5.056 1 P 0 
L 9.37096004 5.056 9.35986004 5.056 1 P 0 
L 9.35986004 5.056 9.35586004 5.06 1 P 0 
L 9.35586004 5.06 9.34293002 5.06 1 P 0 
L 9.34293002 5.06 9.32896004 5.07396998 1 P 0 
L 9.32896004 5.07396998 9.32896004 5.0998 1 P 0 
A 9.32896004 5.0998 9.32526004 5.1035 9.32526004 5.0998 1 P 0 N
L 9.32526004 5.1035 9.31271004 5.1035 1 P 0 
P 8.5 3.61615 5 P 0 0;2=3,4=1
P 9.56531004 5.14 5 P 0 0;2=3,4=1
L 9.56531004 5.14 9.55316004 5.14 1 P 0 
A 9.55316004 5.14 9.54946004 5.1363 9.55316004 5.1363 1 P 0 N
L 9.54946004 5.1363 9.54946004 5.10908002 1 P 0 
L 9.54946004 5.10908002 9.55353996 5.105 1 P 0 
L 9.55353996 5.105 9.61503002 5.105 1 P 0 
L 9.61503002 5.105 9.62578002 5.10311004 1 P 0 
L 9.62578002 5.10311004 9.64291998 5.0911 1 P 0 
L 9.64291998 5.0911 9.64858002 5.08301998 1 P 0 
L 9.64858002 5.08301998 9.66258996 5.00363996 1 P 0 
L 9.66258996 5.00363996 9.66256004 5.00363002 1 P 0 
L 9.66256004 5.00363002 9.68233996 4.89178002 1 P 0 
L 9.68233996 4.89178002 9.66171998 4.77491004 1 P 0 
A 9.66171998 4.77491004 9.64451004 4.74185 9.60068996 4.78567067 1 P 0 Y
L 9.64451004 4.74185 9.6445 4.74183002 1 P 0 
A 9.6445 4.74183002 9.63304724 4.7341815 9.61955719 4.76678002 1 P 0 Y
A 9.63304724 4.7341815 9.61953996 4.7315 9.61955591 4.76678002 1 P 0 Y
L 9.61953996 4.7315 9.60735 4.7315 1 P 0 
A 9.60735 4.7315 9.59785482 4.73295177 9.60730305 4.76296998 1 P 0 Y
A 9.59785482 4.73295177 9.58923996 4.7372 9.60730276 4.76296998 1 P 0 Y
L 9.58923996 4.7372 9.56498002 4.75421004 1 P 0 
L 9.56498002 4.75421004 9.56143002 4.75776004 1 P 0 
A 9.56143002 4.75776004 9.55230453 4.76385807 9.54153839 4.73786998 1 P 0 N
A 9.55230453 4.76385807 9.54153996 4.766 9.54153809 4.73786998 1 P 0 N
A 9.54153996 4.766 9.49126998 4.74516004 9.54151909 4.695 1 P 0 N
L 9.49126998 4.74516004 9.41176004 4.66548002 1 P 0 
L 9.41176004 4.66548002 9.39526998 4.64193002 1 P 0 
L 9.39526998 4.64193002 9.38553996 4.58683002 1 P 0 
L 9.38553996 4.58683002 9.38553996 4.57948996 1 P 0 
A 9.38553996 4.57948996 9.38917884 4.55584567 9.46416004 4.5794875 1 P 0 N
A 9.38917884 4.55584567 9.39976004 4.53438996 9.46416004 4.57948671 1 P 0 N
L 9.39976004 4.53438996 9.47731998 4.42361004 1 P 0 
L 9.47731998 4.42361004 9.50218996 4.28258002 1 P 0 
L 9.50218996 4.28258002 9.46591998 4.07696004 1 P 0 
L 9.46591998 4.07696004 9.27945 3.81063996 1 P 0 
L 9.27945 3.81063996 8.95083996 3.58053002 1 P 0 
L 8.95083996 3.58053002 8.73985 3.54333002 1 P 0 
L 8.73985 3.54333002 8.69258002 3.55166004 1 P 0 
L 8.69258002 3.55166004 8.61461004 3.60623996 1 P 0 
A 8.61461004 3.60623996 8.56759242 3.62942352 8.51576722 3.46505 1 P 0 N
A 8.56759242 3.62942352 8.51578002 3.6374 8.51576703 3.46505 1 P 0 N
L 8.51578002 3.6374 8.5037 3.6374 1 P 0 
L 8.5037 3.6374 8.50328002 3.63738002 1 P 0 
A 8.50328002 3.63738002 8.50093799 3.63616476 8.50370325 3.6337 1 P 0 N
A 8.50093799 3.63616476 8.5 3.6337 8.5037 3.63370276 1 P 0 N
L 8.5 3.6337 8.5 3.61615 1 P 0 
P 8.5 3.66615 5 P 0 0;2=3,4=1
P 9.52531004 5.14 5 P 0 0;2=3,4=1
L 9.52531004 5.14 9.53753996 5.14 1 P 0 
A 9.53753996 5.14 9.54196004 5.13558002 9.53754006 5.13558002 1 P 0 Y
L 9.54196004 5.13558002 9.54196004 5.10596998 1 P 0 
L 9.54196004 5.10596998 9.55043002 5.0975 1 P 0 
L 9.55043002 5.0975 9.5627 5.0975 1 P 0 
L 9.5627 5.0975 9.5682 5.092 1 P 0 
L 9.5682 5.092 9.5793 5.092 1 P 0 
L 9.5793 5.092 9.5848 5.0975 1 P 0 
L 9.5848 5.0975 9.61436998 5.0975 1 P 0 
L 9.61436998 5.0975 9.62283002 5.09601004 1 P 0 
L 9.62283002 5.09601004 9.63753002 5.08571004 1 P 0 
L 9.63753002 5.08571004 9.64148002 5.08008002 1 P 0 
L 9.64148002 5.08008002 9.65178996 5.02145 1 P 0 
L 9.65178996 5.02145 9.64841004 5.01663996 1 P 0 
L 9.64841004 5.01663996 9.65033996 5.00568996 1 P 0 
L 9.65033996 5.00568996 9.65516004 5.00233002 1 P 0 
L 9.65516004 5.00233002 9.67471998 4.89178002 1 P 0 
L 9.67471998 4.89178002 9.65433002 4.77621004 1 P 0 
A 9.65433002 4.77621004 9.6392 4.74715 9.60068996 4.7856688 1 P 0 Y
L 9.6392 4.74715 9.63918996 4.74713996 1 P 0 
A 9.63918996 4.74713996 9.63017451 4.74111496 9.6195436 4.76678002 1 P 0 Y
A 9.63017451 4.74111496 9.61953996 4.739 9.61954272 4.76678002 1 P 0 Y
L 9.61953996 4.739 9.60733996 4.739 1 P 0 
A 9.60733996 4.739 9.60011024 4.74010561 9.6073062 4.76296998 1 P 0 Y
A 9.60011024 4.74010561 9.59355 4.74333996 9.60730551 4.76296998 1 P 0 Y
L 9.59355 4.74333996 9.56983002 4.75998002 1 P 0 
L 9.56983002 4.75998002 9.56673996 4.76306998 1 P 0 
A 9.56673996 4.76306998 9.55517844 4.77079695 9.54154173 4.73788002 1 P 0 N
A 9.55517844 4.77079695 9.54153996 4.77351004 9.54154124 4.73788002 1 P 0 N
A 9.54153996 4.77351004 9.48596004 4.75046004 9.54152992 4.695 1 P 0 N
L 9.48596004 4.75046004 9.40598996 4.67031998 1 P 0 
L 9.40598996 4.67031998 9.38816998 4.64486998 1 P 0 
L 9.38816998 4.64486998 9.37803996 4.58748996 1 P 0 
L 9.37803996 4.58748996 9.37803996 4.5795 1 P 0 
A 9.37803996 4.5795 9.39361004 4.53008002 9.46416004 4.57946998 1 P 0 N
L 9.39361004 4.53008002 9.47021998 4.42066998 1 P 0 
L 9.47021998 4.42066998 9.49456998 4.28258002 1 P 0 
L 9.49456998 4.28258002 9.45881998 4.0799 1 P 0 
L 9.45881998 4.0799 9.27406004 3.81603002 1 P 0 
L 9.27406004 3.81603002 8.9479 3.58763002 1 P 0 
L 8.9479 3.58763002 8.73985 3.55095 1 P 0 
L 8.73985 3.55095 8.69551998 3.55876004 1 P 0 
L 8.69551998 3.55876004 8.61891998 3.61238996 1 P 0 
A 8.61891998 3.61238996 8.51578996 3.6449 8.5157812 3.46503996 1 P 0 N
L 8.51578996 3.6449 8.50346004 3.6449 1 P 0 
L 8.50346004 3.6449 8.50328002 3.64491998 1 P 0 
A 8.50328002 3.64491998 8.50093799 3.64613524 8.50370325 3.6486 1 P 0 Y
A 8.50093799 3.64613524 8.5 3.6486 8.5037 3.64859724 1 P 0 Y
L 8.5 3.6486 8.5 3.66615 1 P 0 
P 8.35 3.66615 5 P 0 0;2=3,4=1
P 9.56531004 4.71973002 5 P 0 0;2=3,4=1
L 8.35 3.66615 8.35 3.6837 1 P 0 
A 8.35 3.6837 8.35093799 3.68616476 8.3537 3.68370276 1 P 0 Y
A 8.35093799 3.68616476 8.35328002 3.68738002 8.35370325 3.6837 1 P 0 Y
L 8.35328002 3.68738002 8.3537 3.6874 1 P 0 
L 8.3537 3.6874 8.41293996 3.6874 1 P 0 
A 8.41293996 3.6874 8.42125 3.67908996 8.41293996 3.67908996 1 P 0 Y
L 8.42125 3.67908996 8.42125 3.65923002 1 P 0 
A 8.42125 3.65923002 8.42563996 3.64863996 8.43621998 3.65923071 1 P 0 N
L 8.42563996 3.64863996 8.43118002 3.6431 1 P 0 
A 8.43118002 3.6431 8.4374878 3.6388812 8.44492766 3.65683002 1 P 0 N
A 8.4374878 3.6388812 8.44493002 3.6374 8.44492864 3.65683002 1 P 0 N
L 8.44493002 3.6374 8.4651 3.6374 1 P 0 
A 8.4651 3.6374 8.47125 3.63125 8.4651 3.63125 1 P 0 Y
L 8.47125 3.63125 8.47125 3.60221004 1 P 0 
A 8.47125 3.60221004 8.48606004 3.5874 8.48606004 3.60221004 1 P 0 N
L 8.48606004 3.5874 8.56965 3.5874 1 P 0 
A 8.56965 3.5874 8.57731476 3.58621959 8.56964616 3.5619 1 P 0 Y
A 8.57731476 3.58621959 8.58426998 3.58278996 8.56964596 3.5619 1 P 0 Y
L 8.58426998 3.58278996 8.66213996 3.52826004 1 P 0 
L 8.66213996 3.52826004 8.73098002 3.51298002 1 P 0 
L 8.73098002 3.51298002 8.94836998 3.5513 1 P 0 
L 8.94836998 3.5513 9.37941004 3.85313996 1 P 0 
L 9.37941004 3.85313996 9.53861004 4.08051004 1 P 0 
L 9.53861004 4.08051004 9.55273002 4.16058996 1 P 0 
L 9.55273002 4.16058996 9.50616998 4.42483002 1 P 0 
L 9.50616998 4.42483002 9.41963996 4.5485 1 P 0 
A 9.41963996 4.5485 9.4121252 4.56380571 9.46581004 4.58066614 1 P 0 Y
A 9.4121252 4.56380571 9.40953996 4.58066004 9.46581004 4.58066575 1 P 0 Y
L 9.40953996 4.58066004 9.40953996 4.58268996 1 P 0 
L 9.40953996 4.58268996 9.41893002 4.63598996 1 P 0 
L 9.41893002 4.63598996 9.42413002 4.64341004 1 P 0 
L 9.42413002 4.64341004 9.43496998 4.651 1 P 0 
L 9.43496998 4.651 9.53318002 4.651 1 P 0 
L 9.53318002 4.651 9.54946004 4.66728002 1 P 0 
L 9.54946004 4.66728002 9.54946004 4.71603002 1 P 0 
A 9.54946004 4.71603002 9.55316004 4.71973002 9.55316004 4.71603002 1 P 0 Y
L 9.55316004 4.71973002 9.56531004 4.71973002 1 P 0 
P 8.35 3.71615 5 P 0 0;2=3,4=1
P 9.52531004 4.71973002 5 P 0 0;2=3,4=1
L 8.35 3.71615 8.35 3.6986 1 P 0 
A 8.35 3.6986 8.35093799 3.69613524 8.3537 3.69859724 1 P 0 N
A 8.35093799 3.69613524 8.35328002 3.69491998 8.35370325 3.6986 1 P 0 N
L 8.35328002 3.69491998 8.35346004 3.6949 1 P 0 
L 8.35346004 3.6949 8.41293996 3.6949 1 P 0 
A 8.41293996 3.6949 8.42875 3.67908996 8.41293996 3.67908996 1 P 0 Y
L 8.42875 3.67908996 8.42875 3.65923002 1 P 0 
A 8.42875 3.65923002 8.43093996 3.65395 8.43621004 3.65923002 1 P 0 N
L 8.43093996 3.65395 8.43648996 3.6484 1 P 0 
A 8.43648996 3.6484 8.44036161 3.64581004 8.4449314 3.65683002 1 P 0 N
A 8.44036161 3.64581004 8.44493002 3.6449 8.44493169 3.65683002 1 P 0 N
L 8.44493002 3.6449 8.4651 3.6449 1 P 0 
A 8.4651 3.6449 8.47875 3.63125 8.4651 3.63125 1 P 0 Y
L 8.47875 3.63125 8.47875 3.60221004 1 P 0 
A 8.47875 3.60221004 8.48606004 3.5949 8.48606004 3.60221004 1 P 0 N
L 8.48606004 3.5949 8.56966004 3.5949 1 P 0 
A 8.56966004 3.5949 8.58858002 3.58893996 8.56966014 3.56188996 1 P 0 Y
L 8.58858002 3.58893996 8.66521998 3.53526004 1 P 0 
L 8.66521998 3.53526004 8.73115 3.52063002 1 P 0 
L 8.73115 3.52063002 8.94543002 3.5584 1 P 0 
L 8.94543002 3.5584 9.37401998 3.85853002 1 P 0 
L 9.37401998 3.85853002 9.53151004 4.08345 1 P 0 
L 9.53151004 4.08345 9.54511004 4.16058996 1 P 0 
L 9.54511004 4.16058996 9.49906998 4.42188996 1 P 0 
L 9.49906998 4.42188996 9.41348002 4.5442 1 P 0 
A 9.41348002 4.5442 9.40496634 4.56154803 9.46581004 4.58064449 1 P 0 Y
A 9.40496634 4.56154803 9.40203996 4.58065 9.46581004 4.58064429 1 P 0 Y
L 9.40203996 4.58065 9.40203996 4.58335 1 P 0 
L 9.40203996 4.58335 9.41183002 4.63893002 1 P 0 
L 9.41183002 4.63893002 9.41873996 4.64881004 1 P 0 
L 9.41873996 4.64881004 9.4326 4.6585 1 P 0 
L 9.4326 4.6585 9.44788002 4.6585 1 P 0 
L 9.44788002 4.6585 9.45238002 4.663 1 P 0 
L 9.45238002 4.663 9.46348002 4.663 1 P 0 
L 9.46348002 4.663 9.46798002 4.6585 1 P 0 
L 9.46798002 4.6585 9.47908002 4.6585 1 P 0 
L 9.47908002 4.6585 9.48358002 4.663 1 P 0 
L 9.48358002 4.663 9.49468002 4.663 1 P 0 
L 9.49468002 4.663 9.49918002 4.6585 1 P 0 
L 9.49918002 4.6585 9.53006998 4.6585 1 P 0 
L 9.53006998 4.6585 9.54196004 4.67038996 1 P 0 
L 9.54196004 4.67038996 9.54196004 4.71603002 1 P 0 
A 9.54196004 4.71603002 9.53826004 4.71973002 9.53826004 4.71603002 1 P 0 N
L 9.53826004 4.71973002 9.52531004 4.71973002 1 P 0 
P 8.74578996 5.14 5 P 0 0;2=3,4=1
P 8.05 3.61615 5 P 0 0;2=3,4=1
L 8.05 3.61615 8.05 3.6337 1 P 0 
A 8.05 3.6337 8.0463 3.6374 8.0463 3.6337 1 P 0 N
L 8.0463 3.6374 7.97313002 3.6374 1 P 0 
A 7.97313002 3.6374 7.94478415 3.64433455 7.97313219 3.69881004 1 P 0 Y
A 7.94478415 3.64433455 7.92283996 3.66356998 7.97313258 3.69881004 1 P 0 Y
L 7.92283996 3.66356998 7.92285 3.66356998 1 P 0 
L 7.92285 3.66356998 7.89355 3.70538996 1 P 0 
A 7.89355 3.70538996 7.88739154 3.71661654 7.9417 3.73910561 1 P 0 Y
A 7.88739154 3.71661654 7.88381004 3.72891004 7.9417 3.73910679 1 P 0 Y
L 7.88381004 3.72891004 7.86163002 3.85463996 1 P 0 
L 7.86163002 3.85463996 7.93785 4.28683996 1 P 0 
L 7.93785 4.28683996 8.04855 4.44495 1 P 0 
L 8.04855 4.44495 8.21033996 4.55823002 1 P 0 
L 8.21033996 4.55823002 8.32511998 4.57846998 1 P 0 
L 8.32511998 4.57846998 8.44756998 4.6642 1 P 0 
L 8.44756998 4.6642 8.44758002 4.66421004 1 P 0 
L 8.44758002 4.66421004 8.48838996 4.69278002 1 P 0 
L 8.48838996 4.69278002 8.53568002 4.76033996 1 P 0 
L 8.53568002 4.76033996 8.54028002 4.78638996 1 P 0 
A 8.54028002 4.78638996 8.54336683 4.79547323 8.57136004 4.780894 1 P 0 Y
A 8.54336683 4.79547323 8.54903996 4.80321004 8.57136004 4.78089518 1 P 0 Y
L 8.54903996 4.80321004 8.54906004 4.80323002 1 P 0 
A 8.54906004 4.80323002 8.58353996 4.81751004 8.58354124 4.76873996 1 P 0 Y
A 8.58353996 4.81751004 8.59914222 4.8206127 8.58354213 4.85828002 1 P 0 N
A 8.59914222 4.8206127 8.61236998 4.82945 8.58354301 4.85828002 1 P 0 N
L 8.61236998 4.82945 8.61238002 4.82946004 1 P 0 
A 8.61238002 4.82946004 8.61762579 4.83731043 8.59526004 4.84657776 1 P 0 N
A 8.61762579 4.83731043 8.61946998 4.84656998 8.59526004 4.84657835 1 P 0 N
A 8.61946998 4.84656998 8.59853996 4.86748996 8.5985499 4.84656998 1 P 0 N
A 8.59853996 4.86748996 8.57616004 4.87676004 8.59853996 4.89913996 1 P 0 Y
L 8.57616004 4.87676004 8.56823002 4.88468996 1 P 0 
A 8.56823002 4.88468996 8.56290807 4.89266043 8.58561004 4.90205669 1 P 0 Y
A 8.56290807 4.89266043 8.56103996 4.90206004 8.58561004 4.90205778 1 P 0 Y
L 8.56103996 4.90206004 8.56103996 4.90561004 1 P 0 
A 8.56103996 4.90561004 8.56332736 4.91715305 8.59118002 4.90563553 1 P 0 Y
A 8.56332736 4.91715305 8.56986004 4.92693996 8.59118002 4.90563533 1 P 0 Y
L 8.56986004 4.92693996 8.57311004 4.93018996 1 P 0 
A 8.57311004 4.93018996 8.59681998 4.94 8.59680866 4.90646998 1 P 0 Y
L 8.59681998 4.94 8.6144 4.94 1 P 0 
A 8.6144 4.94 8.62667638 4.94228425 8.61439833 4.97413996 1 P 0 N
A 8.62667638 4.94228425 8.63731004 4.94883002 8.61439843 4.97413996 1 P 0 N
A 8.63731004 4.94883002 8.63853996 4.95 8.61440502 4.97413996 1 P 0 N
L 8.63853996 4.95 8.63855 4.95 1 P 0 
A 8.63855 4.95 8.63855 4.99156004 8.61776998 4.97078002 1 P 0 N
L 8.63855 4.99156004 8.60806004 5.01291004 1 P 0 
L 8.60806004 5.01291004 8.59551004 5.0254 1 P 0 
A 8.59551004 5.0254 8.58750876 5.03858839 8.61846004 5.04834488 1 P 0 Y
A 8.58750876 5.03858839 8.5865 5.05398002 8.61846004 5.04834577 1 P 0 Y
L 8.5865 5.05398002 8.59031004 5.07553996 1 P 0 
L 8.59031004 5.07553996 8.62008996 5.11808996 1 P 0 
L 8.62008996 5.11808996 8.63853996 5.131 1 P 0 
L 8.63853996 5.131 8.66881998 5.13633002 1 P 0 
L 8.66881998 5.13633002 8.6839 5.13366998 1 P 0 
L 8.6839 5.13366998 8.71136004 5.11443996 1 P 0 
L 8.71136004 5.11443996 8.71136004 5.11443002 1 P 0 
L 8.71136004 5.11443002 8.72573002 5.10438002 1 P 0 
L 8.72573002 5.10438002 8.73636004 5.1025 1 P 0 
L 8.73636004 5.1025 8.74288996 5.1025 1 P 0 
A 8.74288996 5.1025 8.74860187 5.10364429 8.74287352 5.11741004 1 P 0 N
A 8.74860187 5.10364429 8.75343996 5.10688996 8.7428747 5.11741004 1 P 0 N
L 8.75343996 5.10688996 8.75813996 5.11161004 1 P 0 
L 8.75813996 5.11161004 8.75815 5.11161004 1 P 0 
A 8.75815 5.11161004 8.76102648 5.1159189 8.74873002 5.12101309 1 P 0 N
A 8.76102648 5.1159189 8.76203996 5.121 8.74873002 5.12101319 1 P 0 N
L 8.76203996 5.121 8.76203996 5.1355 1 P 0 
A 8.76203996 5.1355 8.75753996 5.14 8.75753996 5.1355 1 P 0 N
L 8.75753996 5.14 8.74578996 5.14 1 P 0 
P 8.78578996 5.14 5 P 0 0;2=3,4=1
P 8.05 3.66615 5 P 0 0;2=3,4=1
L 8.05 3.66615 8.05 3.6486 1 P 0 
A 8.05 3.6486 8.0463 3.6449 8.0463 3.6486 1 P 0 Y
L 8.0463 3.6449 7.97313002 3.6449 1 P 0 
A 7.97313002 3.6449 7.92898996 3.66788002 7.97312894 3.69878002 1 P 0 Y
L 7.92898996 3.66788002 7.8997 3.7097 1 P 0 
A 7.8997 3.7097 7.89432677 3.71948947 7.9417 3.73912224 1 P 0 Y
A 7.89432677 3.71948947 7.8912 3.73021004 7.9417 3.73912264 1 P 0 Y
L 7.8912 3.73021004 7.86925 3.85463996 1 P 0 
L 7.86925 3.85463996 7.94495 4.2839 1 P 0 
L 7.94495 4.2839 8.05393996 4.43956004 1 P 0 
L 8.05393996 4.43956004 8.21328002 4.55113002 1 P 0 
L 8.21328002 4.55113002 8.32806004 4.57136998 1 P 0 
L 8.32806004 4.57136998 8.49378002 4.68738996 1 P 0 
L 8.49378002 4.68738996 8.54278002 4.7574 1 P 0 
L 8.54278002 4.7574 8.54766998 4.78508002 1 P 0 
A 8.54766998 4.78508002 8.55002441 4.79200374 8.57136004 4.78088632 1 P 0 Y
A 8.55002441 4.79200374 8.55435 4.7979 8.57136004 4.78088632 1 P 0 Y
L 8.55435 4.7979 8.55436998 4.79791998 1 P 0 
A 8.55436998 4.79791998 8.58353996 4.81 8.58354045 4.76873996 1 P 0 Y
A 8.58353996 4.81 8.60201614 4.81367451 8.58354163 4.85828002 1 P 0 N
A 8.60201614 4.81367451 8.61768002 4.82413996 8.58354203 4.85828002 1 P 0 N
L 8.61768002 4.82413996 8.61768996 4.82415 1 P 0 
A 8.61768996 4.82415 8.62455728 4.83443238 8.59526004 4.84656476 1 P 0 N
A 8.62455728 4.83443238 8.62696998 4.84656004 8.59526004 4.84656467 1 P 0 N
L 8.62696998 4.84656004 8.62696998 4.84656998 1 P 0 
A 8.62696998 4.84656998 8.59853996 4.875 8.59853996 4.84656998 1 P 0 N
A 8.59853996 4.875 8.58146998 4.88206998 8.59853907 4.89913996 1 P 0 Y
L 8.58146998 4.88206998 8.57353996 4.89 1 P 0 
A 8.57353996 4.89 8.56853996 4.90206998 8.58561004 4.90207067 1 P 0 Y
L 8.56853996 4.90206998 8.56853996 4.90561998 1 P 0 
A 8.56853996 4.90561998 8.57026191 4.91428425 8.59116998 4.90562569 1 P 0 Y
A 8.57026191 4.91428425 8.57516998 4.92163002 8.59116998 4.90562707 1 P 0 Y
L 8.57516998 4.92163002 8.57841998 4.92488002 1 P 0 
A 8.57841998 4.92488002 8.5868623 4.93051929 8.59682205 4.90646998 1 P 0 Y
A 8.5868623 4.93051929 8.59681998 4.9325 8.59682185 4.90646998 1 P 0 Y
L 8.59681998 4.9325 8.61441004 4.9325 1 P 0 
A 8.61441004 4.9325 8.6293812 4.93528661 8.61440443 4.97413996 1 P 0 N
A 8.6293812 4.93528661 8.64235 4.94326998 8.61440532 4.97413996 1 P 0 N
A 8.64235 4.94326998 8.64386004 4.94468996 8.61784695 4.97083996 1 P 0 N
A 8.64386004 4.94468996 8.65466142 4.97112343 8.61776998 4.97077461 1 P 0 N
A 8.65466142 4.97112343 8.64336004 4.99735 8.61776998 4.97077461 1 P 0 N
L 8.64336004 4.99735 8.6129 5.01868996 1 P 0 
L 8.6129 5.01868996 8.60081998 5.03071004 1 P 0 
A 8.60081998 5.03071004 8.59466732 5.04084705 8.61846004 5.04835236 1 P 0 Y
A 8.59466732 5.04084705 8.59388996 5.05268002 8.61846004 5.04835217 1 P 0 Y
L 8.59388996 5.05268002 8.59741004 5.0726 1 P 0 
L 8.59741004 5.0726 8.60783996 5.08748996 1 P 0 
L 8.60783996 5.08748996 8.6154 5.08881004 1 P 0 
L 8.6154 5.08881004 8.62178002 5.09793002 1 P 0 
L 8.62178002 5.09793002 8.62043002 5.10548996 1 P 0 
L 8.62043002 5.10548996 8.62548002 5.1127 1 P 0 
L 8.62548002 5.1127 8.64148002 5.1239 1 P 0 
L 8.64148002 5.1239 8.66881998 5.12871004 1 P 0 
L 8.66881998 5.12871004 8.68096004 5.12656998 1 P 0 
L 8.68096004 5.12656998 8.69053002 5.11986998 1 P 0 
L 8.69053002 5.11986998 8.69161998 5.11353996 1 P 0 
L 8.69161998 5.11353996 8.70073996 5.10716004 1 P 0 
L 8.70073996 5.10716004 8.70705 5.10828996 1 P 0 
L 8.70705 5.10828996 8.72278996 5.09728002 1 P 0 
L 8.72278996 5.09728002 8.7357 5.095 1 P 0 
L 8.7357 5.095 8.74288002 5.095 1 P 0 
A 8.74288002 5.095 8.75147726 5.09671152 8.7428877 5.11741004 1 P 0 N
A 8.75147726 5.09671152 8.75876004 5.10158996 8.7428874 5.11741004 1 P 0 N
L 8.75876004 5.10158996 8.76346004 5.10631004 1 P 0 
A 8.76346004 5.10631004 8.76953996 5.12098996 8.74873002 5.12100974 1 P 0 N
L 8.76953996 5.12098996 8.76953996 5.136 1 P 0 
A 8.76953996 5.136 8.77353996 5.14 8.77353996 5.136 1 P 0 Y
L 8.77353996 5.14 8.78578996 5.14 1 P 0 
P 8.15 3.61615 5 P 0 0;2=3,4=1
P 8.88441004 5.17001998 5 P 0 0;2=3,4=1
L 8.15 3.61615 8.15 3.6337 1 P 0 
A 8.15 3.6337 8.14906201 3.63616476 8.1463 3.63370276 1 P 0 N
A 8.14906201 3.63616476 8.14671998 3.63738002 8.14629675 3.6337 1 P 0 N
L 8.14671998 3.63738002 8.1463 3.6374 1 P 0 
L 8.1463 3.6374 8.13833996 3.6374 1 P 0 
A 8.13833996 3.6374 8.12875 3.62781004 8.13833996 3.62781004 1 P 0 N
L 8.12875 3.62781004 8.12875 3.60255 1 P 0 
A 8.12875 3.60255 8.1136 3.5874 8.1136 3.60255 1 P 0 Y
L 8.1136 3.5874 8.03023996 3.5874 1 P 0 
A 8.03023996 3.5874 7.90068002 3.65483996 8.03024006 3.74556998 1 P 0 Y
L 7.90068002 3.65483996 7.87733002 3.6882 1 P 0 
A 7.87733002 3.6882 7.86178996 3.72575 7.95428996 3.74204045 1 P 0 Y
L 7.86178996 3.72575 7.83868996 3.85661998 1 P 0 
L 7.83868996 3.85661998 7.91596004 4.29491998 1 P 0 
L 7.91596004 4.29491998 8.03433002 4.46396998 1 P 0 
L 8.03433002 4.46396998 8.20088002 4.58063002 1 P 0 
L 8.20088002 4.58063002 8.3124 4.60031004 1 P 0 
L 8.3124 4.60031004 8.46896998 4.70991998 1 P 0 
L 8.46896998 4.70991998 8.4914 4.74195 1 P 0 
L 8.4914 4.74195 8.49138996 4.74195 1 P 0 
L 8.49138996 4.74195 8.51381004 4.77395 1 P 0 
L 8.51381004 4.77395 8.56831004 5.08303002 1 P 0 
L 8.56831004 5.08303002 8.62315 5.16138996 1 P 0 
L 8.62315 5.16138996 8.68626998 5.20558002 1 P 0 
L 8.68626998 5.20558002 8.7541 5.21753002 1 P 0 
L 8.7541 5.21753002 8.81418996 5.20693996 1 P 0 
A 8.81418996 5.20693996 8.82968996 5.19885 8.80907165 5.17823996 1 P 0 Y
L 8.82968996 5.19885 8.84153996 5.187 1 P 0 
A 8.84153996 5.187 8.84746033 5.17814075 8.82223002 5.16768789 1 P 0 Y
A 8.84746033 5.17814075 8.84953996 5.16768996 8.82223002 5.1676878 1 P 0 Y
L 8.84953996 5.16768996 8.84953996 5.162 1 P 0 
A 8.84953996 5.162 8.85064232 5.15645846 8.86403002 5.16200207 1 P 0 N
A 8.85064232 5.15645846 8.85378002 5.15176004 8.86403002 5.16200207 1 P 0 N
L 8.85378002 5.15176004 8.86388002 5.14166004 1 P 0 
A 8.86388002 5.14166004 8.87014695 5.13747156 8.87754272 5.15531998 1 P 0 N
A 8.87014695 5.13747156 8.87753996 5.136 8.87754262 5.15531998 1 P 0 N
L 8.87753996 5.136 8.88066998 5.136 1 P 0 
A 8.88066998 5.136 8.90066004 5.15598996 8.88067008 5.15598996 1 P 0 N
L 8.90066004 5.15598996 8.90066004 5.1649 1 P 0 
A 8.90066004 5.1649 8.89553996 5.17001998 8.89554006 5.1649 1 P 0 N
L 8.89553996 5.17001998 8.88441004 5.17001998 1 P 0 
P 8.15 3.66615 5 P 0 0;2=3,4=1
P 8.92441004 5.17001998 5 P 0 0;2=3,4=1
L 8.15 3.66615 8.15 3.6486 1 P 0 
A 8.15 3.6486 8.1463 3.6449 8.1463 3.6486 1 P 0 Y
L 8.1463 3.6449 8.13833996 3.6449 1 P 0 
A 8.13833996 3.6449 8.12125 3.62781004 8.13833996 3.62781004 1 P 0 N
L 8.12125 3.62781004 8.12125 3.60255 1 P 0 
A 8.12125 3.60255 8.1136 3.5949 8.1136 3.60255 1 P 0 Y
L 8.1136 3.5949 8.03023996 3.5949 1 P 0 
A 8.03023996 3.5949 7.96067333 3.6119249 8.03024163 3.74555 1 P 0 Y
A 7.96067333 3.6119249 7.90683002 3.65915 8.03024183 3.74555 1 P 0 Y
L 7.90683002 3.65915 7.88348002 3.69251004 1 P 0 
A 7.88348002 3.69251004 7.87444016 3.70899774 7.95428996 3.74205571 1 P 0 Y
A 7.87444016 3.70899774 7.86918002 3.72705 7.95428996 3.74205719 1 P 0 Y
L 7.86918002 3.72705 7.84631004 3.85661998 1 P 0 
L 7.84631004 3.85661998 7.92306004 4.29198002 1 P 0 
L 7.92306004 4.29198002 8.03971998 4.45858002 1 P 0 
L 8.03971998 4.45858002 8.20381998 4.57353002 1 P 0 
L 8.20381998 4.57353002 8.31533996 4.59321004 1 P 0 
L 8.31533996 4.59321004 8.47436004 4.70453002 1 P 0 
L 8.47436004 4.70453002 8.52091004 4.77101004 1 P 0 
L 8.52091004 4.77101004 8.57541004 5.08008996 1 P 0 
L 8.57541004 5.08008996 8.62853996 5.156 1 P 0 
L 8.62853996 5.156 8.63883002 5.16321004 1 P 0 
L 8.63883002 5.16321004 8.64453996 5.16218996 1 P 0 
L 8.64453996 5.16218996 8.65365 5.16856998 1 P 0 
L 8.65365 5.16856998 8.65463002 5.17426998 1 P 0 
L 8.65463002 5.17426998 8.66373996 5.18065 1 P 0 
L 8.66373996 5.18065 8.66946004 5.17963002 1 P 0 
L 8.66946004 5.17963002 8.67856998 5.18601004 1 P 0 
L 8.67856998 5.18601004 8.67955 5.19171004 1 P 0 
L 8.67955 5.19171004 8.67955 5.19171998 1 P 0 
L 8.67955 5.19171998 8.68921004 5.19848002 1 P 0 
L 8.68921004 5.19848002 8.7541 5.20991004 1 P 0 
L 8.7541 5.20991004 8.81288002 5.19955 1 P 0 
A 8.81288002 5.19955 8.81909065 5.19742677 8.80906299 5.17823996 1 P 0 Y
A 8.81909065 5.19742677 8.82438002 5.19353996 8.80906427 5.17823996 1 P 0 Y
L 8.82438002 5.19353996 8.83623002 5.18168996 1 P 0 
A 8.83623002 5.18168996 8.84052884 5.17526339 8.82223002 5.16767411 1 P 0 Y
A 8.84052884 5.17526339 8.84203996 5.16768002 8.82223002 5.1676748 1 P 0 Y
L 8.84203996 5.16768002 8.84203996 5.162 1 P 0 
L 8.84203996 5.162 8.84203002 5.16198996 1 P 0 
A 8.84203002 5.16198996 8.8437061 5.15358002 8.86403002 5.16200256 1 P 0 N
A 8.8437061 5.15358002 8.84846998 5.14645 8.86403002 5.16200285 1 P 0 N
L 8.84846998 5.14645 8.85856998 5.13635 1 P 0 
A 8.85856998 5.13635 8.87753996 5.1285 8.87752913 5.15531998 1 P 0 N
L 8.87753996 5.1285 8.88066998 5.1285 1 P 0 
A 8.88066998 5.1285 8.90816004 5.15598996 8.88067008 5.15598996 1 P 0 N
L 8.90816004 5.15598996 8.90816004 5.16631998 1 P 0 
A 8.90816004 5.16631998 8.91186004 5.17001998 8.91186004 5.16631998 1 P 0 Y
L 8.91186004 5.17001998 8.92441004 5.17001998 1 P 0 
P 5.855 0.925 6 P 0 0;2=1,4=1
P 3.88 4.545 6 P 0 0;2=2,4=1
L 5.855 0.925 5.83175 0.90175 2 P 0 
L 5.83175 0.90175 4.91055 0.90175 2 P 0 
L 4.91055 0.90175 3.9038 1.9085 2 P 0 
L 3.9038 1.9085 3.9038 4.3612 2 P 0 
L 3.9038 4.3612 3.88 4.385 2 P 0 
L 3.88 4.385 3.88 4.545 2 P 0 
P 8.1 3.81615 5 P 0 0;2=3,4=1
P 9.10011004 5.0535 5 P 0 0;2=3,4=1
L 9.10011004 5.0535 9.11253996 5.0535 1 P 0 
A 9.11253996 5.0535 9.11636004 5.05731998 9.11254006 5.05731998 1 P 0 N
L 9.11636004 5.05731998 9.11636004 5.09081004 1 P 0 
A 9.11636004 5.09081004 9.11433848 5.10098307 9.08976004 5.09081152 1 P 0 N
A 9.11433848 5.10098307 9.10858002 5.10961004 9.08976004 5.0908124 1 P 0 N
L 9.10858002 5.10961004 9.10651998 5.11166998 1 P 0 
A 9.10651998 5.11166998 9.10282116 5.11413691 9.09847234 5.10361004 1 P 0 N
A 9.10282116 5.11413691 9.09846004 5.115 9.09847185 5.10361004 1 P 0 N
L 9.09846004 5.115 9.08916998 5.115 1 P 0 
L 9.08916998 5.115 9.07683996 5.11281004 1 P 0 
L 9.07683996 5.11281004 9.06171004 5.10221004 1 P 0 
L 9.06171004 5.10221004 9.06058002 5.09573002 1 P 0 
L 9.06058002 5.09573002 9.05146004 5.08935 1 P 0 
L 9.05146004 5.08935 9.04498996 5.09051004 1 P 0 
L 9.04498996 5.09051004 9.03586998 5.08413002 1 P 0 
L 9.03586998 5.08413002 9.03473996 5.07765 1 P 0 
L 9.03473996 5.07765 9.02561998 5.07126998 1 P 0 
L 9.02561998 5.07126998 9.01915 5.07243002 1 P 0 
L 9.01915 5.07243002 9.00973002 5.06583996 1 P 0 
L 9.00973002 5.06583996 8.93181998 4.95455 1 P 0 
L 8.93181998 4.95455 8.92198996 4.89893002 1 P 0 
L 8.92198996 4.89893002 8.92881998 4.8602 1 P 0 
L 8.92881998 4.8602 8.92171998 4.81996004 1 P 0 
L 8.92171998 4.81996004 8.92426998 4.80545 1 P 0 
L 8.92426998 4.80545 8.93466998 4.79061004 1 P 0 
L 8.93466998 4.79061004 8.96176004 4.77163002 1 P 0 
L 8.96176004 4.77163002 8.9907 4.73028996 1 P 0 
L 8.9907 4.73028996 8.99855 4.68581004 1 P 0 
L 8.99855 4.68581004 8.99441998 4.66235 1 P 0 
L 8.99441998 4.66235 8.99738996 4.64548996 1 P 0 
L 8.99738996 4.64548996 8.99361998 4.62413002 1 P 0 
L 8.99361998 4.62413002 8.97685 4.60016004 1 P 0 
L 8.97685 4.60016004 8.8492 4.51078002 1 P 0 
L 8.8492 4.51078002 8.75448002 4.49408996 1 P 0 
A 8.75448002 4.49408996 8.736 4.48446004 8.76051083 4.45996998 1 P 0 N
A 8.736 4.48446004 8.72413937 4.45903819 8.765 4.45545226 1 P 0 N
A 8.72413937 4.45903819 8.73138996 4.43193996 8.765 4.45545197 1 P 0 N
L 8.73138996 4.43193996 8.74076004 4.41855 1 P 0 
L 8.74076004 4.41855 8.74076004 4.41853002 1 P 0 
L 8.74076004 4.41853002 8.74078002 4.41848996 1 P 0 
L 8.74078002 4.41848996 8.77291998 4.38465 1 P 0 
A 8.77291998 4.38465 8.78235098 4.36058514 8.74805 4.36102303 1 P 0 Y
A 8.78235098 4.36058514 8.77231004 4.33676998 8.74805 4.36102283 1 P 0 Y
L 8.77231004 4.33676998 8.76441004 4.32886998 1 P 0 
A 8.76441004 4.32886998 8.7394 4.3185 8.739381 4.35388996 1 P 0 Y
L 8.7394 4.3185 8.7374 4.3185 1 P 0 
A 8.7374 4.3185 8.72586152 4.32027087 8.73738219 4.35686004 1 P 0 Y
A 8.72586152 4.32027087 8.71538996 4.32543002 8.73738169 4.35686004 1 P 0 Y
L 8.71538996 4.32543002 8.67338002 4.35483996 1 P 0 
A 8.67338002 4.35483996 8.65881289 4.36202441 8.6427376 4.31106998 1 P 0 N
A 8.65881289 4.36202441 8.64276004 4.3645 8.6427376 4.31106998 1 P 0 N
L 8.64276004 4.3645 8.63561004 4.3645 1 P 0 
A 8.63561004 4.3645 8.61586004 4.35631998 8.63560906 4.33656998 1 P 0 N
L 8.61586004 4.35631998 8.61585 4.35631004 1 P 0 
A 8.61585 4.35631004 8.61340157 4.35264882 8.62383002 4.34832411 1 P 0 N
A 8.61340157 4.35264882 8.61253996 4.34833002 8.62383002 4.34832293 1 P 0 N
L 8.61253996 4.34833002 8.61253996 4.34488002 1 P 0 
A 8.61253996 4.34488002 8.61813002 4.33141004 8.63158996 4.34489085 1 P 0 N
L 8.61813002 4.33141004 8.62836004 4.32118002 1 P 0 
A 8.62836004 4.32118002 8.65503996 4.25676998 8.56395 4.25676939 1 P 0 Y
A 8.65503996 4.25676998 8.64873898 4.22510463 8.57228996 4.25677657 1 P 0 Y
A 8.64873898 4.22510463 8.6308 4.19826004 8.57228996 4.25677569 1 P 0 Y
L 8.6308 4.19826004 8.62133002 4.18878996 1 P 0 
A 8.62133002 4.18878996 8.5860935 4.17235778 8.58114734 4.22896004 1 P 0 Y
A 8.5860935 4.17235778 8.54853996 4.18243002 8.58114734 4.22896004 1 P 0 Y
L 8.54853996 4.18243002 8.52131998 4.2015 1 P 0 
A 8.52131998 4.2015 8.50814449 4.20503602 8.50987776 4.18518002 1 P 0 N
A 8.50814449 4.20503602 8.49578002 4.19926998 8.50987746 4.18518002 1 P 0 N
L 8.49578002 4.19926998 8.49576998 4.19926004 1 P 0 
A 8.49576998 4.19926004 8.48965 4.18751004 8.51136004 4.18367116 1 P 0 N
L 8.48965 4.18751004 8.48433996 4.15741004 1 P 0 
A 8.48433996 4.15741004 8.42761998 4.04846004 8.28318996 4.19289045 1 P 0 Y
A 8.42761998 4.04846004 8.24665 3.97351004 8.24666033 4.22943996 1 P 0 Y
L 8.24665 3.97351004 8.24596004 3.97351004 1 P 0 
L 8.24596004 3.97351004 8.14338996 3.99158996 1 P 0 
A 8.14338996 3.99158996 8.12255 3.98501004 8.13929104 3.96828002 1 P 0 N
A 8.12255 3.98501004 8.1198 3.98088996 8.13156998 3.97601171 1 P 0 N
A 8.1198 3.98088996 8.11645 3.96923996 8.17011004 3.96011644 1 P 0 N
L 8.11645 3.96923996 8.11518996 3.96183002 1 P 0 
A 8.11518996 3.96183002 8.11243996 3.9293 8.3064 3.92928435 1 P 0 N
L 8.11243996 3.9293 8.11243996 3.92891998 1 P 0 
A 8.11243996 3.92891998 8.11656004 3.91898002 8.12648996 3.92891978 1 P 0 N
L 8.11656004 3.91898002 8.11658002 3.91896004 1 P 0 
A 8.11658002 3.91896004 8.12558661 3.90548573 8.08721998 3.8895877 1 P 0 Y
A 8.12558661 3.90548573 8.12875 3.88958996 8.08721998 3.8895878 1 P 0 Y
L 8.12875 3.88958996 8.12875 3.8497 1 P 0 
A 8.12875 3.8497 8.11645 3.8374 8.11645 3.8497 1 P 0 Y
L 8.11645 3.8374 8.1037 3.8374 1 P 0 
A 8.1037 3.8374 8.1 3.8337 8.1037 3.8337 1 P 0 N
L 8.1 3.8337 8.1 3.81615 1 P 0 
P 8.1 3.86615 5 P 0 0;2=3,4=1
P 9.14011004 5.0535 5 P 0 0;2=3,4=1
L 9.14011004 5.0535 9.12756004 5.0535 1 P 0 
A 9.12756004 5.0535 9.12386004 5.0572 9.12756004 5.0572 1 P 0 Y
L 9.12386004 5.0572 9.12386004 5.09081004 1 P 0 
A 9.12386004 5.09081004 9.11388996 5.11491004 9.08975 5.09081112 1 P 0 N
L 9.11388996 5.11491004 9.11181998 5.11698002 1 P 0 
A 9.11181998 5.11698002 9.10568917 5.12106841 9.09847549 5.10361004 1 P 0 N
A 9.10568917 5.12106841 9.09846004 5.1225 9.09847559 5.10361004 1 P 0 N
L 9.09846004 5.1225 9.0885 5.1225 1 P 0 
L 9.0885 5.1225 9.07388996 5.11991004 1 P 0 
L 9.07388996 5.11991004 9.00433996 5.07123002 1 P 0 
L 9.00433996 5.07123002 8.92471998 4.95748996 1 P 0 
L 8.92471998 4.95748996 8.91436998 4.89893002 1 P 0 
L 8.91436998 4.89893002 8.91458996 4.89763002 1 P 0 
L 8.91458996 4.89763002 8.9146 4.89763002 1 P 0 
L 8.9146 4.89763002 8.9212 4.8602 1 P 0 
L 8.9212 4.8602 8.9141 4.81996004 1 P 0 
L 8.9141 4.81996004 8.91716998 4.80251004 1 P 0 
L 8.91716998 4.80251004 8.92928002 4.78521998 1 P 0 
L 8.92928002 4.78521998 8.9439 4.77496998 1 P 0 
L 8.9439 4.77496998 8.94391004 4.77496998 1 P 0 
L 8.94391004 4.77496998 8.95636998 4.76623996 1 P 0 
L 8.95636998 4.76623996 8.9836 4.72735 1 P 0 
L 8.9836 4.72735 8.99093002 4.68581004 1 P 0 
L 8.99093002 4.68581004 8.9868 4.66235 1 P 0 
L 8.9868 4.66235 8.98976998 4.64548996 1 P 0 
L 8.98976998 4.64548996 8.98651998 4.62706998 1 P 0 
L 8.98651998 4.62706998 8.97146004 4.60555 1 P 0 
L 8.97146004 4.60555 8.84626004 4.51788002 1 P 0 
L 8.84626004 4.51788002 8.75318002 4.50148002 1 P 0 
A 8.75318002 4.50148002 8.73068996 4.48976998 8.7604997 4.45996998 1 P 0 N
A 8.73068996 4.48976998 8.71666132 4.45969734 8.765 4.4554562 1 P 0 N
A 8.71666132 4.45969734 8.72523996 4.42763996 8.765 4.4554564 1 P 0 N
L 8.72523996 4.42763996 8.73406004 4.41503002 1 P 0 
L 8.73406004 4.41503002 8.73426004 4.41473002 1 P 0 
L 8.73426004 4.41473002 8.73456004 4.41413002 1 P 0 
L 8.73456004 4.41413002 8.76748002 4.37948002 1 P 0 
A 8.76748002 4.37948002 8.77484449 4.36068356 8.74805 4.36102638 1 P 0 Y
A 8.77484449 4.36068356 8.767 4.34208002 8.74805 4.36102628 1 P 0 Y
L 8.767 4.34208002 8.7591 4.33418002 1 P 0 
A 8.7591 4.33418002 8.75005846 4.32813041 8.73936762 4.35388996 1 P 0 Y
A 8.75005846 4.32813041 8.73938996 4.326 8.73936752 4.35388996 1 P 0 Y
L 8.73938996 4.326 8.7374 4.326 1 P 0 
A 8.7374 4.326 8.72812067 4.32742756 8.73739656 4.35685 1 P 0 Y
A 8.72812067 4.32742756 8.7197 4.33158002 8.73739547 4.35685 1 P 0 Y
L 8.7197 4.33158002 8.67768996 4.36098996 1 P 0 
A 8.67768996 4.36098996 8.66107628 4.36918002 8.64275532 4.31106998 1 P 0 N
A 8.66107628 4.36918002 8.64276998 4.372 8.64275443 4.31106998 1 P 0 N
L 8.64276998 4.372 8.63561004 4.372 1 P 0 
A 8.63561004 4.372 8.61055 4.36163002 8.6355997 4.33656004 1 P 0 N
L 8.61055 4.36163002 8.61053996 4.36161998 1 P 0 
A 8.61053996 4.36161998 8.60646998 4.35552687 8.62383002 4.34833681 1 P 0 N
A 8.60646998 4.35552687 8.60503996 4.34833996 8.62383002 4.34833691 1 P 0 N
L 8.60503996 4.34833996 8.60503996 4.34486998 1 P 0 
A 8.60503996 4.34486998 8.60706811 4.33471043 8.63158996 4.34488789 1 P 0 N
A 8.60706811 4.33471043 8.61283002 4.3261 8.63158996 4.34488681 1 P 0 N
L 8.61283002 4.3261 8.61281998 4.3261 1 P 0 
L 8.61281998 4.3261 8.62305 4.31586998 1 P 0 
A 8.62305 4.31586998 8.64753002 4.25676998 8.56395 4.25676998 1 P 0 Y
A 8.64753002 4.25676998 8.64180089 4.22797844 8.57228996 4.25677598 1 P 0 Y
A 8.64180089 4.22797844 8.62548996 4.20356998 8.57228996 4.2567749 1 P 0 Y
L 8.62548996 4.20356998 8.61601998 4.1941 1 P 0 
A 8.61601998 4.1941 8.58544045 4.17984134 8.58114675 4.22896998 1 P 0 Y
A 8.58544045 4.17984134 8.55285 4.18858002 8.58114685 4.22896998 1 P 0 Y
L 8.55285 4.18858002 8.52563002 4.20765 1 P 0 
A 8.52563002 4.20765 8.50749154 4.21251732 8.50987805 4.18518002 1 P 0 N
A 8.50749154 4.21251732 8.49046998 4.20458002 8.50987776 4.18518002 1 P 0 N
L 8.49046998 4.20458002 8.49046004 4.20456998 1 P 0 
A 8.49046004 4.20456998 8.48514803 4.19732067 8.51136998 4.18367707 1 P 0 N
A 8.48514803 4.19732067 8.48226004 4.18881004 8.51136998 4.18367717 1 P 0 N
L 8.48226004 4.18881004 8.47695 4.15871004 1 P 0 
A 8.47695 4.15871004 8.42231004 4.05376998 8.28318996 4.19290167 1 P 0 Y
A 8.42231004 4.05376998 8.24665 3.98101004 8.24665118 4.22943002 1 P 0 Y
L 8.24665 3.98101004 8.24661998 3.98101004 1 P 0 
L 8.24661998 3.98101004 8.14468996 3.99898002 1 P 0 
A 8.14468996 3.99898002 8.12991073 3.99800561 8.13929232 3.96828002 1 P 0 N
A 8.12991073 3.99800561 8.11725 3.99031998 8.13929232 3.96828002 1 P 0 N
L 8.11725 3.99031998 8.11723996 3.99031004 1 P 0 
A 8.11723996 3.99031004 8.11286998 3.98376004 8.13158002 3.97600994 1 P 0 N
A 8.11286998 3.98376004 8.10905 3.9705 8.1701 3.96009282 1 P 0 N
L 8.10905 3.9705 8.10778996 3.96308996 1 P 0 
A 8.10778996 3.96308996 8.10493996 3.92931004 8.3064 3.92932313 1 P 0 N
L 8.10493996 3.92931004 8.10493996 3.92891998 1 P 0 
A 8.10493996 3.92891998 8.11125 3.91366998 8.1265 3.92891043 1 P 0 N
L 8.11125 3.91366998 8.11126998 3.91365 1 P 0 
A 8.11126998 3.91365 8.11865502 3.90260768 8.08721998 3.8895748 1 P 0 Y
A 8.11865502 3.90260768 8.12125 3.88958002 8.08721998 3.88957382 1 P 0 Y
L 8.12125 3.88958002 8.12125 3.8497 1 P 0 
A 8.12125 3.8497 8.11645 3.8449 8.11645 3.8497 1 P 0 Y
L 8.11645 3.8449 8.1037 3.8449 1 P 0 
L 8.1037 3.8449 8.10328002 3.84491998 1 P 0 
A 8.10328002 3.84491998 8.10093799 3.84613524 8.10370325 3.8486 1 P 0 Y
A 8.10093799 3.84613524 8.1 3.8486 8.1037 3.84859724 1 P 0 Y
L 8.1 3.8486 8.1 3.86615 1 P 0 
P 8.35 3.81615 5 P 0 0;2=3,4=1
P 9.28185 5.22001998 5 P 0 0;2=3,4=1
L 8.35 3.81615 8.35 3.8337 1 P 0 
A 8.35 3.8337 8.3537 3.8374 8.3537 3.8337 1 P 0 Y
L 8.3537 3.8374 8.36126004 3.8374 1 P 0 
A 8.36126004 3.8374 8.37875 3.85488996 8.36126004 3.85488996 1 P 0 N
L 8.37875 3.85488996 8.37875 3.88308002 1 P 0 
A 8.37875 3.88308002 8.38049616 3.89185846 8.40168002 3.88308179 1 P 0 Y
A 8.38049616 3.89185846 8.38546998 3.8993 8.40168002 3.88308238 1 P 0 Y
L 8.38546998 3.8993 8.4044 3.91823996 1 P 0 
A 8.4044 3.91823996 8.41292618 3.92449724 8.42898346 3.89368002 1 P 0 Y
A 8.41292618 3.92449724 8.42293996 3.9279 8.42898317 3.89368002 1 P 0 Y
L 8.42293996 3.9279 8.5185 3.94473996 1 P 0 
L 8.5185 3.94473996 8.64391004 3.92263996 1 P 0 
A 8.64391004 3.92263996 8.65743927 3.91804222 8.63573504 3.87638002 1 P 0 Y
A 8.65743927 3.91804222 8.66896004 3.90958996 8.63573445 3.87638002 1 P 0 Y
L 8.66896004 3.90958996 8.67338996 3.90516004 1 P 0 
A 8.67338996 3.90516004 8.68386467 3.88949774 8.63925 3.8709939 1 P 0 Y
A 8.68386467 3.88949774 8.68755 3.87101998 8.63925 3.87099311 1 P 0 Y
L 8.68755 3.87101998 8.68755 3.871 1 P 0 
A 8.68755 3.871 8.69048346 3.85622077 8.72616004 3.87098278 1 P 0 N
A 8.69048346 3.85622077 8.69885 3.84368996 8.72616004 3.87098268 1 P 0 N
L 8.69885 3.84368996 8.71473002 3.82781004 1 P 0 
L 8.71473002 3.82781004 8.71485 3.82781004 1 P 0 
A 8.71485 3.82781004 8.79653996 3.83 8.75453967 3.872 1 P 0 N
L 8.79653996 3.83 8.83908002 3.87253996 1 P 0 
A 8.83908002 3.87253996 9.02726998 3.9505 9.02729124 3.68433002 1 P 0 Y
L 9.02726998 3.9505 9.0435 3.9505 1 P 0 
A 9.0435 3.9505 9.09091004 3.96218002 9.0435001 4.05256004 1 P 0 N
L 9.09091004 3.96218002 9.10781004 3.97105 1 P 0 
A 9.10781004 3.97105 9.11935906 3.97827215 9.06586496 4.05096998 1 P 0 N
A 9.11935906 3.97827215 9.12968996 3.98715 9.06586624 4.05096998 1 P 0 N
L 9.12968996 3.98715 9.15756004 4.01501998 1 P 0 
A 9.15756004 4.01501998 9.21978996 4.21236998 8.99911004 4.17347008 1 P 0 N
L 9.21978996 4.21236998 9.14503002 4.63651998 1 P 0 
L 9.14503002 4.63651998 9.14886998 4.65825 1 P 0 
L 9.14886998 4.65825 9.12451004 4.79633002 1 P 0 
L 9.12451004 4.79633002 9.13518002 4.85686004 1 P 0 
L 9.13518002 4.85686004 9.18351004 4.92591998 1 P 0 
L 9.18351004 4.92591998 9.20881004 5.06966998 1 P 0 
L 9.20881004 5.06966998 9.25733002 5.13898996 1 P 0 
L 9.25733002 5.13898996 9.2656 5.18588996 1 P 0 
L 9.2656 5.18588996 9.2656 5.21408002 1 P 0 
A 9.2656 5.21408002 9.27153996 5.22001998 9.27153996 5.21408002 1 P 0 Y
L 9.27153996 5.22001998 9.28185 5.22001998 1 P 0 
P 8.35 3.86615 5 P 0 0;2=3,4=1
P 9.24185 5.22001998 5 P 0 0;2=3,4=1
L 8.35 3.86615 8.35 3.8486 1 P 0 
A 8.35 3.8486 8.35093799 3.84613524 8.3537 3.84859724 1 P 0 N
A 8.35093799 3.84613524 8.35328002 3.84491998 8.35370325 3.8486 1 P 0 N
L 8.35328002 3.84491998 8.3537 3.8449 1 P 0 
L 8.3537 3.8449 8.36126004 3.8449 1 P 0 
A 8.36126004 3.8449 8.37125 3.85488996 8.36126004 3.85488996 1 P 0 N
L 8.37125 3.85488996 8.37125 3.88308002 1 P 0 
A 8.37125 3.88308002 8.37356348 3.8947312 8.40168996 3.88309104 1 P 0 Y
A 8.37356348 3.8947312 8.38016004 3.90461004 8.40168996 3.88309163 1 P 0 Y
L 8.38016004 3.90461004 8.39908996 3.92355 1 P 0 
A 8.39908996 3.92355 8.40946093 3.9311562 8.42897165 3.89368002 1 P 0 Y
A 8.40946093 3.9311562 8.42163996 3.93528996 8.42897195 3.89368002 1 P 0 Y
L 8.42163996 3.93528996 8.45876998 3.94183996 1 P 0 
L 8.45876998 3.94183996 8.46236998 3.94696998 1 P 0 
L 8.46236998 3.94696998 8.47331998 3.94891004 1 P 0 
L 8.47331998 3.94891004 8.47843996 3.9453 1 P 0 
L 8.47843996 3.9453 8.48938996 3.94723996 1 P 0 
L 8.48938996 3.94723996 8.49298002 3.95236998 1 P 0 
L 8.49298002 3.95236998 8.50393996 3.95431004 1 P 0 
L 8.50393996 3.95431004 8.50906004 3.9507 1 P 0 
L 8.50906004 3.9507 8.5185 3.95236004 1 P 0 
L 8.5185 3.95236004 8.64521004 3.93003002 1 P 0 
A 8.64521004 3.93003002 8.66090443 3.92470128 8.63574596 3.87638002 1 P 0 Y
A 8.66090443 3.92470128 8.67426998 3.9149 8.63574577 3.87638002 1 P 0 Y
L 8.67426998 3.9149 8.6787 3.91046998 1 P 0 
A 8.6787 3.91046998 8.69079734 3.89237037 8.63923996 3.87100325 1 P 0 Y
A 8.69079734 3.89237037 8.69505 3.87101998 8.63923996 3.87100226 1 P 0 Y
L 8.69505 3.87101998 8.69505 3.871 1 P 0 
A 8.69505 3.871 8.69741614 3.8590935 8.72615 3.87099203 1 P 0 N
A 8.69741614 3.8590935 8.70416004 3.849 8.72615 3.87099213 1 P 0 N
L 8.70416004 3.849 8.71785 3.83531004 1 P 0 
A 8.71785 3.83531004 8.71986998 3.8334 8.7544938 3.87203996 1 P 0 N
L 8.71986998 3.8334 8.71988002 3.8334 1 P 0 
A 8.71988002 3.8334 8.75593632 3.82013632 8.75454715 3.872 1 P 0 N
A 8.75593632 3.82013632 8.79123002 3.83531004 8.75454734 3.872 1 P 0 N
L 8.79123002 3.83531004 8.83376998 3.87785 1 P 0 
A 8.83376998 3.87785 8.92255404 3.93717018 9.02727756 3.68433002 1 P 0 Y
A 8.92255404 3.93717018 9.02728002 3.958 9.02727805 3.68433002 1 P 0 Y
L 9.02728002 3.958 9.0435 3.958 1 P 0 
A 9.0435 3.958 9.08741998 3.96883002 9.04347815 4.05256004 1 P 0 N
L 9.08741998 3.96883002 9.10431998 3.97768996 1 P 0 
A 9.10431998 3.97768996 9.12438002 3.99246004 9.06583927 4.05096004 1 P 0 N
L 9.12438002 3.99246004 9.15225 4.02033002 1 P 0 
A 9.15225 4.02033002 9.20566063 4.10834144 8.99911004 4.17347667 1 P 0 N
A 9.20566063 4.10834144 9.2124 4.21106998 8.99911004 4.17347726 1 P 0 N
L 9.2124 4.21106998 9.13741004 4.63651998 1 P 0 
L 9.13741004 4.63651998 9.14125 4.65825 1 P 0 
L 9.14125 4.65825 9.11688996 4.79633002 1 P 0 
L 9.11688996 4.79633002 9.12808002 4.8598 1 P 0 
L 9.12808002 4.8598 9.17641004 4.92886004 1 P 0 
L 9.17641004 4.92886004 9.20171004 5.07261004 1 P 0 
L 9.20171004 5.07261004 9.21308996 5.08886998 1 P 0 
L 9.21308996 5.08886998 9.21193002 5.09528002 1 P 0 
L 9.21193002 5.09528002 9.21831998 5.10438996 1 P 0 
L 9.21831998 5.10438996 9.22471998 5.1055 1 P 0 
L 9.22471998 5.1055 9.23111004 5.11461004 1 P 0 
L 9.23111004 5.11461004 9.22995 5.12101998 1 P 0 
L 9.22995 5.12101998 9.23633996 5.13013002 1 P 0 
L 9.23633996 5.13013002 9.24273996 5.13123996 1 P 0 
L 9.24273996 5.13123996 9.25023002 5.14193002 1 P 0 
L 9.25023002 5.14193002 9.2581 5.18655 1 P 0 
L 9.2581 5.18655 9.2581 5.21631998 1 P 0 
A 9.2581 5.21631998 9.2544 5.22001998 9.2544 5.21631998 1 P 0 N
L 9.2544 5.22001998 9.24185 5.22001998 1 P 0 
P 8.45 3.81615 5 P 0 0;2=3,4=1
P 9.21098002 4.78291998 5 P 0 0;2=3,4=1
L 9.21098002 4.78291998 9.19953996 4.78291998 1 P 0 
A 9.19953996 4.78291998 9.19513002 4.77851004 9.19953996 4.77851004 1 P 0 N
L 9.19513002 4.77851004 9.19513002 4.75241998 1 P 0 
L 9.19513002 4.75241998 9.17231004 4.62296998 1 P 0 
L 9.17231004 4.62296998 9.24896004 4.18806998 1 P 0 
A 9.24896004 4.18806998 9.25641535 4.16611083 9.32401004 4.20130492 1 P 0 N
A 9.25641535 4.16611083 9.27013002 4.14741004 9.32401004 4.20130354 1 P 0 N
L 9.27013002 4.14741004 9.28155 4.13598996 1 P 0 
A 9.28155 4.13598996 9.28984577 4.13044764 9.29963504 4.15408002 1 P 0 N
A 9.28984577 4.13044764 9.29963002 4.1285 9.29963593 4.15408002 1 P 0 N
L 9.29963002 4.1285 9.32303002 4.1285 1 P 0 
A 9.32303002 4.1285 9.34049537 4.12503268 9.3230561 4.08291004 1 P 0 Y
A 9.34049537 4.12503268 9.3553 4.11513996 9.32305581 4.08291004 1 P 0 Y
L 9.3553 4.11513996 9.35531004 4.11513996 1 P 0 
A 9.35531004 4.11513996 9.35758996 4.08696998 9.33946004 4.09967992 1 P 0 Y
L 9.35758996 4.08696998 9.32758002 4.04413002 1 P 0 
A 9.32758002 4.04413002 9.32035 4.03953002 9.31841063 4.05056004 1 P 0 Y
L 9.32035 4.03953002 9.21753002 4.02136998 1 P 0 
A 9.21753002 4.02136998 9.19953996 4.01201004 9.22339951 3.98811998 1 P 0 N
L 9.19953996 4.01201004 9.19953996 4.012 1 P 0 
A 9.19953996 4.012 9.18809921 3.99315157 9.23235 3.97918829 1 P 0 N
A 9.18809921 3.99315157 9.18665 3.97115 9.23235 3.97918829 1 P 0 N
L 9.18665 3.97115 9.19963996 3.89733996 1 P 0 
A 9.19963996 3.89733996 9.16451004 3.85548996 9.16451004 3.89115935 1 P 0 Y
A 9.16451004 3.85548996 9.15398671 3.85711467 9.16452352 3.89046998 1 P 0 Y
A 9.15398671 3.85711467 9.14443996 3.86183002 9.16452372 3.89046998 1 P 0 Y
L 9.14443996 3.86183002 9.10206004 3.89151004 1 P 0 
A 9.10206004 3.89151004 9.08850689 3.89819813 9.07356378 3.85083996 1 P 0 N
A 9.08850689 3.89819813 9.07356998 3.9005 9.07356289 3.85083996 1 P 0 N
L 9.07356998 3.9005 9.06818996 3.9005 1 P 0 
A 9.06818996 3.9005 9.02771004 3.86001998 9.06818996 3.86002008 1 P 0 N
L 9.02771004 3.86001998 9.02771004 3.85108002 1 P 0 
L 9.02771004 3.85108002 9.02776998 3.85101998 1 P 0 
L 9.02776998 3.85101998 9.02776998 3.84738002 1 P 0 
L 9.02776998 3.84738002 9.03793002 3.78971998 1 P 0 
A 9.03793002 3.78971998 9.03667333 3.77057884 8.99818996 3.78271722 1 P 0 Y
A 9.03667333 3.77057884 9.02671998 3.75418002 8.99818996 3.78271644 1 P 0 Y
L 9.02671998 3.75418002 9.02611004 3.75356998 1 P 0 
A 9.02611004 3.75356998 8.94691004 3.75356998 8.98651004 3.79316998 1 P 0 Y
L 8.94691004 3.75356998 8.90761004 3.79288002 1 P 0 
A 8.90761004 3.79288002 8.87293996 3.80723996 8.87294124 3.75821004 1 P 0 N
L 8.87293996 3.80723996 8.87201998 3.80723996 1 P 0 
L 8.87201998 3.80723996 8.872 3.80725 1 P 0 
A 8.872 3.80725 8.84875866 3.80236545 8.87289213 3.74526998 1 P 0 N
A 8.84875866 3.80236545 8.82906004 3.7891 8.87289193 3.74526998 1 P 0 N
L 8.82906004 3.7891 8.82905 3.78908996 1 P 0 
A 8.82905 3.78908996 8.82221526 3.77977234 8.85588996 3.76223652 1 P 0 N
A 8.82221526 3.77977234 8.8185 3.76883002 8.85588996 3.76223681 1 P 0 N
L 8.8185 3.76883002 8.80463002 3.69006998 1 P 0 
A 8.80463002 3.69006998 8.78990591 3.66457205 8.76223002 3.69755413 1 P 0 Y
A 8.78990591 3.66457205 8.76223996 3.6545 8.76223356 3.69755 1 P 0 Y
L 8.76223996 3.6545 8.76025 3.6545 1 P 0 
A 8.76025 3.6545 8.72298996 3.66993002 8.76024902 3.7072 1 P 0 Y
L 8.72298996 3.66993002 8.70326004 3.68966004 1 P 0 
A 8.70326004 3.68966004 8.68901004 3.71703996 8.73956004 3.72595069 1 P 0 Y
L 8.68901004 3.71703996 8.66688996 3.84248996 1 P 0 
A 8.66688996 3.84248996 8.65108996 3.87283996 8.61088002 3.83261929 1 P 0 N
L 8.65108996 3.87283996 8.63845 3.88546998 1 P 0 
A 8.63845 3.88546998 8.62967077 3.89287697 8.5903878 3.83741004 1 P 0 N
A 8.62967077 3.89287697 8.61976998 3.8987 8.59038573 3.83741004 1 P 0 N
A 8.61976998 3.8987 8.59915 3.90531998 8.58533337 3.82686004 1 P 0 N
L 8.59915 3.90531998 8.52723002 3.91801998 1 P 0 
A 8.52723002 3.91801998 8.52459321 3.91824006 8.52470394 3.90366004 1 P 0 N
A 8.52459321 3.91824006 8.52196004 3.91798002 8.52470364 3.90366004 1 P 0 N
L 8.52196004 3.91798002 8.50968002 3.91563996 1 P 0 
A 8.50968002 3.91563996 8.50336368 3.91342057 8.5138937 3.89355 1 P 0 N
A 8.50336368 3.91342057 8.49798002 3.90943996 8.51389222 3.89355 1 P 0 N
L 8.49798002 3.90943996 8.4848 3.89625 1 P 0 
A 8.4848 3.89625 8.47875 3.88166998 8.49936998 3.88165896 1 P 0 N
L 8.47875 3.88166998 8.47875 3.85488996 1 P 0 
A 8.47875 3.85488996 8.46126004 3.8374 8.46126004 3.85488996 1 P 0 Y
L 8.46126004 3.8374 8.4537 3.8374 1 P 0 
A 8.4537 3.8374 8.45 3.8337 8.4537 3.8337 1 P 0 N
L 8.45 3.8337 8.45 3.81615 1 P 0 
P 8.45 3.86615 5 P 0 0;2=3,4=1
P 9.17098002 4.78291998 5 P 0 0;2=3,4=1
L 9.17098002 4.78291998 9.18353996 4.78291998 1 P 0 
A 9.18353996 4.78291998 9.18763002 4.77883002 9.18354006 4.77883002 1 P 0 Y
L 9.18763002 4.77883002 9.18763002 4.75308002 1 P 0 
L 9.18763002 4.75308002 9.18203002 4.72138996 1 P 0 
L 9.18203002 4.72138996 9.1757 4.71696004 1 P 0 
L 9.1757 4.71696004 9.17376004 4.70601004 1 P 0 
L 9.17376004 4.70601004 9.17821004 4.69971004 1 P 0 
L 9.17821004 4.69971004 9.17626998 4.68876998 1 P 0 
L 9.17626998 4.68876998 9.16993996 4.68433996 1 P 0 
L 9.16993996 4.68433996 9.168 4.67338996 1 P 0 
L 9.168 4.67338996 9.17245 4.66708002 1 P 0 
L 9.17245 4.66708002 9.17245 4.66701004 1 P 0 
L 9.17245 4.66701004 9.16468996 4.62296998 1 P 0 
L 9.16468996 4.62296998 9.24156998 4.18676998 1 P 0 
A 9.24156998 4.18676998 9.26481998 4.1421 9.32401998 4.20129823 1 P 0 N
L 9.26481998 4.1421 9.27623996 4.13068002 1 P 0 
A 9.27623996 4.13068002 9.28696772 4.12351614 9.29962205 4.15408002 1 P 0 N
A 9.28696772 4.12351614 9.29961998 4.121 9.29962224 4.15408002 1 P 0 N
L 9.29961998 4.121 9.32303996 4.121 1 P 0 
A 9.32303996 4.121 9.33762648 4.11809734 9.32304232 4.08291004 1 P 0 Y
A 9.33762648 4.11809734 9.34998996 4.10983002 9.32304301 4.08291004 1 P 0 Y
L 9.34998996 4.10983002 9.35016004 4.10966004 1 P 0 
A 9.35016004 4.10966004 9.35143996 4.09128002 9.33946004 4.09968032 1 P 0 Y
L 9.35143996 4.09128002 9.32143996 4.04843996 1 P 0 
A 9.32143996 4.04843996 9.32039606 4.04744272 9.31840679 4.05056998 1 P 0 Y
A 9.32039606 4.04744272 9.31905 4.04691998 9.31840709 4.05056998 1 P 0 Y
L 9.31905 4.04691998 9.21623002 4.02876004 1 P 0 
A 9.21623002 4.02876004 9.19423002 4.01731004 9.22340167 3.98811998 1 P 0 N
A 9.19423002 4.01731004 9.18094065 3.99541132 9.23235 3.97919498 1 P 0 N
A 9.18094065 3.99541132 9.17926004 3.96985 9.23235 3.97919537 1 P 0 N
L 9.17926004 3.96985 9.19225 3.89603996 1 P 0 
A 9.19225 3.89603996 9.18608051 3.8730565 9.16451004 3.89116644 1 P 0 Y
A 9.18608051 3.8730565 9.16451004 3.863 9.1645062 3.89116998 1 P 0 Y
A 9.16451004 3.863 9.15624695 3.86427707 9.16452687 3.89048002 1 P 0 Y
A 9.15624695 3.86427707 9.14875 3.86798002 9.16452638 3.89048002 1 P 0 Y
L 9.14875 3.86798002 9.10636998 3.89766004 1 P 0 
A 9.10636998 3.89766004 9.07358002 3.908 9.07358051 3.85083996 1 P 0 N
L 9.07358002 3.908 9.06818996 3.908 1 P 0 
A 9.06818996 3.908 9.02021004 3.86001998 9.06818996 3.86002008 1 P 0 N
L 9.02021004 3.86001998 9.02021004 3.85108002 1 P 0 
L 9.02021004 3.85108002 9.02015 3.85101998 1 P 0 
L 9.02015 3.85101998 9.02015 3.84738002 1 P 0 
L 9.02015 3.84738002 9.03053996 3.78841998 1 P 0 
A 9.03053996 3.78841998 9.02951358 3.77283868 8.99818002 3.78272717 1 P 0 Y
A 9.02951358 3.77283868 9.02141004 3.75948996 8.99818002 3.78272608 1 P 0 Y
L 9.02141004 3.75948996 9.0208 3.75888002 1 P 0 
A 9.0208 3.75888002 8.95221998 3.75888002 8.98651004 3.79316998 1 P 0 Y
L 8.95221998 3.75888002 8.91291004 3.79818996 1 P 0 
L 8.91291004 3.79818996 8.91291004 3.7982 1 P 0 
A 8.91291004 3.7982 8.87293996 3.81475 8.87294045 3.75821004 1 P 0 N
L 8.87293996 3.81475 8.8729 3.81476004 1 P 0 
A 8.8729 3.81476004 8.87188996 3.81475 8.87308563 3.74526998 1 P 0 N
A 8.87188996 3.81475 8.82375 3.79441004 8.87287953 3.74526998 1 P 0 N
L 8.82375 3.79441004 8.82373996 3.7944 1 P 0 
A 8.82373996 3.7944 8.81555669 3.78323711 8.8559 3.76224321 1 P 0 N
A 8.81555669 3.78323711 8.81111004 3.77013002 8.8559 3.76224262 1 P 0 N
L 8.81111004 3.77013002 8.79723996 3.69136998 1 P 0 
A 8.79723996 3.69136998 8.78507884 3.67031457 8.76223002 3.69755118 1 P 0 Y
A 8.78507884 3.67031457 8.76223002 3.662 8.76223081 3.69755 1 P 0 Y
L 8.76223002 3.662 8.76026004 3.662 1 P 0 
A 8.76026004 3.662 8.74296309 3.66544144 8.7602623 3.7072 1 P 0 Y
A 8.74296309 3.66544144 8.7283 3.67523996 8.7602625 3.7072 1 P 0 Y
L 8.7283 3.67523996 8.70856998 3.69496998 1 P 0 
A 8.70856998 3.69496998 8.7006872 3.7057187 8.73956004 3.72596191 1 P 0 Y
A 8.7006872 3.7057187 8.6964 3.71833996 8.73956004 3.72596181 1 P 0 Y
L 8.6964 3.71833996 8.67428002 3.84378996 1 P 0 
A 8.67428002 3.84378996 8.6564 3.87815 8.61088002 3.83263051 1 P 0 N
L 8.6564 3.87815 8.64376004 3.89078002 1 P 0 
A 8.64376004 3.89078002 8.6340122 3.89899902 8.59040472 3.83738996 1 P 0 N
A 8.6340122 3.89899902 8.62301998 3.90546004 8.59040463 3.83738996 1 P 0 N
L 8.62301998 3.90546004 8.62301998 3.90546998 1 P 0 
A 8.62301998 3.90546998 8.61198219 3.90986063 8.58535413 3.82685 1 P 0 N
A 8.61198219 3.90986063 8.60045 3.91271004 8.58535354 3.82685 1 P 0 N
L 8.60045 3.91271004 8.52853002 3.92541004 1 P 0 
A 8.52853002 3.92541004 8.5245373 3.92574341 8.52470374 3.90366004 1 P 0 N
A 8.5245373 3.92574341 8.52055 3.92535 8.52470305 3.90366004 1 P 0 N
L 8.52055 3.92535 8.50828002 3.92301004 1 P 0 
A 8.50828002 3.92301004 8.49985325 3.92005472 8.51388376 3.89353996 1 P 0 N
A 8.49985325 3.92005472 8.49266998 3.91475 8.51388356 3.89353996 1 P 0 N
L 8.49266998 3.91475 8.48556004 3.90763996 1 P 0 
L 8.48556004 3.90763996 8.48556004 3.90763002 1 P 0 
L 8.48556004 3.90763002 8.47948996 3.90156004 1 P 0 
A 8.47948996 3.90156004 8.47339193 3.89243455 8.49938002 3.88166841 1 P 0 N
A 8.47339193 3.89243455 8.47125 3.88166998 8.49938002 3.88166811 1 P 0 N
L 8.47125 3.88166998 8.47125 3.85488996 1 P 0 
A 8.47125 3.85488996 8.46126004 3.8449 8.46126004 3.85488996 1 P 0 Y
L 8.46126004 3.8449 8.4537 3.8449 1 P 0 
L 8.4537 3.8449 8.45328002 3.84491998 1 P 0 
A 8.45328002 3.84491998 8.45093799 3.84613524 8.45370325 3.8486 1 P 0 Y
A 8.45093799 3.84613524 8.45 3.8486 8.4537 3.84859724 1 P 0 Y
L 8.45 3.8486 8.45 3.86615 1 P 0 
P 8.4 3.76615 5 P 0 0;2=3,4=1
P 9.28185 4.642 5 P 0 0;2=3,4=1
L 8.4 3.76615 8.4 3.7837 1 P 0 
A 8.4 3.7837 8.40093799 3.78616476 8.4037 3.78370276 1 P 0 Y
A 8.40093799 3.78616476 8.40328002 3.78738002 8.40370325 3.7837 1 P 0 Y
L 8.40328002 3.78738002 8.4037 3.7874 1 P 0 
L 8.4037 3.7874 8.41126004 3.7874 1 P 0 
A 8.41126004 3.7874 8.42125 3.77741004 8.41126004 3.77741004 1 P 0 Y
L 8.42125 3.77741004 8.42125 3.75215 1 P 0 
A 8.42125 3.75215 8.436 3.7374 8.436 3.75215 1 P 0 N
L 8.436 3.7374 8.55743002 3.7374 1 P 0 
A 8.55743002 3.7374 8.58571004 3.72848002 8.55742992 3.68811004 1 P 0 Y
L 8.58571004 3.72848002 8.62363996 3.70191004 1 P 0 
L 8.62363996 3.70191004 8.68293002 3.61723996 1 P 0 
L 8.68293002 3.61723996 8.69533002 3.60856004 1 P 0 
L 8.69533002 3.60856004 8.69561004 3.60836004 1 P 0 
L 8.69561004 3.60836004 8.69563996 3.60833996 1 P 0 
L 8.69563996 3.60833996 8.70306004 3.60313996 1 P 0 
L 8.70306004 3.60313996 8.70306998 3.60313996 1 P 0 
L 8.70306998 3.60313996 8.71186004 3.59698996 1 P 0 
L 8.71186004 3.59698996 8.73941004 3.59213002 1 P 0 
L 8.73941004 3.59213002 8.93571004 3.62673996 1 P 0 
L 8.93571004 3.62673996 9.24391998 3.84253002 1 P 0 
L 9.24391998 3.84253002 9.41351998 4.08431004 1 P 0 
A 9.41351998 4.08431004 9.42343533 4.12122047 9.36781004 4.11637628 1 P 0 N
A 9.42343533 4.12122047 9.40728996 4.15586004 9.36781004 4.11637618 1 P 0 N
L 9.40728996 4.15586004 9.40138002 4.16176998 1 P 0 
A 9.40138002 4.16176998 9.38339882 4.1737812 9.36218593 4.12256004 1 P 0 N
A 9.38339882 4.1737812 9.36218996 4.178 9.36218602 4.12256004 1 P 0 N
L 9.36218996 4.178 9.33715 4.178 1 P 0 
A 9.33715 4.178 9.3199562 4.18141959 9.33714695 4.22291998 1 P 0 Y
A 9.3199562 4.18141959 9.30538002 4.19116004 9.33714596 4.22291998 1 P 0 Y
L 9.30538002 4.19116004 9.30451998 4.19201998 1 P 0 
A 9.30451998 4.19201998 9.29828809 4.20134774 9.32485 4.21234813 1 P 0 Y
A 9.29828809 4.20134774 9.2961 4.21235 9.32485 4.21234902 1 P 0 Y
L 9.2961 4.21235 9.2961 4.21258002 1 P 0 
L 9.2961 4.21258002 9.29608996 4.21286998 1 P 0 
A 9.29608996 4.21286998 9.29681142 4.21860463 9.31466004 4.21344646 1 P 0 Y
A 9.29681142 4.21860463 9.29926004 4.22383996 9.31466004 4.21344695 1 P 0 Y
L 9.29926004 4.22383996 9.30263002 4.22883996 1 P 0 
A 9.30263002 4.22883996 9.30308996 4.22938996 9.30571998 4.22672323 1 P 0 Y
L 9.30308996 4.22938996 9.31101004 4.23731004 1 P 0 
A 9.31101004 4.23731004 9.31958346 4.24359439 9.3357125 4.2126 1 P 0 Y
A 9.31958346 4.24359439 9.32965 4.24701004 9.3357128 4.2126 1 P 0 Y
L 9.32965 4.24701004 9.40888996 4.26098996 1 P 0 
A 9.40888996 4.26098996 9.43753996 4.29513996 9.40285 4.29515 1 P 0 N
L 9.43753996 4.29513996 9.43753996 4.30058996 1 P 0 
A 9.43753996 4.30058996 9.39738996 4.33428002 9.40333022 4.30058996 1 P 0 N
L 9.39738996 4.33428002 9.3144 4.31963996 1 P 0 
L 9.3144 4.31963996 9.31438002 4.31963996 1 P 0 
A 9.31438002 4.31963996 9.28453996 4.332 9.31437982 4.36183996 1 P 0 Y
A 9.28453996 4.332 9.26256998 4.38503996 9.33758002 4.38504016 1 P 0 Y
L 9.26256998 4.38503996 9.26256998 4.3936 1 P 0 
A 9.26256998 4.3936 9.26292756 4.39734734 9.28148996 4.39368533 1 P 0 Y
A 9.26292756 4.39734734 9.26401998 4.40095 9.28148996 4.39368573 1 P 0 Y
L 9.26401998 4.40095 9.26978996 4.41478996 1 P 0 
L 9.26978996 4.41478996 9.29228002 4.44693002 1 P 0 
L 9.29228002 4.44693002 9.29545 4.46478002 1 P 0 
L 9.29545 4.46478002 9.29261998 4.48093996 1 P 0 
L 9.29261998 4.48093996 9.28183996 4.49628996 1 P 0 
L 9.28183996 4.49628996 9.2428 4.52363996 1 P 0 
L 9.2428 4.52363996 9.23928002 4.52866004 1 P 0 
L 9.23928002 4.52866004 9.23415 4.55773996 1 P 0 
L 9.23415 4.55773996 9.23586998 4.56751998 1 P 0 
L 9.23586998 4.56751998 9.266 4.61051004 1 P 0 
L 9.266 4.61051004 9.266 4.63746004 1 P 0 
A 9.266 4.63746004 9.27053996 4.642 9.27053996 4.63746004 1 P 0 Y
L 9.27053996 4.642 9.28185 4.642 1 P 0 
P 8.4 3.81615 5 P 0 0;2=3,4=1
P 9.24185 4.642 5 P 0 0;2=3,4=1
L 8.4 3.81615 8.4 3.7986 1 P 0 
A 8.4 3.7986 8.4037 3.7949 8.4037 3.7986 1 P 0 N
L 8.4037 3.7949 8.41126004 3.7949 1 P 0 
A 8.41126004 3.7949 8.42875 3.77741004 8.41126004 3.77741004 1 P 0 Y
L 8.42875 3.77741004 8.42875 3.75215 1 P 0 
A 8.42875 3.75215 8.436 3.7449 8.436 3.75215 1 P 0 N
L 8.436 3.7449 8.55743996 3.7449 1 P 0 
A 8.55743996 3.7449 8.57452057 3.74227274 8.55744715 3.68811004 1 P 0 Y
A 8.57452057 3.74227274 8.59001998 3.73463002 8.55744705 3.68811004 1 P 0 Y
L 8.59001998 3.73463002 8.60898996 3.72133002 1 P 0 
L 8.60898996 3.72133002 8.60898996 3.72133996 1 P 0 
L 8.60898996 3.72133996 8.62903002 3.7073 1 P 0 
L 8.62903002 3.7073 8.68831998 3.62263002 1 P 0 
L 8.68831998 3.62263002 8.69963996 3.6147 1 P 0 
L 8.69963996 3.6147 8.69971998 3.61465 1 P 0 
L 8.69971998 3.61465 8.69981004 3.61458996 1 P 0 
L 8.69981004 3.61458996 8.69988002 3.61453996 1 P 0 
L 8.69988002 3.61453996 8.69991998 3.61451004 1 P 0 
L 8.69991998 3.61451004 8.69995 3.61448996 1 P 0 
L 8.69995 3.61448996 8.7148 3.60408996 1 P 0 
L 8.7148 3.60408996 8.73941004 3.59975 1 P 0 
L 8.73941004 3.59975 8.93276998 3.63383996 1 P 0 
L 8.93276998 3.63383996 9.23853002 3.84791998 1 P 0 
L 9.23853002 3.84791998 9.40738002 4.08861998 1 P 0 
A 9.40738002 4.08861998 9.40198002 4.15055 9.36781004 4.11637008 1 P 0 N
L 9.40198002 4.15055 9.39606998 4.15646004 1 P 0 
A 9.39606998 4.15646004 9.38052156 4.16685039 9.36217677 4.12256998 1 P 0 N
A 9.38052156 4.16685039 9.36218002 4.1705 9.36217677 4.12256998 1 P 0 N
L 9.36218002 4.1705 9.33715 4.1705 1 P 0 
A 9.33715 4.1705 9.31708268 4.17448612 9.33713297 4.22291998 1 P 0 Y
A 9.31708268 4.17448612 9.30006998 4.18585 9.33713307 4.22291998 1 P 0 Y
L 9.30006998 4.18585 9.29921004 4.18671004 1 P 0 
A 9.29921004 4.18671004 9.2886 4.21235 9.32486004 4.21233947 1 P 0 Y
L 9.2886 4.21235 9.2886 4.21245 1 P 0 
L 9.2886 4.21245 9.28858996 4.21261998 1 P 0 
L 9.28858996 4.21261998 9.28858996 4.21263996 1 P 0 
A 9.28858996 4.21263996 9.28959783 4.22068927 9.31466004 4.21346339 1 P 0 Y
A 9.28959783 4.22068927 9.29303002 4.22803996 9.31466004 4.21346388 1 P 0 Y
L 9.29303002 4.22803996 9.29641998 4.23305 1 P 0 
A 9.29641998 4.23305 9.29778002 4.2347 9.30573996 4.22675335 1 P 0 Y
L 9.29778002 4.2347 9.3057 4.24261998 1 P 0 
A 9.3057 4.24261998 9.31611821 4.25025295 9.33570699 4.21258996 1 P 0 Y
A 9.31611821 4.25025295 9.32835 4.2544 9.3357063 4.21258996 1 P 0 Y
L 9.32835 4.2544 9.40758002 4.26838002 1 P 0 
A 9.40758002 4.26838002 9.42367589 4.2776813 9.40284587 4.29515 1 P 0 N
A 9.42367589 4.2776813 9.43003002 4.29515 9.40285 4.29514656 1 P 0 N
L 9.43003002 4.29515 9.43003996 4.29515 1 P 0 
L 9.43003996 4.29515 9.43003996 4.30058996 1 P 0 
A 9.43003996 4.30058996 9.42049656 4.3210503 9.40333002 4.3005874 1 P 0 N
A 9.42049656 4.3210503 9.39868996 4.32688996 9.40333219 4.30058996 1 P 0 N
L 9.39868996 4.32688996 9.31506004 4.31213996 1 P 0 
L 9.31506004 4.31213996 9.31438996 4.31213996 1 P 0 
A 9.31438996 4.31213996 9.2953627 4.31591683 9.31436683 4.36183996 1 P 0 Y
A 9.2953627 4.31591683 9.27923002 4.32668996 9.31436594 4.36183996 1 P 0 Y
A 9.27923002 4.32668996 9.25506998 4.38503002 9.33758996 4.38503091 1 P 0 Y
L 9.25506998 4.38503002 9.25506998 4.39358002 1 P 0 
A 9.25506998 4.39358002 9.25556752 4.39881093 9.2815 4.39370522 1 P 0 Y
A 9.25556752 4.39881093 9.25708996 4.40383996 9.2815 4.39370532 1 P 0 Y
L 9.25708996 4.40383996 9.26316998 4.41843002 1 P 0 
L 9.26316998 4.41843002 9.28518002 4.44988002 1 P 0 
L 9.28518002 4.44988002 9.28783002 4.46478996 1 P 0 
L 9.28783002 4.46478996 9.28551004 4.47798996 1 P 0 
L 9.28551004 4.47798996 9.27646004 4.4909 1 P 0 
L 9.27646004 4.4909 9.26475 4.49908996 1 P 0 
L 9.26475 4.49908996 9.25856998 4.49798002 1 P 0 
L 9.25856998 4.49798002 9.24946004 4.50436004 1 P 0 
L 9.24946004 4.50436004 9.2484 4.51055 1 P 0 
L 9.2484 4.51055 9.23741004 4.51825 1 P 0 
L 9.23741004 4.51825 9.23218002 4.52571998 1 P 0 
L 9.23218002 4.52571998 9.22653002 4.55773996 1 P 0 
L 9.22653002 4.55773996 9.22876998 4.57046004 1 P 0 
L 9.22876998 4.57046004 9.24023996 4.58683996 1 P 0 
L 9.24023996 4.58683996 9.23906004 4.59345 1 P 0 
L 9.23906004 4.59345 9.24545 4.60256004 1 P 0 
L 9.24545 4.60256004 9.25206998 4.60371004 1 P 0 
L 9.25206998 4.60371004 9.2585 4.61288002 1 P 0 
L 9.2585 4.61288002 9.2585 4.6383 1 P 0 
A 9.2585 4.6383 9.2548 4.642 9.2548 4.6383 1 P 0 N
L 9.2548 4.642 9.24185 4.642 1 P 0 
P 8.45 3.66615 5 P 0 0;2=3,4=1
P 9.42358002 4.78291998 5 P 0 0;2=3,4=1
L 8.45 3.66615 8.45 3.6837 1 P 0 
A 8.45 3.6837 8.45093799 3.68616476 8.4537 3.68370276 1 P 0 Y
A 8.45093799 3.68616476 8.45328002 3.68738002 8.45370325 3.6837 1 P 0 Y
L 8.45328002 3.68738002 8.4537 3.6874 1 P 0 
L 8.4537 3.6874 8.57455 3.6874 1 P 0 
A 8.57455 3.6874 8.5821563 3.68623002 8.57454695 3.66206998 1 P 0 Y
A 8.5821563 3.68623002 8.58906004 3.68283002 8.57454685 3.66206998 1 P 0 Y
L 8.58906004 3.68283002 8.61441004 3.66508996 1 P 0 
L 8.61441004 3.66508996 8.65476998 3.60746998 1 P 0 
L 8.65476998 3.60746998 8.70198996 3.57441998 1 P 0 
L 8.70198996 3.57441998 8.7428 3.56728002 1 P 0 
L 8.7428 3.56728002 8.94035 3.60211004 1 P 0 
L 8.94035 3.60211004 9.2595 3.8256 1 P 0 
L 9.2595 3.8256 9.44323002 4.08796998 1 P 0 
L 9.44323002 4.08796998 9.47256004 4.25426998 1 P 0 
A 9.47256004 4.25426998 9.47436004 4.27495 9.35465 4.27495128 1 P 0 N
L 9.47436004 4.27495 9.47436004 4.29226998 1 P 0 
A 9.47436004 4.29226998 9.45463002 4.33991004 9.40698002 4.29227028 1 P 0 N
L 9.45463002 4.33991004 9.44246004 4.35208002 1 P 0 
A 9.44246004 4.35208002 9.43151772 4.35939193 9.41860876 4.32823002 1 P 0 N
A 9.43151772 4.35939193 9.41861004 4.36196004 9.41860846 4.32823002 1 P 0 N
L 9.41861004 4.36196004 9.41855 4.36196004 1 P 0 
L 9.41855 4.36196004 9.33765 4.34771004 1 P 0 
A 9.33765 4.34771004 9.32130197 4.34836043 9.33097165 4.38563002 1 P 0 Y
A 9.32130197 4.34836043 9.3067 4.35573996 9.33097156 4.38563002 1 P 0 Y
L 9.3067 4.35573996 9.30668002 4.35576004 1 P 0 
A 9.30668002 4.35576004 9.29634035 4.37123583 9.34041004 4.3894876 1 P 0 Y
A 9.29634035 4.37123583 9.29271004 4.38948996 9.34041004 4.38948829 1 P 0 Y
L 9.29271004 4.38948996 9.29271004 4.38953002 1 P 0 
A 9.29271004 4.38953002 9.30252037 4.41648504 9.33465 4.38952864 1 P 0 Y
A 9.30252037 4.41648504 9.32736004 4.43083002 9.33464892 4.38953002 1 P 0 Y
L 9.32736004 4.43083002 9.37373002 4.43901004 1 P 0 
A 9.37373002 4.43901004 9.39474144 4.45114104 9.36757077 4.47393996 1 P 0 N
A 9.39474144 4.45114104 9.40303996 4.47393996 9.36756998 4.47394085 1 P 0 N
A 9.40303996 4.47393996 9.39440807 4.49765827 9.36613996 4.47394065 1 P 0 N
A 9.39440807 4.49765827 9.37255 4.51028002 9.36613898 4.47393996 1 P 0 N
L 9.37255 4.51028002 9.32478996 4.5187 1 P 0 
L 9.32478996 4.5187 9.27701998 4.52711998 1 P 0 
L 9.27701998 4.52711998 9.27093002 4.53138996 1 P 0 
L 9.27093002 4.53138996 9.26521998 4.53955 1 P 0 
L 9.26521998 4.53955 9.26521998 4.53953996 1 P 0 
L 9.26521998 4.53953996 9.2627 4.55386004 1 P 0 
L 9.2627 4.55386004 9.26485 4.56608002 1 P 0 
L 9.26485 4.56608002 9.2734 4.5783 1 P 0 
L 9.2734 4.5783 9.28958996 4.58961998 1 P 0 
L 9.28958996 4.58961998 9.34311998 4.59908002 1 P 0 
L 9.34311998 4.59908002 9.36008996 4.61093002 1 P 0 
L 9.36008996 4.61093002 9.36531998 4.6184 1 P 0 
L 9.36531998 4.6184 9.37216998 4.65716004 1 P 0 
L 9.37216998 4.65716004 9.40085 4.69813996 1 P 0 
L 9.40085 4.69813996 9.40773002 4.73698996 1 P 0 
L 9.40773002 4.73698996 9.40773002 4.77921998 1 P 0 
A 9.40773002 4.77921998 9.41143002 4.78291998 9.41143002 4.77921998 1 P 0 Y
L 9.41143002 4.78291998 9.42358002 4.78291998 1 P 0 
P 8.45 3.71615 5 P 0 0;2=3,4=1
P 9.38358002 4.78291998 5 P 0 0;2=3,4=1
L 8.45 3.71615 8.45 3.6986 1 P 0 
A 8.45 3.6986 8.45093799 3.69613524 8.4537 3.69859724 1 P 0 N
A 8.45093799 3.69613524 8.45328002 3.69491998 8.45370325 3.6986 1 P 0 N
L 8.45328002 3.69491998 8.45346004 3.6949 1 P 0 
L 8.45346004 3.6949 8.57456004 3.6949 1 P 0 
A 8.57456004 3.6949 8.58441457 3.69338415 8.57455394 3.66206998 1 P 0 Y
A 8.58441457 3.69338415 8.59336004 3.68898002 8.57455453 3.66206998 1 P 0 Y
L 8.59336004 3.68898002 8.60603996 3.68011004 1 P 0 
L 8.60603996 3.68011004 8.60605 3.6801 1 P 0 
L 8.60605 3.6801 8.6198 3.67048002 1 P 0 
L 8.6198 3.67048002 8.66016004 3.61286004 1 P 0 
L 8.66016004 3.61286004 8.70493002 3.58153002 1 P 0 
L 8.70493002 3.58153002 8.74278996 3.5749 1 P 0 
L 8.74278996 3.5749 8.93741004 3.60921004 1 P 0 
L 8.93741004 3.60921004 9.25411004 3.83098996 1 P 0 
L 9.25411004 3.83098996 9.43613002 4.09091004 1 P 0 
L 9.43613002 4.09091004 9.46516998 4.25556998 1 P 0 
A 9.46516998 4.25556998 9.46686004 4.27496004 9.35465 4.27497175 1 P 0 N
L 9.46686004 4.27496004 9.46686004 4.29226998 1 P 0 
A 9.46686004 4.29226998 9.46229892 4.31517923 9.40698002 4.29225679 1 P 0 N
A 9.46229892 4.31517923 9.44931998 4.3346 9.40698002 4.29225679 1 P 0 N
L 9.44931998 4.3346 9.43715 4.34676998 1 P 0 
A 9.43715 4.34676998 9.41916004 4.35445 9.41860089 4.32823002 1 P 0 N
L 9.41916004 4.35445 9.33895 4.34031998 1 P 0 
A 9.33895 4.34031998 9.31922283 4.34114872 9.33097244 4.38563002 1 P 0 Y
A 9.31922283 4.34114872 9.30166004 4.35016998 9.33097264 4.38563002 1 P 0 Y
L 9.30166004 4.35016998 9.30136998 4.35046004 1 P 0 
L 9.30136998 4.35046004 9.30136998 4.35045 1 P 0 
A 9.30136998 4.35045 9.28940689 4.3683623 9.34041004 4.3894747 1 P 0 Y
A 9.28940689 4.3683623 9.28521004 4.38948996 9.34041004 4.38947431 1 P 0 Y
L 9.28521004 4.38948996 9.28521004 4.38953002 1 P 0 
A 9.28521004 4.38953002 9.29677461 4.42130827 9.33465 4.3895315 1 P 0 Y
A 9.29677461 4.42130827 9.32606004 4.43821998 9.33465167 4.38953002 1 P 0 Y
L 9.32606004 4.43821998 9.37243002 4.4464 1 P 0 
A 9.37243002 4.4464 9.38899803 4.45596417 9.36757667 4.47393996 1 P 0 N
A 9.38899803 4.45596417 9.39553996 4.47393996 9.36758002 4.47393711 1 P 0 N
A 9.39553996 4.47393996 9.3886624 4.49283504 9.36613996 4.47393799 1 P 0 N
A 9.3886624 4.49283504 9.37125 4.50288996 9.36614193 4.47393996 1 P 0 N
L 9.37125 4.50288996 9.27408002 4.52001998 1 P 0 
L 9.27408002 4.52001998 9.26553996 4.526 1 P 0 
L 9.26553996 4.526 9.25811998 4.5366 1 P 0 
L 9.25811998 4.5366 9.25508002 4.55386004 1 P 0 
L 9.25508002 4.55386004 9.25775 4.56901998 1 P 0 
L 9.25775 4.56901998 9.26801004 4.58368996 1 P 0 
L 9.26801004 4.58368996 9.28665 4.59671998 1 P 0 
L 9.28665 4.59671998 9.30898996 4.60066998 1 P 0 
L 9.30898996 4.60066998 9.31206004 4.60508996 1 P 0 
L 9.31206004 4.60508996 9.32301004 4.60703002 1 P 0 
L 9.32301004 4.60703002 9.32743002 4.60393002 1 P 0 
L 9.32743002 4.60393002 9.34018002 4.60618002 1 P 0 
L 9.34018002 4.60618002 9.35468996 4.61631998 1 P 0 
L 9.35468996 4.61631998 9.35821998 4.62133996 1 P 0 
L 9.35821998 4.62133996 9.36506998 4.6601 1 P 0 
L 9.36506998 4.6601 9.37388996 4.67273002 1 P 0 
L 9.37388996 4.67273002 9.37251004 4.68051998 1 P 0 
L 9.37251004 4.68051998 9.3789 4.68961998 1 P 0 
L 9.3789 4.68961998 9.38668002 4.69098996 1 P 0 
L 9.38668002 4.69098996 9.39375 4.70108002 1 P 0 
L 9.39375 4.70108002 9.40023002 4.73765 1 P 0 
L 9.40023002 4.73765 9.40023002 4.77921998 1 P 0 
A 9.40023002 4.77921998 9.39653002 4.78291998 9.39653002 4.77921998 1 P 0 N
L 9.39653002 4.78291998 9.38358002 4.78291998 1 P 0 
P 8.4 3.61615 5 P 0 0;2=3,4=1
P 9.49445 4.587 5 P 0 0;2=3,4=1
L 8.4 3.61615 8.4 3.6337 1 P 0 
A 8.4 3.6337 8.40093799 3.63616476 8.4037 3.63370276 1 P 0 Y
A 8.40093799 3.63616476 8.40328002 3.63738002 8.40370325 3.6337 1 P 0 Y
L 8.40328002 3.63738002 8.4037 3.6374 1 P 0 
L 8.4037 3.6374 8.40816998 3.6374 1 P 0 
A 8.40816998 3.6374 8.4108 3.63631004 8.40816919 3.63368002 1 P 0 Y
L 8.4108 3.63631004 8.4108 3.6363 1 P 0 
L 8.4108 3.6363 8.42015 3.62695 1 P 0 
L 8.42015 3.62695 8.42016004 3.62695 1 P 0 
A 8.42016004 3.62695 8.42125 3.62431998 8.41753002 3.62431919 1 P 0 Y
L 8.42125 3.62431998 8.42125 3.55461004 1 P 0 
A 8.42125 3.55461004 8.43846004 3.5374 8.43846004 3.55461004 1 P 0 N
L 8.43846004 3.5374 8.58206998 3.5374 1 P 0 
A 8.58206998 3.5374 8.59110787 3.53601142 8.58207717 3.50733996 1 P 0 Y
A 8.59110787 3.53601142 8.59931004 3.53196998 8.58207736 3.50733996 1 P 0 Y
L 8.59931004 3.53196998 8.64285 3.5015 1 P 0 
L 8.64285 3.5015 8.73026004 3.48608002 1 P 0 
L 8.73026004 3.48608002 8.95356004 3.52546004 1 P 0 
L 8.95356004 3.52546004 9.3968 3.83585 1 P 0 
L 9.3968 3.83585 9.56446998 4.07526998 1 P 0 
L 9.56446998 4.07526998 9.63351998 4.46696004 1 P 0 
L 9.63351998 4.46696004 9.63353002 4.46696004 1 P 0 
L 9.63353002 4.46696004 9.64246004 4.51761004 1 P 0 
L 9.64246004 4.51761004 9.64245 4.51761004 1 P 0 
A 9.64245 4.51761004 9.64261998 4.51955 9.63141998 4.51955394 1 P 0 N
L 9.64261998 4.51955 9.64261998 4.51956998 1 P 0 
A 9.64261998 4.51956998 9.6400562 4.53247195 9.60891004 4.51957707 1 P 0 N
A 9.6400562 4.53247195 9.63275 4.54341004 9.60891004 4.51957677 1 P 0 N
L 9.63275 4.54341004 9.63008002 4.54608002 1 P 0 
A 9.63008002 4.54608002 9.59225 4.56173996 9.59225965 4.50823996 1 P 0 N
L 9.59225 4.56173996 9.58736004 4.56173996 1 P 0 
A 9.58736004 4.56173996 9.58083061 4.56109833 9.58736565 4.52813996 1 P 0 N
A 9.58083061 4.56109833 9.57455 4.5592 9.58736516 4.52813996 1 P 0 N
L 9.57455 4.5592 9.56696004 4.55606998 1 P 0 
L 9.56696004 4.55606998 9.56686004 4.55611998 1 P 0 
L 9.56686004 4.55611998 9.56683002 4.55611004 1 P 0 
L 9.56683002 4.55611004 9.56351004 4.55473002 1 P 0 
L 9.56351004 4.55473002 9.51951998 4.52393002 1 P 0 
L 9.51951998 4.52393002 9.50628002 4.5216 1 P 0 
L 9.50628002 4.5216 9.49678996 4.52328002 1 P 0 
L 9.49678996 4.52328002 9.4941 4.52516004 1 P 0 
L 9.4941 4.52516004 9.49408002 4.52518002 1 P 0 
L 9.49408002 4.52518002 9.49093996 4.52738002 1 P 0 
L 9.49093996 4.52738002 9.48016004 4.54278002 1 P 0 
L 9.48016004 4.54278002 9.47871998 4.55096004 1 P 0 
L 9.47871998 4.55096004 9.47871004 4.55096998 1 P 0 
L 9.47871004 4.55096998 9.47871004 4.5833 1 P 0 
A 9.47871004 4.5833 9.48241004 4.587 9.48241004 4.5833 1 P 0 Y
L 9.48241004 4.587 9.49445 4.587 1 P 0 
P 8.4 3.66615 5 P 0 0;2=3,4=1
P 9.45445 4.587 5 P 0 0;2=3,4=1
L 8.4 3.66615 8.4 3.6486 1 P 0 
A 8.4 3.6486 8.4037 3.6449 8.4037 3.6486 1 P 0 N
L 8.4037 3.6449 8.40818002 3.6449 1 P 0 
A 8.40818002 3.6449 8.41247195 3.6440435 8.40817234 3.63368002 1 P 0 Y
A 8.41247195 3.6440435 8.41611004 3.64161004 8.40817283 3.63368002 1 P 0 Y
L 8.41611004 3.64161004 8.42546004 3.63226004 1 P 0 
A 8.42546004 3.63226004 8.4278935 3.62862195 8.41753002 3.62432283 1 P 0 Y
A 8.4278935 3.62862195 8.42875 3.62433002 8.41753002 3.62432234 1 P 0 Y
L 8.42875 3.62433002 8.42875 3.55461004 1 P 0 
A 8.42875 3.55461004 8.43846004 3.5449 8.43846004 3.55461004 1 P 0 N
L 8.43846004 3.5449 8.58206998 3.5449 1 P 0 
A 8.58206998 3.5449 8.59336654 3.5431685 8.5820939 3.50733996 1 P 0 Y
A 8.59336654 3.5431685 8.60361998 3.53811998 8.58209508 3.50733996 1 P 0 Y
L 8.60361998 3.53811998 8.64578996 3.5086 1 P 0 
L 8.64578996 3.5086 8.73026004 3.4937 1 P 0 
L 8.73026004 3.4937 8.95061998 3.53256004 1 P 0 
L 8.95061998 3.53256004 9.39141004 3.84123996 1 P 0 
L 9.39141004 3.84123996 9.55736998 4.07821004 1 P 0 
L 9.55736998 4.07821004 9.62611998 4.46823996 1 P 0 
L 9.62611998 4.46823996 9.62108002 4.47541998 1 P 0 
L 9.62108002 4.47541998 9.62301998 4.48636998 1 P 0 
L 9.62301998 4.48636998 9.63018996 4.49138002 1 P 0 
L 9.63018996 4.49138002 9.63506004 4.51893002 1 P 0 
A 9.63506004 4.51893002 9.63511998 4.51956998 9.63141998 4.5195937 1 P 0 N
A 9.63511998 4.51956998 9.63312264 4.52959843 9.60891004 4.51956289 1 P 0 N
A 9.63312264 4.52959843 9.62743996 4.5381 9.60891004 4.51956407 1 P 0 N
L 9.62743996 4.5381 9.62476998 4.54076998 1 P 0 
A 9.62476998 4.54076998 9.59226004 4.55423996 9.5922503 4.50825 1 P 0 N
L 9.59226004 4.55423996 9.58736998 4.55423996 1 P 0 
A 9.58736998 4.55423996 9.57741004 4.55226004 9.58737963 4.52815 1 P 0 N
L 9.57741004 4.55226004 9.56983002 4.54913002 1 P 0 
L 9.56983002 4.54913002 9.56978002 4.54901004 1 P 0 
L 9.56978002 4.54901004 9.56645 4.54761998 1 P 0 
L 9.56645 4.54761998 9.55661998 4.54075 1 P 0 
L 9.55661998 4.54075 9.55661004 4.54073996 1 P 0 
L 9.55661004 4.54073996 9.55541998 4.53391998 1 P 0 
L 9.55541998 4.53391998 9.54631004 4.52753996 1 P 0 
L 9.54631004 4.52753996 9.5395 4.52876004 1 P 0 
L 9.5395 4.52876004 9.52246004 4.51683002 1 P 0 
L 9.52246004 4.51683002 9.50628002 4.51398002 1 P 0 
L 9.50628002 4.51398002 9.49385 4.51616998 1 P 0 
L 9.49385 4.51616998 9.48555 4.52198996 1 P 0 
L 9.48555 4.52198996 9.47305 4.53983996 1 P 0 
L 9.47305 4.53983996 9.47121004 4.5503 1 P 0 
L 9.47121004 4.5503 9.47121004 4.5833 1 P 0 
A 9.47121004 4.5833 9.46751004 4.587 9.46751004 4.5833 1 P 0 N
L 9.46751004 4.587 9.45445 4.587 1 P 0 
P 8.1 3.66615 5 P 0 0;2=3,4=1
P 8.74578996 4.667 5 P 0 0;2=3,4=1
L 8.74578996 4.667 8.75833996 4.667 1 P 0 
A 8.75833996 4.667 8.76203996 4.6633 8.75833996 4.6633 1 P 0 Y
L 8.76203996 4.6633 8.76203996 4.63453996 1 P 0 
A 8.76203996 4.63453996 8.76041299 4.62638809 8.74073996 4.63455276 1 P 0 Y
A 8.76041299 4.62638809 8.75578996 4.61948002 8.74073996 4.63455276 1 P 0 Y
L 8.75578996 4.61948002 8.75201004 4.6157 1 P 0 
A 8.75201004 4.6157 8.71211998 4.61566998 8.73205 4.63565 1 P 0 Y
L 8.71211998 4.61566998 8.70435 4.62343002 1 P 0 
L 8.70435 4.62343002 8.69176004 4.64141004 1 P 0 
L 8.69176004 4.64141004 8.67835 4.71741004 1 P 0 
L 8.67835 4.71741004 8.66795 4.73226004 1 P 0 
L 8.66795 4.73226004 8.63698002 4.75396998 1 P 0 
A 8.63698002 4.75396998 8.62711319 4.75883268 8.61626545 4.72438002 1 P 0 N
A 8.62711319 4.75883268 8.61623996 4.7605 8.61626565 4.72438002 1 P 0 N
L 8.61623996 4.7605 8.61621998 4.7605 1 P 0 
A 8.61621998 4.7605 8.55271004 4.7342 8.6162188 4.67066998 1 P 0 N
L 8.55271004 4.7342 8.55268996 4.73418002 1 P 0 
A 8.55268996 4.73418002 8.52824793 4.69390738 8.62276998 4.664094 1 P 0 N
A 8.52824793 4.69390738 8.52516004 4.6469 8.62276998 4.66409311 1 P 0 N
L 8.52516004 4.6469 8.53848996 4.57123996 1 P 0 
A 8.53848996 4.57123996 8.53855 4.57058996 8.5348 4.57057136 1 P 0 Y
L 8.53855 4.57058996 8.53855 4.57053996 1 P 0 
A 8.53855 4.57053996 8.53554272 4.55542421 8.49905 4.57054144 1 P 0 Y
A 8.53554272 4.55542421 8.52698002 4.54261004 8.49905 4.57054144 1 P 0 Y
L 8.52698002 4.54261004 8.52153002 4.53716004 1 P 0 
A 8.52153002 4.53716004 8.50916998 4.52890079 8.49458858 4.5641 1 P 0 Y
A 8.50916998 4.52890079 8.49458996 4.526 8.49458829 4.5641 1 P 0 Y
L 8.49458996 4.526 8.48941004 4.526 1 P 0 
A 8.48941004 4.526 8.48028386 4.52782382 8.48943297 4.54986004 1 P 0 Y
A 8.48028386 4.52782382 8.47255 4.533 8.48943327 4.54986004 1 P 0 Y
L 8.47255 4.533 8.47206998 4.53348002 1 P 0 
A 8.47206998 4.53348002 8.4719 4.53365 8.51300994 4.57458996 1 P 0 Y
L 8.4719 4.53365 8.47186004 4.53368996 1 P 0 
A 8.47186004 4.53368996 8.46069636 4.55013346 8.51355 4.57400502 1 P 0 Y
A 8.46069636 4.55013346 8.45573996 4.56938002 8.51355 4.57400591 1 P 0 Y
A 8.45573996 4.56938002 8.45555 4.57401998 8.51353996 4.57407028 1 P 0 Y
L 8.45555 4.57401998 8.45553996 4.57401004 1 P 0 
L 8.45553996 4.57401004 8.45553996 4.5775 1 P 0 
A 8.45553996 4.5775 8.42553996 4.6075 8.42553996 4.5775 1 P 0 N
L 8.42553996 4.6075 8.42096004 4.6075 1 P 0 
A 8.42096004 4.6075 8.40291772 4.60391624 8.42094636 4.56036004 1 P 0 N
A 8.40291772 4.60391624 8.38761998 4.5937 8.42094547 4.56036004 1 P 0 N
L 8.38761998 4.5937 8.38563996 4.59171998 1 P 0 
A 8.38563996 4.59171998 8.37954705 4.58390709 8.41433996 4.56305591 1 P 0 N
A 8.37954705 4.58390709 8.37553002 4.57485 8.41433996 4.5630562 1 P 0 N
A 8.37553002 4.57485 8.37336004 4.56583002 8.44865 4.55248819 1 P 0 N
L 8.37336004 4.56583002 8.36641004 4.52648996 1 P 0 
A 8.36641004 4.52648996 8.35593996 4.50638996 8.32925 4.53306969 1 P 0 Y
A 8.35593996 4.50638996 8.3181 4.49071004 8.31809961 4.54421004 1 P 0 Y
L 8.3181 4.49071004 8.31801998 4.49071004 1 P 0 
L 8.31801998 4.49071004 8.21133996 4.50951004 1 P 0 
L 8.21133996 4.50951004 8.17303002 4.50273002 1 P 0 
L 8.17303002 4.50273002 8.06358002 4.42613996 1 P 0 
L 8.06358002 4.42613996 7.95866004 4.2763 1 P 0 
L 7.95866004 4.2763 7.93961004 4.16826004 1 P 0 
L 7.93961004 4.16826004 7.93961004 4.16823996 1 P 0 
L 7.93961004 4.16823996 7.9395 4.16761998 1 P 0 
L 7.9395 4.16761998 7.9395 4.16696004 1 P 0 
A 7.9395 4.16696004 7.9689 4.11043002 8.00848996 4.16693002 1 P 0 N
L 7.9689 4.11043002 8.00993002 4.0817 1 P 0 
A 8.00993002 4.0817 8.02007254 4.07014341 7.9914 4.05520827 1 P 0 Y
A 8.02007254 4.07014341 8.02373002 4.05521004 7.9914 4.0552063 1 P 0 Y
L 8.02373002 4.05521004 8.02373002 4.05518996 1 P 0 
L 8.02373002 4.05518996 8.02371998 4.0552 1 P 0 
A 8.02371998 4.0552 8.02108465 4.04190846 7.98901998 4.05517303 1 P 0 Y
A 8.02108465 4.04190846 8.01356004 4.03063996 7.98901998 4.05517323 1 P 0 Y
L 8.01356004 4.03063996 8.01006004 4.02713996 1 P 0 
A 8.01006004 4.02713996 8.00333612 4.02220561 7.99065807 4.04653002 1 P 0 Y
A 8.00333612 4.02220561 7.99543996 4.01951998 7.99065817 4.04653002 1 P 0 Y
L 7.99543996 4.01951998 7.95426004 4.01225 1 P 0 
L 7.95426004 4.01225 7.92291998 3.99033996 1 P 0 
L 7.92291998 3.99033996 7.9033 3.96231004 1 P 0 
L 7.9033 3.96231004 7.88445 3.85546998 1 P 0 
L 7.88445 3.85546998 7.90291004 3.75073996 1 P 0 
A 7.90291004 3.75073996 7.92573002 3.70666004 7.98471004 3.76514055 1 P 0 N
L 7.92573002 3.70666004 7.92703996 3.70535 1 P 0 
A 7.92703996 3.70535 7.94676959 3.69206969 7.97010295 3.74803002 1 P 0 N
A 7.94676959 3.69206969 7.97008996 3.6874 7.97010285 3.74803002 1 P 0 N
L 7.97008996 3.6874 8.09653996 3.6874 1 P 0 
L 8.09653996 3.6874 8.09671998 3.68738002 1 P 0 
A 8.09671998 3.68738002 8.09906201 3.68616476 8.09629675 3.6837 1 P 0 Y
A 8.09906201 3.68616476 8.1 3.6837 8.0963 3.68370276 1 P 0 Y
L 8.1 3.6837 8.1 3.66615 1 P 0 
P 8.1 3.71615 5 P 0 0;2=3,4=1
P 8.78578996 4.667 5 P 0 0;2=3,4=1
L 8.78578996 4.667 8.77323996 4.667 1 P 0 
A 8.77323996 4.667 8.76953996 4.6633 8.77323996 4.6633 1 P 0 N
L 8.76953996 4.6633 8.76953996 4.63453996 1 P 0 
A 8.76953996 4.63453996 8.7611 4.61416998 8.74073996 4.63453927 1 P 0 Y
L 8.7611 4.61416998 8.75731998 4.61038996 1 P 0 
A 8.75731998 4.61038996 8.7320747 4.59992352 8.73205512 4.63565 1 P 0 Y
A 8.7320747 4.59992352 8.70681998 4.61036004 8.73205482 4.63565 1 P 0 Y
L 8.70681998 4.61036004 8.69858002 4.61858996 1 P 0 
L 8.69858002 4.61858996 8.68466004 4.63846998 1 P 0 
L 8.68466004 4.63846998 8.68366998 4.64408002 1 P 0 
L 8.68366998 4.64408002 8.68295 4.64811998 1 P 0 
L 8.68295 4.64811998 8.67681998 4.65241004 1 P 0 
L 8.67681998 4.65241004 8.67488002 4.66336998 1 P 0 
L 8.67488002 4.66336998 8.67918002 4.6695 1 P 0 
L 8.67918002 4.6695 8.67725 4.68045 1 P 0 
L 8.67725 4.68045 8.67111998 4.68473002 1 P 0 
L 8.67111998 4.68473002 8.66918002 4.69568996 1 P 0 
L 8.66918002 4.69568996 8.67348002 4.70181998 1 P 0 
L 8.67348002 4.70181998 8.67125 4.71446998 1 P 0 
L 8.67125 4.71446998 8.66256004 4.72686998 1 P 0 
L 8.66256004 4.72686998 8.63266998 4.74781998 1 P 0 
A 8.63266998 4.74781998 8.61625 4.753 8.61625148 4.72438996 1 P 0 N
L 8.61625 4.753 8.61623002 4.753 1 P 0 
A 8.61623002 4.753 8.58472726 4.74673356 8.61623228 4.67066998 1 P 0 N
A 8.58472726 4.74673356 8.55801998 4.72888996 8.61623219 4.67066998 1 P 0 N
L 8.55801998 4.72888996 8.558 4.72886998 1 P 0 
A 8.558 4.72886998 8.5354065 4.69164862 8.62276998 4.66408652 1 P 0 N
A 8.5354065 4.69164862 8.53255 4.6482 8.62276998 4.66408681 1 P 0 N
L 8.53255 4.6482 8.54588002 4.57256004 1 P 0 
A 8.54588002 4.57256004 8.54605 4.57061004 8.5348 4.57061181 1 P 0 Y
L 8.54605 4.57061004 8.54605 4.57053002 1 P 0 
A 8.54605 4.57053002 8.54247431 4.55254695 8.49905 4.57052835 1 P 0 Y
A 8.54247431 4.55254695 8.53228996 4.5373 8.49905 4.57052776 1 P 0 Y
L 8.53228996 4.5373 8.52683996 4.53185 1 P 0 
A 8.52683996 4.53185 8.51204724 4.52196919 8.49460226 4.5641 1 P 0 Y
A 8.51204724 4.52196919 8.4946 4.5185 8.49460148 4.5641 1 P 0 Y
L 8.4946 4.5185 8.48941998 4.5185 1 P 0 
A 8.48941998 4.5185 8.46723996 4.52768996 8.48941969 4.54986004 1 P 0 Y
L 8.46723996 4.52768996 8.46653002 4.5284 1 P 0 
A 8.46653002 4.5284 8.44825 4.56878002 8.51353996 4.57400906 1 P 0 Y
L 8.44825 4.56878002 8.44803996 4.56898996 1 P 0 
L 8.44803996 4.56898996 8.44803996 4.5775 1 P 0 
A 8.44803996 4.5775 8.42553996 4.6 8.42553996 4.5775 1 P 0 N
L 8.42553996 4.6 8.42096004 4.6 1 P 0 
A 8.42096004 4.6 8.39293002 4.58838996 8.42095945 4.56036004 1 P 0 N
L 8.39293002 4.58838996 8.39095 4.58641004 1 P 0 
A 8.39095 4.58641004 8.38271004 4.57266004 8.41433996 4.56304911 1 P 0 N
A 8.38271004 4.57266004 8.38075 4.56451998 8.44865 4.55247638 1 P 0 N
L 8.38075 4.56451998 8.37728996 4.54486998 1 P 0 
L 8.37728996 4.54486998 8.37728002 4.54486998 1 P 0 
L 8.37728002 4.54486998 8.3738 4.52518002 1 P 0 
A 8.3738 4.52518002 8.36125 4.50108002 8.32925 4.53306161 1 P 0 Y
A 8.36125 4.50108002 8.31811004 4.48321004 8.31810886 4.54421998 1 P 0 Y
L 8.31811004 4.48321004 8.31736004 4.48321004 1 P 0 
L 8.31736004 4.48321004 8.21133996 4.50188996 1 P 0 
L 8.21133996 4.50188996 8.17596998 4.49563002 1 P 0 
L 8.17596998 4.49563002 8.06896998 4.42075 1 P 0 
L 8.06896998 4.42075 7.96576004 4.27336004 1 P 0 
L 7.96576004 4.27336004 7.947 4.16696004 1 P 0 
L 7.947 4.16696004 7.947 4.16695 1 P 0 
A 7.947 4.16695 7.95394291 4.13855837 8.00848996 4.16694203 1 P 0 N
A 7.95394291 4.13855837 7.97321004 4.11658002 8.00848996 4.16694213 1 P 0 N
L 7.97321004 4.11658002 8.01423996 4.08785 1 P 0 
A 8.01423996 4.08785 8.02672677 4.07361407 7.99138996 4.05521319 1 P 0 Y
A 8.02672677 4.07361407 8.03123002 4.05521998 7.99138996 4.05521457 1 P 0 Y
L 8.03123002 4.05521998 8.03123002 4.0552 1 P 0 
A 8.03123002 4.0552 8.02802274 4.03903465 7.98901998 4.05517382 1 P 0 Y
A 8.02802274 4.03903465 8.01886998 4.02533002 7.98901998 4.05517431 1 P 0 Y
L 8.01886998 4.02533002 8.01536998 4.02183002 1 P 0 
A 8.01536998 4.02183002 7.99673996 4.01213002 7.99066929 4.04653002 1 P 0 Y
L 7.99673996 4.01213002 7.9572 4.00515 1 P 0 
L 7.9572 4.00515 7.92831004 3.98495 1 P 0 
L 7.92831004 3.98495 7.9104 3.95936998 1 P 0 
L 7.9104 3.95936998 7.89206998 3.85546998 1 P 0 
L 7.89206998 3.85546998 7.9103 3.75203996 1 P 0 
A 7.9103 3.75203996 7.91761575 3.73040817 7.98471004 3.76515207 1 P 0 N
A 7.91761575 3.73040817 7.93106004 3.71195 7.98471004 3.76515207 1 P 0 N
L 7.93106004 3.71195 7.93236998 3.71063002 1 P 0 
A 7.93236998 3.71063002 7.94966201 3.69899124 7.97010571 3.74803002 1 P 0 N
A 7.94966201 3.69899124 7.9701 3.6949 7.97010699 3.74803002 1 P 0 N
L 7.9701 3.6949 8.0963 3.6949 1 P 0 
L 8.0963 3.6949 8.09671998 3.69491998 1 P 0 
A 8.09671998 3.69491998 8.09906201 3.69613524 8.09629675 3.6986 1 P 0 N
A 8.09906201 3.69613524 8.1 3.6986 8.0963 3.69859724 1 P 0 N
L 8.1 3.6986 8.1 3.71615 1 P 0 
P 8.2 3.66615 5 P 0 0;2=3,4=1
P 8.81665 4.78291998 5 P 0 0;2=3,4=1
L 8.81665 4.78291998 8.82853996 4.78291998 1 P 0 
A 8.82853996 4.78291998 8.8329 4.77856004 8.82854006 4.77856004 1 P 0 Y
L 8.8329 4.77856004 8.8329 4.642 1 P 0 
A 8.8329 4.642 8.82073996 4.61265 8.7914 4.6419999 1 P 0 Y
L 8.82073996 4.61265 8.82068996 4.6126 1 P 0 
A 8.82068996 4.6126 8.79326998 4.58975 8.68133406 4.75195 1 P 0 Y
A 8.79326998 4.58975 8.69386998 4.59006998 8.7438001 4.66138996 1 P 0 Y
L 8.69386998 4.59006998 8.68568996 4.5958 1 P 0 
L 8.68568996 4.5958 8.66503996 4.62526998 1 P 0 
L 8.66503996 4.62526998 8.65281998 4.69461998 1 P 0 
A 8.65281998 4.69461998 8.64987923 4.70330413 8.62318002 4.68942283 1 P 0 N
A 8.64987923 4.70330413 8.64446004 4.7107 8.62318002 4.68942402 1 P 0 N
L 8.64446004 4.7107 8.64445 4.7107 1 P 0 
L 8.64445 4.7107 8.64063996 4.71451004 1 P 0 
A 8.64063996 4.71451004 8.62958533 4.72191004 8.61653671 4.69046004 1 P 0 N
A 8.62958533 4.72191004 8.61653996 4.72451004 8.61653543 4.69046004 1 P 0 N
A 8.61653996 4.72451004 8.56671004 4.70386998 8.61653976 4.65403996 1 P 0 N
L 8.56671004 4.70386998 8.56668996 4.70385 1 P 0 
A 8.56668996 4.70385 8.55607461 4.6879562 8.60133002 4.66922224 1 P 0 N
A 8.55607461 4.6879562 8.55235 4.66921004 8.60133002 4.66922146 1 P 0 N
L 8.55235 4.66921004 8.55235 4.65453002 1 P 0 
L 8.55235 4.65453002 8.56595 4.5773 1 P 0 
A 8.56595 4.5773 8.56681004 4.56748002 8.51015 4.56746535 1 P 0 Y
L 8.56681004 4.56748002 8.56681004 4.56361004 1 P 0 
A 8.56681004 4.56361004 8.56317933 4.54538159 8.51916998 4.56362313 1 P 0 Y
A 8.56317933 4.54538159 8.55285 4.52993002 8.51916998 4.56362333 1 P 0 Y
L 8.55285 4.52993002 8.53085 4.50793002 1 P 0 
A 8.53085 4.50793002 8.51928996 4.50191004 8.51552972 4.52323996 1 P 0 Y
L 8.51928996 4.50191004 8.31885 4.46658002 1 P 0 
L 8.31885 4.46658002 8.20941004 4.48586998 1 P 0 
L 8.20941004 4.48586998 8.18261998 4.48113002 1 P 0 
L 8.18261998 4.48113002 8.07818996 4.408 1 P 0 
L 8.07818996 4.408 7.98155 4.26998002 1 P 0 
L 7.98155 4.26998002 7.96548002 4.17886998 1 P 0 
L 7.96548002 4.17886998 7.96546998 4.17881998 1 P 0 
A 7.96546998 4.17881998 7.96696427 4.15557707 8.01361998 4.17024606 1 P 0 N
A 7.96696427 4.15557707 7.97903996 4.13566004 8.01361998 4.17024518 1 P 0 N
L 7.97903996 4.13566004 8.02191998 4.10563002 1 P 0 
L 8.02191998 4.10563002 8.03636004 4.09118002 1 P 0 
A 8.03636004 4.09118002 8.04648238 4.07603002 8.00331998 4.05814803 1 P 0 Y
A 8.04648238 4.07603002 8.05003996 4.05816004 8.00331998 4.05814803 1 P 0 Y
L 8.05003996 4.05816004 8.05003996 4.03696004 1 P 0 
A 8.05003996 4.03696004 8.04859232 4.02970699 8.03108002 4.03697323 1 P 0 Y
A 8.04859232 4.02970699 8.04448002 4.02356004 8.03108002 4.03697362 1 P 0 Y
L 8.04448002 4.02356004 8.02383002 4.00291004 1 P 0 
A 8.02383002 4.00291004 8.0121 3.9968 8.00827904 4.01845 1 P 0 Y
L 8.0121 3.9968 7.96411004 3.98835 1 P 0 
L 7.96411004 3.98835 7.94123002 3.97235 1 P 0 
L 7.94123002 3.97235 7.92686004 3.95181004 1 P 0 
L 7.92686004 3.95181004 7.91056004 3.85938996 1 P 0 
L 7.91056004 3.85938996 7.92321004 3.78771004 1 P 0 
A 7.92321004 3.78771004 7.92741053 3.77532687 7.96553996 3.79516476 1 P 0 N
A 7.92741053 3.77532687 7.93513996 3.76478002 7.96553996 3.79516486 1 P 0 N
L 7.93513996 3.76478002 7.95838996 3.74153002 1 P 0 
A 7.95838996 3.74153002 7.96836004 3.7374 7.96836033 3.7515 1 P 0 N
L 7.96836004 3.7374 8.1636 3.7374 1 P 0 
A 8.1636 3.7374 8.17125 3.72975 8.1636 3.72975 1 P 0 Y
L 8.17125 3.72975 8.17125 3.70448996 1 P 0 
A 8.17125 3.70448996 8.18833996 3.6874 8.18833996 3.70448996 1 P 0 N
L 8.18833996 3.6874 8.1963 3.6874 1 P 0 
L 8.1963 3.6874 8.19671998 3.68738002 1 P 0 
A 8.19671998 3.68738002 8.19906201 3.68616476 8.19629675 3.6837 1 P 0 Y
A 8.19906201 3.68616476 8.2 3.6837 8.1963 3.68370276 1 P 0 Y
L 8.2 3.6837 8.2 3.66615 1 P 0 
P 8.2 3.71615 5 P 0 0;2=3,4=1
P 8.85665 4.78291998 5 P 0 0;2=3,4=1
L 8.85665 4.78291998 8.8441 4.78291998 1 P 0 
A 8.8441 4.78291998 8.8404 4.77921998 8.8441 4.77921998 1 P 0 N
L 8.8404 4.77921998 8.8404 4.74075 1 P 0 
L 8.8404 4.74075 8.84553996 4.73561004 1 P 0 
L 8.84553996 4.73561004 8.84553996 4.72451004 1 P 0 
L 8.84553996 4.72451004 8.8404 4.71936998 1 P 0 
L 8.8404 4.71936998 8.8404 4.70826998 1 P 0 
L 8.8404 4.70826998 8.84553996 4.70313002 1 P 0 
L 8.84553996 4.70313002 8.84553996 4.69203002 1 P 0 
L 8.84553996 4.69203002 8.8404 4.68688996 1 P 0 
L 8.8404 4.68688996 8.8404 4.642 1 P 0 
A 8.8404 4.642 8.82605 4.60733996 8.79138996 4.64199055 1 P 0 Y
L 8.82605 4.60733996 8.826 4.60728996 1 P 0 
A 8.826 4.60728996 8.79753996 4.58356998 8.68132687 4.75193996 1 P 0 Y
A 8.79753996 4.58356998 8.74349488 4.56681909 8.74380177 4.66138996 1 P 0 Y
A 8.74349488 4.56681909 8.68956004 4.58391998 8.74380157 4.66138996 1 P 0 Y
L 8.68956004 4.58391998 8.6803 4.59041004 1 P 0 
L 8.6803 4.59041004 8.65793996 4.62233002 1 P 0 
L 8.65793996 4.62233002 8.64543002 4.69331998 1 P 0 
A 8.64543002 4.69331998 8.64322028 4.69983888 8.62318002 4.68941171 1 P 0 N
A 8.64322028 4.69983888 8.63915 4.70538996 8.62318002 4.6894123 1 P 0 N
L 8.63915 4.70538996 8.63533002 4.70921004 1 P 0 
A 8.63533002 4.70921004 8.62671033 4.71497579 8.61654311 4.69045 1 P 0 N
A 8.62671033 4.71497579 8.61653996 4.717 8.61654232 4.69045 1 P 0 N
A 8.61653996 4.717 8.57201998 4.69856004 8.61653888 4.65403996 1 P 0 N
L 8.57201998 4.69856004 8.572 4.69853996 1 P 0 
A 8.572 4.69853996 8.56300807 4.68508346 8.60133002 4.66920846 1 P 0 N
A 8.56300807 4.68508346 8.55985 4.66921004 8.60133002 4.66920827 1 P 0 N
L 8.55985 4.66921004 8.55985 4.65518996 1 P 0 
L 8.55985 4.65518996 8.57333996 4.5786 1 P 0 
A 8.57333996 4.5786 8.57431004 4.56748996 8.51013996 4.56748425 1 P 0 Y
L 8.57431004 4.56748996 8.57431004 4.56361004 1 P 0 
A 8.57431004 4.56361004 8.55816004 4.52461998 8.51916998 4.56360974 1 P 0 Y
L 8.55816004 4.52461998 8.53616004 4.50261998 1 P 0 
A 8.53616004 4.50261998 8.52899872 4.49737126 8.51553563 4.52325 1 P 0 Y
A 8.52899872 4.49737126 8.52058996 4.49451998 8.51553583 4.52325 1 P 0 Y
L 8.52058996 4.49451998 8.31885 4.45896004 1 P 0 
L 8.31885 4.45896004 8.20941004 4.47825 1 P 0 
L 8.20941004 4.47825 8.18556004 4.47403002 1 P 0 
L 8.18556004 4.47403002 8.08358002 4.40261004 1 P 0 
L 8.08358002 4.40261004 7.98865 4.26703996 1 P 0 
L 7.98865 4.26703996 7.97286004 4.17748002 1 P 0 
L 7.97286004 4.17748002 7.97285 4.17743002 1 P 0 
A 7.97285 4.17743002 7.97404793 4.15809429 8.01363002 4.17025157 1 P 0 N
A 7.97404793 4.15809429 7.98391004 4.14141998 8.01363002 4.17025167 1 P 0 N
L 7.98391004 4.14141998 8.02676004 4.1114 1 P 0 
L 8.02676004 4.1114 8.04166998 4.09648996 1 P 0 
A 8.04166998 4.09648996 8.05753996 4.05816004 8.00331998 4.05816132 1 P 0 Y
L 8.05753996 4.05816004 8.05753996 4.03695 1 P 0 
A 8.05753996 4.03695 8.04978996 4.01825 8.03108002 4.03696004 1 P 0 Y
L 8.04978996 4.01825 8.02913996 3.9976 1 P 0 
A 8.02913996 3.9976 8.0134 3.98941004 8.00829035 4.01845 1 P 0 Y
L 8.0134 3.98941004 7.96705 3.98125 1 P 0 
L 7.96705 3.98125 7.94661998 3.96696004 1 P 0 
L 7.94661998 3.96696004 7.93396004 3.94886998 1 P 0 
L 7.93396004 3.94886998 7.91818002 3.85938996 1 P 0 
L 7.91818002 3.85938996 7.9306 3.78901004 1 P 0 
A 7.9306 3.78901004 7.93406959 3.77879203 7.96553996 3.79517608 1 P 0 N
A 7.93406959 3.77879203 7.94045 3.77008996 7.96553996 3.79517618 1 P 0 N
L 7.94045 3.77008996 7.9637 3.74683996 1 P 0 
A 7.9637 3.74683996 7.96836004 3.7449 7.96836959 3.75148996 1 P 0 N
L 7.96836004 3.7449 8.1636 3.7449 1 P 0 
A 8.1636 3.7449 8.17875 3.72975 8.1636 3.72975 1 P 0 Y
L 8.17875 3.72975 8.17875 3.70448996 1 P 0 
A 8.17875 3.70448996 8.18833996 3.6949 8.18833996 3.70448996 1 P 0 N
L 8.18833996 3.6949 8.19653996 3.6949 1 P 0 
L 8.19653996 3.6949 8.19671998 3.69491998 1 P 0 
A 8.19671998 3.69491998 8.19906201 3.69613524 8.19629675 3.6986 1 P 0 N
A 8.19906201 3.69613524 8.2 3.6986 8.1963 3.69859724 1 P 0 N
L 8.2 3.6986 8.2 3.71615 1 P 0 
P 8.05 3.76615 5 P 0 0;2=3,4=1
P 8.89061998 4.667 5 P 0 0;2=3,4=1
L 8.05 3.76615 8.05 3.7837 1 P 0 
A 8.05 3.7837 8.04906201 3.78616476 8.0463 3.78370276 1 P 0 N
A 8.04906201 3.78616476 8.04671998 3.78738002 8.04629675 3.7837 1 P 0 N
L 8.04671998 3.78738002 8.04653996 3.7874 1 P 0 
L 8.04653996 3.7874 7.98531998 3.7874 1 P 0 
A 7.98531998 3.7874 7.95681004 3.80223002 7.98530984 3.8222 1 P 0 Y
L 7.95681004 3.80223002 7.94086004 3.82501998 1 P 0 
L 7.94086004 3.82501998 7.93441998 3.86148996 1 P 0 
L 7.93441998 3.86148996 7.94776004 3.9371 1 P 0 
L 7.94776004 3.9371 7.96093002 3.95593002 1 P 0 
L 7.96093002 3.95593002 7.97591004 3.96641004 1 P 0 
L 7.97591004 3.96641004 8.02178996 3.97451004 1 P 0 
A 8.02178996 3.97451004 8.03352116 3.97849882 8.01469567 4.01461998 1 P 0 N
A 8.03352116 3.97849882 8.04351004 3.98583002 8.01469528 4.01461998 1 P 0 N
L 8.04351004 3.98583002 8.06591998 4.00823996 1 P 0 
A 8.06591998 4.00823996 8.07703996 4.03506998 8.03908996 4.03507933 1 P 0 N
L 8.07703996 4.03506998 8.07703996 4.05923996 1 P 0 
A 8.07703996 4.05923996 8.07197313 4.08469803 8.01051004 4.05923199 1 P 0 N
A 8.07197313 4.08469803 8.05755 4.10628002 8.01051004 4.05923297 1 P 0 N
L 8.05755 4.10628002 8.05751998 4.10631004 1 P 0 
A 8.05751998 4.10631004 8.03916004 4.12166998 7.96201949 4.01081004 1 P 0 N
L 8.03916004 4.12166998 8.03913996 4.12166998 1 P 0 
L 8.03913996 4.12166998 8.00478002 4.14573996 1 P 0 
L 8.00478002 4.14573996 8.00478002 4.14573002 1 P 0 
A 8.00478002 4.14573002 7.99394606 4.15809803 8.02466004 4.17407333 1 P 0 Y
A 7.99394606 4.15809803 7.99003996 4.17406998 8.02466004 4.17407303 1 P 0 Y
L 7.99003996 4.17406998 7.99003996 4.18801004 1 P 0 
L 7.99003996 4.18801004 8.0026 4.25918996 1 P 0 
L 8.0026 4.25918996 8.09533996 4.39165 1 P 0 
L 8.09533996 4.39165 8.18805 4.45656004 1 P 0 
L 8.18805 4.45656004 8.2124 4.46086998 1 P 0 
L 8.2124 4.46086998 8.36313996 4.43428002 1 P 0 
L 8.36313996 4.43428002 8.39098996 4.41478002 1 P 0 
L 8.39098996 4.41478002 8.48093996 4.28631998 1 P 0 
A 8.48093996 4.28631998 8.50133012 4.26844449 8.52767283 4.31906004 1 P 0 N
A 8.50133012 4.26844449 8.52766998 4.262 8.52767234 4.31906004 1 P 0 N
L 8.52766998 4.262 8.52906004 4.262 1 P 0 
A 8.52906004 4.262 8.55753996 4.29048002 8.52906004 4.29047992 1 P 0 N
L 8.55753996 4.29048002 8.55753996 4.29506004 1 P 0 
L 8.55753996 4.29506004 8.55753002 4.29505 1 P 0 
A 8.55753002 4.29505 8.54956004 4.32031004 8.51358002 4.29507037 1 P 0 N
L 8.54956004 4.32031004 8.48953002 4.40571998 1 P 0 
A 8.48953002 4.40571998 8.48310659 4.41871427 8.52841004 4.43302421 1 P 0 Y
A 8.48310659 4.41871427 8.4809 4.43303996 8.52841004 4.4330252 1 P 0 Y
A 8.4809 4.43303996 8.48400226 4.4486561 8.52173996 4.43304301 1 P 0 Y
A 8.48400226 4.4486561 8.49283996 4.4619 8.52173996 4.43304429 1 P 0 Y
A 8.49283996 4.4619 8.50530659 4.47022736 8.52000325 4.43473002 1 P 0 Y
A 8.50530659 4.47022736 8.52001004 4.47315 8.52000463 4.43473002 1 P 0 Y
L 8.52001004 4.47315 8.52003002 4.47315 1 P 0 
A 8.52003002 4.47315 8.5345563 4.47091634 8.52003337 4.42481998 1 P 0 Y
A 8.5345563 4.47091634 8.54773996 4.46441998 8.52003435 4.42481998 1 P 0 Y
L 8.54773996 4.46441998 8.6073 4.42271004 1 P 0 
A 8.6073 4.42271004 8.61141122 4.41996388 8.61625768 4.43166998 1 P 0 N
A 8.61141122 4.41996388 8.61626004 4.419 8.61625846 4.43166998 1 P 0 N
L 8.61626004 4.419 8.62116004 4.419 1 P 0 
A 8.62116004 4.419 8.63387923 4.42153228 8.62115591 4.45223002 1 P 0 N
A 8.63387923 4.42153228 8.64466004 4.42873996 8.62115561 4.45223002 1 P 0 N
L 8.64466004 4.42873996 8.65425 4.43833002 1 P 0 
A 8.65425 4.43833002 8.65425 4.46666998 8.64008002 4.4525 1 P 0 N
L 8.65425 4.46666998 8.64223002 4.47868996 1 P 0 
A 8.64223002 4.47868996 8.63435935 4.4976935 8.66123996 4.49769498 1 P 0 Y
A 8.63435935 4.4976935 8.64223002 4.5167 8.66123996 4.49769498 1 P 0 Y
L 8.64223002 4.5167 8.64751998 4.52198002 1 P 0 
A 8.64751998 4.52198002 8.65717293 4.52927421 8.67531585 4.49523002 1 P 0 Y
A 8.65717293 4.52927421 8.66861004 4.53321998 8.67531722 4.49523002 1 P 0 Y
L 8.66861004 4.53321998 8.80851004 4.55793996 1 P 0 
L 8.80851004 4.55793996 8.89931998 4.62148996 1 P 0 
L 8.89931998 4.62148996 8.90686998 4.63228002 1 P 0 
L 8.90686998 4.63228002 8.90686998 4.6633 1 P 0 
A 8.90686998 4.6633 8.90316998 4.667 8.90316998 4.6633 1 P 0 N
L 8.90316998 4.667 8.89061998 4.667 1 P 0 
P 8.05 3.81615 5 P 0 0;2=3,4=1
P 8.93061998 4.667 5 P 0 0;2=3,4=1
L 8.05 3.81615 8.05 3.7986 1 P 0 
A 8.05 3.7986 8.04906201 3.79613524 8.0463 3.79859724 1 P 0 Y
A 8.04906201 3.79613524 8.04671998 3.79491998 8.04629675 3.7986 1 P 0 Y
L 8.04671998 3.79491998 8.0463 3.7949 1 P 0 
L 8.0463 3.7949 7.98531998 3.7949 1 P 0 
A 7.98531998 3.7949 7.97271594 3.79798474 7.98532195 3.8222 1 P 0 Y
A 7.97271594 3.79798474 7.96296004 3.80653996 7.98532185 3.8222 1 P 0 Y
L 7.96296004 3.80653996 7.94796004 3.82796004 1 P 0 
L 7.94796004 3.82796004 7.94203996 3.86148996 1 P 0 
L 7.94203996 3.86148996 7.95486004 3.93416004 1 P 0 
L 7.95486004 3.93416004 7.96631998 3.95053996 1 P 0 
L 7.96631998 3.95053996 7.97885 3.95931004 1 P 0 
L 7.97885 3.95931004 8.02308996 3.96711998 1 P 0 
A 8.02308996 3.96711998 8.03698642 3.97183976 8.01470679 4.01461998 1 P 0 N
A 8.03698642 3.97183976 8.04881998 3.98051998 8.0147064 4.01461998 1 P 0 N
L 8.04881998 3.98051998 8.07123002 4.00293002 1 P 0 
A 8.07123002 4.00293002 8.08453996 4.03506004 8.03908002 4.03507008 1 P 0 N
L 8.08453996 4.03506004 8.08453996 4.05925 1 P 0 
A 8.08453996 4.05925 8.07890472 4.08757618 8.01051004 4.05924606 1 P 0 N
A 8.07890472 4.08757618 8.06286004 4.11158996 8.01051004 4.05924557 1 P 0 N
L 8.06286004 4.11158996 8.06283002 4.11161998 1 P 0 
A 8.06283002 4.11161998 8.05349488 4.12015551 7.96205778 4.01078002 1 P 0 N
A 8.05349488 4.12015551 8.04343996 4.12783002 7.96205679 4.01078002 1 P 0 N
L 8.04343996 4.12783002 8.00908996 4.15188002 1 P 0 
A 8.00908996 4.15188002 7.99753996 4.17408002 8.02465 4.17408002 1 P 0 Y
L 7.99753996 4.17408002 7.99753996 4.18735 1 P 0 
L 7.99753996 4.18735 8.0097 4.25625 1 P 0 
L 8.0097 4.25625 8.10073002 4.38626004 1 P 0 
L 8.10073002 4.38626004 8.19098996 4.44946004 1 P 0 
L 8.19098996 4.44946004 8.2124 4.45325 1 P 0 
L 8.2124 4.45325 8.3602 4.42718002 1 P 0 
L 8.3602 4.42718002 8.3856 4.40938996 1 P 0 
L 8.3856 4.40938996 8.47478996 4.28201004 1 P 0 
A 8.47478996 4.28201004 8.52766998 4.2545 8.52766053 4.31906004 1 P 0 N
L 8.52766998 4.2545 8.52906004 4.2545 1 P 0 
A 8.52906004 4.2545 8.56503996 4.29048002 8.52906004 4.29047992 1 P 0 N
L 8.56503996 4.29048002 8.56503996 4.29505 1 P 0 
A 8.56503996 4.29505 8.5557 4.32461998 8.51358996 4.29505906 1 P 0 N
L 8.5557 4.32461998 8.49566998 4.41003002 1 P 0 
A 8.49566998 4.41003002 8.49026417 4.42097461 8.52841998 4.43301339 1 P 0 Y
A 8.49026417 4.42097461 8.48841004 4.43303996 8.52841998 4.43301329 1 P 0 Y
A 8.48841004 4.43303996 8.49815 4.4566 8.52175 4.4330502 1 P 0 Y
A 8.49815 4.4566 8.50818041 4.46329852 8.52000709 4.43473002 1 P 0 Y
A 8.50818041 4.46329852 8.52001004 4.46565 8.52000778 4.43473002 1 P 0 Y
L 8.52001004 4.46565 8.52001998 4.46565 1 P 0 
A 8.52001998 4.46565 8.53229282 4.46376073 8.52001644 4.42481998 1 P 0 Y
A 8.53229282 4.46376073 8.54343002 4.45826998 8.52001673 4.42481998 1 P 0 Y
L 8.54343002 4.45826998 8.60251998 4.4169 1 P 0 
A 8.60251998 4.4169 8.60888317 4.41289596 8.61625532 4.43166998 1 P 0 N
A 8.60888317 4.41289596 8.61626998 4.4115 8.6162564 4.43166998 1 P 0 N
L 8.61626998 4.4115 8.62116998 4.4115 1 P 0 
A 8.62116998 4.4115 8.64996998 4.42343002 8.621169 4.45223002 1 P 0 N
L 8.64996998 4.42343002 8.65956004 4.43301998 1 P 0 
A 8.65956004 4.43301998 8.65956004 4.47198002 8.64008002 4.4525 1 P 0 N
L 8.65956004 4.47198002 8.64753996 4.484 1 P 0 
A 8.64753996 4.484 8.6418688 4.4976935 8.66123996 4.49769498 1 P 0 Y
A 8.6418688 4.4976935 8.64753996 4.51138996 8.66123996 4.49769498 1 P 0 Y
L 8.64753996 4.51138996 8.65333002 4.51718002 1 P 0 
L 8.65333002 4.51718002 8.65333002 4.51718996 1 P 0 
A 8.65333002 4.51718996 8.66095463 4.52278652 8.67531516 4.49523002 1 P 0 Y
A 8.66095463 4.52278652 8.66991004 4.52583002 8.67531457 4.49523002 1 P 0 Y
L 8.66991004 4.52583002 8.81145 4.55083996 1 P 0 
L 8.81145 4.55083996 8.85778996 4.58326998 1 P 0 
L 8.85778996 4.58326998 8.86371004 4.58221004 1 P 0 
L 8.86371004 4.58221004 8.87281998 4.58858002 1 P 0 
L 8.87281998 4.58858002 8.87386004 4.59451004 1 P 0 
L 8.87386004 4.59451004 8.88296998 4.60088996 1 P 0 
L 8.88296998 4.60088996 8.88888996 4.59983002 1 P 0 
L 8.88888996 4.59983002 8.898 4.6062 1 P 0 
L 8.898 4.6062 8.89903996 4.61213002 1 P 0 
L 8.89903996 4.61213002 8.90471004 4.6161 1 P 0 
L 8.90471004 4.6161 8.91436998 4.62991004 1 P 0 
L 8.91436998 4.62991004 8.91436998 4.6633 1 P 0 
A 8.91436998 4.6633 8.91806998 4.667 8.91806998 4.6633 1 P 0 Y
L 8.91806998 4.667 8.93061998 4.667 1 P 0 
P 9.02925 4.667 5 P 0 0;2=3,4=1
L 8.2 3.81615 8.2 3.8337 1 P 0 
A 8.2 3.8337 8.1963 3.8374 8.1963 3.8337 1 P 0 N
L 8.1963 3.8374 8.18873996 3.8374 1 P 0 
A 8.18873996 3.8374 8.17125 3.85488996 8.18873996 3.85488996 1 P 0 Y
L 8.17125 3.85488996 8.17125 3.87708002 1 P 0 
A 8.17125 3.87708002 8.16616004 3.89321998 8.14311998 3.8770814 1 P 0 N
L 8.16616004 3.89321998 8.14193996 3.92778002 1 P 0 
A 8.14193996 3.92778002 8.14128425 3.95763238 8.16395 3.94319685 1 P 0 Y
A 8.14128425 3.95763238 8.16861004 3.96966004 8.16394665 3.9432 1 P 0 Y
L 8.16861004 3.96966004 8.2485 3.95556004 1 P 0 
A 8.2485 3.95556004 8.24915 3.9555 8.24917136 3.95928002 1 P 0 N
L 8.24915 3.9555 8.24918002 3.9555 1 P 0 
A 8.24918002 3.9555 8.43396998 4.03205 8.24916939 4.21683996 1 P 0 N
L 8.43396998 4.03205 8.46213002 4.06021004 1 P 0 
A 8.46213002 4.06021004 8.49343002 4.12033002 8.38245 4.13990128 1 P 0 N
L 8.49343002 4.12033002 8.49783002 4.14526998 1 P 0 
A 8.49783002 4.14526998 8.50656004 4.16251004 8.53056998 4.13952146 1 P 0 Y
L 8.50656004 4.16251004 8.50671004 4.16266998 1 P 0 
L 8.50671004 4.16266998 8.50681998 4.16276004 1 P 0 
L 8.50681998 4.16276004 8.5069 4.16283996 1 P 0 
L 8.5069 4.16283996 8.50698002 4.16291004 1 P 0 
A 8.50698002 4.16291004 8.52550305 4.17154547 8.52809124 4.14181004 1 P 0 Y
A 8.52550305 4.17154547 8.54523996 4.16623996 8.52809134 4.14181004 1 P 0 Y
L 8.54523996 4.16623996 8.56331998 4.15355 1 P 0 
A 8.56331998 4.15355 8.58976004 4.1452 8.58976132 4.19123996 1 P 0 N
L 8.58976004 4.1452 8.58978002 4.1452 1 P 0 
A 8.58978002 4.1452 8.59899577 4.14703268 8.58977746 4.1693 1 P 0 N
A 8.59899577 4.14703268 8.60681004 4.15225 8.58977746 4.1693 1 P 0 N
L 8.60681004 4.15225 8.61311998 4.15856004 1 P 0 
A 8.61311998 4.15856004 8.61383996 4.15921998 8.62104203 4.15063996 1 P 0 Y
L 8.61383996 4.15921998 8.62316004 4.16703996 1 P 0 
A 8.62316004 4.16703996 8.67896998 4.18986998 8.67894911 4.11028996 1 P 0 Y
L 8.67896998 4.18986998 8.67898996 4.18986998 1 P 0 
A 8.67898996 4.18986998 8.72625 4.1703 8.67898986 4.12301998 1 P 0 Y
L 8.72625 4.1703 8.79216998 4.10436004 1 P 0 
A 8.79216998 4.10436004 8.80467844 4.09600846 8.81941299 4.13161998 1 P 0 N
A 8.80467844 4.09600846 8.81943002 4.09308002 8.81941437 4.13161998 1 P 0 N
L 8.81943002 4.09308002 8.81946998 4.09308002 1 P 0 
A 8.81946998 4.09308002 8.85961004 4.1097 8.81947096 4.14986004 1 P 0 N
L 8.85961004 4.1097 8.86981004 4.11988996 1 P 0 
A 8.86981004 4.11988996 8.88551663 4.1433938 8.8186 4.17111132 1 P 0 N
A 8.88551663 4.1433938 8.89103002 4.17111998 8.8186 4.17111152 1 P 0 N
A 8.89103002 4.17111998 8.87466998 4.20255 8.85266004 4.17112037 1 P 0 N
L 8.87466998 4.20255 8.80596998 4.25063996 1 P 0 
A 8.80596998 4.25063996 8.7867622 4.28389596 8.83201004 4.28785492 1 P 0 Y
A 8.7867622 4.28389596 8.7999 4.31998002 8.83201004 4.28785541 1 P 0 Y
L 8.7999 4.31998002 8.80351004 4.32358996 1 P 0 
A 8.80351004 4.32358996 8.82998435 4.33593465 8.83370256 4.2934 1 P 0 Y
A 8.82998435 4.33593465 8.8582 4.32836998 8.83370266 4.2934 1 P 0 Y
L 8.8582 4.32836998 8.949 4.26478002 1 P 0 
A 8.949 4.26478002 8.97496112 4.25782156 8.97153848 4.29696004 1 P 0 N
A 8.97496112 4.25782156 8.99931998 4.26918002 8.97153858 4.29696004 1 P 0 N
A 8.99931998 4.26918002 9.01428091 4.29158071 8.95043996 4.31802224 1 P 0 N
A 9.01428091 4.29158071 9.01953996 4.318 8.95043996 4.31802205 1 P 0 N
A 9.01953996 4.318 9.01113002 4.33831004 8.99081004 4.3179998 1 P 0 N
L 9.01113002 4.33831004 9.00811004 4.34133002 1 P 0 
A 9.00811004 4.34133002 9.00761004 4.34175 9.00549134 4.33871998 1 P 0 N
L 9.00761004 4.34175 8.8718 4.43683996 1 P 0 
A 8.8718 4.43683996 8.86188238 4.44815994 8.88998002 4.46277224 1 P 0 Y
A 8.86188238 4.44815994 8.85831004 4.46278002 8.88998002 4.46277195 1 P 0 Y
L 8.85831004 4.46278002 8.85831004 4.46736998 1 P 0 
A 8.85831004 4.46736998 8.86162146 4.48401693 8.90181998 4.46736782 1 P 0 Y
A 8.86162146 4.48401693 8.87105 4.49813002 8.90181998 4.46736742 1 P 0 Y
L 8.87105 4.49813002 8.87596004 4.50303996 1 P 0 
A 8.87596004 4.50303996 8.90074872 4.51460049 8.90423415 4.47476998 1 P 0 Y
A 8.90074872 4.51460049 8.92716998 4.50751998 8.90423406 4.47476998 1 P 0 Y
L 8.92716998 4.50751998 8.98196004 4.46915 1 P 0 
A 8.98196004 4.46915 8.99193002 4.466 8.99192913 4.48335 1 P 0 N
L 8.99193002 4.466 8.99453996 4.466 1 P 0 
A 8.99453996 4.466 9.00821998 4.47168002 8.99452913 4.48533996 1 P 0 N
L 9.00821998 4.47168002 9.01706998 4.48051998 1 P 0 
A 9.01706998 4.48051998 9.02031998 4.48691998 9.00893002 4.48867874 1 P 0 N
L 9.02031998 4.48691998 9.02186004 4.49696998 1 P 0 
L 9.02186004 4.49696998 9.0074 4.57903996 1 P 0 
L 9.0074 4.57903996 9.00968996 4.59201004 1 P 0 
L 9.00968996 4.59201004 9.01851998 4.60463996 1 P 0 
L 9.01851998 4.60463996 9.03831004 4.61848996 1 P 0 
L 9.03831004 4.61848996 9.0455 4.62873996 1 P 0 
L 9.0455 4.62873996 9.0455 4.66303996 1 P 0 
A 9.0455 4.66303996 9.04153996 4.667 9.04153996 4.66303996 1 P 0 N
L 9.04153996 4.667 9.02925 4.667 1 P 0 
P 8.2 3.81615 5 P 0 0;2=3,4=1
P 9.06925 4.667 5 P 0 0;2=3,4=1
L 8.2 3.86615 8.2 3.8486 1 P 0 
A 8.2 3.8486 8.1963 3.8449 8.1963 3.8486 1 P 0 Y
L 8.1963 3.8449 8.18873996 3.8449 1 P 0 
A 8.18873996 3.8449 8.17875 3.85488996 8.18873996 3.85488996 1 P 0 Y
L 8.17875 3.85488996 8.17875 3.87708002 1 P 0 
A 8.17875 3.87708002 8.17231004 3.89753002 8.14311998 3.87709872 1 P 0 N
L 8.17231004 3.89753002 8.14808996 3.93208002 1 P 0 
A 8.14808996 3.93208002 8.1476123 3.95359961 8.16395 3.94319715 1 P 0 Y
A 8.1476123 3.95359961 8.16731004 3.96226998 8.16394695 3.9432 1 P 0 Y
L 8.16731004 3.96226998 8.24718002 3.94816998 1 P 0 
A 8.24718002 3.94816998 8.24915 3.948 8.249131 3.95928002 1 P 0 N
L 8.24915 3.948 8.24918002 3.948 1 P 0 
A 8.24918002 3.948 8.43928002 4.02673996 8.24917874 4.21685 1 P 0 N
L 8.43928002 4.02673996 8.46743996 4.0549 1 P 0 
A 8.46743996 4.0549 8.50081998 4.11903002 8.38245 4.13988996 1 P 0 N
L 8.50081998 4.11903002 8.50521998 4.14396998 1 P 0 
A 8.50521998 4.14396998 8.51193002 4.15726004 8.53056998 4.13950994 1 P 0 Y
L 8.51193002 4.15726004 8.51203002 4.15736004 1 P 0 
L 8.51203002 4.15736004 8.51211998 4.15743996 1 P 0 
L 8.51211998 4.15743996 8.51225 4.15756998 1 P 0 
L 8.51225 4.15756998 8.51228996 4.1576 1 P 0 
A 8.51228996 4.1576 8.52615512 4.16406811 8.52809724 4.14181004 1 P 0 Y
A 8.52615512 4.16406811 8.54093002 4.1601 8.52809754 4.14181004 1 P 0 Y
L 8.54093002 4.1601 8.55901004 4.14741004 1 P 0 
A 8.55901004 4.14741004 8.58975 4.1377 8.58975846 4.19123996 1 P 0 N
L 8.58975 4.1377 8.58978996 4.1377 1 P 0 
A 8.58978996 4.1377 8.60187303 4.14010187 8.58978681 4.16931004 1 P 0 N
A 8.60187303 4.14010187 8.61211998 4.14693996 8.58978661 4.16931004 1 P 0 N
L 8.61211998 4.14693996 8.61843002 4.15325 1 P 0 
A 8.61843002 4.15325 8.61866998 4.15346998 8.6210435 4.15063996 1 P 0 Y
L 8.61866998 4.15346998 8.62798996 4.16126004 1 P 0 
A 8.62798996 4.16126004 8.65137579 4.17688435 8.67895591 4.11028996 1 P 0 Y
A 8.65137579 4.17688435 8.67896004 4.18236998 8.67895689 4.11028996 1 P 0 Y
L 8.67896004 4.18236998 8.67898002 4.18236998 1 P 0 
A 8.67898002 4.18236998 8.72093996 4.16498996 8.67898051 4.12303002 1 P 0 Y
L 8.72093996 4.16498996 8.78686004 4.09905 1 P 0 
A 8.78686004 4.09905 8.80180502 4.08907579 8.81940463 4.13163002 1 P 0 N
A 8.80180502 4.08907579 8.81943002 4.08558002 8.81940443 4.13163002 1 P 0 N
L 8.81943002 4.08558002 8.81946004 4.08558002 1 P 0 
A 8.81946004 4.08558002 8.84405502 4.09046565 8.81947402 4.14986004 1 P 0 N
A 8.84405502 4.09046565 8.86491004 4.10438996 8.819475 4.14986004 1 P 0 N
L 8.86491004 4.10438996 8.87511004 4.11458002 1 P 0 
A 8.87511004 4.11458002 8.89245089 4.1405189 8.81861004 4.17111762 1 P 0 N
A 8.89245089 4.1405189 8.89853996 4.17111998 8.81861004 4.17111831 1 P 0 N
A 8.89853996 4.17111998 8.89335846 4.19230276 8.85266998 4.1711249 1 P 0 N
A 8.89335846 4.19230276 8.87898002 4.2087 8.85266998 4.17112648 1 P 0 N
L 8.87898002 4.2087 8.81028002 4.25678996 1 P 0 
A 8.81028002 4.25678996 8.79424705 4.28454902 8.83201998 4.2878561 1 P 0 Y
A 8.79424705 4.28454902 8.80521004 4.31466998 8.83201998 4.2878565 1 P 0 Y
L 8.80521004 4.31466998 8.80881998 4.31828002 1 P 0 
A 8.80881998 4.31828002 8.8306374 4.32845344 8.83370207 4.2934 1 P 0 Y
A 8.8306374 4.32845344 8.85388996 4.32221998 8.83370217 4.2934 1 P 0 Y
L 8.85388996 4.32221998 8.94468996 4.25863002 1 P 0 
A 8.94468996 4.25863002 8.97561496 4.25034409 8.97153248 4.29696004 1 P 0 N
A 8.97561496 4.25034409 9.00463002 4.26388002 8.97153287 4.29696004 1 P 0 N
L 9.00463002 4.26388002 9.00463996 4.26388002 1 P 0 
A 9.00463996 4.26388002 9.02121437 4.28870994 8.95043002 4.31801289 1 P 0 N
A 9.02121437 4.28870994 9.02703996 4.31798996 8.95043002 4.3180128 1 P 0 N
L 9.02703996 4.31798996 9.02705 4.318 1 P 0 
A 9.02705 4.318 9.01643996 4.34361998 8.99081004 4.31799882 1 P 0 N
L 9.01643996 4.34361998 9.01341998 4.34663002 1 P 0 
A 9.01341998 4.34663002 9.01191998 4.3479 9.00546073 4.33875 1 P 0 N
L 9.01191998 4.3479 8.87611004 4.44298996 1 P 0 
A 8.87611004 4.44298996 8.86581004 4.46278002 8.88996998 4.46277894 1 P 0 Y
L 8.86581004 4.46278002 8.86581004 4.46736004 1 P 0 
A 8.86581004 4.46736004 8.86855236 4.48113957 8.90181004 4.46735817 1 P 0 Y
A 8.86855236 4.48113957 8.87636004 4.49281998 8.90181004 4.46735846 1 P 0 Y
L 8.87636004 4.49281998 8.88126998 4.49773002 1 P 0 
A 8.88126998 4.49773002 8.90140787 4.50712018 8.90423898 4.47476004 1 P 0 Y
A 8.90140787 4.50712018 8.92286998 4.50136998 8.90423917 4.47476004 1 P 0 Y
L 8.92286998 4.50136998 8.97765 4.46301004 1 P 0 
A 8.97765 4.46301004 8.98444242 4.45965374 8.99192589 4.48335 1 P 0 N
A 8.98444242 4.45965374 8.99193002 4.4585 8.99192638 4.48335 1 P 0 N
L 8.99193002 4.4585 8.99453996 4.4585 1 P 0 
A 8.99453996 4.4585 9.00481801 4.46054577 8.99453829 4.48535 1 P 0 N
A 9.00481801 4.46054577 9.01353002 4.46636998 8.99453848 4.48535 1 P 0 N
L 9.01353002 4.46636998 9.02236998 4.47521004 1 P 0 
A 9.02236998 4.47521004 9.02589892 4.48006644 9.00893002 4.48868661 1 P 0 N
A 9.02589892 4.48006644 9.02773996 4.48578002 9.00893002 4.4886876 1 P 0 N
L 9.02773996 4.48578002 9.02946998 4.49705 1 P 0 
L 9.02946998 4.49705 9.02643002 4.51433996 1 P 0 
L 9.02643002 4.51433996 9.03085 4.52061004 1 P 0 
L 9.03085 4.52061004 9.02891998 4.53156004 1 P 0 
L 9.02891998 4.53156004 9.02263002 4.53593996 1 P 0 
L 9.02263002 4.53593996 9.0207 4.54688002 1 P 0 
L 9.0207 4.54688002 9.02511004 4.55315 1 P 0 
L 9.02511004 4.55315 9.02318002 4.5641 1 P 0 
L 9.02318002 4.5641 9.01688996 4.56848996 1 P 0 
L 9.01688996 4.56848996 9.01501998 4.57903996 1 P 0 
L 9.01501998 4.57903996 9.01678996 4.58906998 1 P 0 
L 9.01678996 4.58906998 9.02391004 4.59925 1 P 0 
L 9.02391004 4.59925 9.0437 4.6131 1 P 0 
L 9.0437 4.6131 9.053 4.62636998 1 P 0 
L 9.053 4.62636998 9.053 4.6633 1 P 0 
A 9.053 4.6633 9.0567 4.667 9.0567 4.6633 1 P 0 Y
L 9.0567 4.667 9.06925 4.667 1 P 0 
P 8.2 3.86615 5 P 0 0;2=3,4=1
P 5.03268002 2.16615 5 P 0 0;2=3,4=1
P 3.9099 5.395 6 P 0 0;2=2,4=1
L 5.03268002 2.16615 5.05653002 2.19 2 P 0 
L 5.05653002 2.19 5.135 2.19 2 P 0 
L 5.135 2.19 5.145 2.18 2 P 0 
L 5.145 2.18 5.145 1.805 2 P 0 
L 5.145 1.805 5.1055 1.7655 2 P 0 
L 5.1055 1.7655 4.18643996 1.7655 2 P 0 
L 4.18643996 1.7655 3.9968 1.95513996 2 P 0 
L 3.9968 1.95513996 3.9968 4.2318 2 P 0 
L 3.9968 4.2318 4.09325 4.32825 2 P 0 
L 4.09325 4.32825 4.09325 4.70675 2 P 0 
L 4.09325 4.70675 4.08 4.72 2 P 0 
L 4.08 4.72 4.08 4.80221004 2 P 0 
L 4.08 4.80221004 4.12825 4.85046004 2 P 0 
L 4.12825 4.85046004 4.12825 5.20175 2 P 0 
L 4.12825 5.20175 3.995 5.335 2 P 0 
L 3.995 5.335 3.9699 5.335 2 P 0 
L 3.9699 5.335 3.9099 5.395 2 P 0 
P 10.82676998 5.49685 8 P 0 0;2=4,4=0
P 10.99213002 5.49685 8 P 0 0;2=4,4=0
P 11.15748002 5.49685 8 P 0 0;2=4,4=0
P 11.32283996 5.49685 8 P 0 0;2=4,4=0
P 11.48818996 5.49685 8 P 0 0;2=4,4=0
P 11.65353996 5.49685 8 P 0 0;2=4,4=0
P 11.8189 5.49685 8 P 0 0;2=4,4=0
P 11.98425 5.49685 8 P 0 0;2=4,4=0
P 12.14961004 5.49685 8 P 0 0;2=5,4=0
P 10.80498996 5.56656004 6 P 0 0;2=1,4=1
P 10.84498996 5.56656004 6 P 0 0;2=1,4=1
P 10.80498996 5.42656004 6 P 0 0;2=1,4=1
P 10.84498996 5.42656004 6 P 0 0;2=1,4=1
P 11.01035 5.42656004 6 P 0 0;2=1,4=1
P 10.97035 5.42656004 6 P 0 0;2=1,4=1
P 11.01035 5.56656004 6 P 0 0;2=1,4=1
P 10.97035 5.56656004 6 P 0 0;2=1,4=1
P 11.17571004 5.42656004 6 P 0 0;2=1,4=1
P 11.13571004 5.42656004 6 P 0 0;2=1,4=1
P 11.17571004 5.56656004 6 P 0 0;2=1,4=1
P 11.13571004 5.56656004 6 P 0 0;2=1,4=1
P 11.34106998 5.42656004 6 P 0 0;2=1,4=1
P 11.30106998 5.42656004 6 P 0 0;2=1,4=1
P 11.34106998 5.56656004 6 P 0 0;2=1,4=1
P 11.30106998 5.56656004 6 P 0 0;2=1,4=1
P 11.50643002 5.42656004 6 P 0 0;2=1,4=1
P 11.46643002 5.42656004 6 P 0 0;2=1,4=1
P 11.50643002 5.56656004 6 P 0 0;2=1,4=1
P 11.46643002 5.56656004 6 P 0 0;2=1,4=1
P 11.67178996 5.42656004 6 P 0 0;2=1,4=1
P 11.63178996 5.42656004 6 P 0 0;2=1,4=1
P 11.67178996 5.56656004 6 P 0 0;2=1,4=1
P 11.63178996 5.56656004 6 P 0 0;2=1,4=1
P 11.83715 5.42656004 6 P 0 0;2=1,4=1
P 11.79715 5.42656004 6 P 0 0;2=1,4=1
P 11.83715 5.56656004 6 P 0 0;2=1,4=1
P 11.79715 5.56656004 6 P 0 0;2=1,4=1
P 12.00251004 5.42656004 6 P 0 0;2=1,4=1
P 11.96251004 5.42656004 6 P 0 0;2=1,4=1
P 12.00251004 5.56656004 6 P 0 0;2=1,4=1
P 11.96251004 5.56656004 6 P 0 0;2=1,4=1
P 12.16786998 5.42656004 6 P 0 0;2=1,4=1
P 12.12786998 5.42656004 6 P 0 0;2=1,4=1
P 12.16786998 5.56656004 6 P 0 0;2=1,4=1
P 12.12786998 5.56656004 6 P 0 0;2=1,4=1
S P 0
OB 10.78 5.565 I
OS 10.8 5.585
OS 12.19 5.585
OS 12.205 5.57
OS 12.205 5.42
OS 12.19 5.405
OS 10.8 5.405
OS 10.78 5.425
OS 10.78 5.565
OE
SE
P 5.08268002 2.71615 5 P 0 0;2=3,4=1
P 4.06 4.86 6 P 0 0;2=2,4=1
L 4.06 4.86 4.06 4.70001004 2 P 0 
L 4.06 4.70001004 4.04325 4.68326004 2 P 0 
L 4.04325 4.68326004 4.04325 4.30018996 2 P 0 
L 4.04325 4.30018996 3.9813 4.23823996 2 P 0 
L 3.9813 4.23823996 3.9813 1.9487 2 P 0 
L 3.9813 1.9487 4.18 1.75 2 P 0 
L 4.18 1.75 5.115 1.75 2 P 0 
L 5.115 1.75 5.1605 1.7955 2 P 0 
L 5.1605 1.7955 5.1605 2.6995 2 P 0 
L 5.1605 2.6995 5.14385 2.71615 2 P 0 
L 5.14385 2.71615 5.08268002 2.71615 2 P 0 
L 11.865 4.455 11.67761998 4.26761998 6 P 0 
L 11.67761998 4.26761998 11.67761998 2.85 6 P 0 
P 11.67761998 2.85 6 P 0 0;2=1,4=1
P 11.865 4.455 6 P 0 0;2=2,4=1
P 11.235 3.3 6 P 0 0;2=1,4=1
P 5.815 0.925 6 P 0 0;2=2,4=1
L 5.815 0.925 5.843 0.953 2 P 0 
L 5.843 0.953 9.673 0.953 2 P 0 
L 9.673 0.953 10.4517 1.7317 2 P 0 
L 10.4517 1.7317 11.1067 1.7317 2 P 0 
L 11.1067 1.7317 11.205 1.83 2 P 0 
L 11.205 1.83 11.205 2.8 2 P 0 
L 11.205 2.8 11.235 2.83 2 P 0 
L 11.235 2.83 11.235 3.3 2 P 0 
P 10.99998996 4.9531 6 P 0 0;2=1,4=1
P 11.03998996 4.9531 6 P 0 0;2=1,4=1
P 10.99998996 4.9131 6 P 0 0;2=1,4=1
P 11.03998996 4.9131 6 P 0 0;2=1,4=1
P 11.21998996 4.9531 6 P 0 0;2=1,4=1
P 11.17998996 4.9531 6 P 0 0;2=1,4=1
P 11.13498996 4.9531 6 P 0 0;2=1,4=1
P 11.08498996 4.9531 6 P 0 0;2=1,4=1
P 11.21998996 4.9131 6 P 0 0;2=1,4=1
P 11.17998996 4.9131 6 P 0 0;2=1,4=1
P 11.08498996 4.9131 6 P 0 0;2=1,4=1
P 11.13498996 4.9131 6 P 0 0;2=1,4=1
P 10.99998996 5.1631 6 P 0 0;2=1,4=1
P 11.03998996 5.1631 6 P 0 0;2=1,4=1
P 10.99998996 5.1231 6 P 0 0;2=1,4=1
P 10.99998996 5.0381 6 P 0 0;2=1,4=1
P 10.99998996 5.0831 6 P 0 0;2=1,4=1
P 10.99998996 4.9931 6 P 0 0;2=1,4=1
P 11.03998996 4.9931 6 P 0 0;2=1,4=1
P 11.03998996 5.0831 6 P 0 0;2=1,4=1
P 11.03998996 5.0381 6 P 0 0;2=1,4=1
P 11.03998996 5.1231 6 P 0 0;2=1,4=1
P 11.21998996 5.1631 6 P 0 0;2=1,4=1
P 11.17998996 5.1631 6 P 0 0;2=1,4=1
P 11.08498996 5.1631 6 P 0 0;2=1,4=1
P 11.13498996 5.1631 6 P 0 0;2=1,4=1
P 11.21998996 5.1231 6 P 0 0;2=1,4=1
P 11.21998996 5.0381 6 P 0 0;2=1,4=1
P 11.21998996 5.0831 6 P 0 0;2=1,4=1
P 11.21998996 4.9931 6 P 0 0;2=1,4=1
P 11.17998996 4.9931 6 P 0 0;2=1,4=1
P 11.17998996 5.1231 6 P 0 0;2=1,4=1
P 11.17998996 5.0831 6 P 0 0;2=1,4=1
P 11.17998996 5.0381 6 P 0 0;2=1,4=1
P 11.13498996 5.1231 6 P 0 0;2=1,4=1
P 11.08498996 5.1231 6 P 0 0;2=1,4=1
P 11.6269 4.90498996 6 P 0 0;2=1,4=1
P 11.6269 4.85498996 6 P 0 0;2=1,4=1
P 11.4269 4.80998996 6 P 0 0;2=1,4=1
P 11.4269 4.85498996 6 P 0 0;2=1,4=1
P 11.4269 4.90498996 6 P 0 0;2=1,4=1
P 11.4269 4.94998996 6 P 0 0;2=1,4=1
P 11.4769 4.94998996 6 P 0 0;2=1,4=1
P 11.4769 4.80998996 6 P 0 0;2=1,4=1
P 11.5269 4.94998996 6 P 0 0;2=1,4=1
P 11.5269 4.80998996 6 P 0 0;2=1,4=1
P 11.5769 4.94998996 6 P 0 0;2=1,4=1
P 11.6269 4.94998996 6 P 0 0;2=1,4=1
P 11.6269 4.80998996 6 P 0 0;2=1,4=1
P 11.5769 4.80998996 6 P 0 0;2=1,4=1
P 10.82676998 5.71338996 8 P 0 0;2=4,4=0
P 10.99213002 5.71338996 8 P 0 0;2=4,4=0
P 11.15748002 5.71338996 8 P 0 0;2=4,4=0
P 11.32283996 5.71338996 8 P 0 0;2=4,4=0
P 11.48818996 5.71338996 8 P 0 0;2=4,4=0
P 11.65353996 5.71338996 8 P 0 0;2=4,4=0
P 11.8189 5.71338996 8 P 0 0;2=4,4=0
P 11.98425 5.71338996 8 P 0 0;2=4,4=0
P 12.14961004 5.71338996 8 P 0 0;2=4,4=0
P 10.80498996 5.7831 6 P 0 0;2=1,4=1
P 10.84498996 5.7831 6 P 0 0;2=1,4=1
P 10.80498996 5.6431 6 P 0 0;2=1,4=1
P 10.84498996 5.6431 6 P 0 0;2=1,4=1
P 11.01035 5.6431 6 P 0 0;2=1,4=1
P 10.97035 5.6431 6 P 0 0;2=1,4=1
P 11.01035 5.7831 6 P 0 0;2=1,4=1
P 10.97035 5.7831 6 P 0 0;2=1,4=1
P 11.17571004 5.6431 6 P 0 0;2=1,4=1
P 11.13571004 5.6431 6 P 0 0;2=1,4=1
P 11.17571004 5.7831 6 P 0 0;2=1,4=1
P 11.13571004 5.7831 6 P 0 0;2=1,4=1
P 11.34106998 5.6431 6 P 0 0;2=1,4=1
P 11.30106998 5.6431 6 P 0 0;2=1,4=1
P 11.34106998 5.7831 6 P 0 0;2=1,4=1
P 11.30106998 5.7831 6 P 0 0;2=1,4=1
P 11.50643002 5.6431 6 P 0 0;2=1,4=1
P 11.46643002 5.6431 6 P 0 0;2=1,4=1
P 11.50643002 5.7831 6 P 0 0;2=1,4=1
P 11.46643002 5.7831 6 P 0 0;2=1,4=1
P 11.67178996 5.6431 6 P 0 0;2=1,4=1
P 11.63178996 5.6431 6 P 0 0;2=1,4=1
P 11.67178996 5.7831 6 P 0 0;2=1,4=1
P 11.63178996 5.7831 6 P 0 0;2=1,4=1
P 11.83715 5.6431 6 P 0 0;2=1,4=1
P 11.79715 5.6431 6 P 0 0;2=1,4=1
P 11.83715 5.7831 6 P 0 0;2=1,4=1
P 11.79715 5.7831 6 P 0 0;2=1,4=1
P 12.00251004 5.6431 6 P 0 0;2=1,4=1
P 11.96251004 5.6431 6 P 0 0;2=1,4=1
P 12.00251004 5.7831 6 P 0 0;2=1,4=1
P 11.96251004 5.7831 6 P 0 0;2=1,4=1
P 12.16786998 5.6431 6 P 0 0;2=1,4=1
P 12.12786998 5.6431 6 P 0 0;2=1,4=1
P 12.16786998 5.7831 6 P 0 0;2=1,4=1
P 12.12786998 5.7831 6 P 0 0;2=1,4=1
S P 0
OB 11.31405 4.78405 I
OS 11.195 4.9031
OS 10.99498996063 4.9031
OS 10.98998996063 4.9081
OS 10.98998996063 5.12
OS 10.95498996063 5.155
OS 10.577 5.155
OS 10.567 5.165
OS 10.567 5.836
OS 10.616 5.885
OS 12.49 5.885
OS 12.52 5.855
OS 12.52 5.285
OS 12.255 5.02
OS 11.730969980315 5.02
OS 11.7 4.989030019685
OS 11.7 4.825
OS 11.65905 4.78405
OS 11.31405 4.78405
OE
OB 10.79585 5.394980019685 H
OS 12.19415 5.394980019685
OS 12.215019980315 5.41585
OS 12.215019980315 5.57415
OS 12.19415 5.595019980315
OS 10.79585 5.595019980315
OS 10.769980019685 5.56915
OS 10.769980019685 5.42085
OS 10.79585 5.394980019685
OE
OB 12.415380019685 5.695280019685 H
OC 12.415380019685 5.695280019685 12.33465 5.695280019685 N
OE
SE
P 2.74225 5.14 5 P 0 0;2=3,4=1
P 2.04606004 3.61615 5 P 0 0;2=3,4=1
L 2.04606004 3.61615 2.04606004 3.6337 1 P 0 
A 2.04606004 3.6337 2.04236004 3.6374 2.04236004 3.6337 1 P 0 N
L 2.04236004 3.6374 1.96958996 3.6374 1 P 0 
A 1.96958996 3.6374 1.94124419 3.64433455 1.96959222 3.69881004 1 P 0 Y
A 1.94124419 3.64433455 1.9193 3.66356998 1.96959262 3.69881004 1 P 0 Y
L 1.9193 3.66356998 1.91931004 3.66356998 1 P 0 
L 1.91931004 3.66356998 1.89001004 3.70538996 1 P 0 
A 1.89001004 3.70538996 1.88385148 3.71661654 1.93816004 3.7391061 1 P 0 Y
A 1.88385148 3.71661654 1.88026998 3.72891004 1.93816004 3.73910679 1 P 0 Y
L 1.88026998 3.72891004 1.85808996 3.85463996 1 P 0 
L 1.85808996 3.85463996 1.93431004 4.28683996 1 P 0 
L 1.93431004 4.28683996 2.04501004 4.44495 1 P 0 
L 2.04501004 4.44495 2.2068 4.55823002 1 P 0 
L 2.2068 4.55823002 2.32158002 4.57846998 1 P 0 
L 2.32158002 4.57846998 2.44403002 4.6642 1 P 0 
L 2.44403002 4.6642 2.44403996 4.66421004 1 P 0 
L 2.44403996 4.66421004 2.48485 4.69278002 1 P 0 
L 2.48485 4.69278002 2.53213996 4.76033996 1 P 0 
L 2.53213996 4.76033996 2.53673996 4.78638996 1 P 0 
A 2.53673996 4.78638996 2.53982687 4.79547323 2.56781998 4.7808937 1 P 0 Y
A 2.53982687 4.79547323 2.5455 4.80321004 2.56781998 4.78089518 1 P 0 Y
L 2.5455 4.80321004 2.54551998 4.80323002 1 P 0 
A 2.54551998 4.80323002 2.58 4.81751004 2.58000118 4.76873996 1 P 0 Y
A 2.58 4.81751004 2.59560226 4.8206127 2.58000217 4.85828002 1 P 0 N
A 2.59560226 4.8206127 2.60883002 4.82945 2.58000305 4.85828002 1 P 0 N
L 2.60883002 4.82945 2.60883996 4.82946004 1 P 0 
A 2.60883996 4.82946004 2.61408573 4.83731043 2.59171998 4.84657776 1 P 0 N
A 2.61408573 4.83731043 2.61593002 4.84656998 2.59171998 4.84657864 1 P 0 N
A 2.61593002 4.84656998 2.595 4.86748996 2.59500994 4.84656998 1 P 0 N
A 2.595 4.86748996 2.57261998 4.87676004 2.5949999 4.89913996 1 P 0 Y
L 2.57261998 4.87676004 2.56468996 4.88468996 1 P 0 
A 2.56468996 4.88468996 2.55936801 4.89266043 2.58206998 4.90205669 1 P 0 Y
A 2.55936801 4.89266043 2.5575 4.90206004 2.58206998 4.90205748 1 P 0 Y
L 2.5575 4.90206004 2.5575 4.90561004 1 P 0 
A 2.5575 4.90561004 2.5597873 4.91715305 2.58763996 4.90563583 1 P 0 Y
A 2.5597873 4.91715305 2.56631998 4.92693996 2.58763996 4.90563533 1 P 0 Y
L 2.56631998 4.92693996 2.56956998 4.93018996 1 P 0 
A 2.56956998 4.93018996 2.59328002 4.94 2.5932686 4.90646998 1 P 0 Y
L 2.59328002 4.94 2.61086004 4.94 1 P 0 
A 2.61086004 4.94 2.62313632 4.94228425 2.61085827 4.97413996 1 P 0 N
A 2.62313632 4.94228425 2.63376998 4.94883002 2.61085837 4.97413996 1 P 0 N
A 2.63376998 4.94883002 2.635 4.95 2.61086683 4.97413996 1 P 0 N
L 2.635 4.95 2.63501004 4.95 1 P 0 
A 2.63501004 4.95 2.63501004 4.99156004 2.61423002 4.97078002 1 P 0 N
L 2.63501004 4.99156004 2.60451998 5.01291004 1 P 0 
L 2.60451998 5.01291004 2.59196998 5.0254 1 P 0 
A 2.59196998 5.0254 2.5839688 5.03858839 2.61491998 5.04834469 1 P 0 Y
A 2.5839688 5.03858839 2.58296004 5.05398002 2.61491998 5.04834577 1 P 0 Y
L 2.58296004 5.05398002 2.58676998 5.07553996 1 P 0 
L 2.58676998 5.07553996 2.61655 5.11808996 1 P 0 
L 2.61655 5.11808996 2.635 5.131 1 P 0 
L 2.635 5.131 2.66528002 5.13633002 1 P 0 
L 2.66528002 5.13633002 2.68036004 5.13366998 1 P 0 
L 2.68036004 5.13366998 2.70781998 5.11443996 1 P 0 
L 2.70781998 5.11443996 2.70781998 5.11443002 1 P 0 
L 2.70781998 5.11443002 2.72218996 5.10438002 1 P 0 
L 2.72218996 5.10438002 2.73281998 5.1025 1 P 0 
L 2.73281998 5.1025 2.73935 5.1025 1 P 0 
A 2.73935 5.1025 2.74506191 5.10364429 2.73933356 5.11741004 1 P 0 N
A 2.74506191 5.10364429 2.7499 5.10688996 2.73933474 5.11741004 1 P 0 N
L 2.7499 5.10688996 2.7546 5.11161004 1 P 0 
L 2.7546 5.11161004 2.75461004 5.11161004 1 P 0 
A 2.75461004 5.11161004 2.75748652 5.1159189 2.74518996 5.12101319 1 P 0 N
A 2.75748652 5.1159189 2.7585 5.121 2.74518996 5.12101319 1 P 0 N
L 2.7585 5.121 2.7585 5.1355 1 P 0 
A 2.7585 5.1355 2.754 5.14 2.754 5.1355 1 P 0 N
L 2.754 5.14 2.74225 5.14 1 P 0 
P 2.78225 5.14 5 P 0 0;2=3,4=1
P 2.04606004 3.66615 5 P 0 0;2=3,4=1
L 2.04606004 3.66615 2.04606004 3.6486 1 P 0 
A 2.04606004 3.6486 2.04236004 3.6449 2.04236004 3.6486 1 P 0 Y
L 2.04236004 3.6449 1.96958996 3.6449 1 P 0 
A 1.96958996 3.6449 1.92545 3.66788002 1.96958898 3.69878002 1 P 0 Y
L 1.92545 3.66788002 1.89616004 3.7097 1 P 0 
A 1.89616004 3.7097 1.89078681 3.71948947 1.93816004 3.73912224 1 P 0 Y
A 1.89078681 3.71948947 1.88766004 3.73021004 1.93816004 3.73912264 1 P 0 Y
L 1.88766004 3.73021004 1.86571004 3.85463996 1 P 0 
L 1.86571004 3.85463996 1.94141004 4.2839 1 P 0 
L 1.94141004 4.2839 2.0504 4.43956004 1 P 0 
L 2.0504 4.43956004 2.20973996 4.55113002 1 P 0 
L 2.20973996 4.55113002 2.32451998 4.57136998 1 P 0 
L 2.32451998 4.57136998 2.49023996 4.68738996 1 P 0 
L 2.49023996 4.68738996 2.53923996 4.7574 1 P 0 
L 2.53923996 4.7574 2.54413002 4.78508002 1 P 0 
A 2.54413002 4.78508002 2.54648445 4.79200374 2.56781998 4.78088632 1 P 0 Y
A 2.54648445 4.79200374 2.55081004 4.7979 2.56781998 4.78088642 1 P 0 Y
L 2.55081004 4.7979 2.55083002 4.79791998 1 P 0 
A 2.55083002 4.79791998 2.58 4.81 2.58000049 4.76873996 1 P 0 Y
A 2.58 4.81 2.59847608 4.81367461 2.58000128 4.85828002 1 P 0 N
A 2.59847608 4.81367461 2.61413996 4.82413996 2.58000226 4.85828002 1 P 0 N
L 2.61413996 4.82413996 2.61415 4.82415 1 P 0 
A 2.61415 4.82415 2.62101732 4.83443238 2.59171998 4.84656486 1 P 0 N
A 2.62101732 4.83443238 2.62343002 4.84656004 2.59171998 4.84656467 1 P 0 N
L 2.62343002 4.84656004 2.62343002 4.84656998 1 P 0 
A 2.62343002 4.84656998 2.595 4.875 2.595 4.84656998 1 P 0 N
A 2.595 4.875 2.57793002 4.88206998 2.59499911 4.89913996 1 P 0 Y
L 2.57793002 4.88206998 2.57 4.89 1 P 0 
A 2.57 4.89 2.565 4.90206998 2.58206998 4.90207057 1 P 0 Y
L 2.565 4.90206998 2.565 4.90561998 1 P 0 
A 2.565 4.90561998 2.56672195 4.91428425 2.58763002 4.90562569 1 P 0 Y
A 2.56672195 4.91428425 2.57163002 4.92163002 2.58763002 4.90562707 1 P 0 Y
L 2.57163002 4.92163002 2.57488002 4.92488002 1 P 0 
A 2.57488002 4.92488002 2.58332234 4.93051929 2.59328209 4.90646998 1 P 0 Y
A 2.58332234 4.93051929 2.59328002 4.9325 2.59328189 4.90646998 1 P 0 Y
L 2.59328002 4.9325 2.61086998 4.9325 1 P 0 
A 2.61086998 4.9325 2.62584124 4.93528661 2.61086447 4.97413996 1 P 0 N
A 2.62584124 4.93528661 2.63881004 4.94326998 2.61086535 4.97413996 1 P 0 N
A 2.63881004 4.94326998 2.64031998 4.94468996 2.61430522 4.97083996 1 P 0 N
A 2.64031998 4.94468996 2.65112136 4.97112343 2.61423002 4.97077451 1 P 0 N
A 2.65112136 4.97112343 2.63981998 4.99735 2.61423002 4.9707747 1 P 0 N
L 2.63981998 4.99735 2.60936004 5.01868996 1 P 0 
L 2.60936004 5.01868996 2.59728002 5.03071004 1 P 0 
A 2.59728002 5.03071004 2.59112736 5.04084705 2.61491998 5.04835226 1 P 0 Y
A 2.59112736 5.04084705 2.59035 5.05268002 2.61491998 5.04835207 1 P 0 Y
L 2.59035 5.05268002 2.59386998 5.0726 1 P 0 
L 2.59386998 5.0726 2.6043 5.08748996 1 P 0 
L 2.6043 5.08748996 2.61186004 5.08881004 1 P 0 
L 2.61186004 5.08881004 2.61823996 5.09793002 1 P 0 
L 2.61823996 5.09793002 2.61688996 5.10548996 1 P 0 
L 2.61688996 5.10548996 2.62193996 5.1127 1 P 0 
L 2.62193996 5.1127 2.63793996 5.1239 1 P 0 
L 2.63793996 5.1239 2.66528002 5.12871004 1 P 0 
L 2.66528002 5.12871004 2.67741998 5.12656998 1 P 0 
L 2.67741998 5.12656998 2.68698996 5.11986998 1 P 0 
L 2.68698996 5.11986998 2.68808002 5.11353996 1 P 0 
L 2.68808002 5.11353996 2.6972 5.10716004 1 P 0 
L 2.6972 5.10716004 2.70351004 5.10828996 1 P 0 
L 2.70351004 5.10828996 2.71925 5.09728002 1 P 0 
L 2.71925 5.09728002 2.73216004 5.095 1 P 0 
L 2.73216004 5.095 2.73933996 5.095 1 P 0 
A 2.73933996 5.095 2.7479372 5.09671152 2.73934764 5.11741004 1 P 0 N
A 2.7479372 5.09671152 2.75521998 5.10158996 2.73934734 5.11741004 1 P 0 N
L 2.75521998 5.10158996 2.75991998 5.10631004 1 P 0 
A 2.75991998 5.10631004 2.766 5.12098996 2.74518996 5.12100984 1 P 0 N
L 2.766 5.12098996 2.766 5.136 1 P 0 
A 2.766 5.136 2.77 5.14 2.77 5.136 1 P 0 Y
L 2.77 5.14 2.78225 5.14 1 P 0 
P 2.88086998 5.17001998 5 P 0 0;2=3,4=1
P 2.14606004 3.61615 5 P 0 0;2=3,4=1
L 2.14606004 3.61615 2.14606004 3.6337 1 P 0 
A 2.14606004 3.6337 2.14236004 3.6374 2.14236004 3.6337 1 P 0 N
L 2.14236004 3.6374 2.1348 3.6374 1 P 0 
A 2.1348 3.6374 2.12481004 3.62741004 2.1348 3.62741004 1 P 0 N
L 2.12481004 3.62741004 2.12481004 3.60215 1 P 0 
A 2.12481004 3.60215 2.11006004 3.5874 2.11006004 3.60215 1 P 0 Y
L 2.11006004 3.5874 2.0267 3.5874 1 P 0 
A 2.0267 3.5874 1.89713996 3.65483996 2.0267 3.74556998 1 P 0 Y
L 1.89713996 3.65483996 1.87378996 3.6882 1 P 0 
A 1.87378996 3.6882 1.85825 3.72575 1.95075 3.74204026 1 P 0 Y
L 1.85825 3.72575 1.83515 3.85661998 1 P 0 
L 1.83515 3.85661998 1.91241998 4.29491998 1 P 0 
L 1.91241998 4.29491998 2.03078996 4.46396998 1 P 0 
L 2.03078996 4.46396998 2.19733996 4.58063002 1 P 0 
L 2.19733996 4.58063002 2.30886004 4.60031004 1 P 0 
L 2.30886004 4.60031004 2.46543002 4.70991998 1 P 0 
L 2.46543002 4.70991998 2.48786004 4.74195 1 P 0 
L 2.48786004 4.74195 2.48785 4.74195 1 P 0 
L 2.48785 4.74195 2.51026998 4.77395 1 P 0 
L 2.51026998 4.77395 2.56476998 5.08303002 1 P 0 
L 2.56476998 5.08303002 2.61961004 5.16138996 1 P 0 
L 2.61961004 5.16138996 2.68273002 5.20558002 1 P 0 
L 2.68273002 5.20558002 2.75056004 5.21753002 1 P 0 
L 2.75056004 5.21753002 2.81065 5.20693996 1 P 0 
A 2.81065 5.20693996 2.82615 5.19885 2.80553169 5.17823996 1 P 0 Y
L 2.82615 5.19885 2.838 5.187 1 P 0 
A 2.838 5.187 2.84392037 5.17814075 2.81868996 5.1676878 1 P 0 Y
A 2.84392037 5.17814075 2.846 5.16768996 2.81868996 5.1676878 1 P 0 Y
L 2.846 5.16768996 2.846 5.162 1 P 0 
A 2.846 5.162 2.84710226 5.15645856 2.86048996 5.16200187 1 P 0 N
A 2.84710226 5.15645856 2.85023996 5.15176004 2.86048996 5.16200197 1 P 0 N
L 2.85023996 5.15176004 2.86033996 5.14166004 1 P 0 
A 2.86033996 5.14166004 2.86660689 5.13747156 2.87400266 5.15531998 1 P 0 N
A 2.86660689 5.13747156 2.874 5.136 2.87400256 5.15531998 1 P 0 N
L 2.874 5.136 2.87713002 5.136 1 P 0 
A 2.87713002 5.136 2.89711998 5.15598996 2.87713002 5.15598996 1 P 0 N
L 2.89711998 5.15598996 2.89711998 5.1649 1 P 0 
A 2.89711998 5.1649 2.892 5.17001998 2.892 5.1649 1 P 0 N
L 2.892 5.17001998 2.88086998 5.17001998 1 P 0 
P 2.34606004 3.66615 5 P 0 0;2=3,4=1
P 3.56176998 4.71973002 5 P 0 0;2=3,4=1
L 3.56176998 4.71973002 3.54961998 4.71973002 1 P 0 
A 3.54961998 4.71973002 3.54591998 4.71603002 3.54961998 4.71603002 1 P 0 N
L 3.54591998 4.71603002 3.54591998 4.66728002 1 P 0 
L 3.54591998 4.66728002 3.52963996 4.651 1 P 0 
L 3.52963996 4.651 3.43143002 4.651 1 P 0 
L 3.43143002 4.651 3.42058996 4.64341004 1 P 0 
L 3.42058996 4.64341004 3.41538996 4.63598996 1 P 0 
L 3.41538996 4.63598996 3.406 4.58268996 1 P 0 
L 3.406 4.58268996 3.406 4.58066004 1 P 0 
A 3.406 4.58066004 3.40858524 4.56380571 3.46226998 4.58066565 1 P 0 N
A 3.40858524 4.56380571 3.4161 4.5485 3.46226998 4.58066604 1 P 0 N
L 3.4161 4.5485 3.50263002 4.42483002 1 P 0 
L 3.50263002 4.42483002 3.54918996 4.16058996 1 P 0 
L 3.54918996 4.16058996 3.53506998 4.08051004 1 P 0 
L 3.53506998 4.08051004 3.37586998 3.85313996 1 P 0 
L 3.37586998 3.85313996 2.94483002 3.5513 1 P 0 
L 2.94483002 3.5513 2.72743996 3.51298002 1 P 0 
L 2.72743996 3.51298002 2.6586 3.52826004 1 P 0 
L 2.6586 3.52826004 2.58073002 3.58278996 1 P 0 
A 2.58073002 3.58278996 2.5737748 3.58621959 2.566106 3.5619 1 P 0 N
A 2.5737748 3.58621959 2.56611004 3.5874 2.5661062 3.5619 1 P 0 N
L 2.56611004 3.5874 2.48211998 3.5874 1 P 0 
A 2.48211998 3.5874 2.46731004 3.60221004 2.48211998 3.60220994 1 P 0 Y
L 2.46731004 3.60221004 2.46731004 3.63125 1 P 0 
A 2.46731004 3.63125 2.46116004 3.6374 2.46116004 3.63125 1 P 0 N
L 2.46116004 3.6374 2.44098996 3.6374 1 P 0 
A 2.44098996 3.6374 2.43354774 3.6388812 2.44098858 3.65683002 1 P 0 Y
A 2.43354774 3.6388812 2.42723996 3.6431 2.4409876 3.65683002 1 P 0 Y
L 2.42723996 3.6431 2.4217 3.64863996 1 P 0 
A 2.4217 3.64863996 2.41731004 3.65923002 2.43228002 3.65923071 1 P 0 Y
L 2.41731004 3.65923002 2.41731004 3.67908996 1 P 0 
A 2.41731004 3.67908996 2.409 3.6874 2.409 3.67908996 1 P 0 N
L 2.409 3.6874 2.34976004 3.6874 1 P 0 
A 2.34976004 3.6874 2.34606004 3.6837 2.34976004 3.6837 1 P 0 N
L 2.34606004 3.6837 2.34606004 3.66615 1 P 0 
P 2.92086998 5.17001998 5 P 0 0;2=3,4=1
P 2.14606004 3.66615 5 P 0 0;2=3,4=1
L 2.14606004 3.66615 2.14606004 3.6486 1 P 0 
A 2.14606004 3.6486 2.14236004 3.6449 2.14236004 3.6486 1 P 0 Y
L 2.14236004 3.6449 2.1348 3.6449 1 P 0 
A 2.1348 3.6449 2.11731004 3.62741004 2.1348 3.62741004 1 P 0 N
L 2.11731004 3.62741004 2.11731004 3.60215 1 P 0 
A 2.11731004 3.60215 2.11006004 3.5949 2.11006004 3.60215 1 P 0 Y
L 2.11006004 3.5949 2.0267 3.5949 1 P 0 
A 2.0267 3.5949 1.95713337 3.6119249 2.02670167 3.74555 1 P 0 Y
A 1.95713337 3.6119249 1.90328996 3.65915 2.02670167 3.74555 1 P 0 Y
L 1.90328996 3.65915 1.87993996 3.69251004 1 P 0 
A 1.87993996 3.69251004 1.8709001 3.70899774 1.95075 3.74205571 1 P 0 Y
A 1.8709001 3.70899774 1.86563996 3.72705 1.95075 3.74205719 1 P 0 Y
L 1.86563996 3.72705 1.84276998 3.85661998 1 P 0 
L 1.84276998 3.85661998 1.91951998 4.29198002 1 P 0 
L 1.91951998 4.29198002 2.03618002 4.45858002 1 P 0 
L 2.03618002 4.45858002 2.20028002 4.57353002 1 P 0 
L 2.20028002 4.57353002 2.3118 4.59321004 1 P 0 
L 2.3118 4.59321004 2.47081998 4.70453002 1 P 0 
L 2.47081998 4.70453002 2.51736998 4.77101004 1 P 0 
L 2.51736998 4.77101004 2.57186998 5.08008996 1 P 0 
L 2.57186998 5.08008996 2.625 5.156 1 P 0 
L 2.625 5.156 2.63528996 5.16321004 1 P 0 
L 2.63528996 5.16321004 2.641 5.16218996 1 P 0 
L 2.641 5.16218996 2.65011004 5.16856998 1 P 0 
L 2.65011004 5.16856998 2.65108996 5.17426998 1 P 0 
L 2.65108996 5.17426998 2.6602 5.18065 1 P 0 
L 2.6602 5.18065 2.66591998 5.17963002 1 P 0 
L 2.66591998 5.17963002 2.67503002 5.18601004 1 P 0 
L 2.67503002 5.18601004 2.67601004 5.19171004 1 P 0 
L 2.67601004 5.19171004 2.67601004 5.19171998 1 P 0 
L 2.67601004 5.19171998 2.68566998 5.19848002 1 P 0 
L 2.68566998 5.19848002 2.75056004 5.20991004 1 P 0 
L 2.75056004 5.20991004 2.80933996 5.19955 1 P 0 
A 2.80933996 5.19955 2.81555059 5.19742677 2.80552293 5.17823996 1 P 0 Y
A 2.81555059 5.19742677 2.82083996 5.19353996 2.80552421 5.17823996 1 P 0 Y
L 2.82083996 5.19353996 2.83268996 5.18168996 1 P 0 
A 2.83268996 5.18168996 2.83698878 5.17526339 2.81868996 5.16767411 1 P 0 Y
A 2.83698878 5.17526339 2.8385 5.16768002 2.81868996 5.16767451 1 P 0 Y
L 2.8385 5.16768002 2.8385 5.162 1 P 0 
L 2.8385 5.162 2.83848996 5.16198996 1 P 0 
A 2.83848996 5.16198996 2.84016614 5.15358002 2.86048996 5.16200276 1 P 0 N
A 2.84016614 5.15358002 2.84493002 5.14645 2.86048996 5.16200276 1 P 0 N
L 2.84493002 5.14645 2.85503002 5.13635 1 P 0 
A 2.85503002 5.13635 2.874 5.1285 2.87398917 5.15531998 1 P 0 N
L 2.874 5.1285 2.87713002 5.1285 1 P 0 
A 2.87713002 5.1285 2.90461998 5.15598996 2.87713002 5.15598996 1 P 0 N
L 2.90461998 5.15598996 2.90461998 5.16631998 1 P 0 
A 2.90461998 5.16631998 2.90831998 5.17001998 2.90831998 5.16631998 1 P 0 Y
L 2.90831998 5.17001998 2.92086998 5.17001998 1 P 0 
P 2.34606004 3.71615 5 P 0 0;2=3,4=1
P 3.52176998 4.71973002 5 P 0 0;2=3,4=1
L 3.52176998 4.71973002 3.53471998 4.71973002 1 P 0 
A 3.53471998 4.71973002 3.53841998 4.71603002 3.53471998 4.71603002 1 P 0 Y
L 3.53841998 4.71603002 3.53841998 4.67038996 1 P 0 
L 3.53841998 4.67038996 3.52653002 4.6585 1 P 0 
L 3.52653002 4.6585 3.49563996 4.6585 1 P 0 
L 3.49563996 4.6585 3.49113996 4.663 1 P 0 
L 3.49113996 4.663 3.48003996 4.663 1 P 0 
L 3.48003996 4.663 3.47553996 4.6585 1 P 0 
L 3.47553996 4.6585 3.46443996 4.6585 1 P 0 
L 3.46443996 4.6585 3.45993996 4.663 1 P 0 
L 3.45993996 4.663 3.44883996 4.663 1 P 0 
L 3.44883996 4.663 3.44433996 4.6585 1 P 0 
L 3.44433996 4.6585 3.42906004 4.6585 1 P 0 
L 3.42906004 4.6585 3.4152 4.64881004 1 P 0 
L 3.4152 4.64881004 3.40828996 4.63893002 1 P 0 
L 3.40828996 4.63893002 3.3985 4.58335 1 P 0 
L 3.3985 4.58335 3.3985 4.58065 1 P 0 
A 3.3985 4.58065 3.40142638 4.56154803 3.46226998 4.58064429 1 P 0 N
A 3.40142638 4.56154803 3.40993996 4.5442 3.46226998 4.58064409 1 P 0 N
L 3.40993996 4.5442 3.49553002 4.42188996 1 P 0 
L 3.49553002 4.42188996 3.54156998 4.16058996 1 P 0 
L 3.54156998 4.16058996 3.52796998 4.08345 1 P 0 
L 3.52796998 4.08345 3.37048002 3.85853002 1 P 0 
L 3.37048002 3.85853002 2.94188996 3.5584 1 P 0 
L 2.94188996 3.5584 2.72761004 3.52063002 1 P 0 
L 2.72761004 3.52063002 2.66168002 3.53526004 1 P 0 
L 2.66168002 3.53526004 2.58503996 3.58893996 1 P 0 
A 2.58503996 3.58893996 2.56611998 3.5949 2.56612008 3.56188996 1 P 0 N
L 2.56611998 3.5949 2.48211998 3.5949 1 P 0 
A 2.48211998 3.5949 2.47481004 3.60221004 2.48211998 3.60220994 1 P 0 Y
L 2.47481004 3.60221004 2.47481004 3.63125 1 P 0 
A 2.47481004 3.63125 2.46116004 3.6449 2.46116004 3.63125 1 P 0 N
L 2.46116004 3.6449 2.44098996 3.6449 1 P 0 
A 2.44098996 3.6449 2.43642156 3.64581004 2.44099163 3.65683002 1 P 0 Y
A 2.43642156 3.64581004 2.43255 3.6484 2.44099154 3.65683002 1 P 0 Y
L 2.43255 3.6484 2.427 3.65395 1 P 0 
A 2.427 3.65395 2.42481004 3.65923002 2.43226998 3.65922992 1 P 0 Y
L 2.42481004 3.65923002 2.42481004 3.67908996 1 P 0 
A 2.42481004 3.67908996 2.409 3.6949 2.409 3.67908996 1 P 0 N
L 2.409 3.6949 2.34976004 3.6949 1 P 0 
A 2.34976004 3.6949 2.34606004 3.6986 2.34976004 3.6986 1 P 0 Y
L 2.34606004 3.6986 2.34606004 3.71615 1 P 0 
P 2.39606004 3.61615 5 P 0 0;2=3,4=1
P 3.49091004 4.587 5 P 0 0;2=3,4=1
L 3.49091004 4.587 3.47886998 4.587 1 P 0 
A 3.47886998 4.587 3.47516998 4.5833 3.47886998 4.5833 1 P 0 N
L 3.47516998 4.5833 3.47516998 4.55096998 1 P 0 
L 3.47516998 4.55096998 3.47518002 4.55096004 1 P 0 
L 3.47518002 4.55096004 3.47661998 4.54278002 1 P 0 
L 3.47661998 4.54278002 3.4874 4.52738002 1 P 0 
L 3.4874 4.52738002 3.49053996 4.52518002 1 P 0 
L 3.49053996 4.52518002 3.49056004 4.52516004 1 P 0 
L 3.49056004 4.52516004 3.49325 4.52328002 1 P 0 
L 3.49325 4.52328002 3.50273996 4.5216 1 P 0 
L 3.50273996 4.5216 3.51598002 4.52393002 1 P 0 
L 3.51598002 4.52393002 3.55996998 4.55473002 1 P 0 
L 3.55996998 4.55473002 3.56328996 4.55611004 1 P 0 
L 3.56328996 4.55611004 3.56331998 4.55611998 1 P 0 
L 3.56331998 4.55611998 3.56341998 4.55606998 1 P 0 
L 3.56341998 4.55606998 3.57101004 4.5592 1 P 0 
A 3.57101004 4.5592 3.57729055 4.56109823 3.5838248 4.52813996 1 P 0 Y
A 3.57729055 4.56109823 3.58381998 4.56173996 3.58382608 4.52813996 1 P 0 Y
L 3.58381998 4.56173996 3.58871004 4.56173996 1 P 0 
A 3.58871004 4.56173996 3.62653996 4.54608002 3.58871959 4.50823996 1 P 0 Y
L 3.62653996 4.54608002 3.62921004 4.54341004 1 P 0 
A 3.62921004 4.54341004 3.63651624 4.53247195 3.60536998 4.51957667 1 P 0 Y
A 3.63651624 4.53247195 3.63908002 4.51956998 3.60536998 4.51957707 1 P 0 Y
L 3.63908002 4.51956998 3.63908002 4.51955 1 P 0 
A 3.63908002 4.51955 3.63891004 4.51761004 3.62788002 4.51955394 1 P 0 Y
L 3.63891004 4.51761004 3.63891998 4.51761004 1 P 0 
L 3.63891998 4.51761004 3.62998996 4.46696004 1 P 0 
L 3.62998996 4.46696004 3.62998002 4.46696004 1 P 0 
L 3.62998002 4.46696004 3.56093002 4.07526998 1 P 0 
L 3.56093002 4.07526998 3.39326004 3.83585 1 P 0 
L 3.39326004 3.83585 2.95001998 3.52546004 1 P 0 
L 2.95001998 3.52546004 2.72671998 3.48608002 1 P 0 
L 2.72671998 3.48608002 2.63931004 3.5015 1 P 0 
L 2.63931004 3.5015 2.59576998 3.53196998 1 P 0 
A 2.59576998 3.53196998 2.58756791 3.53601142 2.5785372 3.50733996 1 P 0 N
A 2.58756791 3.53601142 2.57853002 3.5374 2.5785372 3.50733996 1 P 0 N
L 2.57853002 3.5374 2.43491998 3.5374 1 P 0 
A 2.43491998 3.5374 2.41731004 3.55501004 2.43491998 3.55500994 1 P 0 Y
L 2.41731004 3.55501004 2.41731004 3.62431998 1 P 0 
A 2.41731004 3.62431998 2.41621998 3.62695 2.41358996 3.624319 1 P 0 N
L 2.41621998 3.62695 2.41621004 3.62695 1 P 0 
L 2.41621004 3.62695 2.40686004 3.6363 1 P 0 
L 2.40686004 3.6363 2.40686004 3.63631004 1 P 0 
A 2.40686004 3.63631004 2.40423002 3.6374 2.40422923 3.63368002 1 P 0 N
L 2.40423002 3.6374 2.39976004 3.6374 1 P 0 
A 2.39976004 3.6374 2.39606004 3.6337 2.39976004 3.6337 1 P 0 N
L 2.39606004 3.6337 2.39606004 3.61615 1 P 0 
P 2.39606004 3.66615 5 P 0 0;2=3,4=1
P 3.45091004 4.587 5 P 0 0;2=3,4=1
L 3.45091004 4.587 3.46396998 4.587 1 P 0 
A 3.46396998 4.587 3.46766998 4.5833 3.46396998 4.5833 1 P 0 Y
L 3.46766998 4.5833 3.46766998 4.5503 1 P 0 
L 3.46766998 4.5503 3.46951004 4.53983996 1 P 0 
L 3.46951004 4.53983996 3.48201004 4.52198996 1 P 0 
L 3.48201004 4.52198996 3.49031004 4.51616998 1 P 0 
L 3.49031004 4.51616998 3.50273996 4.51398002 1 P 0 
L 3.50273996 4.51398002 3.51891998 4.51683002 1 P 0 
L 3.51891998 4.51683002 3.53596004 4.52876004 1 P 0 
L 3.53596004 4.52876004 3.54276998 4.52753996 1 P 0 
L 3.54276998 4.52753996 3.55188002 4.53391998 1 P 0 
L 3.55188002 4.53391998 3.55306998 4.54073996 1 P 0 
L 3.55306998 4.54073996 3.55308002 4.54075 1 P 0 
L 3.55308002 4.54075 3.56291004 4.54761998 1 P 0 
L 3.56291004 4.54761998 3.56623996 4.54901004 1 P 0 
L 3.56623996 4.54901004 3.56628996 4.54913002 1 P 0 
L 3.56628996 4.54913002 3.57386998 4.55226004 1 P 0 
A 3.57386998 4.55226004 3.58383002 4.55423996 3.58383957 4.52815 1 P 0 Y
L 3.58383002 4.55423996 3.58871998 4.55423996 1 P 0 
A 3.58871998 4.55423996 3.62123002 4.54076998 3.58871033 4.50825 1 P 0 Y
L 3.62123002 4.54076998 3.6239 4.5381 1 P 0 
A 3.6239 4.5381 3.62958268 4.52959843 3.60536998 4.51956398 1 P 0 Y
A 3.62958268 4.52959843 3.63158002 4.51956998 3.60536998 4.51956289 1 P 0 Y
A 3.63158002 4.51956998 3.63151998 4.51893002 3.62788002 4.51959429 1 P 0 Y
L 3.63151998 4.51893002 3.62665 4.49138002 1 P 0 
L 3.62665 4.49138002 3.61948002 4.48636998 1 P 0 
L 3.61948002 4.48636998 3.61753996 4.47541998 1 P 0 
L 3.61753996 4.47541998 3.62258002 4.46823996 1 P 0 
L 3.62258002 4.46823996 3.55383002 4.07821004 1 P 0 
L 3.55383002 4.07821004 3.38786998 3.84123996 1 P 0 
L 3.38786998 3.84123996 2.94708002 3.53256004 1 P 0 
L 2.94708002 3.53256004 2.72671998 3.4937 1 P 0 
L 2.72671998 3.4937 2.64225 3.5086 1 P 0 
L 2.64225 3.5086 2.60008002 3.53811998 1 P 0 
A 2.60008002 3.53811998 2.58982657 3.5431685 2.57855512 3.50733996 1 P 0 N
A 2.58982657 3.5431685 2.57853002 3.5449 2.57855394 3.50733996 1 P 0 N
L 2.57853002 3.5449 2.43491998 3.5449 1 P 0 
A 2.43491998 3.5449 2.42481004 3.55501004 2.43491998 3.55500994 1 P 0 Y
L 2.42481004 3.55501004 2.42481004 3.62433002 1 P 0 
A 2.42481004 3.62433002 2.42395344 3.62862195 2.41358996 3.62432215 1 P 0 N
A 2.42395344 3.62862195 2.42151998 3.63226004 2.41358996 3.62432283 1 P 0 N
L 2.42151998 3.63226004 2.41216998 3.64161004 1 P 0 
A 2.41216998 3.64161004 2.40853189 3.6440435 2.40423278 3.63368002 1 P 0 N
A 2.40853189 3.6440435 2.40423996 3.6449 2.40423228 3.63368002 1 P 0 N
L 2.40423996 3.6449 2.39976004 3.6449 1 P 0 
A 2.39976004 3.6449 2.39606004 3.6486 2.39976004 3.6486 1 P 0 Y
L 2.39606004 3.6486 2.39606004 3.66615 1 P 0 
P 2.49606004 3.61615 5 P 0 0;2=3,4=1
P 3.56176998 5.14 5 P 0 0;2=3,4=1
L 3.56176998 5.14 3.54961998 5.14 1 P 0 
A 3.54961998 5.14 3.54591998 5.1363 3.54961998 5.1363 1 P 0 N
L 3.54591998 5.1363 3.54591998 5.10908002 1 P 0 
L 3.54591998 5.10908002 3.55 5.105 1 P 0 
L 3.55 5.105 3.61148996 5.105 1 P 0 
L 3.61148996 5.105 3.62223996 5.10311004 1 P 0 
L 3.62223996 5.10311004 3.63938002 5.0911 1 P 0 
L 3.63938002 5.0911 3.64503996 5.08301998 1 P 0 
L 3.64503996 5.08301998 3.65905 5.00363996 1 P 0 
L 3.65905 5.00363996 3.65901998 5.00363002 1 P 0 
L 3.65901998 5.00363002 3.6788 4.89178002 1 P 0 
L 3.6788 4.89178002 3.65818002 4.77491004 1 P 0 
A 3.65818002 4.77491004 3.64096998 4.74185 3.59715 4.78567087 1 P 0 Y
L 3.64096998 4.74185 3.64096004 4.74183002 1 P 0 
A 3.64096004 4.74183002 3.62950728 4.7341815 3.61601722 4.76678002 1 P 0 Y
A 3.62950728 4.7341815 3.616 4.7315 3.61601594 4.76678002 1 P 0 Y
L 3.616 4.7315 3.60381004 4.7315 1 P 0 
A 3.60381004 4.7315 3.59431486 4.73295177 3.60376309 4.76296998 1 P 0 Y
A 3.59431486 4.73295177 3.5857 4.7372 3.6037628 4.76296998 1 P 0 Y
L 3.5857 4.7372 3.56143996 4.75421004 1 P 0 
L 3.56143996 4.75421004 3.55788996 4.75776004 1 P 0 
A 3.55788996 4.75776004 3.54876457 4.76385807 3.53799823 4.73786998 1 P 0 N
A 3.54876457 4.76385807 3.538 4.766 3.53799813 4.73786998 1 P 0 N
A 3.538 4.766 3.48773002 4.74516004 3.53797913 4.695 1 P 0 N
L 3.48773002 4.74516004 3.40821998 4.66548002 1 P 0 
L 3.40821998 4.66548002 3.39173002 4.64193002 1 P 0 
L 3.39173002 4.64193002 3.382 4.58683002 1 P 0 
L 3.382 4.58683002 3.382 4.57948996 1 P 0 
A 3.382 4.57948996 3.38563878 4.55584567 3.46061998 4.5794872 1 P 0 N
A 3.38563878 4.55584567 3.39621998 4.53438996 3.46061998 4.57948671 1 P 0 N
L 3.39621998 4.53438996 3.47378002 4.42361004 1 P 0 
L 3.47378002 4.42361004 3.49865 4.28258002 1 P 0 
L 3.49865 4.28258002 3.46238002 4.07696004 1 P 0 
L 3.46238002 4.07696004 3.27591004 3.81063996 1 P 0 
L 3.27591004 3.81063996 2.9473 3.58053002 1 P 0 
L 2.9473 3.58053002 2.73631004 3.54333002 1 P 0 
L 2.73631004 3.54333002 2.68903996 3.55166004 1 P 0 
L 2.68903996 3.55166004 2.61106998 3.60623996 1 P 0 
A 2.61106998 3.60623996 2.56405236 3.62942352 2.51222717 3.46505 1 P 0 N
A 2.56405236 3.62942352 2.51223996 3.6374 2.51222697 3.46505 1 P 0 N
L 2.51223996 3.6374 2.49976004 3.6374 1 P 0 
A 2.49976004 3.6374 2.49606004 3.6337 2.49976004 3.6337 1 P 0 N
L 2.49606004 3.6337 2.49606004 3.61615 1 P 0 
P 2.49606004 3.66615 5 P 0 0;2=3,4=1
P 3.52176998 5.14 5 P 0 0;2=3,4=1
L 3.52176998 5.14 3.534 5.14 1 P 0 
A 3.534 5.14 3.53841998 5.13558002 3.534 5.13558002 1 P 0 Y
L 3.53841998 5.13558002 3.53841998 5.10596998 1 P 0 
L 3.53841998 5.10596998 3.54688996 5.0975 1 P 0 
L 3.54688996 5.0975 3.55916004 5.0975 1 P 0 
L 3.55916004 5.0975 3.56466004 5.092 1 P 0 
L 3.56466004 5.092 3.57576004 5.092 1 P 0 
L 3.57576004 5.092 3.58126004 5.0975 1 P 0 
L 3.58126004 5.0975 3.61083002 5.0975 1 P 0 
L 3.61083002 5.0975 3.61928996 5.09601004 1 P 0 
L 3.61928996 5.09601004 3.63398996 5.08571004 1 P 0 
L 3.63398996 5.08571004 3.63793996 5.08008002 1 P 0 
L 3.63793996 5.08008002 3.64825 5.02145 1 P 0 
L 3.64825 5.02145 3.64486998 5.01663996 1 P 0 
L 3.64486998 5.01663996 3.6468 5.00568996 1 P 0 
L 3.6468 5.00568996 3.65161998 5.00233002 1 P 0 
L 3.65161998 5.00233002 3.67118002 4.89178002 1 P 0 
L 3.67118002 4.89178002 3.65078996 4.77621004 1 P 0 
A 3.65078996 4.77621004 3.63566004 4.74715 3.59715 4.7856687 1 P 0 Y
L 3.63566004 4.74715 3.63565 4.74713996 1 P 0 
A 3.63565 4.74713996 3.62663455 4.74111496 3.61600364 4.76678002 1 P 0 Y
A 3.62663455 4.74111496 3.616 4.739 3.61600276 4.76678002 1 P 0 Y
L 3.616 4.739 3.6038 4.739 1 P 0 
A 3.6038 4.739 3.59657028 4.74010561 3.60376624 4.76296998 1 P 0 Y
A 3.59657028 4.74010561 3.59001004 4.74333996 3.60376555 4.76296998 1 P 0 Y
L 3.59001004 4.74333996 3.56628996 4.75998002 1 P 0 
L 3.56628996 4.75998002 3.5632 4.76306998 1 P 0 
A 3.5632 4.76306998 3.55163848 4.77079695 3.53800177 4.73788002 1 P 0 N
A 3.55163848 4.77079695 3.538 4.77351004 3.53800128 4.73788002 1 P 0 N
A 3.538 4.77351004 3.48241998 4.75046004 3.53798986 4.695 1 P 0 N
L 3.48241998 4.75046004 3.40245 4.67031998 1 P 0 
L 3.40245 4.67031998 3.38463002 4.64486998 1 P 0 
L 3.38463002 4.64486998 3.3745 4.58748996 1 P 0 
L 3.3745 4.58748996 3.3745 4.5795 1 P 0 
A 3.3745 4.5795 3.39006998 4.53008002 3.46061998 4.57946978 1 P 0 N
L 3.39006998 4.53008002 3.46668002 4.42066998 1 P 0 
L 3.46668002 4.42066998 3.49103002 4.28258002 1 P 0 
L 3.49103002 4.28258002 3.45528002 4.0799 1 P 0 
L 3.45528002 4.0799 3.27051998 3.81603002 1 P 0 
L 3.27051998 3.81603002 2.94436004 3.58763002 1 P 0 
L 2.94436004 3.58763002 2.73631004 3.55095 1 P 0 
L 2.73631004 3.55095 2.69198002 3.55876004 1 P 0 
L 2.69198002 3.55876004 2.61538002 3.61238996 1 P 0 
A 2.61538002 3.61238996 2.51225 3.6449 2.51224124 3.46503996 1 P 0 N
L 2.51225 3.6449 2.49976004 3.6449 1 P 0 
A 2.49976004 3.6449 2.49606004 3.6486 2.49976004 3.6486 1 P 0 Y
L 2.49606004 3.6486 2.49606004 3.66615 1 P 0 
P 2.44606004 3.66615 5 P 0 0;2=3,4=1
P 3.42003996 4.78291998 5 P 0 0;2=3,4=1
L 3.42003996 4.78291998 3.40788996 4.78291998 1 P 0 
A 3.40788996 4.78291998 3.40418996 4.77921998 3.40788996 4.77921998 1 P 0 N
L 3.40418996 4.77921998 3.40418996 4.73698996 1 P 0 
L 3.40418996 4.73698996 3.39731004 4.69813996 1 P 0 
L 3.39731004 4.69813996 3.36863002 4.65716004 1 P 0 
L 3.36863002 4.65716004 3.36178002 4.6184 1 P 0 
L 3.36178002 4.6184 3.35655 4.61093002 1 P 0 
L 3.35655 4.61093002 3.33958002 4.59908002 1 P 0 
L 3.33958002 4.59908002 3.28605 4.58961998 1 P 0 
L 3.28605 4.58961998 3.26986004 4.5783 1 P 0 
L 3.26986004 4.5783 3.26131004 4.56608002 1 P 0 
L 3.26131004 4.56608002 3.25916004 4.55386004 1 P 0 
L 3.25916004 4.55386004 3.26168002 4.53953996 1 P 0 
L 3.26168002 4.53953996 3.26168002 4.53955 1 P 0 
L 3.26168002 4.53955 3.26738996 4.53138996 1 P 0 
L 3.26738996 4.53138996 3.27348002 4.52711998 1 P 0 
L 3.27348002 4.52711998 3.32125 4.5187 1 P 0 
L 3.32125 4.5187 3.36901004 4.51028002 1 P 0 
A 3.36901004 4.51028002 3.39086811 4.49765827 3.36259902 4.47393996 1 P 0 Y
A 3.39086811 4.49765827 3.3995 4.47393996 3.3626 4.47394065 1 P 0 Y
A 3.3995 4.47393996 3.39120138 4.45114104 3.36403002 4.47394094 1 P 0 Y
A 3.39120138 4.45114104 3.37018996 4.43901004 3.36403071 4.47393996 1 P 0 Y
L 3.37018996 4.43901004 3.32381998 4.43083002 1 P 0 
A 3.32381998 4.43083002 3.29898032 4.41648504 3.33110886 4.38953002 1 P 0 N
A 3.29898032 4.41648504 3.28916998 4.38953002 3.33111004 4.38952864 1 P 0 N
L 3.28916998 4.38953002 3.28916998 4.38948996 1 P 0 
A 3.28916998 4.38948996 3.2928003 4.37123583 3.33686998 4.38948829 1 P 0 N
A 3.2928003 4.37123583 3.30313996 4.35576004 3.33686998 4.3894876 1 P 0 N
L 3.30313996 4.35576004 3.30316004 4.35573996 1 P 0 
A 3.30316004 4.35573996 3.31776201 4.34836043 3.32743159 4.38563002 1 P 0 N
A 3.31776201 4.34836043 3.33411004 4.34771004 3.32743169 4.38563002 1 P 0 N
L 3.33411004 4.34771004 3.41501004 4.36196004 1 P 0 
L 3.41501004 4.36196004 3.41506998 4.36196004 1 P 0 
A 3.41506998 4.36196004 3.42797766 4.35939193 3.41506841 4.32823002 1 P 0 Y
A 3.42797766 4.35939193 3.43891998 4.35208002 3.4150687 4.32823002 1 P 0 Y
L 3.43891998 4.35208002 3.45108996 4.33991004 1 P 0 
A 3.45108996 4.33991004 3.47081998 4.29226998 3.40343996 4.29227028 1 P 0 Y
L 3.47081998 4.29226998 3.47081998 4.27495 1 P 0 
A 3.47081998 4.27495 3.46901998 4.25426998 3.35111004 4.27495128 1 P 0 Y
L 3.46901998 4.25426998 3.43968996 4.08796998 1 P 0 
L 3.43968996 4.08796998 3.25596004 3.8256 1 P 0 
L 3.25596004 3.8256 2.93681004 3.60211004 1 P 0 
L 2.93681004 3.60211004 2.73926004 3.56728002 1 P 0 
L 2.73926004 3.56728002 2.69845 3.57441998 1 P 0 
L 2.69845 3.57441998 2.65123002 3.60746998 1 P 0 
L 2.65123002 3.60746998 2.61086998 3.66508996 1 P 0 
L 2.61086998 3.66508996 2.58551998 3.68283002 1 P 0 
A 2.58551998 3.68283002 2.57861152 3.6862315 2.57100689 3.66206998 1 P 0 N
A 2.57861152 3.6862315 2.571 3.6874 2.57100679 3.66206998 1 P 0 N
L 2.571 3.6874 2.44976004 3.6874 1 P 0 
A 2.44976004 3.6874 2.44606004 3.6837 2.44976004 3.6837 1 P 0 N
L 2.44606004 3.6837 2.44606004 3.66615 1 P 0 
P 4.30605 4.6631 6 P 0 0;2=1,4=1
P 4.34105 4.6431 6 P 0 0;2=1,4=1
P 4.38605 4.6431 6 P 0 0;2=1,4=1
P 4.42605 4.6631 6 P 0 0;2=1,4=1
P 4.46605 4.6631 6 P 0 0;2=1,4=1
P 4.30605 4.7031 6 P 0 0;2=1,4=1
P 4.42605 4.7031 6 P 0 0;2=1,4=1
P 4.46605 4.7031 6 P 0 0;2=1,4=1
P 4.26605 4.6631 6 P 0 0;2=1,4=1
P 4.26605 4.7031 6 P 0 0;2=1,4=1
P 4.65605 4.6631 6 P 0 0;2=1,4=1
P 4.69605 4.6631 6 P 0 0;2=1,4=1
P 4.65605 4.7031 6 P 0 0;2=1,4=1
P 4.69605 4.7031 6 P 0 0;2=1,4=1
P 4.73105 4.6431 6 P 0 0;2=1,4=1
P 4.81605 4.6631 6 P 0 0;2=1,4=1
P 4.85605 4.6631 6 P 0 0;2=1,4=1
P 4.81605 4.7031 6 P 0 0;2=1,4=1
P 4.85605 4.7031 6 P 0 0;2=1,4=1
P 4.77605 4.6431 6 P 0 0;2=1,4=1
P 5.17605 4.7131 6 P 0 0;2=1,4=1
P 5.17605 4.6731 6 P 0 0;2=1,4=1
P 5.08105 4.6731 6 P 0 0;2=1,4=1
P 5.13105 4.6731 6 P 0 0;2=1,4=1
P 5.03605 4.6731 6 P 0 0;2=1,4=1
P 5.03605 4.7131 6 P 0 0;2=1,4=1
P 4.30605 4.7481 6 P 0 0;2=1,4=1
P 4.30605 4.7931 6 P 0 0;2=1,4=1
P 4.30605 4.8381 6 P 0 0;2=1,4=1
P 4.38605 4.8381 6 P 0 0;2=1,4=1
P 4.34605 4.8381 6 P 0 0;2=1,4=1
P 4.46605 4.8381 6 P 0 0;2=1,4=1
P 4.42605 4.8381 6 P 0 0;2=1,4=1
P 4.42605 4.7931 6 P 0 0;2=1,4=1
P 4.42605 4.7481 6 P 0 0;2=1,4=1
P 4.46605 4.7931 6 P 0 0;2=1,4=1
P 4.46605 4.7481 6 P 0 0;2=1,4=1
P 4.26605 4.7481 6 P 0 0;2=1,4=1
P 4.26605 4.7931 6 P 0 0;2=1,4=1
P 4.26605 4.8381 6 P 0 0;2=1,4=1
P 4.65605 4.8381 6 P 0 0;2=1,4=1
P 4.65605 4.7931 6 P 0 0;2=1,4=1
P 4.65605 4.7481 6 P 0 0;2=1,4=1
P 4.69605 4.8381 6 P 0 0;2=1,4=1
P 4.69605 4.7931 6 P 0 0;2=1,4=1
P 4.69605 4.7481 6 P 0 0;2=1,4=1
P 4.73605 4.8381 6 P 0 0;2=1,4=1
P 4.81605 4.8381 6 P 0 0;2=1,4=1
P 4.81605 4.7931 6 P 0 0;2=1,4=1
P 4.81605 4.7481 6 P 0 0;2=1,4=1
P 4.85605 4.8381 6 P 0 0;2=1,4=1
P 4.85605 4.7931 6 P 0 0;2=1,4=1
P 4.85605 4.7481 6 P 0 0;2=1,4=1
P 4.77605 4.8381 6 P 0 0;2=1,4=1
P 5.08105 4.8431 6 P 0 0;2=1,4=1
P 5.13105 4.8431 6 P 0 0;2=1,4=1
P 5.17605 4.8431 6 P 0 0;2=1,4=1
P 5.17605 4.8031 6 P 0 0;2=1,4=1
P 5.17605 4.7581 6 P 0 0;2=1,4=1
P 5.03605 4.8431 6 P 0 0;2=1,4=1
P 5.03605 4.8031 6 P 0 0;2=1,4=1
P 5.03605 4.7581 6 P 0 0;2=1,4=1
P 4.58268002 2.96615 5 P 0 0;2=3,4=1
P 4.63268002 2.96615 5 P 0 0;2=3,4=1
P 4.63268002 3.11615 5 P 0 0;2=3,4=1
P 4.58268002 3.01615 5 P 0 0;2=3,4=1
P 4.58268002 3.11615 5 P 0 0;2=3,4=1
P 4.63268002 3.01615 5 P 0 0;2=3,4=1
P 4.63268002 3.31615 5 P 0 0;2=3,4=1
P 4.58268002 3.26615 5 P 0 0;2=3,4=1
P 4.58268002 3.31615 5 P 0 0;2=3,4=1
P 4.63268002 3.26615 5 P 0 0;2=3,4=1
P 4.63268002 3.16615 5 P 0 0;2=3,4=1
P 4.58268002 3.16615 5 P 0 0;2=3,4=1
P 4.58268002 3.46615 5 P 0 0;2=3,4=1
P 4.63268002 3.41615 5 P 0 0;2=3,4=1
P 4.63268002 3.46615 5 P 0 0;2=3,4=1
P 4.58268002 3.41615 5 P 0 0;2=3,4=1
P 4.58268002 3.61615 5 P 0 0;2=3,4=1
P 4.58268002 3.56615 5 P 0 0;2=3,4=1
P 4.63268002 3.61615 5 P 0 0;2=3,4=1
P 4.63268002 3.56615 5 P 0 0;2=3,4=1
P 4.58268002 3.71615 5 P 0 0;2=3,4=1
P 4.63268002 3.71615 5 P 0 0;2=3,4=1
P 4.58268002 3.76615 5 P 0 0;2=3,4=1
P 4.58268002 3.86615 5 P 0 0;2=3,4=1
P 4.63268002 3.76615 5 P 0 0;2=3,4=1
P 4.63268002 3.86615 5 P 0 0;2=3,4=1
P 4.68268002 2.96615 5 P 0 0;2=3,4=1
P 4.73268002 2.96615 5 P 0 0;2=3,4=1
P 4.78268002 2.96615 5 P 0 0;2=3,4=1
P 4.68268002 3.11615 5 P 0 0;2=3,4=1
P 4.68268002 3.01615 5 P 0 0;2=3,4=1
P 4.73268002 3.11615 5 P 0 0;2=3,4=1
P 4.73268002 3.01615 5 P 0 0;2=3,4=1
P 4.78268002 3.11615 5 P 0 0;2=3,4=1
P 4.78268002 3.01615 5 P 0 0;2=3,4=1
P 4.73268002 3.31615 5 P 0 0;2=3,4=1
P 4.73268002 3.26615 5 P 0 0;2=3,4=1
P 4.68268002 3.26615 5 P 0 0;2=3,4=1
P 4.68268002 3.31615 5 P 0 0;2=3,4=1
P 4.78268002 3.26615 5 P 0 0;2=3,4=1
P 4.78268002 3.31615 5 P 0 0;2=3,4=1
P 4.73268002 3.16615 5 P 0 0;2=3,4=1
P 4.68268002 3.16615 5 P 0 0;2=3,4=1
P 4.78268002 3.16615 5 P 0 0;2=3,4=1
P 4.73268002 3.41615 5 P 0 0;2=3,4=1
P 4.68268002 3.41615 5 P 0 0;2=3,4=1
P 4.68268002 3.46615 5 P 0 0;2=3,4=1
P 4.73268002 3.46615 5 P 0 0;2=3,4=1
P 4.78268002 3.46615 5 P 0 0;2=3,4=1
P 4.78268002 3.41615 5 P 0 0;2=3,4=1
P 4.73268002 3.56615 5 P 0 0;2=3,4=1
P 4.73268002 3.61615 5 P 0 0;2=3,4=1
P 4.68268002 3.56615 5 P 0 0;2=3,4=1
P 4.68268002 3.61615 5 P 0 0;2=3,4=1
P 4.78268002 3.61615 5 P 0 0;2=3,4=1
P 4.78268002 3.56615 5 P 0 0;2=3,4=1
P 4.73268002 3.71615 5 P 0 0;2=3,4=1
P 4.68268002 3.71615 5 P 0 0;2=3,4=1
P 4.78268002 3.71615 5 P 0 0;2=3,4=1
P 4.73268002 3.76615 5 P 0 0;2=3,4=1
P 4.73268002 3.86615 5 P 0 0;2=3,4=1
P 4.68268002 3.76615 5 P 0 0;2=3,4=1
P 4.68268002 3.86615 5 P 0 0;2=3,4=1
P 4.78268002 3.76615 5 P 0 0;2=3,4=1
P 4.78268002 3.86615 5 P 0 0;2=3,4=1
P 4.88268002 3.86615 5 P 0 0;2=3,4=1
P 4.83268002 3.86615 5 P 0 0;2=3,4=1
P 5.03268002 3.86615 5 P 0 0;2=3,4=1
P 4.93268002 3.86615 5 P 0 0;2=3,4=1
P 4.98268002 3.86615 5 P 0 0;2=3,4=1
P 4.88268002 3.76615 5 P 0 0;2=3,4=1
P 4.83268002 3.76615 5 P 0 0;2=3,4=1
P 5.03268002 3.76615 5 P 0 0;2=3,4=1
P 4.93268002 3.76615 5 P 0 0;2=3,4=1
P 4.98268002 3.76615 5 P 0 0;2=3,4=1
P 4.88268002 3.71615 5 P 0 0;2=3,4=1
P 4.83268002 3.71615 5 P 0 0;2=3,4=1
P 5.03268002 3.71615 5 P 0 0;2=3,4=1
P 4.93268002 3.71615 5 P 0 0;2=3,4=1
P 4.98268002 3.71615 5 P 0 0;2=3,4=1
P 4.88268002 3.61615 5 P 0 0;2=3,4=1
P 4.83268002 3.61615 5 P 0 0;2=3,4=1
P 5.03268002 3.61615 5 P 0 0;2=3,4=1
P 4.93268002 3.61615 5 P 0 0;2=3,4=1
P 4.98268002 3.61615 5 P 0 0;2=3,4=1
P 4.88268002 3.56615 5 P 0 0;2=3,4=1
P 4.83268002 3.56615 5 P 0 0;2=3,4=1
P 5.03268002 3.56615 5 P 0 0;2=3,4=1
P 4.93268002 3.56615 5 P 0 0;2=3,4=1
P 4.98268002 3.56615 5 P 0 0;2=3,4=1
P 4.88268002 3.46615 5 P 0 0;2=3,4=1
P 4.83268002 3.46615 5 P 0 0;2=3,4=1
P 5.03268002 3.46615 5 P 0 0;2=3,4=1
P 4.93268002 3.46615 5 P 0 0;2=3,4=1
P 4.98268002 3.46615 5 P 0 0;2=3,4=1
P 4.88268002 3.41615 5 P 0 0;2=3,4=1
P 4.83268002 3.41615 5 P 0 0;2=3,4=1
P 5.03268002 3.41615 5 P 0 0;2=3,4=1
P 4.93268002 3.41615 5 P 0 0;2=3,4=1
P 4.98268002 3.41615 5 P 0 0;2=3,4=1
P 4.88268002 3.31615 5 P 0 0;2=3,4=1
P 4.83268002 3.31615 5 P 0 0;2=3,4=1
P 5.03268002 3.31615 5 P 0 0;2=3,4=1
P 4.93268002 3.31615 5 P 0 0;2=3,4=1
P 4.98268002 3.31615 5 P 0 0;2=3,4=1
P 4.83268002 3.26615 5 P 0 0;2=3,4=1
P 4.88268002 3.26615 5 P 0 0;2=3,4=1
P 4.98268002 3.26615 5 P 0 0;2=3,4=1
P 4.93268002 3.26615 5 P 0 0;2=3,4=1
P 5.03268002 3.26615 5 P 0 0;2=3,4=1
P 4.83268002 3.16615 5 P 0 0;2=3,4=1
P 4.88268002 3.16615 5 P 0 0;2=3,4=1
P 4.98268002 3.16615 5 P 0 0;2=3,4=1
P 4.93268002 3.16615 5 P 0 0;2=3,4=1
P 5.03268002 3.16615 5 P 0 0;2=3,4=1
P 4.83268002 3.11615 5 P 0 0;2=3,4=1
P 4.88268002 3.11615 5 P 0 0;2=3,4=1
P 4.98268002 3.11615 5 P 0 0;2=3,4=1
P 4.93268002 3.11615 5 P 0 0;2=3,4=1
P 5.03268002 3.11615 5 P 0 0;2=3,4=1
P 4.83268002 3.01615 5 P 0 0;2=3,4=1
P 4.88268002 3.01615 5 P 0 0;2=3,4=1
P 4.98268002 3.01615 5 P 0 0;2=3,4=1
P 4.93268002 3.01615 5 P 0 0;2=3,4=1
P 5.03268002 3.01615 5 P 0 0;2=3,4=1
P 4.83268002 2.96615 5 P 0 0;2=3,4=1
P 4.88268002 2.96615 5 P 0 0;2=3,4=1
P 4.98268002 2.96615 5 P 0 0;2=3,4=1
P 4.93268002 2.96615 5 P 0 0;2=3,4=1
P 5.03268002 2.96615 5 P 0 0;2=3,4=1
S P 0
OB 4.29998996063 2.958 I
OS 4.25605 3.00193996063
OS 4.25605 4.8381
OS 4.26605 4.8481
OS 5.18105 4.8481
OS 5.22106003937 4.80808996063
OS 5.22106003937 3.033
OS 5.14606003937 2.958
OS 4.29998996063 2.958
OE
OB 4.5987 3.06615 H
OC 4.5987 3.06615 4.582680019685 3.06615 N
OE
OB 4.6487 3.06615 H
OC 4.6487 3.06615 4.632680019685 3.06615 N
OE
OB 4.5987 3.21615 H
OC 4.5987 3.21615 4.582680019685 3.21615 N
OE
OB 4.6487 3.21615 H
OC 4.6487 3.21615 4.632680019685 3.21615 N
OE
OB 4.5987 3.36615 H
OC 4.5987 3.36615 4.582680019685 3.36615 N
OE
OB 4.6487 3.36615 H
OC 4.6487 3.36615 4.632680019685 3.36615 N
OE
OB 4.5987 3.51615 H
OC 4.5987 3.51615 4.582680019685 3.51615 N
OE
OB 4.6487 3.51615 H
OC 4.6487 3.51615 4.632680019685 3.51615 N
OE
OB 4.5987 3.66615 H
OC 4.5987 3.66615 4.582680019685 3.66615 N
OE
OB 4.5987 3.81615 H
OC 4.5987 3.81615 4.582680019685 3.81615 N
OE
OB 4.6487 3.66615 H
OC 4.6487 3.66615 4.632680019685 3.66615 N
OE
OB 4.6487 3.81615 H
OC 4.6487 3.81615 4.632680019685 3.81615 N
OE
OB 4.8987 3.06615 H
OC 4.8987 3.06615 4.882680019685 3.06615 N
OE
OB 4.8487 3.06615 H
OC 4.8487 3.06615 4.832680019685 3.06615 N
OE
OB 4.6987 3.06615 H
OC 4.6987 3.06615 4.682680019685 3.06615 N
OE
OB 4.7487 3.06615 H
OC 4.7487 3.06615 4.732680019685 3.06615 N
OE
OB 4.7987 3.06615 H
OC 4.7987 3.06615 4.782680019685 3.06615 N
OE
OB 4.8987 3.21615 H
OC 4.8987 3.21615 4.882680019685 3.21615 N
OE
OB 4.8487 3.21615 H
OC 4.8487 3.21615 4.832680019685 3.21615 N
OE
OB 4.8487 3.36615 H
OC 4.8487 3.36615 4.832680019685 3.36615 N
OE
OB 4.8987 3.36615 H
OC 4.8987 3.36615 4.882680019685 3.36615 N
OE
OB 4.6987 3.21615 H
OC 4.6987 3.21615 4.682680019685 3.21615 N
OE
OB 4.6987 3.36615 H
OC 4.6987 3.36615 4.682680019685 3.36615 N
OE
OB 4.7487 3.21615 H
OC 4.7487 3.21615 4.732680019685 3.21615 N
OE
OB 4.7987 3.21615 H
OC 4.7987 3.21615 4.782680019685 3.21615 N
OE
OB 4.7487 3.36615 H
OC 4.7487 3.36615 4.732680019685 3.36615 N
OE
OB 4.7987 3.36615 H
OC 4.7987 3.36615 4.782680019685 3.36615 N
OE
OB 4.8487 3.51615 H
OC 4.8487 3.51615 4.832680019685 3.51615 N
OE
OB 4.8987 3.51615 H
OC 4.8987 3.51615 4.882680019685 3.51615 N
OE
OB 4.6987 3.51615 H
OC 4.6987 3.51615 4.682680019685 3.51615 N
OE
OB 4.7487 3.51615 H
OC 4.7487 3.51615 4.732680019685 3.51615 N
OE
OB 4.7987 3.51615 H
OC 4.7987 3.51615 4.782680019685 3.51615 N
OE
OB 4.8487 3.81615 H
OC 4.8487 3.81615 4.832680019685 3.81615 N
OE
OB 4.8987 3.81615 H
OC 4.8987 3.81615 4.882680019685 3.81615 N
OE
OB 4.8487 3.66615 H
OC 4.8487 3.66615 4.832680019685 3.66615 N
OE
OB 4.8987 3.66615 H
OC 4.8987 3.66615 4.882680019685 3.66615 N
OE
OB 4.6987 3.66615 H
OC 4.6987 3.66615 4.682680019685 3.66615 N
OE
OB 4.6987 3.81615 H
OC 4.6987 3.81615 4.682680019685 3.81615 N
OE
OB 4.7487 3.66615 H
OC 4.7487 3.66615 4.732680019685 3.66615 N
OE
OB 4.7487 3.81615 H
OC 4.7487 3.81615 4.732680019685 3.81615 N
OE
OB 4.7987 3.66615 H
OC 4.7987 3.66615 4.782680019685 3.66615 N
OE
OB 4.7987 3.81615 H
OC 4.7987 3.81615 4.782680019685 3.81615 N
OE
OB 5.0487 3.06615 H
OC 5.0487 3.06615 5.032680019685 3.06615 N
OE
OB 4.9487 3.06615 H
OC 4.9487 3.06615 4.932680019685 3.06615 N
OE
OB 4.9987 3.06615 H
OC 4.9987 3.06615 4.982680019685 3.06615 N
OE
OB 5.0487 3.21615 H
OC 5.0487 3.21615 5.032680019685 3.21615 N
OE
OB 4.9487 3.21615 H
OC 4.9487 3.21615 4.932680019685 3.21615 N
OE
OB 4.9987 3.21615 H
OC 4.9987 3.21615 4.982680019685 3.21615 N
OE
OB 4.9987 3.36615 H
OC 4.9987 3.36615 4.982680019685 3.36615 N
OE
OB 4.9487 3.36615 H
OC 4.9487 3.36615 4.932680019685 3.36615 N
OE
OB 5.0487 3.36615 H
OC 5.0487 3.36615 5.032680019685 3.36615 N
OE
OB 4.9987 3.51615 H
OC 4.9987 3.51615 4.982680019685 3.51615 N
OE
OB 4.9487 3.51615 H
OC 4.9487 3.51615 4.932680019685 3.51615 N
OE
OB 5.0487 3.51615 H
OC 5.0487 3.51615 5.032680019685 3.51615 N
OE
OB 4.9987 3.81615 H
OC 4.9987 3.81615 4.982680019685 3.81615 N
OE
OB 4.9487 3.81615 H
OC 4.9487 3.81615 4.932680019685 3.81615 N
OE
OB 4.9987 3.66615 H
OC 4.9987 3.66615 4.982680019685 3.66615 N
OE
OB 4.9487 3.66615 H
OC 4.9487 3.66615 4.932680019685 3.66615 N
OE
OB 5.0487 3.66615 H
OC 5.0487 3.66615 5.032680019685 3.66615 N
OE
OB 5.0487 3.81615 H
OC 5.0487 3.81615 5.032680019685 3.81615 N
OE
OB 5.045269980315 4.22441003937 H
OC 5.045269980315 4.22441003937 4.832680019685 4.22441003937 N
OE
SE
P 2.44606004 3.71615 5 P 0 0;2=3,4=1
P 3.38003996 4.78291998 5 P 0 0;2=3,4=1
L 3.38003996 4.78291998 3.39298996 4.78291998 1 P 0 
A 3.39298996 4.78291998 3.39668996 4.77921998 3.39298996 4.77921998 1 P 0 Y
L 3.39668996 4.77921998 3.39668996 4.73765 1 P 0 
L 3.39668996 4.73765 3.39021004 4.70108002 1 P 0 
L 3.39021004 4.70108002 3.38313996 4.69098996 1 P 0 
L 3.38313996 4.69098996 3.37536004 4.68961998 1 P 0 
L 3.37536004 4.68961998 3.36896998 4.68051998 1 P 0 
L 3.36896998 4.68051998 3.37035 4.67273002 1 P 0 
L 3.37035 4.67273002 3.36153002 4.6601 1 P 0 
L 3.36153002 4.6601 3.35468002 4.62133996 1 P 0 
L 3.35468002 4.62133996 3.35115 4.61631998 1 P 0 
L 3.35115 4.61631998 3.33663996 4.60618002 1 P 0 
L 3.33663996 4.60618002 3.32388996 4.60393002 1 P 0 
L 3.32388996 4.60393002 3.31946998 4.60703002 1 P 0 
L 3.31946998 4.60703002 3.30851998 4.60508996 1 P 0 
L 3.30851998 4.60508996 3.30545 4.60066998 1 P 0 
L 3.30545 4.60066998 3.28311004 4.59671998 1 P 0 
L 3.28311004 4.59671998 3.26446998 4.58368996 1 P 0 
L 3.26446998 4.58368996 3.25421004 4.56901998 1 P 0 
L 3.25421004 4.56901998 3.25153996 4.55386004 1 P 0 
L 3.25153996 4.55386004 3.25458002 4.5366 1 P 0 
L 3.25458002 4.5366 3.262 4.526 1 P 0 
L 3.262 4.526 3.27053996 4.52001998 1 P 0 
L 3.27053996 4.52001998 3.36771004 4.50288996 1 P 0 
A 3.36771004 4.50288996 3.38512244 4.49283504 3.36260197 4.47393996 1 P 0 Y
A 3.38512244 4.49283504 3.392 4.47393996 3.3626 4.47393799 1 P 0 Y
A 3.392 4.47393996 3.38545807 4.45596417 3.36403996 4.4739372 1 P 0 Y
A 3.38545807 4.45596417 3.36888996 4.4464 3.36403671 4.47393996 1 P 0 Y
L 3.36888996 4.4464 3.32251998 4.43821998 1 P 0 
A 3.32251998 4.43821998 3.29323465 4.42130827 3.33111171 4.38953002 1 P 0 N
A 3.29323465 4.42130827 3.28166998 4.38953002 3.33111004 4.3895313 1 P 0 N
L 3.28166998 4.38953002 3.28166998 4.38948996 1 P 0 
A 3.28166998 4.38948996 3.28586683 4.3683623 3.33686998 4.38947431 1 P 0 N
A 3.28586683 4.3683623 3.29783002 4.35045 3.33686998 4.3894749 1 P 0 N
L 3.29783002 4.35045 3.29783002 4.35046004 1 P 0 
L 3.29783002 4.35046004 3.29811998 4.35016998 1 P 0 
A 3.29811998 4.35016998 3.31568278 4.34114872 3.32743258 4.38563002 1 P 0 N
A 3.31568278 4.34114872 3.33541004 4.34031998 3.32743248 4.38563002 1 P 0 N
L 3.33541004 4.34031998 3.41561998 4.35445 1 P 0 
A 3.41561998 4.35445 3.43361004 4.34676998 3.41506093 4.32823002 1 P 0 Y
L 3.43361004 4.34676998 3.44578002 4.3346 1 P 0 
A 3.44578002 4.3346 3.45875896 4.31517923 3.40343996 4.29225669 1 P 0 Y
A 3.45875896 4.31517923 3.46331998 4.29226998 3.40343996 4.29225709 1 P 0 Y
L 3.46331998 4.29226998 3.46331998 4.27496004 1 P 0 
A 3.46331998 4.27496004 3.46163002 4.25556998 3.35111004 4.27497116 1 P 0 Y
L 3.46163002 4.25556998 3.43258996 4.09091004 1 P 0 
L 3.43258996 4.09091004 3.25056998 3.83098996 1 P 0 
L 3.25056998 3.83098996 2.93386998 3.60921004 1 P 0 
L 2.93386998 3.60921004 2.73925 3.5749 1 P 0 
L 2.73925 3.5749 2.70138996 3.58153002 1 P 0 
L 2.70138996 3.58153002 2.65661998 3.61286004 1 P 0 
L 2.65661998 3.61286004 2.61626004 3.67048002 1 P 0 
L 2.61626004 3.67048002 2.58981998 3.68898002 1 P 0 
A 2.58981998 3.68898002 2.58086496 3.69338711 2.57101467 3.66206998 1 P 0 N
A 2.58086496 3.69338711 2.571 3.6949 2.57101368 3.66206998 1 P 0 N
L 2.571 3.6949 2.44976004 3.6949 1 P 0 
A 2.44976004 3.6949 2.44606004 3.6986 2.44976004 3.6986 1 P 0 Y
L 2.44606004 3.6986 2.44606004 3.71615 1 P 0 
P 2.19606004 3.81615 5 P 0 0;2=3,4=1
P 3.02571004 4.667 5 P 0 0;2=3,4=1
L 3.02571004 4.667 3.038 4.667 1 P 0 
A 3.038 4.667 3.04196004 4.66303996 3.038 4.66303996 1 P 0 Y
L 3.04196004 4.66303996 3.04196004 4.62873996 1 P 0 
L 3.04196004 4.62873996 3.03476998 4.61848996 1 P 0 
L 3.03476998 4.61848996 3.01498002 4.60463996 1 P 0 
L 3.01498002 4.60463996 3.00615 4.59201004 1 P 0 
L 3.00615 4.59201004 3.00386004 4.57903996 1 P 0 
L 3.00386004 4.57903996 3.01831998 4.49696998 1 P 0 
L 3.01831998 4.49696998 3.01678002 4.48691998 1 P 0 
A 3.01678002 4.48691998 3.01353002 4.48051998 3.00538996 4.48867874 1 P 0 Y
L 3.01353002 4.48051998 3.00468002 4.47168002 1 P 0 
A 3.00468002 4.47168002 2.991 4.466 2.99098917 4.48533996 1 P 0 Y
L 2.991 4.466 2.98838996 4.466 1 P 0 
A 2.98838996 4.466 2.97841998 4.46915 2.98838907 4.48335 1 P 0 Y
L 2.97841998 4.46915 2.92363002 4.50751998 1 P 0 
A 2.92363002 4.50751998 2.89720866 4.51460049 2.90069409 4.47476998 1 P 0 N
A 2.89720866 4.51460049 2.87241998 4.50303996 2.90069409 4.47476998 1 P 0 N
L 2.87241998 4.50303996 2.86751004 4.49813002 1 P 0 
A 2.86751004 4.49813002 2.8580815 4.48401693 2.89828002 4.46736742 1 P 0 N
A 2.8580815 4.48401693 2.85476998 4.46736998 2.89828002 4.46736752 1 P 0 N
L 2.85476998 4.46736998 2.85476998 4.46278002 1 P 0 
A 2.85476998 4.46278002 2.85834242 4.44815984 2.88643996 4.46277205 1 P 0 N
A 2.85834242 4.44815984 2.86826004 4.43683996 2.88643996 4.46277224 1 P 0 N
L 2.86826004 4.43683996 3.00406998 4.34175 1 P 0 
A 3.00406998 4.34175 3.00456998 4.34133002 3.00195128 4.33871998 1 P 0 Y
L 3.00456998 4.34133002 3.00758996 4.33831004 1 P 0 
A 3.00758996 4.33831004 3.016 4.318 2.98726998 4.31799961 1 P 0 Y
A 3.016 4.318 3.01074094 4.29158071 2.9469 4.31802205 1 P 0 Y
A 3.01074094 4.29158071 2.99578002 4.26918002 2.9469 4.31802224 1 P 0 Y
A 2.99578002 4.26918002 2.97142116 4.25782156 2.96799862 4.29696004 1 P 0 Y
A 2.97142116 4.25782156 2.94546004 4.26478002 2.96799852 4.29696004 1 P 0 Y
L 2.94546004 4.26478002 2.85466004 4.32836998 1 P 0 
A 2.85466004 4.32836998 2.82644439 4.33593474 2.8301625 4.2934 1 P 0 N
A 2.82644439 4.33593474 2.79996998 4.32358996 2.8301626 4.2934 1 P 0 N
L 2.79996998 4.32358996 2.79636004 4.31998002 1 P 0 
A 2.79636004 4.31998002 2.78322224 4.28389596 2.82846998 4.28785541 1 P 0 N
A 2.78322224 4.28389596 2.80243002 4.25063996 2.82846998 4.28785492 1 P 0 N
L 2.80243002 4.25063996 2.87113002 4.20255 1 P 0 
A 2.87113002 4.20255 2.88748996 4.17111998 2.84911998 4.17112047 1 P 0 Y
A 2.88748996 4.17111998 2.86626998 4.11988996 2.81506004 4.17111142 1 P 0 Y
L 2.86626998 4.11988996 2.85606998 4.1097 1 P 0 
A 2.85606998 4.1097 2.81593002 4.09308002 2.81593091 4.14986004 1 P 0 Y
L 2.81593002 4.09308002 2.81588996 4.09308002 1 P 0 
A 2.81588996 4.09308002 2.80113848 4.09600846 2.81587441 4.13161998 1 P 0 Y
A 2.80113848 4.09600846 2.78863002 4.10436004 2.81587303 4.13161998 1 P 0 Y
L 2.78863002 4.10436004 2.72271004 4.1703 1 P 0 
A 2.72271004 4.1703 2.67545 4.18986998 2.6754499 4.12301998 1 P 0 N
L 2.67545 4.18986998 2.67543002 4.18986998 1 P 0 
A 2.67543002 4.18986998 2.61961998 4.16703996 2.67540906 4.11028996 1 P 0 N
L 2.61961998 4.16703996 2.6103 4.15921998 1 P 0 
A 2.6103 4.15921998 2.60958002 4.15856004 2.61750207 4.15063996 1 P 0 N
L 2.60958002 4.15856004 2.60326998 4.15225 1 P 0 
A 2.60326998 4.15225 2.59545571 4.14703268 2.5862374 4.1693 1 P 0 Y
A 2.59545571 4.14703268 2.58623996 4.1452 2.5862374 4.1693 1 P 0 Y
L 2.58623996 4.1452 2.58621998 4.1452 1 P 0 
A 2.58621998 4.1452 2.55978002 4.15355 2.58622136 4.19123996 1 P 0 Y
L 2.55978002 4.15355 2.5417 4.16623996 1 P 0 
A 2.5417 4.16623996 2.52196309 4.17154547 2.52455138 4.14181004 1 P 0 N
A 2.52196309 4.17154547 2.50343996 4.16291004 2.52455118 4.14181004 1 P 0 N
L 2.50343996 4.16291004 2.50336004 4.16283996 1 P 0 
L 2.50336004 4.16283996 2.50328002 4.16276004 1 P 0 
L 2.50328002 4.16276004 2.50316998 4.16266998 1 P 0 
L 2.50316998 4.16266998 2.50301998 4.16251004 1 P 0 
A 2.50301998 4.16251004 2.49428996 4.14526998 2.52703002 4.13952146 1 P 0 N
L 2.49428996 4.14526998 2.48988996 4.12033002 1 P 0 
A 2.48988996 4.12033002 2.45858996 4.06021004 2.37891004 4.13990118 1 P 0 Y
L 2.45858996 4.06021004 2.43043002 4.03205 1 P 0 
A 2.43043002 4.03205 2.24563996 3.9555 2.24562943 4.21683996 1 P 0 Y
L 2.24563996 3.9555 2.24561004 3.9555 1 P 0 
A 2.24561004 3.9555 2.24496004 3.95556004 2.2456314 3.95928002 1 P 0 Y
L 2.24496004 3.95556004 2.16506998 3.96966004 1 P 0 
A 2.16506998 3.96966004 2.13737963 3.95746919 2.16034892 3.94283996 1 P 0 N
A 2.13737963 3.95746919 2.13803996 3.92721998 2.16035 3.94283878 1 P 0 N
L 2.13803996 3.92721998 2.16521998 3.88841998 1 P 0 
A 2.16521998 3.88841998 2.1667687 3.8852752 2.15578002 3.88181732 1 P 0 Y
A 2.1667687 3.8852752 2.1673 3.88181004 2.15578002 3.88181703 1 P 0 Y
L 2.1673 3.88181004 2.16731004 3.88181998 1 P 0 
L 2.16731004 3.88181998 2.16731004 3.85488996 1 P 0 
A 2.16731004 3.85488996 2.1848 3.8374 2.1848 3.85488996 1 P 0 N
L 2.1848 3.8374 2.19236004 3.8374 1 P 0 
A 2.19236004 3.8374 2.19606004 3.8337 2.19236004 3.8337 1 P 0 Y
L 2.19606004 3.8337 2.19606004 3.81615 1 P 0 
P 2.19606004 3.86615 5 P 0 0;2=3,4=1
P 3.06571004 4.667 5 P 0 0;2=3,4=1
L 3.06571004 4.667 3.05316004 4.667 1 P 0 
A 3.05316004 4.667 3.04946004 4.6633 3.05316004 4.6633 1 P 0 N
L 3.04946004 4.6633 3.04946004 4.62636998 1 P 0 
L 3.04946004 4.62636998 3.04016004 4.6131 1 P 0 
L 3.04016004 4.6131 3.02036998 4.59925 1 P 0 
L 3.02036998 4.59925 3.01325 4.58906998 1 P 0 
L 3.01325 4.58906998 3.01148002 4.57903996 1 P 0 
L 3.01148002 4.57903996 3.01335 4.56848996 1 P 0 
L 3.01335 4.56848996 3.01963996 4.5641 1 P 0 
L 3.01963996 4.5641 3.02156998 4.55315 1 P 0 
L 3.02156998 4.55315 3.01716004 4.54688002 1 P 0 
L 3.01716004 4.54688002 3.01908996 4.53593996 1 P 0 
L 3.01908996 4.53593996 3.02538002 4.53156004 1 P 0 
L 3.02538002 4.53156004 3.02731004 4.52061004 1 P 0 
L 3.02731004 4.52061004 3.02288996 4.51433996 1 P 0 
L 3.02288996 4.51433996 3.02593002 4.49705 1 P 0 
L 3.02593002 4.49705 3.0242 4.48578002 1 P 0 
A 3.0242 4.48578002 3.02235896 4.48006644 3.00538996 4.4886876 1 P 0 Y
A 3.02235896 4.48006644 3.01883002 4.47521004 3.00538996 4.48868671 1 P 0 Y
L 3.01883002 4.47521004 3.00998996 4.46636998 1 P 0 
A 3.00998996 4.46636998 3.00127805 4.46054577 2.99099833 4.48535 1 P 0 Y
A 3.00127805 4.46054577 2.991 4.4585 2.99099833 4.48535 1 P 0 Y
L 2.991 4.4585 2.98838996 4.4585 1 P 0 
A 2.98838996 4.4585 2.98090236 4.45965384 2.98838661 4.48335 1 P 0 Y
A 2.98090236 4.45965384 2.97411004 4.46301004 2.98838573 4.48335 1 P 0 Y
L 2.97411004 4.46301004 2.91933002 4.50136998 1 P 0 
A 2.91933002 4.50136998 2.89786791 4.50712018 2.90069921 4.47476004 1 P 0 N
A 2.89786791 4.50712018 2.87773002 4.49773002 2.90069902 4.47476004 1 P 0 N
L 2.87773002 4.49773002 2.87281998 4.49281998 1 P 0 
A 2.87281998 4.49281998 2.8650123 4.48113957 2.89826998 4.46735846 1 P 0 N
A 2.8650123 4.48113957 2.86226998 4.46736004 2.89826998 4.46735817 1 P 0 N
L 2.86226998 4.46736004 2.86226998 4.46278002 1 P 0 
A 2.86226998 4.46278002 2.87256998 4.44298996 2.88643002 4.46277904 1 P 0 N
L 2.87256998 4.44298996 3.00838002 4.3479 1 P 0 
A 3.00838002 4.3479 3.00988002 4.34663002 3.00192077 4.33875 1 P 0 Y
L 3.00988002 4.34663002 3.0129 4.34361998 1 P 0 
A 3.0129 4.34361998 3.02351004 4.318 2.98726998 4.31799882 1 P 0 Y
L 3.02351004 4.318 3.0235 4.31798996 1 P 0 
A 3.0235 4.31798996 3.01767441 4.28870994 2.94688996 4.31801289 1 P 0 Y
A 3.01767441 4.28870994 3.0011 4.26388002 2.94688996 4.31801299 1 P 0 Y
L 3.0011 4.26388002 3.00108996 4.26388002 1 P 0 
A 3.00108996 4.26388002 2.972075 4.25034409 2.96799282 4.29696004 1 P 0 Y
A 2.972075 4.25034409 2.94115 4.25863002 2.96799252 4.29696004 1 P 0 Y
L 2.94115 4.25863002 2.85035 4.32221998 1 P 0 
A 2.85035 4.32221998 2.82709744 4.32845344 2.8301622 4.2934 1 P 0 N
A 2.82709744 4.32845344 2.80528002 4.31828002 2.83016211 4.2934 1 P 0 N
L 2.80528002 4.31828002 2.80166998 4.31466998 1 P 0 
A 2.80166998 4.31466998 2.79070699 4.28454902 2.82848002 4.2878565 1 P 0 N
A 2.79070699 4.28454902 2.80673996 4.25678996 2.82848002 4.2878561 1 P 0 N
L 2.80673996 4.25678996 2.87543996 4.2087 1 P 0 
A 2.87543996 4.2087 2.88981841 4.19230276 2.84913002 4.17112657 1 P 0 Y
A 2.88981841 4.19230276 2.895 4.17111998 2.84913002 4.1711247 1 P 0 Y
A 2.895 4.17111998 2.88891083 4.1405188 2.81506998 4.17111841 1 P 0 Y
A 2.88891083 4.1405188 2.87156998 4.11458002 2.81506998 4.17111772 1 P 0 Y
L 2.87156998 4.11458002 2.86136998 4.10438996 1 P 0 
A 2.86136998 4.10438996 2.84051496 4.09046565 2.81593494 4.14986004 1 P 0 Y
A 2.84051496 4.09046565 2.81591998 4.08558002 2.81593396 4.14986004 1 P 0 Y
L 2.81591998 4.08558002 2.81588996 4.08558002 1 P 0 
A 2.81588996 4.08558002 2.79826496 4.08907579 2.81586437 4.13163002 1 P 0 Y
A 2.79826496 4.08907579 2.78331998 4.09905 2.81586457 4.13163002 1 P 0 Y
L 2.78331998 4.09905 2.7174 4.16498996 1 P 0 
A 2.7174 4.16498996 2.67543996 4.18236998 2.67544055 4.12303002 1 P 0 N
L 2.67543996 4.18236998 2.67541998 4.18236998 1 P 0 
A 2.67541998 4.18236998 2.64783573 4.17688435 2.67541683 4.11028996 1 P 0 N
A 2.64783573 4.17688435 2.62445 4.16126004 2.67541604 4.11028996 1 P 0 N
L 2.62445 4.16126004 2.61513002 4.15346998 1 P 0 
A 2.61513002 4.15346998 2.61488996 4.15325 2.61750246 4.15063996 1 P 0 N
L 2.61488996 4.15325 2.60858002 4.14693996 1 P 0 
A 2.60858002 4.14693996 2.59833307 4.14010187 2.58624665 4.16931004 1 P 0 Y
A 2.59833307 4.14010187 2.58625 4.1377 2.58624685 4.16931004 1 P 0 Y
L 2.58625 4.1377 2.58621004 4.1377 1 P 0 
A 2.58621004 4.1377 2.55546998 4.14741004 2.58621841 4.19123996 1 P 0 Y
L 2.55546998 4.14741004 2.53738996 4.1601 1 P 0 
A 2.53738996 4.1601 2.52261516 4.16406811 2.52455748 4.14181004 1 P 0 N
A 2.52261516 4.16406811 2.50875 4.1576 2.52455728 4.14181004 1 P 0 N
L 2.50875 4.1576 2.50871004 4.15756998 1 P 0 
L 2.50871004 4.15756998 2.50858002 4.15743996 1 P 0 
L 2.50858002 4.15743996 2.50848996 4.15736004 1 P 0 
L 2.50848996 4.15736004 2.50838996 4.15726004 1 P 0 
A 2.50838996 4.15726004 2.50168002 4.14396998 2.52703002 4.13951004 1 P 0 N
L 2.50168002 4.14396998 2.49728002 4.11903002 1 P 0 
A 2.49728002 4.11903002 2.4639 4.0549 2.37891004 4.13988996 1 P 0 Y
L 2.4639 4.0549 2.43573996 4.02673996 1 P 0 
A 2.43573996 4.02673996 2.24563996 3.948 2.24563868 4.21685 1 P 0 Y
L 2.24563996 3.948 2.24561004 3.948 1 P 0 
A 2.24561004 3.948 2.24363996 3.94816998 2.24559094 3.95928002 1 P 0 Y
L 2.24363996 3.94816998 2.16376998 3.96226998 1 P 0 
A 2.16376998 3.96226998 2.14370768 3.95343652 2.16034921 3.94283996 1 P 0 N
A 2.14370768 3.95343652 2.14418996 3.93151998 2.16035 3.94283917 1 P 0 N
L 2.14418996 3.93151998 2.17136998 3.89273002 1 P 0 
A 2.17136998 3.89273002 2.17393061 3.88753494 2.15578002 3.88181722 1 P 0 Y
A 2.17393061 3.88753494 2.17481004 3.88181004 2.15578002 3.88181673 1 P 0 Y
L 2.17481004 3.88181004 2.17481004 3.85488996 1 P 0 
A 2.17481004 3.85488996 2.1848 3.8449 2.1848 3.85488996 1 P 0 N
L 2.1848 3.8449 2.19236004 3.8449 1 P 0 
A 2.19236004 3.8449 2.19606004 3.8486 2.19236004 3.8486 1 P 0 N
L 2.19606004 3.8486 2.19606004 3.86615 1 P 0 
P 3.27831004 4.642 5 P 0 0;2=3,4=1
P 2.39606004 3.76615 5 P 0 0;2=3,4=1
L 2.39606004 3.76615 2.39606004 3.7837 1 P 0 
A 2.39606004 3.7837 2.39976004 3.7874 2.39976004 3.7837 1 P 0 Y
L 2.39976004 3.7874 2.40731998 3.7874 1 P 0 
A 2.40731998 3.7874 2.41731004 3.77741004 2.40732008 3.77741004 1 P 0 Y
L 2.41731004 3.77741004 2.41731004 3.75215 1 P 0 
A 2.41731004 3.75215 2.43206004 3.7374 2.43206004 3.75215 1 P 0 N
L 2.43206004 3.7374 2.55388996 3.7374 1 P 0 
A 2.55388996 3.7374 2.58216998 3.72848002 2.55388986 3.68811004 1 P 0 Y
L 2.58216998 3.72848002 2.6201 3.70191004 1 P 0 
L 2.6201 3.70191004 2.67938996 3.61723996 1 P 0 
L 2.67938996 3.61723996 2.69178996 3.60856004 1 P 0 
L 2.69178996 3.60856004 2.69206998 3.60836004 1 P 0 
L 2.69206998 3.60836004 2.6921 3.60833996 1 P 0 
L 2.6921 3.60833996 2.69951998 3.60313996 1 P 0 
L 2.69951998 3.60313996 2.69953002 3.60313996 1 P 0 
L 2.69953002 3.60313996 2.70831998 3.59698996 1 P 0 
L 2.70831998 3.59698996 2.73586998 3.59213002 1 P 0 
L 2.73586998 3.59213002 2.93216998 3.62673996 1 P 0 
L 2.93216998 3.62673996 3.24038002 3.84253002 1 P 0 
L 3.24038002 3.84253002 3.40998002 4.08431004 1 P 0 
A 3.40998002 4.08431004 3.41989537 4.12122047 3.36426998 4.11637628 1 P 0 N
A 3.41989537 4.12122047 3.40375 4.15586004 3.36426998 4.11637608 1 P 0 N
L 3.40375 4.15586004 3.39783996 4.16176998 1 P 0 
A 3.39783996 4.16176998 3.37985886 4.1737812 3.35864577 4.12256004 1 P 0 N
A 3.37985886 4.1737812 3.35865 4.178 3.35864606 4.12256004 1 P 0 N
L 3.35865 4.178 3.33361004 4.178 1 P 0 
A 3.33361004 4.178 3.31641614 4.18141959 3.33360689 4.22291998 1 P 0 Y
A 3.31641614 4.18141959 3.30183996 4.19116004 3.33360591 4.22291998 1 P 0 Y
L 3.30183996 4.19116004 3.30098002 4.19201998 1 P 0 
A 3.30098002 4.19201998 3.29474813 4.20134774 3.32131004 4.21234813 1 P 0 Y
A 3.29474813 4.20134774 3.29256004 4.21235 3.32131004 4.21234902 1 P 0 Y
L 3.29256004 4.21235 3.29256004 4.21258002 1 P 0 
L 3.29256004 4.21258002 3.29255 4.21286998 1 P 0 
A 3.29255 4.21286998 3.29327136 4.21860463 3.31111998 4.21344675 1 P 0 Y
A 3.29327136 4.21860463 3.29571998 4.22383996 3.31111998 4.21344695 1 P 0 Y
L 3.29571998 4.22383996 3.29908996 4.22883996 1 P 0 
A 3.29908996 4.22883996 3.29955 4.22938996 3.30218002 4.22672274 1 P 0 Y
L 3.29955 4.22938996 3.30746998 4.23731004 1 P 0 
A 3.30746998 4.23731004 3.3160435 4.24359449 3.33217264 4.2126 1 P 0 Y
A 3.3160435 4.24359449 3.32611004 4.24701004 3.33217254 4.2126 1 P 0 Y
L 3.32611004 4.24701004 3.40535 4.26098996 1 P 0 
A 3.40535 4.26098996 3.434 4.29513996 3.39931004 4.29515 1 P 0 N
L 3.434 4.29513996 3.434 4.30058996 1 P 0 
A 3.434 4.30058996 3.39385 4.33428002 3.39979026 4.30058996 1 P 0 N
L 3.39385 4.33428002 3.31086004 4.31963996 1 P 0 
L 3.31086004 4.31963996 3.31083996 4.31963996 1 P 0 
A 3.31083996 4.31963996 3.281 4.332 3.31083986 4.36183996 1 P 0 Y
A 3.281 4.332 3.25903002 4.38503996 3.33403996 4.38504006 1 P 0 Y
L 3.25903002 4.38503996 3.25903002 4.3936 1 P 0 
A 3.25903002 4.3936 3.2593876 4.39734734 3.27795 4.39368533 1 P 0 Y
A 3.2593876 4.39734734 3.26048002 4.40095 3.27795 4.39368573 1 P 0 Y
L 3.26048002 4.40095 3.26625 4.41478996 1 P 0 
L 3.26625 4.41478996 3.28873996 4.44693002 1 P 0 
L 3.28873996 4.44693002 3.29191004 4.46478002 1 P 0 
L 3.29191004 4.46478002 3.28908002 4.48093996 1 P 0 
L 3.28908002 4.48093996 3.2783 4.49628996 1 P 0 
L 3.2783 4.49628996 3.23926004 4.52363996 1 P 0 
L 3.23926004 4.52363996 3.23573996 4.52866004 1 P 0 
L 3.23573996 4.52866004 3.23061004 4.55773996 1 P 0 
L 3.23061004 4.55773996 3.23233002 4.56751998 1 P 0 
L 3.23233002 4.56751998 3.26246004 4.61051004 1 P 0 
L 3.26246004 4.61051004 3.26246004 4.63746004 1 P 0 
A 3.26246004 4.63746004 3.267 4.642 3.267 4.63746004 1 P 0 Y
L 3.267 4.642 3.27831004 4.642 1 P 0 
P 3.23831004 4.642 5 P 0 0;2=3,4=1
P 2.39606004 3.81615 5 P 0 0;2=3,4=1
L 2.39606004 3.81615 2.39606004 3.7986 1 P 0 
A 2.39606004 3.7986 2.39976004 3.7949 2.39976004 3.7986 1 P 0 N
L 2.39976004 3.7949 2.40731998 3.7949 1 P 0 
A 2.40731998 3.7949 2.42481004 3.77741004 2.40732008 3.77741004 1 P 0 Y
L 2.42481004 3.77741004 2.42481004 3.75215 1 P 0 
A 2.42481004 3.75215 2.43206004 3.7449 2.43206004 3.75215 1 P 0 N
L 2.43206004 3.7449 2.55388996 3.7449 1 P 0 
A 2.55388996 3.7449 2.57097579 3.74227421 2.55390699 3.68811004 1 P 0 Y
A 2.57097579 3.74227421 2.58648002 3.73463002 2.55390728 3.68811004 1 P 0 Y
L 2.58648002 3.73463002 2.62548996 3.7073 1 P 0 
L 2.62548996 3.7073 2.68478002 3.62263002 1 P 0 
L 2.68478002 3.62263002 2.6961 3.6147 1 P 0 
L 2.6961 3.6147 2.69618002 3.61465 1 P 0 
L 2.69618002 3.61465 2.69626998 3.61458996 1 P 0 
L 2.69626998 3.61458996 2.69633996 3.61453996 1 P 0 
L 2.69633996 3.61453996 2.69638002 3.61451004 1 P 0 
L 2.69638002 3.61451004 2.69641004 3.61448996 1 P 0 
L 2.69641004 3.61448996 2.71126004 3.60408996 1 P 0 
L 2.71126004 3.60408996 2.73586998 3.59975 1 P 0 
L 2.73586998 3.59975 2.92923002 3.63383996 1 P 0 
L 2.92923002 3.63383996 3.23498996 3.84791998 1 P 0 
L 3.23498996 3.84791998 3.40383996 4.08861998 1 P 0 
A 3.40383996 4.08861998 3.39843996 4.15055 3.36426998 4.11637008 1 P 0 N
L 3.39843996 4.15055 3.39253002 4.15646004 1 P 0 
A 3.39253002 4.15646004 3.3769815 4.16685049 3.35863661 4.12256998 1 P 0 N
A 3.3769815 4.16685049 3.35863996 4.1705 3.35863691 4.12256998 1 P 0 N
L 3.35863996 4.1705 3.33361004 4.1705 1 P 0 
A 3.33361004 4.1705 3.31354272 4.17448612 3.33359301 4.22291998 1 P 0 Y
A 3.31354272 4.17448612 3.29653002 4.18585 3.33359311 4.22291998 1 P 0 Y
L 3.29653002 4.18585 3.29566998 4.18671004 1 P 0 
A 3.29566998 4.18671004 3.28506004 4.21235 3.32131998 4.21233937 1 P 0 Y
L 3.28506004 4.21235 3.28506004 4.21245 1 P 0 
L 3.28506004 4.21245 3.28505 4.21261998 1 P 0 
L 3.28505 4.21261998 3.28505 4.21263996 1 P 0 
A 3.28505 4.21263996 3.28605787 4.22068917 3.31111998 4.21346339 1 P 0 Y
A 3.28605787 4.22068917 3.28948996 4.22803996 3.31111998 4.21346427 1 P 0 Y
L 3.28948996 4.22803996 3.29288002 4.23305 1 P 0 
A 3.29288002 4.23305 3.29423996 4.2347 3.3022 4.22675384 1 P 0 Y
L 3.29423996 4.2347 3.30216004 4.24261998 1 P 0 
A 3.30216004 4.24261998 3.31257825 4.25025295 3.33216703 4.21258996 1 P 0 Y
A 3.31257825 4.25025295 3.32481004 4.2544 3.33216634 4.21258996 1 P 0 Y
L 3.32481004 4.2544 3.40403996 4.26838002 1 P 0 
A 3.40403996 4.26838002 3.42013583 4.2776813 3.39930581 4.29515 1 P 0 N
A 3.42013583 4.2776813 3.42648996 4.29515 3.39931004 4.29514656 1 P 0 N
L 3.42648996 4.29515 3.4265 4.29515 1 P 0 
L 3.4265 4.29515 3.4265 4.30058996 1 P 0 
A 3.4265 4.30058996 3.41695659 4.3210503 3.39978996 4.3005873 1 P 0 N
A 3.41695659 4.3210503 3.39515 4.32688996 3.39979222 4.30058996 1 P 0 N
L 3.39515 4.32688996 3.31151998 4.31213996 1 P 0 
L 3.31151998 4.31213996 3.31085 4.31213996 1 P 0 
A 3.31085 4.31213996 3.29182264 4.31591683 3.31082677 4.36183996 1 P 0 Y
A 3.29182264 4.31591683 3.27568996 4.32668996 3.31082589 4.36183996 1 P 0 Y
A 3.27568996 4.32668996 3.25153002 4.38503002 3.33405 4.38503081 1 P 0 Y
L 3.25153002 4.38503002 3.25153002 4.39358002 1 P 0 
A 3.25153002 4.39358002 3.25202756 4.39881093 3.27796004 4.39370522 1 P 0 Y
A 3.25202756 4.39881093 3.25355 4.40383996 3.27796004 4.39370532 1 P 0 Y
L 3.25355 4.40383996 3.25963002 4.41843002 1 P 0 
L 3.25963002 4.41843002 3.28163996 4.44988002 1 P 0 
L 3.28163996 4.44988002 3.28428996 4.46478996 1 P 0 
L 3.28428996 4.46478996 3.28196998 4.47798996 1 P 0 
L 3.28196998 4.47798996 3.27291998 4.4909 1 P 0 
L 3.27291998 4.4909 3.26121004 4.49908996 1 P 0 
L 3.26121004 4.49908996 3.25503002 4.49798002 1 P 0 
L 3.25503002 4.49798002 3.24591998 4.50436004 1 P 0 
L 3.24591998 4.50436004 3.24486004 4.51055 1 P 0 
L 3.24486004 4.51055 3.23386998 4.51825 1 P 0 
L 3.23386998 4.51825 3.22863996 4.52571998 1 P 0 
L 3.22863996 4.52571998 3.22298996 4.55773996 1 P 0 
L 3.22298996 4.55773996 3.22523002 4.57046004 1 P 0 
L 3.22523002 4.57046004 3.2367 4.58683996 1 P 0 
L 3.2367 4.58683996 3.23551998 4.59345 1 P 0 
L 3.23551998 4.59345 3.24191004 4.60256004 1 P 0 
L 3.24191004 4.60256004 3.24853002 4.60371004 1 P 0 
L 3.24853002 4.60371004 3.25496004 4.61288002 1 P 0 
L 3.25496004 4.61288002 3.25496004 4.6383 1 P 0 
A 3.25496004 4.6383 3.25126004 4.642 3.25126004 4.6383 1 P 0 N
L 3.25126004 4.642 3.23831004 4.642 1 P 0 
P 3.34916998 5.1035 5 P 0 0;2=3,4=1
P 2.49606004 3.76615 5 P 0 0;2=3,4=1
L 2.49606004 3.76615 2.49606004 3.7837 1 P 0 
A 2.49606004 3.7837 2.49976004 3.7874 2.49976004 3.7837 1 P 0 Y
L 2.49976004 3.7874 2.5494 3.7874 1 P 0 
A 2.5494 3.7874 2.55897923 3.78592224 2.54939331 3.75556998 1 P 0 Y
A 2.55897923 3.78592224 2.56766998 3.78163002 2.549394 3.75556998 1 P 0 Y
L 2.56766998 3.78163002 2.63705 3.73303002 1 P 0 
L 2.63705 3.73303002 2.70635 3.6341 1 P 0 
L 2.70635 3.6341 2.72176998 3.62328996 1 P 0 
L 2.72176998 3.62328996 2.73973002 3.62011998 1 P 0 
L 2.73973002 3.62011998 2.92558002 3.65288996 1 P 0 
L 2.92558002 3.65288996 3.07696004 3.75888002 1 P 0 
L 3.07696004 3.75888002 3.22805 3.86466998 1 P 0 
L 3.22805 3.86466998 3.38348002 4.08668996 1 P 0 
A 3.38348002 4.08668996 3.39028002 4.11208002 3.352 4.10872657 1 P 0 N
A 3.39028002 4.11208002 3.37916998 4.1359 3.352 4.10872648 1 P 0 N
L 3.37916998 4.1359 3.37916004 4.13591004 1 P 0 
A 3.37916004 4.13591004 3.3695564 4.14295118 3.35147539 4.10821998 1 P 0 N
A 3.3695564 4.14295118 3.35828002 4.14678002 3.35147539 4.10821998 1 P 0 N
L 3.35828002 4.14678002 3.30928002 4.15543002 1 P 0 
A 3.30928002 4.15543002 3.28641998 4.16733002 3.31672028 4.19763002 1 P 0 Y
L 3.28641998 4.16733002 3.27703996 4.17671004 1 P 0 
A 3.27703996 4.17671004 3.27127323 4.18457451 3.29968996 4.19936496 1 P 0 Y
A 3.27127323 4.18457451 3.26813996 4.19381004 3.29968996 4.19936447 1 P 0 Y
L 3.26813996 4.19381004 3.1928 4.62115 1 P 0 
L 3.1928 4.62115 3.20465 4.68838002 1 P 0 
L 3.20465 4.68838002 3.21313996 4.7005 1 P 0 
L 3.21313996 4.7005 3.23005 4.71233002 1 P 0 
L 3.23005 4.71233002 3.25203002 4.71621004 1 P 0 
L 3.25203002 4.71621004 3.29303996 4.74493002 1 P 0 
L 3.29303996 4.74493002 3.32663002 4.79291998 1 P 0 
L 3.32663002 4.79291998 3.33901998 4.86318002 1 P 0 
L 3.33901998 4.86318002 3.35238996 4.88226998 1 P 0 
L 3.35238996 4.88226998 3.37581004 4.89866998 1 P 0 
L 3.37581004 4.89866998 3.40151998 4.9032 1 P 0 
L 3.40151998 4.9032 3.43268996 4.8977 1 P 0 
L 3.43268996 4.8977 3.44701998 4.90023002 1 P 0 
L 3.44701998 4.90023002 3.45655 4.90693002 1 P 0 
L 3.45655 4.90693002 3.47223996 4.92928002 1 P 0 
L 3.47223996 4.92928002 3.47811998 4.96263996 1 P 0 
L 3.47811998 4.96263996 3.46598996 5.03138002 1 P 0 
L 3.46598996 5.03138002 3.4527 5.05036998 1 P 0 
L 3.4527 5.05036998 3.43183996 5.06498002 1 P 0 
L 3.43183996 5.06498002 3.41746998 5.0675 1 P 0 
L 3.41746998 5.0675 3.3425 5.0675 1 P 0 
L 3.3425 5.0675 3.33291998 5.07708002 1 P 0 
L 3.33291998 5.07708002 3.33291998 5.09941998 1 P 0 
A 3.33291998 5.09941998 3.337 5.1035 3.337 5.09941998 1 P 0 Y
L 3.337 5.1035 3.34916998 5.1035 1 P 0 
P 3.30916998 5.1035 5 P 0 0;2=3,4=1
P 2.49606004 3.81615 5 P 0 0;2=3,4=1
L 2.49606004 3.81615 2.49606004 3.7986 1 P 0 
A 2.49606004 3.7986 2.49976004 3.7949 2.49976004 3.7986 1 P 0 N
L 2.49976004 3.7949 2.54941004 3.7949 1 P 0 
A 2.54941004 3.7949 2.56124321 3.79307746 2.54940787 3.75556004 1 P 0 Y
A 2.56124321 3.79307746 2.57198002 3.78778002 2.54940768 3.75556004 1 P 0 Y
L 2.57198002 3.78778002 2.64243996 3.73841998 1 P 0 
L 2.64243996 3.73841998 2.71173996 3.63948996 1 P 0 
L 2.71173996 3.63948996 2.72471004 3.63038996 1 P 0 
L 2.72471004 3.63038996 2.73973002 3.62773996 1 P 0 
L 2.73973002 3.62773996 2.92263996 3.65998996 1 P 0 
L 2.92263996 3.65998996 3.22266004 3.87006004 1 P 0 
L 3.22266004 3.87006004 3.37733002 4.091 1 P 0 
A 3.37733002 4.091 3.38279872 4.11142707 3.352 4.10872687 1 P 0 N
A 3.38279872 4.11142707 3.37386004 4.13058996 3.352 4.10872697 1 P 0 N
L 3.37386004 4.13058996 3.37385 4.1306 1 P 0 
A 3.37385 4.1306 3.36609114 4.13629213 3.35146398 4.10821998 1 P 0 N
A 3.36609114 4.13629213 3.35698002 4.13938996 3.35146427 4.10821998 1 P 0 N
L 3.35698002 4.13938996 3.30798002 4.14803996 1 P 0 
A 3.30798002 4.14803996 3.28111004 4.16201998 3.31670915 4.19763002 1 P 0 Y
L 3.28111004 4.16201998 3.27173002 4.1714 1 P 0 
A 3.27173002 4.1714 3.26461427 4.18110925 3.29968996 4.19935344 1 P 0 Y
A 3.26461427 4.18110925 3.26075 4.19251004 3.29968996 4.19935335 1 P 0 Y
L 3.26075 4.19251004 3.18518002 4.62115 1 P 0 
L 3.18518002 4.62115 3.19755 4.69131998 1 P 0 
L 3.19755 4.69131998 3.20775 4.70588996 1 P 0 
L 3.20775 4.70588996 3.22711004 4.71943002 1 P 0 
L 3.22711004 4.71943002 3.24908002 4.72331004 1 P 0 
L 3.24908002 4.72331004 3.24908996 4.72331004 1 P 0 
L 3.24908996 4.72331004 3.26478996 4.73431004 1 P 0 
L 3.26478996 4.73431004 3.26481004 4.73433002 1 P 0 
L 3.26481004 4.73433002 3.28765 4.75031998 1 P 0 
L 3.28765 4.75031998 3.31953002 4.79586004 1 P 0 
L 3.31953002 4.79586004 3.33191998 4.86611998 1 P 0 
L 3.33191998 4.86611998 3.347 4.88766004 1 P 0 
L 3.347 4.88766004 3.37286998 4.90576998 1 P 0 
L 3.37286998 4.90576998 3.40151998 4.91081998 1 P 0 
L 3.40151998 4.91081998 3.43268996 4.90531998 1 P 0 
L 3.43268996 4.90531998 3.44406998 4.90733002 1 P 0 
L 3.44406998 4.90733002 3.45116004 4.91231004 1 P 0 
L 3.45116004 4.91231004 3.46513996 4.93221998 1 P 0 
L 3.46513996 4.93221998 3.4705 4.96263996 1 P 0 
L 3.4705 4.96263996 3.45888996 5.02843996 1 P 0 
L 3.45888996 5.02843996 3.44731004 5.04498002 1 P 0 
L 3.44731004 5.04498002 3.43231998 5.05548002 1 P 0 
L 3.43231998 5.05548002 3.43233002 5.05548002 1 P 0 
L 3.43233002 5.05548002 3.4289 5.05788002 1 P 0 
L 3.4289 5.05788002 3.41681004 5.06 1 P 0 
L 3.41681004 5.06 3.40161998 5.06 1 P 0 
L 3.40161998 5.06 3.39761998 5.056 1 P 0 
L 3.39761998 5.056 3.38651998 5.056 1 P 0 
L 3.38651998 5.056 3.38251998 5.06 1 P 0 
L 3.38251998 5.06 3.37141998 5.06 1 P 0 
L 3.37141998 5.06 3.36741998 5.056 1 P 0 
L 3.36741998 5.056 3.35631998 5.056 1 P 0 
L 3.35631998 5.056 3.35231998 5.06 1 P 0 
L 3.35231998 5.06 3.33938996 5.06 1 P 0 
L 3.33938996 5.06 3.32541998 5.07396998 1 P 0 
L 3.32541998 5.07396998 3.32541998 5.0998 1 P 0 
A 3.32541998 5.0998 3.32171998 5.1035 3.32171998 5.0998 1 P 0 N
L 3.32171998 5.1035 3.30916998 5.1035 1 P 0 
P 2.74225 4.667 5 P 0 0;2=3,4=1
P 2.09606004 3.66615 5 P 0 0;2=3,4=1
L 2.09606004 3.66615 2.09606004 3.6837 1 P 0 
A 2.09606004 3.6837 2.09236004 3.6874 2.09236004 3.6837 1 P 0 N
L 2.09236004 3.6874 1.95475 3.6874 1 P 0 
A 1.95475 3.6874 1.94782234 3.68877963 1.9547315 3.70538996 1 P 0 Y
A 1.94782234 3.68877963 1.94196004 3.69271998 1.95473159 3.70538996 1 P 0 Y
L 1.94196004 3.69271998 1.91568996 3.71921998 1 P 0 
A 1.91568996 3.71921998 1.89936998 3.75073996 1.95788002 3.76104951 1 P 0 Y
L 1.89936998 3.75073996 1.88091004 3.85546998 1 P 0 
L 1.88091004 3.85546998 1.89976004 3.96231004 1 P 0 
L 1.89976004 3.96231004 1.91938002 3.99033996 1 P 0 
L 1.91938002 3.99033996 1.95071998 4.01225 1 P 0 
L 1.95071998 4.01225 1.9919 4.01951998 1 P 0 
A 1.9919 4.01951998 1.99979606 4.02220561 1.98711801 4.04653002 1 P 0 N
A 1.99979606 4.02220561 2.00651998 4.02713996 1.98711801 4.04653002 1 P 0 N
L 2.00651998 4.02713996 2.01001998 4.03063996 1 P 0 
A 2.01001998 4.03063996 2.01754459 4.04190846 1.98548002 4.05517323 1 P 0 N
A 2.01754459 4.04190846 2.02018002 4.0552 1.98548002 4.05517323 1 P 0 N
L 2.02018002 4.0552 2.02018996 4.05518996 1 P 0 
L 2.02018996 4.05518996 2.02018996 4.05521004 1 P 0 
A 2.02018996 4.05521004 2.01653248 4.07014341 1.98786004 4.0552064 1 P 0 N
A 2.01653248 4.07014341 2.00638996 4.0817 1.98786004 4.05520837 1 P 0 N
L 2.00638996 4.0817 1.96536004 4.11043002 1 P 0 
A 1.96536004 4.11043002 1.93596004 4.16696004 2.00495 4.16693002 1 P 0 Y
L 1.93596004 4.16696004 1.93596004 4.16761998 1 P 0 
L 1.93596004 4.16761998 1.93606998 4.16823996 1 P 0 
L 1.93606998 4.16823996 1.93606998 4.16826004 1 P 0 
L 1.93606998 4.16826004 1.95511998 4.2763 1 P 0 
L 1.95511998 4.2763 2.06003996 4.42613996 1 P 0 
L 2.06003996 4.42613996 2.16948996 4.50273002 1 P 0 
L 2.16948996 4.50273002 2.2078 4.50951004 1 P 0 
L 2.2078 4.50951004 2.31448002 4.49071004 1 P 0 
L 2.31448002 4.49071004 2.31456004 4.49071004 1 P 0 
A 2.31456004 4.49071004 2.3524 4.50638996 2.31455965 4.54421004 1 P 0 N
A 2.3524 4.50638996 2.36286998 4.52648996 2.32571004 4.53306949 1 P 0 N
L 2.36286998 4.52648996 2.36981998 4.56583002 1 P 0 
A 2.36981998 4.56583002 2.37198996 4.57485 2.44511004 4.55248809 1 P 0 Y
A 2.37198996 4.57485 2.37600709 4.58390709 2.4108 4.56305581 1 P 0 Y
A 2.37600709 4.58390709 2.3821 4.59171998 2.4108 4.56305591 1 P 0 Y
L 2.3821 4.59171998 2.38408002 4.5937 1 P 0 
A 2.38408002 4.5937 2.39937766 4.60391624 2.41740561 4.56036004 1 P 0 Y
A 2.39937766 4.60391624 2.41741998 4.6075 2.4174063 4.56036004 1 P 0 Y
L 2.41741998 4.6075 2.422 4.6075 1 P 0 
A 2.422 4.6075 2.452 4.5775 2.422 4.5775 1 P 0 Y
L 2.452 4.5775 2.452 4.57401004 1 P 0 
L 2.452 4.57401004 2.45201004 4.57401998 1 P 0 
A 2.45201004 4.57401998 2.4522 4.56938002 2.51 4.57407028 1 P 0 N
A 2.4522 4.56938002 2.4571564 4.55013346 2.51001004 4.57400591 1 P 0 N
A 2.4571564 4.55013346 2.46831998 4.53368996 2.51001004 4.57400482 1 P 0 N
L 2.46831998 4.53368996 2.46836004 4.53365 1 P 0 
A 2.46836004 4.53365 2.46853002 4.53348002 2.50946998 4.57458996 1 P 0 N
L 2.46853002 4.53348002 2.46901004 4.533 1 P 0 
A 2.46901004 4.533 2.4767439 4.52782382 2.48589331 4.54986004 1 P 0 N
A 2.4767439 4.52782382 2.48586998 4.526 2.48589301 4.54986004 1 P 0 N
L 2.48586998 4.526 2.49105 4.526 1 P 0 
A 2.49105 4.526 2.50563002 4.52890079 2.49104833 4.5641 1 P 0 N
A 2.50563002 4.52890079 2.51798996 4.53716004 2.49104843 4.5641 1 P 0 N
L 2.51798996 4.53716004 2.52343996 4.54261004 1 P 0 
A 2.52343996 4.54261004 2.53200276 4.55542421 2.49551004 4.57054163 1 P 0 N
A 2.53200276 4.55542421 2.53501004 4.57053996 2.49551004 4.57054144 1 P 0 N
L 2.53501004 4.57053996 2.53501004 4.57058996 1 P 0 
A 2.53501004 4.57058996 2.53495 4.57123996 2.53126004 4.57057136 1 P 0 N
L 2.53495 4.57123996 2.52161998 4.6469 1 P 0 
A 2.52161998 4.6469 2.52470787 4.69390738 2.61923002 4.66409311 1 P 0 Y
A 2.52470787 4.69390738 2.54915 4.73418002 2.61923002 4.6640938 1 P 0 Y
L 2.54915 4.73418002 2.54916998 4.7342 1 P 0 
A 2.54916998 4.7342 2.61268002 4.7605 2.61267874 4.67066998 1 P 0 Y
L 2.61268002 4.7605 2.6127 4.7605 1 P 0 
A 2.6127 4.7605 2.62357313 4.75883258 2.6127253 4.72438002 1 P 0 Y
A 2.62357313 4.75883258 2.63343996 4.75396998 2.61272569 4.72438002 1 P 0 Y
L 2.63343996 4.75396998 2.66441004 4.73226004 1 P 0 
L 2.66441004 4.73226004 2.67481004 4.71741004 1 P 0 
L 2.67481004 4.71741004 2.68821998 4.64141004 1 P 0 
L 2.68821998 4.64141004 2.70081004 4.62343002 1 P 0 
L 2.70081004 4.62343002 2.70858002 4.61566998 1 P 0 
A 2.70858002 4.61566998 2.74846998 4.6157 2.72850994 4.63565 1 P 0 N
L 2.74846998 4.6157 2.75225 4.61948002 1 P 0 
A 2.75225 4.61948002 2.75687303 4.62638809 2.7372 4.63455276 1 P 0 N
A 2.75687303 4.62638809 2.7585 4.63453996 2.7372 4.63455276 1 P 0 N
L 2.7585 4.63453996 2.7585 4.6633 1 P 0 
A 2.7585 4.6633 2.7548 4.667 2.7548 4.6633 1 P 0 N
L 2.7548 4.667 2.74225 4.667 1 P 0 
P 2.44606004 3.81615 5 P 0 0;2=3,4=1
P 3.20743996 4.78291998 5 P 0 0;2=3,4=1
L 3.20743996 4.78291998 3.196 4.78291998 1 P 0 
A 3.196 4.78291998 3.19158996 4.77851004 3.1959999 4.77851004 1 P 0 N
L 3.19158996 4.77851004 3.19158996 4.75241998 1 P 0 
L 3.19158996 4.75241998 3.16876998 4.62296998 1 P 0 
L 3.16876998 4.62296998 3.24541998 4.18806998 1 P 0 
A 3.24541998 4.18806998 3.2528753 4.16611083 3.32046998 4.20130492 1 P 0 N
A 3.2528753 4.16611083 3.26658996 4.14741004 3.32046998 4.20130354 1 P 0 N
L 3.26658996 4.14741004 3.27801004 4.13598996 1 P 0 
A 3.27801004 4.13598996 3.28630581 4.13044764 3.29609508 4.15408002 1 P 0 N
A 3.28630581 4.13044764 3.29608996 4.1285 3.29609596 4.15408002 1 P 0 N
L 3.29608996 4.1285 3.31948996 4.1285 1 P 0 
A 3.31948996 4.1285 3.33695532 4.12503268 3.31951604 4.08291004 1 P 0 Y
A 3.33695532 4.12503268 3.35176004 4.11513996 3.31951594 4.08291004 1 P 0 Y
L 3.35176004 4.11513996 3.35176998 4.11513996 1 P 0 
A 3.35176998 4.11513996 3.35405 4.08696998 3.33591998 4.09967982 1 P 0 Y
L 3.35405 4.08696998 3.32403996 4.04413002 1 P 0 
A 3.32403996 4.04413002 3.31681004 4.03953002 3.31487057 4.05056004 1 P 0 Y
L 3.31681004 4.03953002 3.21398996 4.02136998 1 P 0 
A 3.21398996 4.02136998 3.196 4.01201004 3.21985955 3.98811998 1 P 0 N
L 3.196 4.01201004 3.196 4.012 1 P 0 
A 3.196 4.012 3.18455925 3.99315157 3.22881004 3.97918829 1 P 0 N
A 3.18455925 3.99315157 3.18311004 3.97115 3.22881004 3.97918829 1 P 0 N
L 3.18311004 3.97115 3.1961 3.89733996 1 P 0 
A 3.1961 3.89733996 3.16096998 3.85548996 3.16096998 3.89115945 1 P 0 Y
A 3.16096998 3.85548996 3.15044675 3.85711476 3.16098386 3.89046998 1 P 0 Y
A 3.15044675 3.85711476 3.1409 3.86183002 3.16098346 3.89046998 1 P 0 Y
L 3.1409 3.86183002 3.09851998 3.89151004 1 P 0 
A 3.09851998 3.89151004 3.08496683 3.89819813 3.07002372 3.85083996 1 P 0 N
A 3.08496683 3.89819813 3.07003002 3.9005 3.07002283 3.85083996 1 P 0 N
L 3.07003002 3.9005 3.06465 3.9005 1 P 0 
A 3.06465 3.9005 3.02416998 3.86001998 3.06465 3.86001998 1 P 0 N
L 3.02416998 3.86001998 3.02416998 3.85108002 1 P 0 
L 3.02416998 3.85108002 3.02423002 3.85101998 1 P 0 
L 3.02423002 3.85101998 3.02423002 3.84738002 1 P 0 
L 3.02423002 3.84738002 3.03438996 3.78971998 1 P 0 
A 3.03438996 3.78971998 3.03313337 3.77057884 2.99465 3.78271703 1 P 0 Y
A 3.03313337 3.77057884 3.02318002 3.75418002 2.99465 3.78271644 1 P 0 Y
L 3.02318002 3.75418002 3.02256998 3.75356998 1 P 0 
A 3.02256998 3.75356998 2.94336998 3.75356998 2.98296998 3.79316998 1 P 0 Y
L 2.94336998 3.75356998 2.90406998 3.79288002 1 P 0 
A 2.90406998 3.79288002 2.8694 3.80723996 2.86940118 3.75821004 1 P 0 N
L 2.8694 3.80723996 2.86848002 3.80723996 1 P 0 
L 2.86848002 3.80723996 2.86846004 3.80725 1 P 0 
A 2.86846004 3.80725 2.8452186 3.80236545 2.86935207 3.74526998 1 P 0 N
A 2.8452186 3.80236545 2.82551998 3.7891 2.86935187 3.74526998 1 P 0 N
L 2.82551998 3.7891 2.82551004 3.78908996 1 P 0 
A 2.82551004 3.78908996 2.8186753 3.77977234 2.85235 3.76223652 1 P 0 N
A 2.8186753 3.77977234 2.81496004 3.76883002 2.85235 3.76223681 1 P 0 N
L 2.81496004 3.76883002 2.80108996 3.69006998 1 P 0 
A 2.80108996 3.69006998 2.78636585 3.66457205 2.75868996 3.69755413 1 P 0 Y
A 2.78636585 3.66457205 2.7587 3.6545 2.7586935 3.69755 1 P 0 Y
L 2.7587 3.6545 2.75671004 3.6545 1 P 0 
A 2.75671004 3.6545 2.71945 3.66993002 2.75670906 3.7072 1 P 0 Y
L 2.71945 3.66993002 2.69971998 3.68966004 1 P 0 
A 2.69971998 3.68966004 2.68546998 3.71703996 2.73601998 3.72595069 1 P 0 Y
L 2.68546998 3.71703996 2.66335 3.84248996 1 P 0 
A 2.66335 3.84248996 2.64755 3.87283996 2.60733996 3.83261919 1 P 0 N
L 2.64755 3.87283996 2.63491004 3.88546998 1 P 0 
A 2.63491004 3.88546998 2.62613081 3.89287697 2.58684783 3.83741004 1 P 0 N
A 2.62613081 3.89287697 2.61623002 3.8987 2.58684577 3.83741004 1 P 0 N
A 2.61623002 3.8987 2.59561004 3.90531998 2.58179341 3.82686004 1 P 0 N
L 2.59561004 3.90531998 2.52368996 3.91801998 1 P 0 
A 2.52368996 3.91801998 2.52105315 3.91824006 2.52116388 3.90366004 1 P 0 N
A 2.52105315 3.91824006 2.51841998 3.91798002 2.52116358 3.90366004 1 P 0 N
L 2.51841998 3.91798002 2.50613996 3.91563996 1 P 0 
A 2.50613996 3.91563996 2.49982362 3.91342057 2.51035364 3.89355 1 P 0 N
A 2.49982362 3.91342057 2.49443996 3.90943996 2.51035217 3.89355 1 P 0 N
L 2.49443996 3.90943996 2.48021998 3.89521998 1 P 0 
L 2.48021998 3.89521998 2.48023002 3.89521998 1 P 0 
A 2.48023002 3.89521998 2.47622195 3.88922303 2.49331998 3.88213337 1 P 0 N
A 2.47622195 3.88922303 2.47481004 3.88215 2.49331998 3.88213248 1 P 0 N
L 2.47481004 3.88215 2.47481004 3.85488996 1 P 0 
A 2.47481004 3.85488996 2.45731998 3.8374 2.45732008 3.85488996 1 P 0 Y
L 2.45731998 3.8374 2.44976004 3.8374 1 P 0 
A 2.44976004 3.8374 2.44606004 3.8337 2.44976004 3.8337 1 P 0 N
L 2.44606004 3.8337 2.44606004 3.81615 1 P 0 
P 2.78225 4.667 5 P 0 0;2=3,4=1
P 2.09606004 3.71615 5 P 0 0;2=3,4=1
L 2.09606004 3.71615 2.09606004 3.6986 1 P 0 
A 2.09606004 3.6986 2.09236004 3.6949 2.09236004 3.6986 1 P 0 Y
L 2.09236004 3.6949 1.95473996 3.6949 1 P 0 
A 1.95473996 3.6949 1.95070463 3.69570502 1.95473465 3.70538996 1 P 0 Y
A 1.95070463 3.69570502 1.94728996 3.698 1.95473524 3.70538996 1 P 0 Y
L 1.94728996 3.698 1.92101998 3.7245 1 P 0 
A 1.92101998 3.7245 1.91178524 3.73718032 1.95788002 3.76104705 1 P 0 Y
A 1.91178524 3.73718032 1.90676004 3.75203996 1.95788002 3.76104803 1 P 0 Y
L 1.90676004 3.75203996 1.88853002 3.85546998 1 P 0 
L 1.88853002 3.85546998 1.90686004 3.95936998 1 P 0 
L 1.90686004 3.95936998 1.92476998 3.98495 1 P 0 
L 1.92476998 3.98495 1.95366004 4.00515 1 P 0 
L 1.95366004 4.00515 1.9932 4.01213002 1 P 0 
A 1.9932 4.01213002 2.01183002 4.02183002 1.98712933 4.04653002 1 P 0 N
L 2.01183002 4.02183002 2.01533002 4.02533002 1 P 0 
A 2.01533002 4.02533002 2.02448268 4.03903465 1.98548002 4.05517402 1 P 0 N
A 2.02448268 4.03903465 2.02768996 4.0552 1.98548002 4.05517382 1 P 0 N
L 2.02768996 4.0552 2.02768996 4.05521998 1 P 0 
A 2.02768996 4.05521998 2.02318671 4.07361407 1.98785 4.05521467 1 P 0 N
A 2.02318671 4.07361407 2.0107 4.08785 1.98785 4.05521339 1 P 0 N
L 2.0107 4.08785 1.96966998 4.11658002 1 P 0 
A 1.96966998 4.11658002 1.95040295 4.13855837 2.00495 4.16694203 1 P 0 Y
A 1.95040295 4.13855837 1.94346004 4.16695 2.00495 4.16694203 1 P 0 Y
L 1.94346004 4.16695 1.94346004 4.16696004 1 P 0 
L 1.94346004 4.16696004 1.96221998 4.27336004 1 P 0 
L 1.96221998 4.27336004 2.06543002 4.42075 1 P 0 
L 2.06543002 4.42075 2.17243002 4.49563002 1 P 0 
L 2.17243002 4.49563002 2.2078 4.50188996 1 P 0 
L 2.2078 4.50188996 2.31381998 4.48321004 1 P 0 
L 2.31381998 4.48321004 2.31456998 4.48321004 1 P 0 
A 2.31456998 4.48321004 2.35771004 4.50108002 2.3145689 4.54421998 1 P 0 N
A 2.35771004 4.50108002 2.37026004 4.52518002 2.32571004 4.53306161 1 P 0 N
L 2.37026004 4.52518002 2.37373996 4.54486998 1 P 0 
L 2.37373996 4.54486998 2.37375 4.54486998 1 P 0 
L 2.37375 4.54486998 2.37721004 4.56451998 1 P 0 
A 2.37721004 4.56451998 2.37916998 4.57266004 2.44511004 4.55247717 1 P 0 Y
A 2.37916998 4.57266004 2.38741004 4.58641004 2.4108 4.56304892 1 P 0 Y
L 2.38741004 4.58641004 2.38938996 4.58838996 1 P 0 
A 2.38938996 4.58838996 2.41741998 4.6 2.41741939 4.56036004 1 P 0 Y
L 2.41741998 4.6 2.422 4.6 1 P 0 
A 2.422 4.6 2.4445 4.5775 2.422 4.5775 1 P 0 Y
L 2.4445 4.5775 2.4445 4.56898996 1 P 0 
L 2.4445 4.56898996 2.44471004 4.56878002 1 P 0 
A 2.44471004 4.56878002 2.46298996 4.5284 2.51 4.57400896 1 P 0 N
L 2.46298996 4.5284 2.4637 4.52768996 1 P 0 
A 2.4637 4.52768996 2.48588002 4.5185 2.48587972 4.54986004 1 P 0 N
L 2.48588002 4.5185 2.49106004 4.5185 1 P 0 
A 2.49106004 4.5185 2.50850728 4.52196919 2.49106152 4.5641 1 P 0 N
A 2.50850728 4.52196919 2.5233 4.53185 2.4910623 4.5641 1 P 0 N
L 2.5233 4.53185 2.52875 4.5373 1 P 0 
A 2.52875 4.5373 2.53893435 4.55254695 2.49551004 4.57052776 1 P 0 N
A 2.53893435 4.55254695 2.54251004 4.57053002 2.49551004 4.57052835 1 P 0 N
L 2.54251004 4.57053002 2.54251004 4.57061004 1 P 0 
A 2.54251004 4.57061004 2.54233996 4.57256004 2.53126004 4.57061122 1 P 0 N
L 2.54233996 4.57256004 2.52901004 4.6482 1 P 0 
A 2.52901004 4.6482 2.53186654 4.69164862 2.61923002 4.66408681 1 P 0 Y
A 2.53186654 4.69164862 2.55446004 4.72886998 2.61923002 4.66408652 1 P 0 Y
L 2.55446004 4.72886998 2.55448002 4.72888996 1 P 0 
A 2.55448002 4.72888996 2.5811873 4.74673356 2.61269222 4.67066998 1 P 0 Y
A 2.5811873 4.74673356 2.61268996 4.753 2.61269232 4.67066998 1 P 0 Y
L 2.61268996 4.753 2.61271004 4.753 1 P 0 
A 2.61271004 4.753 2.62913002 4.74781998 2.61271152 4.72438996 1 P 0 Y
L 2.62913002 4.74781998 2.65901998 4.72686998 1 P 0 
L 2.65901998 4.72686998 2.66771004 4.71446998 1 P 0 
L 2.66771004 4.71446998 2.66993996 4.70181998 1 P 0 
L 2.66993996 4.70181998 2.66563996 4.69568996 1 P 0 
L 2.66563996 4.69568996 2.66758002 4.68473002 1 P 0 
L 2.66758002 4.68473002 2.67371004 4.68045 1 P 0 
L 2.67371004 4.68045 2.67563996 4.6695 1 P 0 
L 2.67563996 4.6695 2.67133996 4.66336998 1 P 0 
L 2.67133996 4.66336998 2.67328002 4.65241004 1 P 0 
L 2.67328002 4.65241004 2.67941004 4.64811998 1 P 0 
L 2.67941004 4.64811998 2.68013002 4.64408002 1 P 0 
L 2.68013002 4.64408002 2.68111998 4.63846998 1 P 0 
L 2.68111998 4.63846998 2.69503996 4.61858996 1 P 0 
L 2.69503996 4.61858996 2.70328002 4.61036004 1 P 0 
A 2.70328002 4.61036004 2.72853474 4.59992352 2.72851486 4.63565 1 P 0 N
A 2.72853474 4.59992352 2.75378002 4.61038996 2.72851516 4.63565 1 P 0 N
L 2.75378002 4.61038996 2.75756004 4.61416998 1 P 0 
A 2.75756004 4.61416998 2.766 4.63453996 2.7372 4.63453927 1 P 0 N
L 2.766 4.63453996 2.766 4.6633 1 P 0 
A 2.766 4.6633 2.7697 4.667 2.7697 4.6633 1 P 0 Y
L 2.7697 4.667 2.78225 4.667 1 P 0 
P 2.44606004 3.86615 5 P 0 0;2=3,4=1
P 3.16743996 4.78291998 5 P 0 0;2=3,4=1
L 3.16743996 4.78291998 3.18 4.78291998 1 P 0 
A 3.18 4.78291998 3.18408996 4.77883002 3.18 4.77883002 1 P 0 Y
L 3.18408996 4.77883002 3.18408996 4.75308002 1 P 0 
L 3.18408996 4.75308002 3.17848996 4.72138996 1 P 0 
L 3.17848996 4.72138996 3.17216004 4.71696004 1 P 0 
L 3.17216004 4.71696004 3.17021998 4.70601004 1 P 0 
L 3.17021998 4.70601004 3.17466998 4.69971004 1 P 0 
L 3.17466998 4.69971004 3.17273002 4.68876998 1 P 0 
L 3.17273002 4.68876998 3.1664 4.68433996 1 P 0 
L 3.1664 4.68433996 3.16446004 4.67338996 1 P 0 
L 3.16446004 4.67338996 3.16891004 4.66708002 1 P 0 
L 3.16891004 4.66708002 3.16891004 4.66701004 1 P 0 
L 3.16891004 4.66701004 3.16115 4.62296998 1 P 0 
L 3.16115 4.62296998 3.23803002 4.18676998 1 P 0 
A 3.23803002 4.18676998 3.26128002 4.1421 3.32048002 4.20129823 1 P 0 N
L 3.26128002 4.1421 3.2727 4.13068002 1 P 0 
A 3.2727 4.13068002 3.28342776 4.12351614 3.29608209 4.15408002 1 P 0 N
A 3.28342776 4.12351614 3.29608002 4.121 3.29608228 4.15408002 1 P 0 N
L 3.29608002 4.121 3.3195 4.121 1 P 0 
A 3.3195 4.121 3.33408652 4.11809734 3.31950236 4.08291004 1 P 0 Y
A 3.33408652 4.11809734 3.34645 4.10983002 3.31950305 4.08291004 1 P 0 Y
L 3.34645 4.10983002 3.34661998 4.10966004 1 P 0 
A 3.34661998 4.10966004 3.3479 4.09128002 3.33591998 4.09968032 1 P 0 Y
L 3.3479 4.09128002 3.3179 4.04843996 1 P 0 
A 3.3179 4.04843996 3.3168561 4.04744272 3.31486683 4.05056998 1 P 0 Y
A 3.3168561 4.04744272 3.31551004 4.04691998 3.31486713 4.05056998 1 P 0 Y
L 3.31551004 4.04691998 3.21268996 4.02876004 1 P 0 
A 3.21268996 4.02876004 3.19068996 4.01731004 3.21986161 3.98811998 1 P 0 N
A 3.19068996 4.01731004 3.17740059 3.99541132 3.22881004 3.97919488 1 P 0 N
A 3.17740059 3.99541132 3.17571998 3.96985 3.22881004 3.97919537 1 P 0 N
L 3.17571998 3.96985 3.18871004 3.89603996 1 P 0 
A 3.18871004 3.89603996 3.18254045 3.8730565 3.16096998 3.89116654 1 P 0 Y
A 3.18254045 3.8730565 3.16096998 3.863 3.16096614 3.89116998 1 P 0 Y
A 3.16096998 3.863 3.15270689 3.86427717 3.16098711 3.89048002 1 P 0 Y
A 3.15270689 3.86427717 3.14521004 3.86798002 3.16098612 3.89048002 1 P 0 Y
L 3.14521004 3.86798002 3.10283002 3.89766004 1 P 0 
A 3.10283002 3.89766004 3.07003996 3.908 3.07004055 3.85083996 1 P 0 N
L 3.07003996 3.908 3.06465 3.908 1 P 0 
A 3.06465 3.908 3.01666998 3.86001998 3.06465 3.86001998 1 P 0 N
L 3.01666998 3.86001998 3.01666998 3.85108002 1 P 0 
L 3.01666998 3.85108002 3.01661004 3.85101998 1 P 0 
L 3.01661004 3.85101998 3.01661004 3.84738002 1 P 0 
L 3.01661004 3.84738002 3.027 3.78841998 1 P 0 
A 3.027 3.78841998 3.02597362 3.77283858 2.99463996 3.78272707 1 P 0 Y
A 3.02597362 3.77283858 3.01786998 3.75948996 2.99463996 3.78272648 1 P 0 Y
L 3.01786998 3.75948996 3.01726004 3.75888002 1 P 0 
A 3.01726004 3.75888002 2.94868002 3.75888002 2.98297008 3.79316998 1 P 0 Y
L 2.94868002 3.75888002 2.90936998 3.79818996 1 P 0 
L 2.90936998 3.79818996 2.90936998 3.7982 1 P 0 
A 2.90936998 3.7982 2.8694 3.81475 2.86940039 3.75821004 1 P 0 N
L 2.8694 3.81475 2.86936004 3.81476004 1 P 0 
A 2.86936004 3.81476004 2.86835 3.81475 2.86954567 3.74526998 1 P 0 N
A 2.86835 3.81475 2.82021004 3.79441004 2.86933957 3.74526998 1 P 0 N
L 2.82021004 3.79441004 2.8202 3.7944 1 P 0 
A 2.8202 3.7944 2.81201673 3.78323711 2.85236004 3.76224321 1 P 0 N
A 2.81201673 3.78323711 2.80756998 3.77013002 2.85236004 3.76224222 1 P 0 N
L 2.80756998 3.77013002 2.7937 3.69136998 1 P 0 
A 2.7937 3.69136998 2.78153888 3.67031447 2.75868996 3.69755108 1 P 0 Y
A 2.78153888 3.67031447 2.75868996 3.662 2.75869094 3.69755 1 P 0 Y
L 2.75868996 3.662 2.75671998 3.662 1 P 0 
A 2.75671998 3.662 2.73942313 3.66544154 2.75672254 3.7072 1 P 0 Y
A 2.73942313 3.66544154 2.72476004 3.67523996 2.75672224 3.7072 1 P 0 Y
L 2.72476004 3.67523996 2.70503002 3.69496998 1 P 0 
A 2.70503002 3.69496998 2.69286004 3.71833996 2.73601998 3.72596181 1 P 0 Y
L 2.69286004 3.71833996 2.67073996 3.84378996 1 P 0 
A 2.67073996 3.84378996 2.65286004 3.87815 2.60733996 3.83263061 1 P 0 N
L 2.65286004 3.87815 2.64021998 3.89078002 1 P 0 
A 2.64021998 3.89078002 2.63047224 3.89899902 2.58686417 3.83738996 1 P 0 N
A 2.63047224 3.89899902 2.61948002 3.90546004 2.58686467 3.83738996 1 P 0 N
L 2.61948002 3.90546004 2.61948002 3.90546998 1 P 0 
A 2.61948002 3.90546998 2.60844222 3.90986063 2.58181417 3.82685 1 P 0 N
A 2.60844222 3.90986063 2.59691004 3.91271004 2.58181358 3.82685 1 P 0 N
L 2.59691004 3.91271004 2.52498996 3.92541004 1 P 0 
A 2.52498996 3.92541004 2.52099724 3.92574341 2.52116368 3.90366004 1 P 0 N
A 2.52099724 3.92574341 2.51701004 3.92535 2.52116309 3.90366004 1 P 0 N
L 2.51701004 3.92535 2.50473996 3.92301004 1 P 0 
A 2.50473996 3.92301004 2.49631329 3.92005472 2.5103438 3.89353996 1 P 0 N
A 2.49631329 3.92005472 2.48913002 3.91475 2.5103436 3.89353996 1 P 0 N
L 2.48913002 3.91475 2.47491004 3.90053002 1 P 0 
L 2.47491004 3.90053002 2.47491998 3.90053002 1 P 0 
A 2.47491998 3.90053002 2.46929114 3.89210039 2.49333002 3.88214262 1 P 0 N
A 2.46929114 3.89210039 2.46731004 3.88216004 2.49333002 3.88214183 1 P 0 N
L 2.46731004 3.88216004 2.46731004 3.85488996 1 P 0 
A 2.46731004 3.85488996 2.45731998 3.8449 2.45732008 3.85488996 1 P 0 Y
L 2.45731998 3.8449 2.44976004 3.8449 1 P 0 
A 2.44976004 3.8449 2.44606004 3.8486 2.44976004 3.8486 1 P 0 Y
L 2.44606004 3.8486 2.44606004 3.86615 1 P 0 
P 2.34606004 3.81615 5 P 0 0;2=3,4=1
P 3.27831004 5.22001998 5 P 0 0;2=3,4=1
L 3.27831004 5.22001998 3.268 5.22001998 1 P 0 
A 3.268 5.22001998 3.26206004 5.21408002 3.268 5.21408002 1 P 0 N
L 3.26206004 5.21408002 3.26206004 5.18588996 1 P 0 
L 3.26206004 5.18588996 3.25378996 5.13898996 1 P 0 
L 3.25378996 5.13898996 3.20526998 5.06966998 1 P 0 
L 3.20526998 5.06966998 3.17996998 4.92591998 1 P 0 
L 3.17996998 4.92591998 3.13163996 4.85686004 1 P 0 
L 3.13163996 4.85686004 3.12096998 4.79633002 1 P 0 
L 3.12096998 4.79633002 3.14533002 4.65825 1 P 0 
L 3.14533002 4.65825 3.14148996 4.63651998 1 P 0 
L 3.14148996 4.63651998 3.21625 4.21236998 1 P 0 
A 3.21625 4.21236998 3.15401998 4.01501998 2.99556998 4.17347018 1 P 0 Y
L 3.15401998 4.01501998 3.12615 3.98715 1 P 0 
A 3.12615 3.98715 3.11581909 3.97827215 3.06232628 4.05096998 1 P 0 Y
A 3.11581909 3.97827215 3.10426998 3.97105 3.06232539 4.05096998 1 P 0 Y
L 3.10426998 3.97105 3.08736998 3.96218002 1 P 0 
A 3.08736998 3.96218002 3.03996004 3.9505 3.03996004 4.05256004 1 P 0 Y
L 3.03996004 3.9505 3.02373002 3.9505 1 P 0 
A 3.02373002 3.9505 2.83553996 3.87253996 3.02375118 3.68433002 1 P 0 N
L 2.83553996 3.87253996 2.793 3.83 1 P 0 
A 2.793 3.83 2.71131004 3.82781004 2.7509997 3.872 1 P 0 Y
L 2.71131004 3.82781004 2.71118996 3.82781004 1 P 0 
L 2.71118996 3.82781004 2.69531004 3.84368996 1 P 0 
A 2.69531004 3.84368996 2.6869435 3.85622077 2.72261998 3.87098268 1 P 0 Y
A 2.6869435 3.85622077 2.68401004 3.871 2.72261998 3.87098278 1 P 0 Y
L 2.68401004 3.871 2.68401004 3.87101998 1 P 0 
A 2.68401004 3.87101998 2.6803247 3.88949774 2.63571004 3.87099311 1 P 0 N
A 2.6803247 3.88949774 2.66985 3.90516004 2.63571004 3.8709939 1 P 0 N
L 2.66985 3.90516004 2.66541998 3.90958996 1 P 0 
A 2.66541998 3.90958996 2.65389921 3.91804222 2.63219439 3.87638002 1 P 0 N
A 2.65389921 3.91804222 2.64036998 3.92263996 2.63219498 3.87638002 1 P 0 N
L 2.64036998 3.92263996 2.51496004 3.94473996 1 P 0 
L 2.51496004 3.94473996 2.4194 3.9279 1 P 0 
A 2.4194 3.9279 2.40938622 3.92449724 2.42544321 3.89368002 1 P 0 N
A 2.40938622 3.92449724 2.40086004 3.91823996 2.4254435 3.89368002 1 P 0 N
L 2.40086004 3.91823996 2.38193002 3.8993 1 P 0 
A 2.38193002 3.8993 2.37666732 3.89143228 2.39911004 3.88211437 1 P 0 N
A 2.37666732 3.89143228 2.37481004 3.88215 2.39911004 3.88211476 1 P 0 N
L 2.37481004 3.88215 2.37481004 3.85488996 1 P 0 
A 2.37481004 3.85488996 2.35731998 3.8374 2.35732008 3.85488996 1 P 0 Y
L 2.35731998 3.8374 2.34976004 3.8374 1 P 0 
A 2.34976004 3.8374 2.34606004 3.8337 2.34976004 3.8337 1 P 0 N
L 2.34606004 3.8337 2.34606004 3.81615 1 P 0 
P 2.34606004 3.86615 5 P 0 0;2=3,4=1
P 3.23831004 5.22001998 5 P 0 0;2=3,4=1
L 3.23831004 5.22001998 3.25086004 5.22001998 1 P 0 
A 3.25086004 5.22001998 3.25456004 5.21631998 3.25086004 5.21631998 1 P 0 Y
L 3.25456004 5.21631998 3.25456004 5.18655 1 P 0 
L 3.25456004 5.18655 3.24668996 5.14193002 1 P 0 
L 3.24668996 5.14193002 3.2392 5.13123996 1 P 0 
L 3.2392 5.13123996 3.2328 5.13013002 1 P 0 
L 3.2328 5.13013002 3.22641004 5.12101998 1 P 0 
L 3.22641004 5.12101998 3.22756998 5.11461004 1 P 0 
L 3.22756998 5.11461004 3.22118002 5.1055 1 P 0 
L 3.22118002 5.1055 3.21478002 5.10438996 1 P 0 
L 3.21478002 5.10438996 3.20838996 5.09528002 1 P 0 
L 3.20838996 5.09528002 3.20955 5.08886998 1 P 0 
L 3.20955 5.08886998 3.19816998 5.07261004 1 P 0 
L 3.19816998 5.07261004 3.17286998 4.92886004 1 P 0 
L 3.17286998 4.92886004 3.12453996 4.8598 1 P 0 
L 3.12453996 4.8598 3.11335 4.79633002 1 P 0 
L 3.11335 4.79633002 3.13771004 4.65825 1 P 0 
L 3.13771004 4.65825 3.13386998 4.63651998 1 P 0 
L 3.13386998 4.63651998 3.20886004 4.21106998 1 P 0 
A 3.20886004 4.21106998 3.20212067 4.10834144 2.99556998 4.17347726 1 P 0 Y
A 3.20212067 4.10834144 3.14871004 4.02033002 2.99556998 4.17347667 1 P 0 Y
L 3.14871004 4.02033002 3.12083996 3.99246004 1 P 0 
A 3.12083996 3.99246004 3.10078002 3.97768996 3.06229902 4.05096004 1 P 0 Y
L 3.10078002 3.97768996 3.08388002 3.96883002 1 P 0 
A 3.08388002 3.96883002 3.03996004 3.958 3.03993819 4.05256004 1 P 0 Y
L 3.03996004 3.958 3.02373996 3.958 1 P 0 
A 3.02373996 3.958 2.91901407 3.93717008 3.02373829 3.68433002 1 P 0 N
A 2.91901407 3.93717008 2.83023002 3.87785 3.0237373 3.68433002 1 P 0 N
L 2.83023002 3.87785 2.78768996 3.83531004 1 P 0 
A 2.78768996 3.83531004 2.75239636 3.82013632 2.75100728 3.872 1 P 0 Y
A 2.75239636 3.82013632 2.71633996 3.8334 2.75100709 3.872 1 P 0 Y
L 2.71633996 3.8334 2.71633002 3.8334 1 P 0 
A 2.71633002 3.8334 2.71431004 3.83531004 2.75095384 3.87203996 1 P 0 Y
L 2.71431004 3.83531004 2.70061998 3.849 1 P 0 
A 2.70061998 3.849 2.69387618 3.8590935 2.72261004 3.87099193 1 P 0 Y
A 2.69387618 3.8590935 2.69151004 3.871 2.72261004 3.87099203 1 P 0 Y
L 2.69151004 3.871 2.69151004 3.87101998 1 P 0 
A 2.69151004 3.87101998 2.68725738 3.89237037 2.6357 3.87100226 1 P 0 N
A 2.68725738 3.89237037 2.67516004 3.91046998 2.6357 3.87100325 1 P 0 N
L 2.67516004 3.91046998 2.67073002 3.9149 1 P 0 
A 2.67073002 3.9149 2.65736447 3.92470128 2.63220581 3.87638002 1 P 0 N
A 2.65736447 3.92470128 2.64166998 3.93003002 2.6322061 3.87638002 1 P 0 N
L 2.64166998 3.93003002 2.51496004 3.95236004 1 P 0 
L 2.51496004 3.95236004 2.50551998 3.9507 1 P 0 
L 2.50551998 3.9507 2.5004 3.95431004 1 P 0 
L 2.5004 3.95431004 2.48943996 3.95236998 1 P 0 
L 2.48943996 3.95236998 2.48585 3.94723996 1 P 0 
L 2.48585 3.94723996 2.4749 3.9453 1 P 0 
L 2.4749 3.9453 2.46978002 3.94891004 1 P 0 
L 2.46978002 3.94891004 2.45883002 3.94696998 1 P 0 
L 2.45883002 3.94696998 2.45523002 3.94183996 1 P 0 
L 2.45523002 3.94183996 2.4181 3.93528996 1 P 0 
A 2.4181 3.93528996 2.40592096 3.9311562 2.42543199 3.89368002 1 P 0 N
A 2.40592096 3.9311562 2.39555 3.92355 2.42543169 3.89368002 1 P 0 N
L 2.39555 3.92355 2.37661998 3.90461004 1 P 0 
A 2.37661998 3.90461004 2.36973573 3.89430965 2.39911004 3.88212805 1 P 0 N
A 2.36973573 3.89430965 2.36731004 3.88216004 2.39911004 3.88212805 1 P 0 N
L 2.36731004 3.88216004 2.36731004 3.85488996 1 P 0 
A 2.36731004 3.85488996 2.35731998 3.8449 2.35732008 3.85488996 1 P 0 Y
L 2.35731998 3.8449 2.34976004 3.8449 1 P 0 
A 2.34976004 3.8449 2.34606004 3.8486 2.34976004 3.8486 1 P 0 Y
L 2.34606004 3.8486 2.34606004 3.86615 1 P 0 
P 2.19606004 3.66615 5 P 0 0;2=3,4=1
P 2.81311004 4.78291998 5 P 0 0;2=3,4=1
L 2.81311004 4.78291998 2.825 4.78291998 1 P 0 
A 2.825 4.78291998 2.82936004 4.77856004 2.8250001 4.77856004 1 P 0 Y
L 2.82936004 4.77856004 2.82936004 4.642 1 P 0 
A 2.82936004 4.642 2.8172 4.61265 2.78786004 4.6419999 1 P 0 Y
L 2.8172 4.61265 2.81715 4.6126 1 P 0 
A 2.81715 4.6126 2.78973002 4.58975 2.67779409 4.75195 1 P 0 Y
A 2.78973002 4.58975 2.69033002 4.59006998 2.74026014 4.66138996 1 P 0 Y
L 2.69033002 4.59006998 2.68215 4.5958 1 P 0 
L 2.68215 4.5958 2.6615 4.62526998 1 P 0 
L 2.6615 4.62526998 2.64928002 4.69461998 1 P 0 
A 2.64928002 4.69461998 2.64633927 4.70330413 2.61963996 4.68942283 1 P 0 N
A 2.64633927 4.70330413 2.64091998 4.7107 2.61963996 4.68942372 1 P 0 N
L 2.64091998 4.7107 2.64091004 4.7107 1 P 0 
L 2.64091004 4.7107 2.6371 4.71451004 1 P 0 
A 2.6371 4.71451004 2.62604537 4.72191004 2.61299675 4.69046004 1 P 0 N
A 2.62604537 4.72191004 2.613 4.72451004 2.61299547 4.69046004 1 P 0 N
A 2.613 4.72451004 2.56316998 4.70386998 2.6129997 4.65403996 1 P 0 N
L 2.56316998 4.70386998 2.56315 4.70385 1 P 0 
A 2.56315 4.70385 2.55253455 4.6879562 2.59778996 4.66922205 1 P 0 N
A 2.55253455 4.6879562 2.54881004 4.66921004 2.59778996 4.66922175 1 P 0 N
L 2.54881004 4.66921004 2.54881004 4.65453002 1 P 0 
L 2.54881004 4.65453002 2.56241004 4.5773 1 P 0 
A 2.56241004 4.5773 2.56326998 4.56748002 2.50661004 4.56746594 1 P 0 Y
L 2.56326998 4.56748002 2.56326998 4.56361004 1 P 0 
A 2.56326998 4.56361004 2.55963927 4.54538159 2.51563002 4.56362303 1 P 0 Y
A 2.55963927 4.54538159 2.54931004 4.52993002 2.51563002 4.56362303 1 P 0 Y
L 2.54931004 4.52993002 2.52731004 4.50793002 1 P 0 
A 2.52731004 4.50793002 2.51575 4.50191004 2.51198976 4.52323996 1 P 0 Y
L 2.51575 4.50191004 2.31531004 4.46658002 1 P 0 
L 2.31531004 4.46658002 2.20586998 4.48586998 1 P 0 
L 2.20586998 4.48586998 2.17908002 4.48113002 1 P 0 
L 2.17908002 4.48113002 2.07465 4.408 1 P 0 
L 2.07465 4.408 1.97801004 4.26998002 1 P 0 
L 1.97801004 4.26998002 1.96193996 4.17886998 1 P 0 
L 1.96193996 4.17886998 1.96193002 4.17881998 1 P 0 
A 1.96193002 4.17881998 1.96342431 4.15557707 2.01008002 4.17024606 1 P 0 N
A 1.96342431 4.15557707 1.9755 4.13566004 2.01008002 4.17024518 1 P 0 N
L 1.9755 4.13566004 2.01838002 4.10563002 1 P 0 
L 2.01838002 4.10563002 2.03281998 4.09118002 1 P 0 
A 2.03281998 4.09118002 2.04294232 4.07603002 1.99978002 4.05814803 1 P 0 Y
A 2.04294232 4.07603002 2.0465 4.05816004 1.99978002 4.05814783 1 P 0 Y
L 2.0465 4.05816004 2.0465 4.03696004 1 P 0 
A 2.0465 4.03696004 2.04505226 4.02970699 2.02753996 4.03697352 1 P 0 Y
A 2.04505226 4.02970699 2.04093996 4.02356004 2.02753996 4.03697362 1 P 0 Y
L 2.04093996 4.02356004 2.02028996 4.00291004 1 P 0 
A 2.02028996 4.00291004 2.00856004 3.9968 2.00473898 4.01845 1 P 0 Y
L 2.00856004 3.9968 1.96056998 3.98835 1 P 0 
L 1.96056998 3.98835 1.93768996 3.97235 1 P 0 
L 1.93768996 3.97235 1.92331998 3.95181004 1 P 0 
L 1.92331998 3.95181004 1.90701998 3.85938996 1 P 0 
L 1.90701998 3.85938996 1.91966998 3.78771004 1 P 0 
A 1.91966998 3.78771004 1.92387057 3.77532677 1.962 3.79516496 1 P 0 N
A 1.92387057 3.77532677 1.9316 3.76478002 1.962 3.79516506 1 P 0 N
L 1.9316 3.76478002 1.95485 3.74153002 1 P 0 
A 1.95485 3.74153002 1.96481998 3.7374 1.96482037 3.7515 1 P 0 N
L 1.96481998 3.7374 2.16006004 3.7374 1 P 0 
A 2.16006004 3.7374 2.16731004 3.73015 2.16006004 3.73015 1 P 0 Y
L 2.16731004 3.73015 2.16731004 3.70488996 1 P 0 
A 2.16731004 3.70488996 2.1848 3.6874 2.1848 3.70488996 1 P 0 N
L 2.1848 3.6874 2.19236004 3.6874 1 P 0 
A 2.19236004 3.6874 2.19606004 3.6837 2.19236004 3.6837 1 P 0 Y
L 2.19606004 3.6837 2.19606004 3.66615 1 P 0 
P 2.19606004 3.71615 5 P 0 0;2=3,4=1
P 2.85311004 4.78291998 5 P 0 0;2=3,4=1
L 2.85311004 4.78291998 2.84056004 4.78291998 1 P 0 
A 2.84056004 4.78291998 2.83686004 4.77921998 2.84056004 4.77921998 1 P 0 N
L 2.83686004 4.77921998 2.83686004 4.74075 1 P 0 
L 2.83686004 4.74075 2.842 4.73561004 1 P 0 
L 2.842 4.73561004 2.842 4.72451004 1 P 0 
L 2.842 4.72451004 2.83686004 4.71936998 1 P 0 
L 2.83686004 4.71936998 2.83686004 4.70826998 1 P 0 
L 2.83686004 4.70826998 2.842 4.70313002 1 P 0 
L 2.842 4.70313002 2.842 4.69203002 1 P 0 
L 2.842 4.69203002 2.83686004 4.68688996 1 P 0 
L 2.83686004 4.68688996 2.83686004 4.642 1 P 0 
A 2.83686004 4.642 2.82251004 4.60733996 2.78785 4.64199055 1 P 0 Y
L 2.82251004 4.60733996 2.82246004 4.60728996 1 P 0 
A 2.82246004 4.60728996 2.794 4.58356998 2.67778691 4.75193996 1 P 0 Y
A 2.794 4.58356998 2.73995492 4.56681909 2.74026181 4.66138996 1 P 0 Y
A 2.73995492 4.56681909 2.68601998 4.58391998 2.74026152 4.66138996 1 P 0 Y
L 2.68601998 4.58391998 2.67676004 4.59041004 1 P 0 
L 2.67676004 4.59041004 2.6544 4.62233002 1 P 0 
L 2.6544 4.62233002 2.64188996 4.69331998 1 P 0 
A 2.64188996 4.69331998 2.63968022 4.69983888 2.61963996 4.68941171 1 P 0 N
A 2.63968022 4.69983888 2.63561004 4.70538996 2.61963996 4.6894126 1 P 0 N
L 2.63561004 4.70538996 2.63178996 4.70921004 1 P 0 
A 2.63178996 4.70921004 2.62317037 4.71497579 2.61300295 4.69045 1 P 0 N
A 2.62317037 4.71497579 2.613 4.717 2.61300236 4.69045 1 P 0 N
A 2.613 4.717 2.56848002 4.69856004 2.61299892 4.65403996 1 P 0 N
L 2.56848002 4.69856004 2.56846004 4.69853996 1 P 0 
A 2.56846004 4.69853996 2.55946811 4.68508346 2.59778996 4.66920846 1 P 0 N
A 2.55946811 4.68508346 2.55631004 4.66921004 2.59778996 4.66920837 1 P 0 N
L 2.55631004 4.66921004 2.55631004 4.65518996 1 P 0 
L 2.55631004 4.65518996 2.5698 4.5786 1 P 0 
A 2.5698 4.5786 2.57076998 4.56748996 2.5066 4.56748484 1 P 0 Y
L 2.57076998 4.56748996 2.57076998 4.56361004 1 P 0 
A 2.57076998 4.56361004 2.55461998 4.52461998 2.51563002 4.56360965 1 P 0 Y
L 2.55461998 4.52461998 2.53261998 4.50261998 1 P 0 
A 2.53261998 4.50261998 2.52545876 4.49737126 2.51199537 4.52325 1 P 0 Y
A 2.52545876 4.49737126 2.51705 4.49451998 2.51199587 4.52325 1 P 0 Y
L 2.51705 4.49451998 2.31531004 4.45896004 1 P 0 
L 2.31531004 4.45896004 2.20586998 4.47825 1 P 0 
L 2.20586998 4.47825 2.18201998 4.47403002 1 P 0 
L 2.18201998 4.47403002 2.08003996 4.40261004 1 P 0 
L 2.08003996 4.40261004 1.98511004 4.26703996 1 P 0 
L 1.98511004 4.26703996 1.96931998 4.17748002 1 P 0 
L 1.96931998 4.17748002 1.96931004 4.17743002 1 P 0 
A 1.96931004 4.17743002 1.97050797 4.15809439 2.01008996 4.17025157 1 P 0 N
A 1.97050797 4.15809439 1.98036998 4.14141998 2.01008996 4.17025138 1 P 0 N
L 1.98036998 4.14141998 2.02321998 4.1114 1 P 0 
L 2.02321998 4.1114 2.03813002 4.09648996 1 P 0 
A 2.03813002 4.09648996 2.054 4.05816004 1.99978002 4.05816132 1 P 0 Y
L 2.054 4.05816004 2.054 4.03695 1 P 0 
A 2.054 4.03695 2.04625 4.01825 2.02753996 4.03696014 1 P 0 Y
L 2.04625 4.01825 2.0256 3.9976 1 P 0 
A 2.0256 3.9976 2.00986004 3.98941004 2.00475039 4.01845 1 P 0 Y
L 2.00986004 3.98941004 1.96351004 3.98125 1 P 0 
L 1.96351004 3.98125 1.94308002 3.96696004 1 P 0 
L 1.94308002 3.96696004 1.93041998 3.94886998 1 P 0 
L 1.93041998 3.94886998 1.91463996 3.85938996 1 P 0 
L 1.91463996 3.85938996 1.92706004 3.78901004 1 P 0 
A 1.92706004 3.78901004 1.93052963 3.77879203 1.962 3.79517608 1 P 0 N
A 1.93052963 3.77879203 1.93691004 3.77008996 1.962 3.79517618 1 P 0 N
L 1.93691004 3.77008996 1.96016004 3.74683996 1 P 0 
A 1.96016004 3.74683996 1.96481998 3.7449 1.96482963 3.75148996 1 P 0 N
L 1.96481998 3.7449 2.16006004 3.7449 1 P 0 
A 2.16006004 3.7449 2.17481004 3.73015 2.16006004 3.73015 1 P 0 Y
L 2.17481004 3.73015 2.17481004 3.70488996 1 P 0 
A 2.17481004 3.70488996 2.1848 3.6949 2.1848 3.70488996 1 P 0 N
L 2.1848 3.6949 2.19236004 3.6949 1 P 0 
A 2.19236004 3.6949 2.19606004 3.6986 2.19236004 3.6986 1 P 0 N
L 2.19606004 3.6986 2.19606004 3.71615 1 P 0 
P 2.09606004 3.81615 5 P 0 0;2=3,4=1
P 3.09656998 5.0535 5 P 0 0;2=3,4=1
L 3.09656998 5.0535 3.109 5.0535 1 P 0 
A 3.109 5.0535 3.11281998 5.05731998 3.109 5.05731998 1 P 0 N
L 3.11281998 5.05731998 3.11281998 5.09081004 1 P 0 
A 3.11281998 5.09081004 3.11079843 5.10098307 3.08621998 5.09081152 1 P 0 N
A 3.11079843 5.10098307 3.10503996 5.10961004 3.08621998 5.0908124 1 P 0 N
L 3.10503996 5.10961004 3.10298002 5.11166998 1 P 0 
A 3.10298002 5.11166998 3.0992811 5.11413691 3.09493248 5.10361004 1 P 0 N
A 3.0992811 5.11413691 3.09491998 5.115 3.09493179 5.10361004 1 P 0 N
L 3.09491998 5.115 3.08563002 5.115 1 P 0 
L 3.08563002 5.115 3.0733 5.11281004 1 P 0 
L 3.0733 5.11281004 3.05816998 5.10221004 1 P 0 
L 3.05816998 5.10221004 3.05703996 5.09573002 1 P 0 
L 3.05703996 5.09573002 3.04791998 5.08935 1 P 0 
L 3.04791998 5.08935 3.04145 5.09051004 1 P 0 
L 3.04145 5.09051004 3.03233002 5.08413002 1 P 0 
L 3.03233002 5.08413002 3.0312 5.07765 1 P 0 
L 3.0312 5.07765 3.02208002 5.07126998 1 P 0 
L 3.02208002 5.07126998 3.01561004 5.07243002 1 P 0 
L 3.01561004 5.07243002 3.00618996 5.06583996 1 P 0 
L 3.00618996 5.06583996 2.92828002 4.95455 1 P 0 
L 2.92828002 4.95455 2.91845 4.89893002 1 P 0 
L 2.91845 4.89893002 2.92528002 4.8602 1 P 0 
L 2.92528002 4.8602 2.91818002 4.81996004 1 P 0 
L 2.91818002 4.81996004 2.92073002 4.80545 1 P 0 
L 2.92073002 4.80545 2.93113002 4.79061004 1 P 0 
L 2.93113002 4.79061004 2.95821998 4.77163002 1 P 0 
L 2.95821998 4.77163002 2.98716004 4.73028996 1 P 0 
L 2.98716004 4.73028996 2.99501004 4.68581004 1 P 0 
L 2.99501004 4.68581004 2.99088002 4.66235 1 P 0 
L 2.99088002 4.66235 2.99385 4.64548996 1 P 0 
L 2.99385 4.64548996 2.99008002 4.62413002 1 P 0 
L 2.99008002 4.62413002 2.97331004 4.60016004 1 P 0 
L 2.97331004 4.60016004 2.84566004 4.51078002 1 P 0 
L 2.84566004 4.51078002 2.75093996 4.49408996 1 P 0 
A 2.75093996 4.49408996 2.73246004 4.48446004 2.75697087 4.45996998 1 P 0 N
A 2.73246004 4.48446004 2.72059941 4.45903819 2.76146004 4.45545226 1 P 0 N
A 2.72059941 4.45903819 2.72785 4.43193996 2.76146004 4.45545197 1 P 0 N
L 2.72785 4.43193996 2.73721998 4.41855 1 P 0 
L 2.73721998 4.41855 2.73721998 4.41853002 1 P 0 
L 2.73721998 4.41853002 2.73723996 4.41848996 1 P 0 
L 2.73723996 4.41848996 2.76938002 4.38465 1 P 0 
A 2.76938002 4.38465 2.77881102 4.36058514 2.74451004 4.36102303 1 P 0 Y
A 2.77881102 4.36058514 2.76876998 4.33676998 2.74451004 4.36102293 1 P 0 Y
L 2.76876998 4.33676998 2.76086998 4.32886998 1 P 0 
A 2.76086998 4.32886998 2.73586004 4.3185 2.73584094 4.35388996 1 P 0 Y
L 2.73586004 4.3185 2.73386004 4.3185 1 P 0 
A 2.73386004 4.3185 2.72232156 4.32027087 2.73384222 4.35686004 1 P 0 Y
A 2.72232156 4.32027087 2.71185 4.32543002 2.73384173 4.35686004 1 P 0 Y
L 2.71185 4.32543002 2.66983996 4.35483996 1 P 0 
A 2.66983996 4.35483996 2.65527283 4.36202441 2.63919754 4.31106998 1 P 0 N
A 2.65527283 4.36202441 2.63921998 4.3645 2.63919754 4.31106998 1 P 0 N
L 2.63921998 4.3645 2.63206998 4.3645 1 P 0 
A 2.63206998 4.3645 2.61231998 4.35631998 2.632069 4.33656998 1 P 0 N
L 2.61231998 4.35631998 2.61231004 4.35631004 1 P 0 
A 2.61231004 4.35631004 2.60986161 4.35264882 2.62028996 4.34832421 1 P 0 N
A 2.60986161 4.35264882 2.609 4.34833002 2.62028996 4.34832293 1 P 0 N
L 2.609 4.34833002 2.609 4.34488002 1 P 0 
A 2.609 4.34488002 2.61458996 4.33141004 2.62805 4.34489075 1 P 0 N
L 2.61458996 4.33141004 2.62481998 4.32118002 1 P 0 
A 2.62481998 4.32118002 2.6515 4.25676998 2.56041004 4.25676929 1 P 0 Y
A 2.6515 4.25676998 2.64519902 4.22510463 2.56875 4.25677657 1 P 0 Y
A 2.64519902 4.22510463 2.62726004 4.19826004 2.56875 4.25677569 1 P 0 Y
L 2.62726004 4.19826004 2.61778996 4.18878996 1 P 0 
A 2.61778996 4.18878996 2.58255344 4.17235778 2.57760728 4.22896004 1 P 0 Y
A 2.58255344 4.17235778 2.545 4.18243002 2.57760728 4.22896004 1 P 0 Y
L 2.545 4.18243002 2.51778002 4.2015 1 P 0 
A 2.51778002 4.2015 2.50460453 4.20503602 2.5063378 4.18518002 1 P 0 N
A 2.50460453 4.20503602 2.49223996 4.19926998 2.5063373 4.18518002 1 P 0 N
L 2.49223996 4.19926998 2.49223002 4.19926004 1 P 0 
A 2.49223002 4.19926004 2.48611004 4.18751004 2.50781998 4.18367116 1 P 0 N
L 2.48611004 4.18751004 2.4808 4.15741004 1 P 0 
A 2.4808 4.15741004 2.42408002 4.04846004 2.27965 4.19289045 1 P 0 Y
A 2.42408002 4.04846004 2.24311004 3.97351004 2.24312037 4.22943996 1 P 0 Y
L 2.24311004 3.97351004 2.24241998 3.97351004 1 P 0 
L 2.24241998 3.97351004 2.13985 3.99158996 1 P 0 
A 2.13985 3.99158996 2.11901004 3.98501004 2.13575108 3.96828002 1 P 0 N
A 2.11901004 3.98501004 2.11626004 3.98088996 2.12803002 3.97601171 1 P 0 N
A 2.11626004 3.98088996 2.11291004 3.96923996 2.16656998 3.96011654 1 P 0 N
L 2.11291004 3.96923996 2.11165 3.96183002 1 P 0 
A 2.11165 3.96183002 2.1089 3.9293 2.30286004 3.92928435 1 P 0 N
L 2.1089 3.9293 2.1089 3.92891998 1 P 0 
A 2.1089 3.92891998 2.11301998 3.91898002 2.12295 3.92891969 1 P 0 N
L 2.11301998 3.91898002 2.11303996 3.91896004 1 P 0 
A 2.11303996 3.91896004 2.12481004 3.89055 2.08463996 3.89055098 1 P 0 Y
L 2.12481004 3.89055 2.12481004 3.85488996 1 P 0 
A 2.12481004 3.85488996 2.10731998 3.8374 2.10732008 3.85488996 1 P 0 Y
L 2.10731998 3.8374 2.09976004 3.8374 1 P 0 
A 2.09976004 3.8374 2.09606004 3.8337 2.09976004 3.8337 1 P 0 N
L 2.09606004 3.8337 2.09606004 3.81615 1 P 0 
P 2.09606004 3.86615 5 P 0 0;2=3,4=1
P 3.13656998 5.0535 5 P 0 0;2=3,4=1
L 3.13656998 5.0535 3.12401998 5.0535 1 P 0 
A 3.12401998 5.0535 3.12031998 5.0572 3.12401998 5.0572 1 P 0 Y
L 3.12031998 5.0572 3.12031998 5.09081004 1 P 0 
A 3.12031998 5.09081004 3.11035 5.11491004 3.08621004 5.09081122 1 P 0 N
L 3.11035 5.11491004 3.10828002 5.11698002 1 P 0 
A 3.10828002 5.11698002 3.10214921 5.1210685 3.09493524 5.10361004 1 P 0 N
A 3.10214921 5.1210685 3.09491998 5.1225 3.09493583 5.10361004 1 P 0 N
L 3.09491998 5.1225 3.08496004 5.1225 1 P 0 
L 3.08496004 5.1225 3.07035 5.11991004 1 P 0 
L 3.07035 5.11991004 3.0008 5.07123002 1 P 0 
L 3.0008 5.07123002 2.92118002 4.95748996 1 P 0 
L 2.92118002 4.95748996 2.91083002 4.89893002 1 P 0 
L 2.91083002 4.89893002 2.91105 4.89763002 1 P 0 
L 2.91105 4.89763002 2.91106004 4.89763002 1 P 0 
L 2.91106004 4.89763002 2.91766004 4.8602 1 P 0 
L 2.91766004 4.8602 2.91056004 4.81996004 1 P 0 
L 2.91056004 4.81996004 2.91363002 4.80251004 1 P 0 
L 2.91363002 4.80251004 2.92573996 4.78521998 1 P 0 
L 2.92573996 4.78521998 2.94036004 4.77496998 1 P 0 
L 2.94036004 4.77496998 2.94036998 4.77496998 1 P 0 
L 2.94036998 4.77496998 2.95283002 4.76623996 1 P 0 
L 2.95283002 4.76623996 2.98006004 4.72735 1 P 0 
L 2.98006004 4.72735 2.98738996 4.68581004 1 P 0 
L 2.98738996 4.68581004 2.98326004 4.66235 1 P 0 
L 2.98326004 4.66235 2.98623002 4.64548996 1 P 0 
L 2.98623002 4.64548996 2.98298002 4.62706998 1 P 0 
L 2.98298002 4.62706998 2.96791998 4.60555 1 P 0 
L 2.96791998 4.60555 2.84271998 4.51788002 1 P 0 
L 2.84271998 4.51788002 2.74963996 4.50148002 1 P 0 
A 2.74963996 4.50148002 2.72715 4.48976998 2.75695974 4.45996998 1 P 0 N
A 2.72715 4.48976998 2.71312136 4.45969734 2.76146004 4.4554562 1 P 0 N
A 2.71312136 4.45969734 2.7217 4.42763996 2.76146004 4.4554564 1 P 0 N
L 2.7217 4.42763996 2.73051998 4.41503002 1 P 0 
L 2.73051998 4.41503002 2.73071998 4.41473002 1 P 0 
L 2.73071998 4.41473002 2.73101998 4.41413002 1 P 0 
L 2.73101998 4.41413002 2.76393996 4.37948002 1 P 0 
A 2.76393996 4.37948002 2.77130443 4.36068356 2.74451004 4.36102638 1 P 0 Y
A 2.77130443 4.36068356 2.76346004 4.34208002 2.74451004 4.36102608 1 P 0 Y
L 2.76346004 4.34208002 2.75556004 4.33418002 1 P 0 
A 2.75556004 4.33418002 2.7465185 4.32813041 2.73582766 4.35388996 1 P 0 Y
A 2.7465185 4.32813041 2.73585 4.326 2.73582756 4.35388996 1 P 0 Y
L 2.73585 4.326 2.73386004 4.326 1 P 0 
A 2.73386004 4.326 2.72458071 4.32742756 2.73385659 4.35685 1 P 0 Y
A 2.72458071 4.32742756 2.71616004 4.33158002 2.73385551 4.35685 1 P 0 Y
L 2.71616004 4.33158002 2.67415 4.36098996 1 P 0 
A 2.67415 4.36098996 2.65753632 4.36918002 2.63921535 4.31106998 1 P 0 N
A 2.65753632 4.36918002 2.63923002 4.372 2.63921447 4.31106998 1 P 0 N
L 2.63923002 4.372 2.63206998 4.372 1 P 0 
A 2.63206998 4.372 2.60701004 4.36163002 2.63205974 4.33656004 1 P 0 N
L 2.60701004 4.36163002 2.607 4.36161998 1 P 0 
A 2.607 4.36161998 2.60293002 4.35552687 2.62028996 4.34833691 1 P 0 N
A 2.60293002 4.35552687 2.6015 4.34833996 2.62028996 4.34833691 1 P 0 N
L 2.6015 4.34833996 2.6015 4.34486998 1 P 0 
A 2.6015 4.34486998 2.60352805 4.33471043 2.62805 4.3448877 1 P 0 N
A 2.60352805 4.33471043 2.60928996 4.3261 2.62805 4.34488691 1 P 0 N
L 2.60928996 4.3261 2.60928002 4.3261 1 P 0 
L 2.60928002 4.3261 2.61951004 4.31586998 1 P 0 
A 2.61951004 4.31586998 2.64398996 4.25676998 2.56041004 4.25677008 1 P 0 Y
A 2.64398996 4.25676998 2.63826083 4.22797844 2.56875 4.25677598 1 P 0 Y
A 2.63826083 4.22797844 2.62195 4.20356998 2.56875 4.25677461 1 P 0 Y
L 2.62195 4.20356998 2.61248002 4.1941 1 P 0 
A 2.61248002 4.1941 2.58190049 4.17984134 2.57760679 4.22896998 1 P 0 Y
A 2.58190049 4.17984134 2.54931004 4.18858002 2.57760689 4.22896998 1 P 0 Y
L 2.54931004 4.18858002 2.52208996 4.20765 1 P 0 
A 2.52208996 4.20765 2.50395148 4.21251732 2.50633799 4.18518002 1 P 0 N
A 2.50395148 4.21251732 2.48693002 4.20458002 2.5063378 4.18518002 1 P 0 N
L 2.48693002 4.20458002 2.48691998 4.20456998 1 P 0 
A 2.48691998 4.20456998 2.48160797 4.19732067 2.50783002 4.18367707 1 P 0 N
A 2.48160797 4.19732067 2.47871998 4.18881004 2.50783002 4.18367717 1 P 0 N
L 2.47871998 4.18881004 2.47341004 4.15871004 1 P 0 
A 2.47341004 4.15871004 2.41876998 4.05376998 2.27965 4.19290177 1 P 0 Y
A 2.41876998 4.05376998 2.24311004 3.98101004 2.24311112 4.22943002 1 P 0 Y
L 2.24311004 3.98101004 2.24308002 3.98101004 1 P 0 
L 2.24308002 3.98101004 2.14115 3.99898002 1 P 0 
A 2.14115 3.99898002 2.12637077 3.99800561 2.13575236 3.96828002 1 P 0 N
A 2.12637077 3.99800561 2.11371004 3.99031998 2.13575236 3.96828002 1 P 0 N
L 2.11371004 3.99031998 2.1137 3.99031004 1 P 0 
A 2.1137 3.99031004 2.10933002 3.98376004 2.12803996 3.97601004 1 P 0 N
A 2.10933002 3.98376004 2.10551004 3.9705 2.16656004 3.96009282 1 P 0 N
L 2.10551004 3.9705 2.10425 3.96308996 1 P 0 
A 2.10425 3.96308996 2.1014 3.92931004 2.30286004 3.92932313 1 P 0 N
L 2.1014 3.92931004 2.1014 3.92891998 1 P 0 
A 2.1014 3.92891998 2.10771004 3.91366998 2.12296004 3.92891043 1 P 0 N
L 2.10771004 3.91366998 2.10773002 3.91365 1 P 0 
A 2.10773002 3.91365 2.11481772 3.90305305 2.08463996 3.8905376 1 P 0 Y
A 2.11481772 3.90305305 2.11731004 3.89055 2.08463996 3.8905376 1 P 0 Y
L 2.11731004 3.89055 2.11731004 3.85488996 1 P 0 
A 2.11731004 3.85488996 2.10731998 3.8449 2.10732008 3.85488996 1 P 0 Y
L 2.10731998 3.8449 2.09976004 3.8449 1 P 0 
A 2.09976004 3.8449 2.09606004 3.8486 2.09976004 3.8486 1 P 0 Y
L 2.09606004 3.8486 2.09606004 3.86615 1 P 0 
P 2.88708002 4.667 5 P 0 0;2=3,4=1
P 2.04606004 3.76615 5 P 0 0;2=3,4=1
L 2.04606004 3.76615 2.04606004 3.7837 1 P 0 
A 2.04606004 3.7837 2.04236004 3.7874 2.04236004 3.7837 1 P 0 N
L 2.04236004 3.7874 1.98178002 3.7874 1 P 0 
A 1.98178002 3.7874 1.95326998 3.80223002 1.98176978 3.8222 1 P 0 Y
L 1.95326998 3.80223002 1.93731998 3.82501998 1 P 0 
L 1.93731998 3.82501998 1.93088002 3.86148996 1 P 0 
L 1.93088002 3.86148996 1.94421998 3.9371 1 P 0 
L 1.94421998 3.9371 1.95738996 3.95593002 1 P 0 
L 1.95738996 3.95593002 1.97236998 3.96641004 1 P 0 
L 1.97236998 3.96641004 2.01825 3.97451004 1 P 0 
A 2.01825 3.97451004 2.0299812 3.97849882 2.01115571 4.01461998 1 P 0 N
A 2.0299812 3.97849882 2.03996998 3.98583002 2.01115502 4.01461998 1 P 0 N
L 2.03996998 3.98583002 2.06238002 4.00823996 1 P 0 
A 2.06238002 4.00823996 2.0735 4.03506998 2.03555 4.03507933 1 P 0 N
L 2.0735 4.03506998 2.0735 4.05923996 1 P 0 
A 2.0735 4.05923996 2.06843317 4.08469803 2.00696998 4.05923199 1 P 0 N
A 2.06843317 4.08469803 2.05401004 4.10628002 2.00696998 4.05923297 1 P 0 N
L 2.05401004 4.10628002 2.05398002 4.10631004 1 P 0 
A 2.05398002 4.10631004 2.03561998 4.12166998 1.95848002 4.01081004 1 P 0 N
L 2.03561998 4.12166998 2.0356 4.12166998 1 P 0 
L 2.0356 4.12166998 2.00123996 4.14573996 1 P 0 
L 2.00123996 4.14573996 2.00123996 4.14573002 1 P 0 
A 2.00123996 4.14573002 1.990406 4.15809803 2.02111998 4.17407333 1 P 0 Y
A 1.990406 4.15809803 1.9865 4.17406998 2.02111998 4.17407283 1 P 0 Y
L 1.9865 4.17406998 1.9865 4.18801004 1 P 0 
L 1.9865 4.18801004 1.99906004 4.25918996 1 P 0 
L 1.99906004 4.25918996 2.0918 4.39165 1 P 0 
L 2.0918 4.39165 2.18451004 4.45656004 1 P 0 
L 2.18451004 4.45656004 2.20886004 4.46086998 1 P 0 
L 2.20886004 4.46086998 2.3596 4.43428002 1 P 0 
L 2.3596 4.43428002 2.38745 4.41478002 1 P 0 
L 2.38745 4.41478002 2.4774 4.28631998 1 P 0 
A 2.4774 4.28631998 2.49779016 4.26844449 2.52413287 4.31906004 1 P 0 N
A 2.49779016 4.26844449 2.52413002 4.262 2.52413238 4.31906004 1 P 0 N
L 2.52413002 4.262 2.52551998 4.262 1 P 0 
A 2.52551998 4.262 2.554 4.29048002 2.52551998 4.29048002 1 P 0 N
L 2.554 4.29048002 2.554 4.29506004 1 P 0 
L 2.554 4.29506004 2.55398996 4.29505 1 P 0 
A 2.55398996 4.29505 2.54601998 4.32031004 2.51003996 4.29507037 1 P 0 N
L 2.54601998 4.32031004 2.48598996 4.40571998 1 P 0 
A 2.48598996 4.40571998 2.47956663 4.41871427 2.52486998 4.43302382 1 P 0 Y
A 2.47956663 4.41871427 2.47736004 4.43303996 2.52486998 4.4330252 1 P 0 Y
A 2.47736004 4.43303996 2.4804623 4.4486561 2.5182 4.43304301 1 P 0 Y
A 2.4804623 4.4486561 2.4893 4.4619 2.5182 4.43304429 1 P 0 Y
A 2.4893 4.4619 2.50176654 4.47022736 2.51646339 4.43473002 1 P 0 Y
A 2.50176654 4.47022736 2.51646998 4.47315 2.51646457 4.43473002 1 P 0 Y
L 2.51646998 4.47315 2.51648996 4.47315 1 P 0 
A 2.51648996 4.47315 2.53101624 4.47091644 2.5164936 4.42481998 1 P 0 Y
A 2.53101624 4.47091644 2.5442 4.46441998 2.51649409 4.42481998 1 P 0 Y
L 2.5442 4.46441998 2.60376004 4.42271004 1 P 0 
A 2.60376004 4.42271004 2.60787116 4.41996388 2.61271791 4.43166998 1 P 0 N
A 2.60787116 4.41996388 2.61271998 4.419 2.61271841 4.43166998 1 P 0 N
L 2.61271998 4.419 2.61761998 4.419 1 P 0 
A 2.61761998 4.419 2.63033917 4.42153228 2.61761585 4.45223002 1 P 0 N
A 2.63033917 4.42153228 2.64111998 4.42873996 2.61761555 4.45223002 1 P 0 N
L 2.64111998 4.42873996 2.65071004 4.43833002 1 P 0 
A 2.65071004 4.43833002 2.65071004 4.46666998 2.63653996 4.4525 1 P 0 N
L 2.65071004 4.46666998 2.63868996 4.47868996 1 P 0 
A 2.63868996 4.47868996 2.63081939 4.4976935 2.6577 4.49769488 1 P 0 Y
A 2.63081939 4.4976935 2.63868996 4.5167 2.6577 4.49769508 1 P 0 Y
L 2.63868996 4.5167 2.64398002 4.52198002 1 P 0 
A 2.64398002 4.52198002 2.65363287 4.52927421 2.67177598 4.49523002 1 P 0 Y
A 2.65363287 4.52927421 2.66506998 4.53321998 2.67177717 4.49523002 1 P 0 Y
L 2.66506998 4.53321998 2.80496998 4.55793996 1 P 0 
L 2.80496998 4.55793996 2.89578002 4.62148996 1 P 0 
L 2.89578002 4.62148996 2.90333002 4.63228002 1 P 0 
L 2.90333002 4.63228002 2.90333002 4.6633 1 P 0 
A 2.90333002 4.6633 2.89963002 4.667 2.89963002 4.6633 1 P 0 N
L 2.89963002 4.667 2.88708002 4.667 1 P 0 
P 2.92708002 4.667 5 P 0 0;2=3,4=1
P 2.04606004 3.81615 5 P 0 0;2=3,4=1
L 2.04606004 3.81615 2.04606004 3.7986 1 P 0 
A 2.04606004 3.7986 2.04236004 3.7949 2.04236004 3.7986 1 P 0 Y
L 2.04236004 3.7949 1.98178002 3.7949 1 P 0 
A 1.98178002 3.7949 1.96917589 3.79798465 1.98178169 3.8222 1 P 0 Y
A 1.96917589 3.79798465 1.95941998 3.80653996 1.98178199 3.8222 1 P 0 Y
L 1.95941998 3.80653996 1.94441998 3.82796004 1 P 0 
L 1.94441998 3.82796004 1.9385 3.86148996 1 P 0 
L 1.9385 3.86148996 1.95131998 3.93416004 1 P 0 
L 1.95131998 3.93416004 1.96278002 3.95053996 1 P 0 
L 1.96278002 3.95053996 1.97531004 3.95931004 1 P 0 
L 1.97531004 3.95931004 2.01955 3.96711998 1 P 0 
A 2.01955 3.96711998 2.03344636 3.97183976 2.01116673 4.01461998 1 P 0 N
A 2.03344636 3.97183976 2.04528002 3.98051998 2.01116663 4.01461998 1 P 0 N
L 2.04528002 3.98051998 2.06768996 4.00293002 1 P 0 
A 2.06768996 4.00293002 2.081 4.03506004 2.03553996 4.03507018 1 P 0 N
L 2.081 4.03506004 2.081 4.05925 1 P 0 
A 2.081 4.05925 2.07536467 4.08757618 2.00696998 4.05924577 1 P 0 N
A 2.07536467 4.08757618 2.05931998 4.11158996 2.00696998 4.05924557 1 P 0 N
L 2.05931998 4.11158996 2.05928996 4.11161998 1 P 0 
A 2.05928996 4.11161998 2.0399 4.12783002 1.95851673 4.01078002 1 P 0 N
L 2.0399 4.12783002 2.00555 4.15188002 1 P 0 
A 2.00555 4.15188002 1.994 4.17408002 2.02111004 4.17408002 1 P 0 Y
L 1.994 4.17408002 1.994 4.18735 1 P 0 
L 1.994 4.18735 2.00616004 4.25625 1 P 0 
L 2.00616004 4.25625 2.09718996 4.38626004 1 P 0 
L 2.09718996 4.38626004 2.18745 4.44946004 1 P 0 
L 2.18745 4.44946004 2.20886004 4.45325 1 P 0 
L 2.20886004 4.45325 2.35666004 4.42718002 1 P 0 
L 2.35666004 4.42718002 2.38206004 4.40938996 1 P 0 
L 2.38206004 4.40938996 2.47125 4.28201004 1 P 0 
A 2.47125 4.28201004 2.52413002 4.2545 2.52412057 4.31906004 1 P 0 N
L 2.52413002 4.2545 2.52551998 4.2545 1 P 0 
A 2.52551998 4.2545 2.5615 4.29048002 2.52551998 4.29048002 1 P 0 N
L 2.5615 4.29048002 2.5615 4.29505 1 P 0 
A 2.5615 4.29505 2.55216004 4.32461998 2.51005 4.29505906 1 P 0 N
L 2.55216004 4.32461998 2.49213002 4.41003002 1 P 0 
A 2.49213002 4.41003002 2.48672421 4.42097461 2.52488002 4.43301339 1 P 0 Y
A 2.48672421 4.42097461 2.48486998 4.43303996 2.52488002 4.43301368 1 P 0 Y
A 2.48486998 4.43303996 2.49461004 4.4566 2.51821004 4.4330501 1 P 0 Y
A 2.49461004 4.4566 2.50464045 4.46329843 2.51646693 4.43473002 1 P 0 Y
A 2.50464045 4.46329843 2.51646998 4.46565 2.51646801 4.43473002 1 P 0 Y
L 2.51646998 4.46565 2.51648002 4.46565 1 P 0 
A 2.51648002 4.46565 2.52875285 4.46376073 2.51647648 4.42481998 1 P 0 Y
A 2.52875285 4.46376073 2.53988996 4.45826998 2.51647657 4.42481998 1 P 0 Y
L 2.53988996 4.45826998 2.59898002 4.4169 1 P 0 
A 2.59898002 4.4169 2.60534321 4.41289596 2.61271535 4.43166998 1 P 0 N
A 2.60534321 4.41289596 2.61273002 4.4115 2.61271644 4.43166998 1 P 0 N
L 2.61273002 4.4115 2.61763002 4.4115 1 P 0 
A 2.61763002 4.4115 2.64643002 4.42343002 2.61762904 4.45223002 1 P 0 N
L 2.64643002 4.42343002 2.65601998 4.43301998 1 P 0 
A 2.65601998 4.43301998 2.65601998 4.47198002 2.63653996 4.4525 1 P 0 N
L 2.65601998 4.47198002 2.644 4.484 1 P 0 
A 2.644 4.484 2.63832884 4.4976935 2.6577 4.49769498 1 P 0 Y
A 2.63832884 4.4976935 2.644 4.51138996 2.6577 4.49769498 1 P 0 Y
L 2.644 4.51138996 2.64978996 4.51718002 1 P 0 
L 2.64978996 4.51718002 2.64978996 4.51718996 1 P 0 
A 2.64978996 4.51718996 2.65741457 4.52278652 2.6717751 4.49523002 1 P 0 Y
A 2.65741457 4.52278652 2.66636998 4.52583002 2.67177451 4.49523002 1 P 0 Y
L 2.66636998 4.52583002 2.80791004 4.55083996 1 P 0 
L 2.80791004 4.55083996 2.85425 4.58326998 1 P 0 
L 2.85425 4.58326998 2.86016998 4.58221004 1 P 0 
L 2.86016998 4.58221004 2.86928002 4.58858002 1 P 0 
L 2.86928002 4.58858002 2.87031998 4.59451004 1 P 0 
L 2.87031998 4.59451004 2.87943002 4.60088996 1 P 0 
L 2.87943002 4.60088996 2.88535 4.59983002 1 P 0 
L 2.88535 4.59983002 2.89446004 4.6062 1 P 0 
L 2.89446004 4.6062 2.8955 4.61213002 1 P 0 
L 2.8955 4.61213002 2.90116998 4.6161 1 P 0 
L 2.90116998 4.6161 2.91083002 4.62991004 1 P 0 
L 2.91083002 4.62991004 2.91083002 4.6633 1 P 0 
A 2.91083002 4.6633 2.91453002 4.667 2.91453002 4.6633 1 P 0 Y
L 2.91453002 4.667 2.92708002 4.667 1 P 0 
P 8.15 3.76615 5 P 0 0;2=3,4=1
P 9.02925 5.165 5 P 0 0;2=3,4=1
L 9.02925 5.165 9.03871004 5.165 1 P 0 
A 9.03871004 5.165 9.04353996 5.163 9.03871083 5.15816998 1 P 0 Y
A 9.04353996 5.163 9.0455 5.15826998 9.03881004 5.1582689 1 P 0 Y
L 9.0455 5.15826998 9.0455 5.14255 1 P 0 
A 9.0455 5.14255 9.03861998 5.12933996 9.02938002 5.14254892 1 P 0 Y
L 9.03861998 5.12933996 9.02533996 5.12005 1 P 0 
L 9.02533996 5.12005 8.9767 5.11148002 1 P 0 
L 8.9767 5.11148002 8.94515 5.08938996 1 P 0 
L 8.94515 5.08938996 8.91778002 5.0503 1 P 0 
L 8.91778002 5.0503 8.89081004 4.89735 1 P 0 
L 8.89081004 4.89735 8.89773996 4.85798002 1 P 0 
L 8.89773996 4.85798002 8.89128002 4.82136004 1 P 0 
L 8.89128002 4.82136004 8.89613996 4.79383002 1 P 0 
L 8.89613996 4.79383002 8.91335 4.76923002 1 P 0 
L 8.91335 4.76923002 8.94036998 4.75033002 1 P 0 
L 8.94036998 4.75033002 8.96258996 4.71861004 1 P 0 
L 8.96258996 4.71861004 8.96836004 4.68576004 1 P 0 
L 8.96836004 4.68576004 8.96423996 4.66235 1 P 0 
L 8.96423996 4.66235 8.96663996 4.64873002 1 P 0 
L 8.96663996 4.64873002 8.96418002 4.63476004 1 P 0 
L 8.96418002 4.63476004 8.95525 4.62201004 1 P 0 
L 8.95525 4.62201004 8.83866004 4.54038002 1 P 0 
L 8.83866004 4.54038002 8.70068996 4.51605 1 P 0 
A 8.70068996 4.51605 8.68750266 4.51157953 8.70861722 4.47098002 1 P 0 N
A 8.68750266 4.51157953 8.67626998 4.50335 8.70861654 4.47098002 1 P 0 N
L 8.67626998 4.50335 8.67623002 4.50331004 1 P 0 
A 8.67623002 4.50331004 8.67185896 4.49662569 8.69003996 4.48950797 1 P 0 N
A 8.67185896 4.49662569 8.67053002 4.48875 8.69003996 4.48950787 1 P 0 N
A 8.67053002 4.48875 8.67513996 4.47778002 8.68628996 4.48891919 1 P 0 N
L 8.67513996 4.47778002 8.68493996 4.46798002 1 P 0 
A 8.68493996 4.46798002 8.69093376 4.45902687 8.66546004 4.448456 1 P 0 Y
A 8.69093376 4.45902687 8.69303996 4.44846004 8.66546004 4.4484561 1 P 0 Y
L 8.69303996 4.44846004 8.69303996 4.44398002 1 P 0 
A 8.69303996 4.44398002 8.69094203 4.43339311 8.66531998 4.44397175 1 P 0 Y
A 8.69094203 4.43339311 8.68496004 4.42441004 8.66531998 4.44397195 1 P 0 Y
L 8.68496004 4.42441004 8.67431998 4.41376998 1 P 0 
L 8.67431998 4.41376998 8.67431998 4.41378002 1 P 0 
A 8.67431998 4.41378002 8.65957431 4.40296467 8.63178671 4.45631004 1 P 0 Y
A 8.65957431 4.40296467 8.64226004 4.39708002 8.63178652 4.45631004 1 P 0 Y
L 8.64226004 4.39708002 8.60073996 4.38973996 1 P 0 
A 8.60073996 4.38973996 8.58026673 4.37791703 8.60674705 4.3557 1 P 0 N
A 8.58026673 4.37791703 8.57218002 4.3557 8.60675 4.35569724 1 P 0 N
A 8.57218002 4.3557 8.57530846 4.33532047 8.64006998 4.35569183 1 P 0 N
A 8.57530846 4.33532047 8.58441004 4.31681998 8.64006998 4.35569173 1 P 0 N
L 8.58441004 4.31681998 8.61236998 4.2769 1 P 0 
A 8.61236998 4.2769 8.61844872 4.2645685 8.57533002 4.25097736 1 P 0 Y
A 8.61844872 4.2645685 8.62053996 4.25098002 8.57533002 4.25097746 1 P 0 Y
L 8.62053996 4.25098002 8.62053996 4.24733996 1 P 0 
A 8.62053996 4.24733996 8.60945 4.22058002 8.58271004 4.24733967 1 P 0 Y
L 8.60945 4.22058002 8.60141998 4.21255 1 P 0 
A 8.60141998 4.21255 8.5915938 4.20597844 8.57999754 4.23395 1 P 0 Y
A 8.5915938 4.20597844 8.58 4.20366998 8.57999764 4.23395 1 P 0 Y
L 8.58 4.20366998 8.57833002 4.20366998 1 P 0 
A 8.57833002 4.20366998 8.56686004 4.20728002 8.5783185 4.22366004 1 P 0 Y
L 8.56686004 4.20728002 8.53111998 4.23228996 1 P 0 
A 8.53111998 4.23228996 8.49838002 4.24261004 8.49836831 4.18548002 1 P 0 N
L 8.49838002 4.24261004 8.49831998 4.24261004 1 P 0 
A 8.49831998 4.24261004 8.48483474 4.23996654 8.49830866 4.20695 1 P 0 N
A 8.48483474 4.23996654 8.47335 4.23241998 8.49830787 4.20695 1 P 0 N
L 8.47335 4.23241998 8.47333996 4.23241998 1 P 0 
A 8.47333996 4.23241998 8.47285 4.23193002 8.49623996 4.20903002 1 P 0 N
L 8.47285 4.23193002 8.47286004 4.23193002 1 P 0 
A 8.47286004 4.23193002 8.46728917 4.22422343 8.49781004 4.20802756 1 P 0 N
A 8.46728917 4.22422343 8.46403002 4.21528996 8.49781004 4.20802736 1 P 0 N
L 8.46403002 4.21528996 8.45668002 4.17368996 1 P 0 
L 8.45668002 4.17368996 8.45668002 4.17366998 1 P 0 
A 8.45668002 4.17366998 8.40351004 4.07153996 8.26813996 4.20692047 1 P 0 Y
L 8.40351004 4.07153996 8.4035 4.07153002 1 P 0 
A 8.4035 4.07153002 8.33277707 4.02426772 8.24934537 4.22566004 1 P 0 Y
A 8.33277707 4.02426772 8.24935 4.00766998 8.24934567 4.22566004 1 P 0 Y
L 8.24935 4.00766998 8.24926004 4.00766998 1 P 0 
A 8.24926004 4.00766998 8.21566004 4.01071004 8.24926093 4.19488002 1 P 0 Y
L 8.21566004 4.01071004 8.13976004 4.02401004 1 P 0 
A 8.13976004 4.02401004 8.11750079 4.02155463 8.13284557 3.98456998 1 P 0 N
A 8.11750079 4.02155463 8.10003996 4.00753002 8.13284429 3.98456998 1 P 0 N
L 8.10003996 4.00753002 8.06128996 3.95218002 1 P 0 
A 8.06128996 3.95218002 8.05589508 3.9412378 8.09413996 3.92918278 1 P 0 N
A 8.05589508 3.9412378 8.05403996 3.92918002 8.09413996 3.92918209 1 P 0 N
L 8.05403996 3.92918002 8.05403996 3.91501004 1 P 0 
A 8.05403996 3.91501004 8.05607264 3.90474537 8.08085 3.91498553 1 P 0 N
A 8.05607264 3.90474537 8.06188002 3.89603996 8.08085 3.91498455 1 P 0 N
L 8.06188002 3.89603996 8.06936998 3.88855 1 P 0 
A 8.06936998 3.88855 8.07076073 3.88647766 8.06486998 3.88402717 1 P 0 Y
A 8.07076073 3.88647766 8.07125 3.88403002 8.06486998 3.88402736 1 P 0 Y
L 8.07125 3.88403002 8.07125 3.80448996 1 P 0 
A 8.07125 3.80448996 8.08833996 3.7874 8.08833996 3.80448996 1 P 0 N
L 8.08833996 3.7874 8.14653996 3.7874 1 P 0 
L 8.14653996 3.7874 8.14671998 3.78738002 1 P 0 
A 8.14671998 3.78738002 8.14906201 3.78616476 8.14629675 3.7837 1 P 0 Y
A 8.14906201 3.78616476 8.15 3.7837 8.1463 3.78370276 1 P 0 Y
L 8.15 3.7837 8.15 3.76615 1 P 0 
P 8.15 3.81615 5 P 0 0;2=3,4=1
P 9.06925 5.165 5 P 0 0;2=3,4=1
L 9.06925 5.165 9.05853996 5.165 1 P 0 
A 9.05853996 5.165 9.053 5.15946004 9.05853996 5.15946004 1 P 0 N
L 9.053 5.15946004 9.053 5.14255 1 P 0 
A 9.053 5.14255 9.04291998 5.12318996 9.02936998 5.14254902 1 P 0 Y
L 9.04291998 5.12318996 9.02828002 5.11295 1 P 0 
L 9.02828002 5.11295 8.97963996 5.10438002 1 P 0 
L 8.97963996 5.10438002 8.95053996 5.084 1 P 0 
L 8.95053996 5.084 8.9458 5.07723996 1 P 0 
L 8.9458 5.07723996 8.94691004 5.07096998 1 P 0 
L 8.94691004 5.07096998 8.94053002 5.06186998 1 P 0 
L 8.94053002 5.06186998 8.93428002 5.06078002 1 P 0 
L 8.93428002 5.06078002 8.92488002 5.04736004 1 P 0 
L 8.92488002 5.04736004 8.91618002 4.99793002 1 P 0 
L 8.91618002 4.99793002 8.92108002 4.99096004 1 P 0 
L 8.92108002 4.99096004 8.91913996 4.98001998 1 P 0 
L 8.91913996 4.98001998 8.91216004 4.97515 1 P 0 
L 8.91216004 4.97515 8.89843002 4.89735 1 P 0 
L 8.89843002 4.89735 8.90536004 4.85798002 1 P 0 
L 8.90536004 4.85798002 8.8989 4.82136004 1 P 0 
L 8.8989 4.82136004 8.90323996 4.79676998 1 P 0 
L 8.90323996 4.79676998 8.91873996 4.77461998 1 P 0 
L 8.91873996 4.77461998 8.94576004 4.75571998 1 P 0 
L 8.94576004 4.75571998 8.96968996 4.72155 1 P 0 
L 8.96968996 4.72155 8.97598002 4.68576004 1 P 0 
L 8.97598002 4.68576004 8.97186004 4.66235 1 P 0 
L 8.97186004 4.66235 8.97426004 4.64873002 1 P 0 
L 8.97426004 4.64873002 8.97281998 4.64046004 1 P 0 
L 8.97281998 4.64046004 8.9728 4.64046004 1 P 0 
L 8.9728 4.64046004 8.97128002 4.63181998 1 P 0 
L 8.97128002 4.63181998 8.96063996 4.61661998 1 P 0 
L 8.96063996 4.61661998 8.8416 4.53328002 1 P 0 
L 8.8416 4.53328002 8.70198996 4.50866004 1 P 0 
A 8.70198996 4.50866004 8.68158002 4.49803996 8.70862835 4.47098002 1 P 0 N
L 8.68158002 4.49803996 8.68153996 4.498 1 P 0 
A 8.68153996 4.498 8.67882707 4.49383602 8.69003996 4.48949636 1 P 0 N
A 8.67882707 4.49383602 8.67803002 4.48893002 8.69003996 4.48949656 1 P 0 N
A 8.67803002 4.48893002 8.68045 4.48308996 8.68628996 4.4889313 1 P 0 N
L 8.68045 4.48308996 8.69025 4.47328996 1 P 0 
A 8.69025 4.47328996 8.70053996 4.44846998 8.66546004 4.44846939 1 P 0 Y
L 8.70053996 4.44846998 8.70053996 4.44396998 1 P 0 
A 8.70053996 4.44396998 8.69787087 4.43052116 8.66531004 4.44397254 1 P 0 Y
A 8.69787087 4.43052116 8.69026998 4.41911004 8.66531004 4.44397274 1 P 0 Y
L 8.69026998 4.41911004 8.67963002 4.40846998 1 P 0 
A 8.67963002 4.40846998 8.66304439 4.39630709 8.63179439 4.45631004 1 P 0 Y
A 8.66304439 4.39630709 8.64356998 4.38968996 8.63179478 4.45631004 1 P 0 Y
L 8.64356998 4.38968996 8.60205 4.38235 1 P 0 
A 8.60205 4.38235 8.57968002 4.3557 8.60673996 4.35569951 1 P 0 N
A 8.57968002 4.3557 8.59056004 4.32111998 8.64006998 4.35569902 1 P 0 N
L 8.59056004 4.32111998 8.61851998 4.28121004 1 P 0 
A 8.61851998 4.28121004 8.62803996 4.25098996 8.57531998 4.25099154 1 P 0 Y
L 8.62803996 4.25098996 8.62803996 4.24733996 1 P 0 
A 8.62803996 4.24733996 8.62459114 4.22998386 8.58271004 4.24732677 1 P 0 Y
A 8.62459114 4.22998386 8.61476004 4.21526998 8.58271004 4.24732549 1 P 0 Y
L 8.61476004 4.21526998 8.60673002 4.20723996 1 P 0 
A 8.60673002 4.20723996 8.58001004 4.19616998 8.58001102 4.23395 1 P 0 Y
L 8.58001004 4.19616998 8.57833996 4.19616998 1 P 0 
A 8.57833996 4.19616998 8.57006811 4.19743553 8.57831457 4.22366998 1 P 0 Y
A 8.57006811 4.19743553 8.56256004 4.20113002 8.57831427 4.22366998 1 P 0 Y
L 8.56256004 4.20113002 8.52681998 4.22613996 1 P 0 
A 8.52681998 4.22613996 8.49836998 4.23511004 8.49836112 4.18548002 1 P 0 N
L 8.49836998 4.23511004 8.49831998 4.23511004 1 P 0 
A 8.49831998 4.23511004 8.47841004 4.22686004 8.49832018 4.20696004 1 P 0 N
L 8.47841004 4.22686004 8.47823002 4.22668002 1 P 0 
A 8.47823002 4.22668002 8.47393041 4.22072844 8.4978 4.20801319 1 P 0 N
A 8.47393041 4.22072844 8.47138996 4.21383996 8.4978 4.2080127 1 P 0 N
L 8.47138996 4.21383996 8.46418002 4.17303002 1 P 0 
L 8.46418002 4.17303002 8.46418002 4.17301004 1 P 0 
A 8.46418002 4.17301004 8.40881998 4.06623002 8.26813002 4.20691132 1 P 0 Y
L 8.40881998 4.06623002 8.40881004 4.06621998 1 P 0 
A 8.40881004 4.06621998 8.24936004 4.00016998 8.24935896 4.22566004 1 P 0 Y
L 8.24936004 4.00016998 8.24925 4.00016998 1 P 0 
A 8.24925 4.00016998 8.21433996 4.00331998 8.24922195 4.19488002 1 P 0 Y
L 8.21433996 4.00331998 8.13846998 4.01661998 1 P 0 
A 8.13846998 4.01661998 8.12037766 4.01462195 8.13285295 3.98456998 1 P 0 N
A 8.12037766 4.01462195 8.10618996 4.00321998 8.13285344 3.98456998 1 P 0 N
L 8.10618996 4.00321998 8.06743996 3.94786998 1 P 0 
A 8.06743996 3.94786998 8.06305699 3.93897805 8.09413996 3.92918297 1 P 0 N
A 8.06305699 3.93897805 8.06155 3.92918002 8.09413996 3.92918238 1 P 0 N
L 8.06155 3.92918002 8.06153996 3.92918996 1 P 0 
L 8.06153996 3.92918996 8.06153996 3.915 1 P 0 
A 8.06153996 3.915 8.0630061 3.90760807 8.08085 3.91498868 1 P 0 N
A 8.0630061 3.90760807 8.06718996 3.90133996 8.08085 3.91498819 1 P 0 N
L 8.06718996 3.90133996 8.07466998 3.89386004 1 P 0 
A 8.07466998 3.89386004 8.07875 3.88403996 8.06486998 3.88403071 1 P 0 Y
L 8.07875 3.88403996 8.07875 3.80448996 1 P 0 
A 8.07875 3.80448996 8.08833996 3.7949 8.08833996 3.80448996 1 P 0 N
L 8.08833996 3.7949 8.1463 3.7949 1 P 0 
L 8.1463 3.7949 8.14671998 3.79491998 1 P 0 
A 8.14671998 3.79491998 8.14906201 3.79613524 8.14629675 3.7986 1 P 0 N
A 8.14906201 3.79613524 8.15 3.7986 8.1463 3.79859724 1 P 0 N
L 8.15 3.7986 8.15 3.81615 1 P 0 
P 2.14606004 3.76615 5 P 0 0;2=3,4=1
P 3.02571004 5.165 5 P 0 0;2=3,4=1
L 3.02571004 5.165 3.03516998 5.165 1 P 0 
A 3.03516998 5.165 3.04 5.163 3.03517087 5.15816998 1 P 0 Y
A 3.04 5.163 3.04196004 5.15826998 3.03526998 5.1582688 1 P 0 Y
L 3.04196004 5.15826998 3.04196004 5.14255 1 P 0 
A 3.04196004 5.14255 3.03508002 5.12933996 3.02583996 5.14254902 1 P 0 Y
L 3.03508002 5.12933996 3.0218 5.12005 1 P 0 
L 3.0218 5.12005 2.97316004 5.11148002 1 P 0 
L 2.97316004 5.11148002 2.94161004 5.08938996 1 P 0 
L 2.94161004 5.08938996 2.91423996 5.0503 1 P 0 
L 2.91423996 5.0503 2.88726998 4.89735 1 P 0 
L 2.88726998 4.89735 2.8942 4.85798002 1 P 0 
L 2.8942 4.85798002 2.88773996 4.82136004 1 P 0 
L 2.88773996 4.82136004 2.8926 4.79383002 1 P 0 
L 2.8926 4.79383002 2.90981004 4.76923002 1 P 0 
L 2.90981004 4.76923002 2.93683002 4.75033002 1 P 0 
L 2.93683002 4.75033002 2.95905 4.71861004 1 P 0 
L 2.95905 4.71861004 2.96481998 4.68576004 1 P 0 
L 2.96481998 4.68576004 2.9607 4.66235 1 P 0 
L 2.9607 4.66235 2.9631 4.64873002 1 P 0 
L 2.9631 4.64873002 2.96063996 4.63476004 1 P 0 
L 2.96063996 4.63476004 2.95171004 4.62201004 1 P 0 
L 2.95171004 4.62201004 2.83511998 4.54038002 1 P 0 
L 2.83511998 4.54038002 2.69715 4.51605 1 P 0 
A 2.69715 4.51605 2.6839627 4.51157953 2.70507726 4.47098002 1 P 0 N
A 2.6839627 4.51157953 2.67273002 4.50335 2.70507657 4.47098002 1 P 0 N
L 2.67273002 4.50335 2.67268996 4.50331004 1 P 0 
A 2.67268996 4.50331004 2.6683189 4.49662569 2.6865 4.48950797 1 P 0 N
A 2.6683189 4.49662569 2.66698996 4.48875 2.6865 4.48950787 1 P 0 N
A 2.66698996 4.48875 2.6716 4.47778002 2.68275 4.48891939 1 P 0 N
L 2.6716 4.47778002 2.6814 4.46798002 1 P 0 
A 2.6814 4.46798002 2.6873938 4.45902687 2.66191998 4.448456 1 P 0 Y
A 2.6873938 4.45902687 2.6895 4.44846004 2.66191998 4.4484561 1 P 0 Y
L 2.6895 4.44846004 2.6895 4.44398002 1 P 0 
A 2.6895 4.44398002 2.68740197 4.43339311 2.66178002 4.44397205 1 P 0 Y
A 2.68740197 4.43339311 2.68141998 4.42441004 2.66178002 4.44397195 1 P 0 Y
L 2.68141998 4.42441004 2.67078002 4.41376998 1 P 0 
L 2.67078002 4.41376998 2.67078002 4.41378002 1 P 0 
A 2.67078002 4.41378002 2.65603435 4.40296467 2.62824675 4.45631004 1 P 0 Y
A 2.65603435 4.40296467 2.63871998 4.39708002 2.62824665 4.45631004 1 P 0 Y
L 2.63871998 4.39708002 2.5972 4.38973996 1 P 0 
A 2.5972 4.38973996 2.57672677 4.37791703 2.60320709 4.3557 1 P 0 N
A 2.57672677 4.37791703 2.56863996 4.3557 2.60321004 4.35569705 1 P 0 N
A 2.56863996 4.3557 2.57176841 4.33532047 2.63653002 4.35569183 1 P 0 N
A 2.57176841 4.33532047 2.58086998 4.31681998 2.63653002 4.35569173 1 P 0 N
L 2.58086998 4.31681998 2.60883002 4.2769 1 P 0 
A 2.60883002 4.2769 2.61490876 4.2645685 2.57178996 4.25097736 1 P 0 Y
A 2.61490876 4.2645685 2.617 4.25098002 2.57178996 4.25097746 1 P 0 Y
L 2.617 4.25098002 2.617 4.24733996 1 P 0 
A 2.617 4.24733996 2.60591004 4.22058002 2.57916998 4.24733967 1 P 0 Y
L 2.60591004 4.22058002 2.59788002 4.21255 1 P 0 
A 2.59788002 4.21255 2.58805384 4.20597844 2.57645758 4.23395 1 P 0 Y
A 2.58805384 4.20597844 2.57646004 4.20366998 2.57645768 4.23395 1 P 0 Y
L 2.57646004 4.20366998 2.57478996 4.20366998 1 P 0 
A 2.57478996 4.20366998 2.56331998 4.20728002 2.57477844 4.22366004 1 P 0 Y
L 2.56331998 4.20728002 2.52758002 4.23228996 1 P 0 
A 2.52758002 4.23228996 2.49483996 4.24261004 2.49482835 4.18548002 1 P 0 N
L 2.49483996 4.24261004 2.49478002 4.24261004 1 P 0 
A 2.49478002 4.24261004 2.48129469 4.23996654 2.4947686 4.20695 1 P 0 N
A 2.48129469 4.23996654 2.46981004 4.23241998 2.49476811 4.20695 1 P 0 N
L 2.46981004 4.23241998 2.4698 4.23241998 1 P 0 
A 2.4698 4.23241998 2.46931004 4.23193002 2.4927 4.20903002 1 P 0 N
L 2.46931004 4.23193002 2.46931998 4.23193002 1 P 0 
A 2.46931998 4.23193002 2.46374911 4.22422343 2.49426998 4.20802756 1 P 0 N
A 2.46374911 4.22422343 2.46048996 4.21528996 2.49426998 4.20802736 1 P 0 N
L 2.46048996 4.21528996 2.45313996 4.17368996 1 P 0 
L 2.45313996 4.17368996 2.45313996 4.17366998 1 P 0 
A 2.45313996 4.17366998 2.39996998 4.07153996 2.2646 4.20692047 1 P 0 Y
L 2.39996998 4.07153996 2.39996004 4.07153002 1 P 0 
A 2.39996004 4.07153002 2.32923711 4.02426772 2.24580541 4.22566004 1 P 0 Y
A 2.32923711 4.02426772 2.24581004 4.00766998 2.24580571 4.22566004 1 P 0 Y
L 2.24581004 4.00766998 2.24571998 4.00766998 1 P 0 
A 2.24571998 4.00766998 2.21211998 4.01071004 2.24572087 4.19488002 1 P 0 Y
L 2.21211998 4.01071004 2.13621998 4.02401004 1 P 0 
A 2.13621998 4.02401004 2.11396073 4.02155453 2.12930571 3.98456998 1 P 0 N
A 2.11396073 4.02155453 2.0965 4.00753002 2.12930413 3.98456998 1 P 0 N
L 2.0965 4.00753002 2.05775 3.95218002 1 P 0 
A 2.05775 3.95218002 2.05235512 3.9412378 2.0906 3.92918278 1 P 0 N
A 2.05235512 3.9412378 2.0505 3.92918002 2.0906 3.92918209 1 P 0 N
L 2.0505 3.92918002 2.0505 3.91501004 1 P 0 
A 2.0505 3.91501004 2.05253268 3.90474537 2.07731004 3.91498553 1 P 0 N
A 2.05253268 3.90474537 2.05833996 3.89603996 2.07731004 3.91498435 1 P 0 N
L 2.05833996 3.89603996 2.06583002 3.88855 1 P 0 
A 2.06583002 3.88855 2.06692264 3.88692224 2.06228002 3.88498652 1 P 0 Y
A 2.06692264 3.88692224 2.06731004 3.885 2.06228002 3.88498642 1 P 0 Y
L 2.06731004 3.885 2.06731004 3.80488996 1 P 0 
A 2.06731004 3.80488996 2.0848 3.7874 2.0848 3.80488996 1 P 0 N
L 2.0848 3.7874 2.14236004 3.7874 1 P 0 
A 2.14236004 3.7874 2.14606004 3.7837 2.14236004 3.7837 1 P 0 Y
L 2.14606004 3.7837 2.14606004 3.76615 1 P 0 
P 10.58661004 2.76615 5 P 0 0;2=3,4=1
P 4 5.29 6 P 0 0;2=2,4=1
L 10.58661004 2.76615 10.32885 2.76615 2 P 0 
L 10.32885 2.76615 10.24 2.855 2 P 0 
L 10.24 2.855 10.04 2.855 2 P 0 
L 10.04 2.855 9.895 2.71 2 P 0 
L 9.895 2.71 9.895 1.93905 2 P 0 
L 9.895 1.93905 9.73 1.77405 2 P 0 
L 9.73 1.77405 6.77983002 1.77405 2 P 0 
L 6.77983002 1.77405 6.00528002 0.9995 2 P 0 
L 6.00528002 0.9995 4.88395 0.9995 2 P 0 
L 4.88395 0.9995 3.9503 1.93315 2 P 0 
L 3.9503 1.93315 3.9503 4.36336004 2 P 0 
L 3.9503 4.36336004 3.9805 4.39356004 2 P 0 
L 3.9805 4.39356004 3.9805 4.5845 2 P 0 
L 3.9805 4.5845 3.96325 4.60175 2 P 0 
L 3.96325 4.60175 3.96325 4.82825 2 P 0 
L 3.96325 4.82825 4.00975 4.87475 2 P 0 
L 4.00975 4.87475 4.00975 5.28025 2 P 0 
L 4.00975 5.28025 4 5.29 2 P 0 
P 2.14606004 3.81615 5 P 0 0;2=3,4=1
P 3.06571004 5.165 5 P 0 0;2=3,4=1
L 3.06571004 5.165 3.055 5.165 1 P 0 
A 3.055 5.165 3.04946004 5.15946004 3.055 5.15946004 1 P 0 N
L 3.04946004 5.15946004 3.04946004 5.14255 1 P 0 
A 3.04946004 5.14255 3.03938002 5.12318996 3.02583002 5.14254902 1 P 0 Y
L 3.03938002 5.12318996 3.02473996 5.11295 1 P 0 
L 3.02473996 5.11295 2.9761 5.10438002 1 P 0 
L 2.9761 5.10438002 2.947 5.084 1 P 0 
L 2.947 5.084 2.94226004 5.07723996 1 P 0 
L 2.94226004 5.07723996 2.94336998 5.07096998 1 P 0 
L 2.94336998 5.07096998 2.93698996 5.06186998 1 P 0 
L 2.93698996 5.06186998 2.93073996 5.06078002 1 P 0 
L 2.93073996 5.06078002 2.92133996 5.04736004 1 P 0 
L 2.92133996 5.04736004 2.91263996 4.99793002 1 P 0 
L 2.91263996 4.99793002 2.91753996 4.99096004 1 P 0 
L 2.91753996 4.99096004 2.9156 4.98001998 1 P 0 
L 2.9156 4.98001998 2.90861998 4.97515 1 P 0 
L 2.90861998 4.97515 2.89488996 4.89735 1 P 0 
L 2.89488996 4.89735 2.90181998 4.85798002 1 P 0 
L 2.90181998 4.85798002 2.89536004 4.82136004 1 P 0 
L 2.89536004 4.82136004 2.8997 4.79676998 1 P 0 
L 2.8997 4.79676998 2.9152 4.77461998 1 P 0 
L 2.9152 4.77461998 2.94221998 4.75571998 1 P 0 
L 2.94221998 4.75571998 2.96615 4.72155 1 P 0 
L 2.96615 4.72155 2.97243996 4.68576004 1 P 0 
L 2.97243996 4.68576004 2.96831998 4.66235 1 P 0 
L 2.96831998 4.66235 2.97071998 4.64873002 1 P 0 
L 2.97071998 4.64873002 2.96928002 4.64046004 1 P 0 
L 2.96928002 4.64046004 2.96926004 4.64046004 1 P 0 
L 2.96926004 4.64046004 2.96773996 4.63181998 1 P 0 
L 2.96773996 4.63181998 2.9571 4.61661998 1 P 0 
L 2.9571 4.61661998 2.83806004 4.53328002 1 P 0 
L 2.83806004 4.53328002 2.69845 4.50866004 1 P 0 
A 2.69845 4.50866004 2.67803996 4.49803996 2.70508819 4.47098002 1 P 0 N
L 2.67803996 4.49803996 2.678 4.498 1 P 0 
A 2.678 4.498 2.67528701 4.49383602 2.6865 4.48949606 1 P 0 N
A 2.67528701 4.49383602 2.67448996 4.48893002 2.6865 4.48949656 1 P 0 N
A 2.67448996 4.48893002 2.67511929 4.48576929 2.68275 4.48893169 1 P 0 N
A 2.67511929 4.48576929 2.67691004 4.48308996 2.68275 4.4889312 1 P 0 N
L 2.67691004 4.48308996 2.68671004 4.47328996 1 P 0 
A 2.68671004 4.47328996 2.697 4.44846998 2.66191998 4.44846939 1 P 0 Y
L 2.697 4.44846998 2.697 4.44396998 1 P 0 
A 2.697 4.44396998 2.69433091 4.43052116 2.66176998 4.44397254 1 P 0 Y
A 2.69433091 4.43052116 2.68673002 4.41911004 2.66176998 4.44397274 1 P 0 Y
L 2.68673002 4.41911004 2.67608996 4.40846998 1 P 0 
A 2.67608996 4.40846998 2.65950433 4.39630709 2.62825433 4.45631004 1 P 0 Y
A 2.65950433 4.39630709 2.64003002 4.38968996 2.62825472 4.45631004 1 P 0 Y
L 2.64003002 4.38968996 2.59851004 4.38235 1 P 0 
A 2.59851004 4.38235 2.57613996 4.3557 2.6032 4.35569941 1 P 0 N
A 2.57613996 4.3557 2.58701998 4.32111998 2.63653002 4.35569911 1 P 0 N
L 2.58701998 4.32111998 2.61498002 4.28121004 1 P 0 
A 2.61498002 4.28121004 2.6245 4.25098996 2.57178002 4.25099154 1 P 0 Y
L 2.6245 4.25098996 2.6245 4.24733996 1 P 0 
A 2.6245 4.24733996 2.62105118 4.22998386 2.57916998 4.24732677 1 P 0 Y
A 2.62105118 4.22998386 2.61121998 4.21526998 2.57916998 4.24732579 1 P 0 Y
L 2.61121998 4.21526998 2.60318996 4.20723996 1 P 0 
A 2.60318996 4.20723996 2.57646998 4.19616998 2.57647096 4.23395 1 P 0 Y
L 2.57646998 4.19616998 2.5748 4.19616998 1 P 0 
A 2.5748 4.19616998 2.56652805 4.19743543 2.57477421 4.22366998 1 P 0 Y
A 2.56652805 4.19743543 2.55901998 4.20113002 2.57477451 4.22366998 1 P 0 Y
L 2.55901998 4.20113002 2.52328002 4.22613996 1 P 0 
A 2.52328002 4.22613996 2.49483002 4.23511004 2.49482116 4.18548002 1 P 0 N
L 2.49483002 4.23511004 2.49478002 4.23511004 1 P 0 
A 2.49478002 4.23511004 2.47486998 4.22686004 2.49478012 4.20696004 1 P 0 N
L 2.47486998 4.22686004 2.47468996 4.22668002 1 P 0 
A 2.47468996 4.22668002 2.47039045 4.22072835 2.49426004 4.20801368 1 P 0 N
A 2.47039045 4.22072835 2.46785 4.21383996 2.49426004 4.2080125 1 P 0 N
L 2.46785 4.21383996 2.46063996 4.17303002 1 P 0 
L 2.46063996 4.17303002 2.46063996 4.17301004 1 P 0 
A 2.46063996 4.17301004 2.40528002 4.06623002 2.26458996 4.20691122 1 P 0 Y
L 2.40528002 4.06623002 2.40526998 4.06621998 1 P 0 
A 2.40526998 4.06621998 2.24581998 4.00016998 2.2458189 4.22566004 1 P 0 Y
L 2.24581998 4.00016998 2.24571004 4.00016998 1 P 0 
A 2.24571004 4.00016998 2.2108 4.00331998 2.24568199 4.19488002 1 P 0 Y
L 2.2108 4.00331998 2.13493002 4.01661998 1 P 0 
A 2.13493002 4.01661998 2.1168377 4.01462195 2.12931299 3.98456998 1 P 0 N
A 2.1168377 4.01462195 2.10265 4.00321998 2.12931348 3.98456998 1 P 0 N
L 2.10265 4.00321998 2.0639 3.94786998 1 P 0 
A 2.0639 3.94786998 2.05951703 3.93897805 2.0906 3.92918297 1 P 0 N
A 2.05951703 3.93897805 2.05801004 3.92918002 2.0906 3.92918238 1 P 0 N
L 2.05801004 3.92918002 2.058 3.92918996 1 P 0 
L 2.058 3.92918996 2.058 3.915 1 P 0 
A 2.058 3.915 2.05946811 3.90761348 2.07731004 3.91499882 1 P 0 N
A 2.05946811 3.90761348 2.06365 3.90135 2.07731004 3.91499803 1 P 0 N
L 2.06365 3.90135 2.07113996 3.89386004 1 P 0 
A 2.07113996 3.89386004 2.07481004 3.885 2.06228002 3.8849998 1 P 0 Y
L 2.07481004 3.885 2.07481004 3.80488996 1 P 0 
A 2.07481004 3.80488996 2.0848 3.7949 2.0848 3.80488996 1 P 0 N
L 2.0848 3.7949 2.14236004 3.7949 1 P 0 
A 2.14236004 3.7949 2.14606004 3.7986 2.14236004 3.7986 1 P 0 N
L 2.14606004 3.7986 2.14606004 3.81615 1 P 0 
P 11.08661004 2.71615 5 P 0 0;2=3,4=1
P 3.985 4.88998996 6 P 0 0;2=2,4=1
L 11.08661004 2.71615 11.14385 2.71615 2 P 0 
L 11.14385 2.71615 11.165 2.695 2 P 0 
L 11.165 2.695 11.165 1.845 2 P 0 
L 11.165 1.845 11.0827 1.7627 2 P 0 
L 11.0827 1.7627 9.7777 1.7627 2 P 0 
L 9.7777 1.7627 9.75425 1.73925 2 P 0 
L 9.75425 1.73925 6.79425 1.73925 2 P 0 
L 6.79425 1.73925 6.0235 0.9685 2 P 0 
L 6.0235 0.9685 4.86573002 0.9685 2 P 0 
L 4.86573002 0.9685 3.9193 1.91493002 2 P 0 
L 3.9193 1.91493002 3.9193 4.3707 2 P 0 
L 3.9193 4.3707 3.91 4.38 2 P 0 
L 3.91 4.38 3.91 4.59 2 P 0 
L 3.91 4.59 3.865 4.635 2 P 0 
L 3.865 4.635 3.865 4.82 2 P 0 
L 3.865 4.82 3.93498996 4.88998996 2 P 0 
L 3.93498996 4.88998996 3.985 4.88998996 2 P 0 
L 1.88908002 -1.91246004 1.89293002 -1.91246004 0 P 0 ;0
L 1.89126998 -1.91146004 1.89656998 -1.91146004 0 P 0 ;0
L 1.89393996 -1.91046004 1.9155 -1.91046004 0 P 0 ;0
L 1.91593996 -1.91246004 1.92048996 -1.91246004 0 P 0 ;0
L 1.9126 -1.91146004 1.9184 -1.91146004 0 P 0 ;0
L 1.89763002 -1.90946004 1.91016998 -1.90946004 0 P 0 ;0
L 1.89053002 -1.96001004 1.8974 -1.96001004 0 P 0 ;0
L 1.89053002 -1.95901004 1.8974 -1.95901004 0 P 0 ;0
L 1.89053002 -1.95801004 1.8974 -1.95801004 0 P 0 ;0
L 1.89053002 -1.95701004 1.8974 -1.95701004 0 P 0 ;0
L 1.89053002 -1.95601004 1.8974 -1.95601004 0 P 0 ;0
L 1.89053002 -1.95501004 1.8974 -1.95501004 0 P 0 ;0
L 1.89053002 -1.95401004 1.8974 -1.95401004 0 P 0 ;0
L 1.89053002 -1.95301004 1.89741004 -1.95301004 0 P 0 ;0
L 1.89053002 -1.95201004 1.89741998 -1.95201004 0 P 0 ;0
L 1.89053002 -1.95101004 1.89743996 -1.95101004 0 P 0 ;0
L 1.89053002 -1.95001004 1.89745 -1.95001004 0 P 0 ;0
L 1.89053002 -1.94901004 1.89746004 -1.94901004 0 P 0 ;0
L 1.89053002 -1.94801004 1.89753002 -1.94801004 0 P 0 ;0
L 1.89053002 -1.94701004 1.8977 -1.94701004 0 P 0 ;0
L 1.89053002 -1.94601004 1.89798002 -1.94601004 0 P 0 ;0
L 1.89053002 -1.94501004 1.89861004 -1.94501004 0 P 0 ;0
L 1.89053002 -1.94401004 1.90005 -1.94401004 0 P 0 ;0
L 1.89053002 -1.94301004 1.9113 -1.94301004 0 P 0 ;0
L 1.89053002 -1.94201004 1.91168002 -1.94201004 0 P 0 ;0
L 1.89053002 -1.94101004 1.91246998 -1.94101004 0 P 0 ;0
L 1.89053002 -1.94001004 1.90093996 -1.94001004 0 P 0 ;0
L 1.89053002 -1.93901004 1.89856004 -1.93901004 0 P 0 ;0
L 1.89053002 -1.93801004 1.89786998 -1.93801004 0 P 0 ;0
L 1.89053002 -1.93701004 1.89753996 -1.93701004 0 P 0 ;0
L 1.89053002 -1.93601004 1.89746998 -1.93601004 0 P 0 ;0
L 1.89053002 -1.93501004 1.89743996 -1.93501004 0 P 0 ;0
L 1.89053002 -1.93401004 1.89741998 -1.93401004 0 P 0 ;0
L 1.89053002 -1.93301004 1.8974 -1.93301004 0 P 0 ;0
L 1.89053002 -1.93201004 1.8974 -1.93201004 0 P 0 ;0
L 1.89053002 -1.93101004 1.8974 -1.93101004 0 P 0 ;0
L 1.89053002 -1.93001004 1.8974 -1.93001004 0 P 0 ;0
L 1.89053002 -1.92901004 1.8974 -1.92901004 0 P 0 ;0
L 1.89053002 -1.92801004 1.89753002 -1.92801004 0 P 0 ;0
L 1.89053002 -1.92701004 1.89793996 -1.92701004 0 P 0 ;0
L 1.89053002 -1.92601004 1.91713002 -1.92601004 0 P 0 ;0
L 1.89053002 -1.92501004 1.91628996 -1.92501004 0 P 0 ;0
L 1.89053002 -1.92401004 1.91513996 -1.92401004 0 P 0 ;0
L 1.89053002 -1.92301004 1.91321998 -1.92301004 0 P 0 ;0
L 1.89053002 -1.92201004 1.90551004 -1.92201004 0 P 0 ;0
L 1.89438996 -1.97246004 1.91331004 -1.97246004 0 P 0 ;0
L 1.89106998 -1.97146004 1.89973002 -1.97146004 0 P 0 ;0
L 1.88878002 -1.97046004 1.8949 -1.97046004 0 P 0 ;0
L 1.88698002 -1.96946004 1.89206998 -1.96946004 0 P 0 ;0
L 1.88546004 -1.96846004 1.88986998 -1.96846004 0 P 0 ;0
L 1.88416998 -1.96746004 1.88808996 -1.96746004 0 P 0 ;0
L 1.88288002 -1.96646004 1.88655 -1.96646004 0 P 0 ;0
L 1.88176998 -1.96546004 1.88518002 -1.96546004 0 P 0 ;0
L 1.88068996 -1.96446004 1.88393996 -1.96446004 0 P 0 ;0
L 1.87968996 -1.96346004 1.88286004 -1.96346004 0 P 0 ;0
L 1.87878002 -1.96246004 1.88186004 -1.96246004 0 P 0 ;0
L 1.8786 -1.92046004 1.88126998 -1.92046004 0 P 0 ;0
L 1.87946998 -1.91946004 1.88223002 -1.91946004 0 P 0 ;0
L 1.88048002 -1.91846004 1.88321004 -1.91846004 0 P 0 ;0
L 1.88153996 -1.91746004 1.88436998 -1.91746004 0 P 0 ;0
L 1.88273002 -1.91646004 1.88558996 -1.91646004 0 P 0 ;0
L 1.88406004 -1.91546004 1.88696998 -1.91546004 0 P 0 ;0
L 1.88548996 -1.91446004 1.88853002 -1.91446004 0 P 0 ;0
L 1.88718002 -1.91346004 1.89041998 -1.91346004 0 P 0 ;0
L 1.90896004 -1.92963996 1.90921998 -1.92991998 0 P 0 ;0
L 1.90921998 -1.92991998 1.90945 -1.93021998 0 P 0 ;0
L 1.90945 -1.93021998 1.90966004 -1.93053002 0 P 0 ;0
L 1.90966004 -1.93053002 1.90983002 -1.93086004 0 P 0 ;0
L 1.90983002 -1.93086004 1.90998002 -1.93121004 0 P 0 ;0
L 1.90998002 -1.93121004 1.9101 -1.93156998 0 P 0 ;0
L 1.9101 -1.93156998 1.91018996 -1.93193996 0 P 0 ;0
L 1.91018996 -1.93193996 1.91023996 -1.93231004 0 P 0 ;0
L 1.91023996 -1.93231004 1.91026998 -1.93265 0 P 0 ;0
L 1.91026998 -1.93265 1.91026004 -1.93298002 0 P 0 ;0
L 1.91026004 -1.93298002 1.91023002 -1.93331004 0 P 0 ;0
L 1.91023002 -1.93331004 1.91016998 -1.93363996 0 P 0 ;0
L 1.91016998 -1.93363996 1.91008996 -1.93396004 0 P 0 ;0
L 1.91008996 -1.93396004 1.90998002 -1.93428002 0 P 0 ;0
L 1.90998002 -1.93428002 1.90983996 -1.93458002 0 P 0 ;0
L 1.90983996 -1.93458002 1.90968996 -1.93486998 0 P 0 ;0
L 1.90968996 -1.93486998 1.90951004 -1.93516004 0 P 0 ;0
L 1.90951004 -1.93516004 1.90921004 -1.93556004 0 P 0 ;0
L 1.90921004 -1.93556004 1.90888002 -1.93593002 0 P 0 ;0
L 1.90888002 -1.93593002 1.90853002 -1.93626998 0 P 0 ;0
L 1.90853002 -1.93626998 1.90815 -1.93658996 0 P 0 ;0
L 1.90815 -1.93658996 1.90773996 -1.93686998 0 P 0 ;0
L 1.90773996 -1.93686998 1.90731998 -1.93711998 0 P 0 ;0
L 1.90731998 -1.93711998 1.90686998 -1.93733996 0 P 0 ;0
L 1.90686998 -1.93733996 1.90615 -1.93761004 0 P 0 ;0
L 1.90615 -1.93761004 1.90541998 -1.93783002 0 P 0 ;0
L 1.90541998 -1.93783002 1.90466004 -1.93798002 0 P 0 ;0
L 1.90466004 -1.93798002 1.9039 -1.93808002 0 P 0 ;0
L 1.9039 -1.93808002 1.90311998 -1.9381 0 P 0 ;0
L 1.90311998 -1.9381 1.90196004 -1.93808002 0 P 0 ;0
L 1.90196004 -1.93808002 1.90078996 -1.93798996 0 P 0 ;0
L 1.90078996 -1.93798996 1.90068002 -1.93798002 0 P 0 ;0
L 1.90068002 -1.93798002 1.90058002 -1.93795 0 P 0 ;0
L 1.90058002 -1.93795 1.90046998 -1.93791998 0 P 0 ;0
L 1.90046998 -1.93791998 1.90038002 -1.93788002 0 P 0 ;0
L 1.90038002 -1.93788002 1.90028002 -1.93783002 0 P 0 ;0
L 1.90028002 -1.93783002 1.90018996 -1.93778002 0 P 0 ;0
L 1.90018996 -1.93778002 1.9001 -1.93771004 0 P 0 ;0
L 1.9001 -1.93771004 1.90001998 -1.93763996 0 P 0 ;0
L 1.90001998 -1.93763996 1.89988002 -1.93748002 0 P 0 ;0
L 1.89988002 -1.93748002 1.89978002 -1.93733996 0 P 0 ;0
L 1.89978002 -1.93733996 1.89961998 -1.93703996 0 P 0 ;0
L 1.89961998 -1.93703996 1.89956998 -1.93688002 0 P 0 ;0
L 1.89956998 -1.93688002 1.89951998 -1.93671004 0 P 0 ;0
L 1.89951998 -1.93671004 1.89948996 -1.93655 0 P 0 ;0
L 1.89948996 -1.93655 1.89946998 -1.93636998 0 P 0 ;0
L 1.89946998 -1.93636998 1.8994 -1.93323002 0 P 0 ;0
L 1.8994 -1.93323002 1.8994 -1.92833002 0 P 0 ;0
L 1.8994 -1.92833002 1.90353996 -1.92833002 0 P 0 ;0
L 1.90353996 -1.92833002 1.90436998 -1.92835 0 P 0 ;0
L 1.90436998 -1.92835 1.9052 -1.92843002 0 P 0 ;0
L 1.9052 -1.92843002 1.90603002 -1.92853996 0 P 0 ;0
L 1.90603002 -1.92853996 1.90683996 -1.92871004 0 P 0 ;0
L 1.90683996 -1.92871004 1.90751004 -1.9289 0 P 0 ;0
L 1.90751004 -1.9289 1.90818002 -1.92913002 0 P 0 ;0
L 1.90818002 -1.92913002 1.90851998 -1.92928996 0 P 0 ;0
L 1.90851998 -1.92928996 1.90868002 -1.92938996 0 P 0 ;0
L 1.90868002 -1.92938996 1.90883002 -1.92951004 0 P 0 ;0
L 1.90883002 -1.92951004 1.90896004 -1.92963996 0 P 0 ;0
L 1.91188996 -1.96001004 1.91638996 -1.96001004 0 P 0 ;0
L 1.91156998 -1.95901004 1.91926998 -1.95901004 0 P 0 ;0
L 1.91125 -1.95801004 1.91891998 -1.95801004 0 P 0 ;0
L 1.91091998 -1.95701004 1.91853002 -1.95701004 0 P 0 ;0
L 1.9106 -1.95601004 1.91811004 -1.95601004 0 P 0 ;0
L 1.91025 -1.95501004 1.91765 -1.95501004 0 P 0 ;0
L 1.90988996 -1.95401004 1.91718996 -1.95401004 0 P 0 ;0
L 1.90953002 -1.95301004 1.91673002 -1.95301004 0 P 0 ;0
L 1.90918002 -1.95201004 1.91626998 -1.95201004 0 P 0 ;0
L 1.90881998 -1.95101004 1.91576004 -1.95101004 0 P 0 ;0
L 1.90841004 -1.95001004 1.91523996 -1.95001004 0 P 0 ;0
L 1.90793996 -1.94901004 1.91471004 -1.94901004 0 P 0 ;0
L 1.90738996 -1.94801004 1.91418002 -1.94801004 0 P 0 ;0
L 1.90676998 -1.94701004 1.9136 -1.94701004 0 P 0 ;0
L 1.90598996 -1.94601004 1.91261004 -1.94601004 0 P 0 ;0
L 1.90495 -1.94501004 1.91175 -1.94501004 0 P 0 ;0
L 1.90325 -1.94401004 1.91133002 -1.94401004 0 P 0 ;0
L 1.90456004 -1.94001004 1.91383002 -1.94001004 0 P 0 ;0
L 1.90801004 -1.93901004 1.91523002 -1.93901004 0 P 0 ;0
L 1.90956998 -1.93801004 1.91635 -1.93801004 0 P 0 ;0
L 1.9106 -1.93701004 1.91718002 -1.93701004 0 P 0 ;0
L 1.91133996 -1.93601004 1.91781004 -1.93601004 0 P 0 ;0
L 1.91183996 -1.93501004 1.91826004 -1.93501004 0 P 0 ;0
L 1.91213002 -1.93401004 1.9186 -1.93401004 0 P 0 ;0
L 1.91226004 -1.93301004 1.9188 -1.93301004 0 P 0 ;0
L 1.91221998 -1.93201004 1.9189 -1.93201004 0 P 0 ;0
L 1.91201998 -1.93101004 1.9189 -1.93101004 0 P 0 ;0
L 1.91163996 -1.93001004 1.91878996 -1.93001004 0 P 0 ;0
L 1.91105 -1.92901004 1.91856998 -1.92901004 0 P 0 ;0
L 1.91013996 -1.92801004 1.91823002 -1.92801004 0 P 0 ;0
L 1.90816998 -1.92701004 1.91776004 -1.92701004 0 P 0 ;0
L 1.90313996 -1.94011004 1.90316998 -1.9401 0 P 0 ;0
L 1.90316998 -1.9401 1.9032 -1.9401 0 P 0 ;0
L 1.9032 -1.9401 1.90398002 -1.94006998 0 P 0 ;0
L 1.90398002 -1.94006998 1.90406004 -1.94006998 0 P 0 ;0
L 1.90406004 -1.94006998 1.90413996 -1.94006004 0 P 0 ;0
L 1.90413996 -1.94006004 1.9049 -1.93996998 0 P 0 ;0
L 1.9049 -1.93996998 1.90493996 -1.93996004 0 P 0 ;0
L 1.90493996 -1.93996004 1.90498996 -1.93996004 0 P 0 ;0
L 1.90498996 -1.93996004 1.90506998 -1.93993996 0 P 0 ;0
L 1.90506998 -1.93993996 1.90581998 -1.93978002 0 P 0 ;0
L 1.90581998 -1.93978002 1.90586004 -1.93978002 0 P 0 ;0
L 1.90586004 -1.93978002 1.90593996 -1.93976004 0 P 0 ;0
L 1.90593996 -1.93976004 1.90596998 -1.93973996 0 P 0 ;0
L 1.90596998 -1.93973996 1.90671004 -1.93953002 0 P 0 ;0
L 1.90671004 -1.93953002 1.90678996 -1.93951004 0 P 0 ;0
L 1.90678996 -1.93951004 1.90758996 -1.93921004 0 P 0 ;0
L 1.90758996 -1.93921004 1.90766004 -1.93916998 0 P 0 ;0
L 1.90766004 -1.93916998 1.9077 -1.93915 0 P 0 ;0
L 1.9077 -1.93915 1.90773996 -1.93913996 0 P 0 ;0
L 1.90773996 -1.93913996 1.90818996 -1.93891998 0 P 0 ;0
L 1.90818996 -1.93891998 1.90821998 -1.9389 0 P 0 ;0
L 1.90821998 -1.9389 1.90826004 -1.93888996 0 P 0 ;0
L 1.90826004 -1.93888996 1.90828996 -1.93886998 0 P 0 ;0
L 1.90828996 -1.93886998 1.90833002 -1.93885 0 P 0 ;0
L 1.90833002 -1.93885 1.90875 -1.9386 0 P 0 ;0
L 1.90875 -1.9386 1.90883002 -1.93856004 0 P 0 ;0
L 1.90883002 -1.93856004 1.90888996 -1.93851004 0 P 0 ;0
L 1.90888996 -1.93851004 1.90928996 -1.93823002 0 P 0 ;0
L 1.90928996 -1.93823002 1.90933002 -1.9382 0 P 0 ;0
L 1.90933002 -1.9382 1.90936004 -1.93818002 0 P 0 ;0
L 1.90936004 -1.93818002 1.90938996 -1.93815 0 P 0 ;0
L 1.90938996 -1.93815 1.90941998 -1.93813002 0 P 0 ;0
L 1.90941998 -1.93813002 1.9098 -1.93781998 0 P 0 ;0
L 1.9098 -1.93781998 1.90986004 -1.93776004 0 P 0 ;0
L 1.90986004 -1.93776004 1.90988996 -1.93773996 0 P 0 ;0
L 1.90988996 -1.93773996 1.90991998 -1.93771004 0 P 0 ;0
L 1.90991998 -1.93771004 1.91028002 -1.93736004 0 P 0 ;0
L 1.91028002 -1.93736004 1.91038996 -1.93725 0 P 0 ;0
L 1.91038996 -1.93725 1.91071004 -1.93688002 0 P 0 ;0
L 1.91071004 -1.93688002 1.91073996 -1.93685 0 P 0 ;0
L 1.91073996 -1.93685 1.91116004 -1.9363 0 P 0 ;0
L 1.91116004 -1.9363 1.9112 -1.93623002 0 P 0 ;0
L 1.9112 -1.93623002 1.91138002 -1.93595 0 P 0 ;0
L 1.91138002 -1.93595 1.9114 -1.93591004 0 P 0 ;0
L 1.9114 -1.93591004 1.91143996 -1.93585 0 P 0 ;0
L 1.91143996 -1.93585 1.91146004 -1.93581004 0 P 0 ;0
L 1.91146004 -1.93581004 1.91161004 -1.93551998 0 P 0 ;0
L 1.91161004 -1.93551998 1.91163002 -1.93548996 0 P 0 ;0
L 1.91163002 -1.93548996 1.91165 -1.93545 0 P 0 ;0
L 1.91165 -1.93545 1.91166004 -1.93541004 0 P 0 ;0
L 1.91166004 -1.93541004 1.91168002 -1.93538002 0 P 0 ;0
L 1.91168002 -1.93538002 1.91181004 -1.93506998 0 P 0 ;0
L 1.91181004 -1.93506998 1.91183996 -1.935 0 P 0 ;0
L 1.91183996 -1.935 1.91186004 -1.93496004 0 P 0 ;0
L 1.91186004 -1.93496004 1.91186998 -1.93493002 0 P 0 ;0
L 1.91186998 -1.93493002 1.91198002 -1.93461004 0 P 0 ;0
L 1.91198002 -1.93461004 1.91198996 -1.93456998 0 P 0 ;0
L 1.91198996 -1.93456998 1.912 -1.93453996 0 P 0 ;0
L 1.912 -1.93453996 1.9121 -1.93413996 0 P 0 ;0
L 1.9121 -1.93413996 1.91211998 -1.9341 0 P 0 ;0
L 1.91211998 -1.9341 1.91211998 -1.93406004 0 P 0 ;0
L 1.91211998 -1.93406004 1.91213002 -1.93401998 0 P 0 ;0
L 1.91213002 -1.93401998 1.91213996 -1.93398996 0 P 0 ;0
L 1.91213996 -1.93398996 1.9122 -1.93366004 0 P 0 ;0
L 1.9122 -1.93366004 1.91221004 -1.93358002 0 P 0 ;0
L 1.91221004 -1.93358002 1.91221004 -1.93353996 0 P 0 ;0
L 1.91221004 -1.93353996 1.91221998 -1.9335 0 P 0 ;0
L 1.91221998 -1.9335 1.91225 -1.93316998 0 P 0 ;0
L 1.91225 -1.93316998 1.91226004 -1.93308996 0 P 0 ;0
L 1.91226004 -1.93308996 1.91226004 -1.93268002 0 P 0 ;0
L 1.91226004 -1.93268002 1.91226998 -1.93263996 0 P 0 ;0
L 1.91226998 -1.93263996 1.91226998 -1.9326 0 P 0 ;0
L 1.91226998 -1.9326 1.91226004 -1.93251998 0 P 0 ;0
L 1.91226004 -1.93251998 1.91223996 -1.93218996 0 P 0 ;0
L 1.91223996 -1.93218996 1.91223996 -1.93215 0 P 0 ;0
L 1.91223996 -1.93215 1.91223002 -1.9321 0 P 0 ;0
L 1.91223002 -1.9321 1.91223002 -1.93206004 0 P 0 ;0
L 1.91223002 -1.93206004 1.91221998 -1.93201998 0 P 0 ;0
L 1.91221998 -1.93201998 1.91216998 -1.93163996 0 P 0 ;0
L 1.91216998 -1.93163996 1.91216004 -1.9316 0 P 0 ;0
L 1.91216004 -1.9316 1.91213996 -1.93151004 0 P 0 ;0
L 1.91213996 -1.93151004 1.91213002 -1.93146998 0 P 0 ;0
L 1.91213002 -1.93146998 1.91205 -1.93111004 0 P 0 ;0
L 1.91205 -1.93111004 1.91203996 -1.93106004 0 P 0 ;0
L 1.91203996 -1.93106004 1.91203002 -1.93101998 0 P 0 ;0
L 1.91203002 -1.93101998 1.91201004 -1.93098002 0 P 0 ;0
L 1.91201004 -1.93098002 1.912 -1.93093996 0 P 0 ;0
L 1.912 -1.93093996 1.91188002 -1.93058002 0 P 0 ;0
L 1.91188002 -1.93058002 1.91186998 -1.93053996 0 P 0 ;0
L 1.91186998 -1.93053996 1.91185 -1.9305 0 P 0 ;0
L 1.91185 -1.9305 1.91183996 -1.93046004 0 P 0 ;0
L 1.91183996 -1.93046004 1.91181998 -1.93043002 0 P 0 ;0
L 1.91181998 -1.93043002 1.91166998 -1.93008002 0 P 0 ;0
L 1.91166998 -1.93008002 1.91166004 -1.93003996 0 P 0 ;0
L 1.91166004 -1.93003996 1.9116 -1.92991998 0 P 0 ;0
L 1.9116 -1.92991998 1.91141998 -1.92958996 0 P 0 ;0
L 1.91141998 -1.92958996 1.9114 -1.92955 0 P 0 ;0
L 1.9114 -1.92955 1.91138002 -1.92951998 0 P 0 ;0
L 1.91138002 -1.92951998 1.91133002 -1.92945 0 P 0 ;0
L 1.91133002 -1.92945 1.91113002 -1.92913002 0 P 0 ;0
L 1.91113002 -1.92913002 1.91111004 -1.92908996 0 P 0 ;0
L 1.91111004 -1.92908996 1.91108996 -1.92906004 0 P 0 ;0
L 1.91108996 -1.92906004 1.91106004 -1.92901998 0 P 0 ;0
L 1.91106004 -1.92901998 1.91103002 -1.92898996 0 P 0 ;0
L 1.91103002 -1.92898996 1.9108 -1.92868996 0 P 0 ;0
L 1.9108 -1.92868996 1.91076998 -1.92866004 0 P 0 ;0
L 1.91076998 -1.92866004 1.91075 -1.92861998 0 P 0 ;0
L 1.91075 -1.92861998 1.91068996 -1.92856004 0 P 0 ;0
L 1.91068996 -1.92856004 1.91043002 -1.92828002 0 P 0 ;0
L 1.91043002 -1.92828002 1.91035 -1.9282 0 P 0 ;0
L 1.91035 -1.9282 1.91033002 -1.92816998 0 P 0 ;0
L 1.91033002 -1.92816998 1.91018996 -1.92803996 0 P 0 ;0
L 1.91018996 -1.92803996 1.91018002 -1.92803996 0 P 0 ;0
L 1.91018002 -1.92803996 1.91016004 -1.92801998 0 P 0 ;0
L 1.91016004 -1.92801998 1.91011998 -1.92798996 0 P 0 ;0
L 1.91011998 -1.92798996 1.91006004 -1.92793002 0 P 0 ;0
L 1.91006004 -1.92793002 1.90991004 -1.92781998 0 P 0 ;0
L 1.90991004 -1.92781998 1.90988002 -1.9278 0 P 0 ;0
L 1.90988002 -1.9278 1.90983996 -1.92776998 0 P 0 ;0
L 1.90983996 -1.92776998 1.90976998 -1.92771998 0 P 0 ;0
L 1.90976998 -1.92771998 1.90961004 -1.92761998 0 P 0 ;0
L 1.90961004 -1.92761998 1.90953996 -1.92756998 0 P 0 ;0
L 1.90953996 -1.92756998 1.9095 -1.92755 0 P 0 ;0
L 1.9095 -1.92755 1.90946998 -1.92753002 0 P 0 ;0
L 1.90946998 -1.92753002 1.9093 -1.92743996 0 P 0 ;0
L 1.9093 -1.92743996 1.90926004 -1.92741998 0 P 0 ;0
L 1.90926004 -1.92741998 1.90923002 -1.9274 0 P 0 ;0
L 1.90923002 -1.9274 1.90915 -1.92736998 0 P 0 ;0
L 1.90915 -1.92736998 1.90896998 -1.92728996 0 P 0 ;0
L 1.90896998 -1.92728996 1.90893996 -1.92728002 0 P 0 ;0
L 1.90893996 -1.92728002 1.9089 -1.92726004 0 P 0 ;0
L 1.9089 -1.92726004 1.90886998 -1.92725 0 P 0 ;0
L 1.90886998 -1.92725 1.90883002 -1.92723996 0 P 0 ;0
L 1.90883002 -1.92723996 1.90816004 -1.92701004 0 P 0 ;0
L 1.90816004 -1.92701004 1.90813996 -1.927 0 P 0 ;0
L 1.90813996 -1.927 1.9081 -1.92698996 0 P 0 ;0
L 1.9081 -1.92698996 1.90803996 -1.92696998 0 P 0 ;0
L 1.90803996 -1.92696998 1.90736998 -1.92678002 0 P 0 ;0
L 1.90736998 -1.92678002 1.90723996 -1.92675 0 P 0 ;0
L 1.90723996 -1.92675 1.90643002 -1.92658996 0 P 0 ;0
L 1.90643002 -1.92658996 1.90636998 -1.92656998 0 P 0 ;0
L 1.90636998 -1.92656998 1.90633996 -1.92656998 0 P 0 ;0
L 1.90633996 -1.92656998 1.90631004 -1.92656004 0 P 0 ;0
L 1.90631004 -1.92656004 1.90548996 -1.92645 0 P 0 ;0
L 1.90548996 -1.92645 1.90543996 -1.92643996 0 P 0 ;0
L 1.90543996 -1.92643996 1.9054 -1.92643002 0 P 0 ;0
L 1.9054 -1.92643002 1.90538002 -1.92643002 0 P 0 ;0
L 1.90538002 -1.92643002 1.90455 -1.92636004 0 P 0 ;0
L 1.90455 -1.92636004 1.90443002 -1.92636004 0 P 0 ;0
L 1.90443002 -1.92636004 1.9036 -1.92633002 0 P 0 ;0
L 1.9036 -1.92633002 1.8994 -1.92633002 0 P 0 ;0
L 1.8994 -1.92633002 1.89798002 -1.92691004 0 P 0 ;0
L 1.89798002 -1.92691004 1.8974 -1.92833002 0 P 0 ;0
L 1.8974 -1.92833002 1.8974 -1.93328002 0 P 0 ;0
L 1.8974 -1.93328002 1.89748002 -1.93643002 0 P 0 ;0
L 1.89748002 -1.93643002 1.89748002 -1.93656004 0 P 0 ;0
L 1.89748002 -1.93656004 1.8975 -1.93673002 0 P 0 ;0
L 1.8975 -1.93673002 1.89751004 -1.93681004 0 P 0 ;0
L 1.89751004 -1.93681004 1.89751998 -1.9369 0 P 0 ;0
L 1.89751998 -1.9369 1.89755 -1.93706004 0 P 0 ;0
L 1.89755 -1.93706004 1.89758002 -1.93718996 0 P 0 ;0
L 1.89758002 -1.93718996 1.89758996 -1.93723002 0 P 0 ;0
L 1.89758996 -1.93723002 1.89763002 -1.9374 0 P 0 ;0
L 1.89763002 -1.9374 1.89763996 -1.93743996 0 P 0 ;0
L 1.89763996 -1.93743996 1.89766004 -1.93748002 0 P 0 ;0
L 1.89766004 -1.93748002 1.89768002 -1.93756004 0 P 0 ;0
L 1.89768002 -1.93756004 1.89773996 -1.93771998 0 P 0 ;0
L 1.89773996 -1.93771998 1.89776004 -1.93776004 0 P 0 ;0
L 1.89776004 -1.93776004 1.89776998 -1.9378 0 P 0 ;0
L 1.89776998 -1.9378 1.89781004 -1.93788002 0 P 0 ;0
L 1.89781004 -1.93788002 1.89788002 -1.93803996 0 P 0 ;0
L 1.89788002 -1.93803996 1.8979 -1.93808002 0 P 0 ;0
L 1.8979 -1.93808002 1.89791998 -1.93811004 0 P 0 ;0
L 1.89791998 -1.93811004 1.89796004 -1.93818996 0 P 0 ;0
L 1.89796004 -1.93818996 1.89803996 -1.93833996 0 P 0 ;0
L 1.89803996 -1.93833996 1.89813996 -1.93848002 0 P 0 ;0
L 1.89813996 -1.93848002 1.89823002 -1.93861998 0 P 0 ;0
L 1.89823002 -1.93861998 1.89828002 -1.93868996 0 P 0 ;0
L 1.89828002 -1.93868996 1.89831004 -1.93873002 0 P 0 ;0
L 1.89831004 -1.93873002 1.89833996 -1.93876004 0 P 0 ;0
L 1.89833996 -1.93876004 1.8984 -1.93883996 0 P 0 ;0
L 1.8984 -1.93883996 1.89848996 -1.93893002 0 P 0 ;0
L 1.89848996 -1.93893002 1.89851004 -1.93896004 0 P 0 ;0
L 1.89851004 -1.93896004 1.89868002 -1.93913002 0 P 0 ;0
L 1.89868002 -1.93913002 1.89871004 -1.93915 0 P 0 ;0
L 1.89871004 -1.93915 1.89878996 -1.93921998 0 P 0 ;0
L 1.89878996 -1.93921998 1.89885 -1.93928002 0 P 0 ;0
L 1.89885 -1.93928002 1.89888002 -1.9393 0 P 0 ;0
L 1.89888002 -1.9393 1.89891998 -1.93931998 0 P 0 ;0
L 1.89891998 -1.93931998 1.89901004 -1.93938996 0 P 0 ;0
L 1.89901004 -1.93938996 1.89903996 -1.93941004 0 P 0 ;0
L 1.89903996 -1.93941004 1.89906998 -1.93943996 0 P 0 ;0
L 1.89906998 -1.93943996 1.8991 -1.93946004 0 P 0 ;0
L 1.8991 -1.93946004 1.89913996 -1.93948002 0 P 0 ;0
L 1.89913996 -1.93948002 1.89923002 -1.93953996 0 P 0 ;0
L 1.89923002 -1.93953996 1.89926998 -1.93956004 0 P 0 ;0
L 1.89926998 -1.93956004 1.8993 -1.93958002 0 P 0 ;0
L 1.8993 -1.93958002 1.89933996 -1.9396 0 P 0 ;0
L 1.89933996 -1.9396 1.89936998 -1.93961004 0 P 0 ;0
L 1.89936998 -1.93961004 1.89938002 -1.93961004 0 P 0 ;0
L 1.89938002 -1.93961004 1.89946998 -1.93966004 0 P 0 ;0
L 1.89946998 -1.93966004 1.89953996 -1.9397 0 P 0 ;0
L 1.89953996 -1.9397 1.89971998 -1.93976998 0 P 0 ;0
L 1.89971998 -1.93976998 1.89975 -1.93978996 0 P 0 ;0
L 1.89975 -1.93978996 1.89978996 -1.9398 0 P 0 ;0
L 1.89978996 -1.9398 1.89986998 -1.93983002 0 P 0 ;0
L 1.89986998 -1.93983002 1.89996998 -1.93986004 0 P 0 ;0
L 1.89996998 -1.93986004 1.90001004 -1.93986998 0 P 0 ;0
L 1.90001004 -1.93986998 1.90005 -1.93988996 0 P 0 ;0
L 1.90005 -1.93988996 1.90013002 -1.9399 0 P 0 ;0
L 1.90013002 -1.9399 1.90023002 -1.93993002 0 P 0 ;0
L 1.90023002 -1.93993002 1.90023996 -1.93993002 0 P 0 ;0
L 1.90023996 -1.93993002 1.90028002 -1.93993996 0 P 0 ;0
L 1.90028002 -1.93993996 1.90031004 -1.93995 0 P 0 ;0
L 1.90031004 -1.93995 1.90036004 -1.93995 0 P 0 ;0
L 1.90036004 -1.93995 1.9004 -1.93996004 0 P 0 ;0
L 1.9004 -1.93996004 1.9005 -1.93996998 0 P 0 ;0
L 1.9005 -1.93996998 1.90061004 -1.93998996 0 P 0 ;0
L 1.90061004 -1.93998996 1.90063996 -1.93998996 0 P 0 ;0
L 1.90063996 -1.93998996 1.90181004 -1.94006998 0 P 0 ;0
L 1.90181004 -1.94006998 1.90183996 -1.94008002 0 P 0 ;0
L 1.90183996 -1.94008002 1.90191004 -1.94008002 0 P 0 ;0
L 1.90191004 -1.94008002 1.90308002 -1.9401 0 P 0 ;0
L 1.90308002 -1.9401 1.90311004 -1.9401 0 P 0 ;0
L 1.90311004 -1.9401 1.90313996 -1.94011004 0 P 0 ;0
L 1.90841004 -1.97146004 1.91683996 -1.97146004 0 P 0 ;0
L 1.9135 -1.97046004 1.91931004 -1.97046004 0 P 0 ;0
L 1.91655 -1.96946004 1.92131004 -1.96946004 0 P 0 ;0
L 1.91891998 -1.96846004 1.92301004 -1.96846004 0 P 0 ;0
L 1.92088996 -1.96746004 1.9245 -1.96746004 0 P 0 ;0
L 1.92251004 -1.96646004 1.9258 -1.96646004 0 P 0 ;0
L 1.92391004 -1.96546004 1.92696004 -1.96546004 0 P 0 ;0
L 1.92513002 -1.96446004 1.92803002 -1.96446004 0 P 0 ;0
L 1.9262 -1.96346004 1.92898996 -1.96346004 0 P 0 ;0
L 1.92713996 -1.96246004 1.92986004 -1.96246004 0 P 0 ;0
L 1.928 -1.96146004 1.93068996 -1.96146004 0 P 0 ;0
L 1.92878002 -1.96046004 1.93143002 -1.96046004 0 P 0 ;0
L 1.92951004 -1.95946004 1.93216004 -1.95946004 0 P 0 ;0
L 1.93016998 -1.95846004 1.93278996 -1.95846004 0 P 0 ;0
L 1.93078002 -1.95746004 1.93341004 -1.95746004 0 P 0 ;0
L 1.93133002 -1.95646004 1.93396004 -1.95646004 0 P 0 ;0
L 1.93185 -1.95546004 1.93448996 -1.95546004 0 P 0 ;0
L 1.93231004 -1.95446004 1.93495 -1.95446004 0 P 0 ;0
L 1.93275 -1.95346004 1.93541004 -1.95346004 0 P 0 ;0
L 1.93311998 -1.95246004 1.93586004 -1.95246004 0 P 0 ;0
L 1.93348002 -1.95146004 1.93628996 -1.95146004 0 P 0 ;0
L 1.93376998 -1.95046004 1.93666004 -1.95046004 0 P 0 ;0
L 1.93405 -1.94946004 1.93693002 -1.94946004 0 P 0 ;0
L 1.93428002 -1.94846004 1.93715 -1.94846004 0 P 0 ;0
L 1.93446998 -1.94746004 1.93733002 -1.94746004 0 P 0 ;0
L 1.93466004 -1.94646004 1.93743002 -1.94646004 0 P 0 ;0
L 1.93478996 -1.94546004 1.93748996 -1.94546004 0 P 0 ;0
L 1.9349 -1.94446998 1.93751998 -1.94446998 0 P 0 ;0
L 1.93496998 -1.94346004 1.93755 -1.94346004 0 P 0 ;0
L 1.93501998 -1.94246004 1.93758002 -1.94246004 0 P 0 ;0
L 1.93505 -1.94146998 1.93758996 -1.94146998 0 P 0 ;0
L 1.93503002 -1.94046004 1.93755 -1.94046004 0 P 0 ;0
L 1.935 -1.93946004 1.93751998 -1.93946004 0 P 0 ;0
L 1.93491998 -1.93846004 1.93748002 -1.93846004 0 P 0 ;0
L 1.93481004 -1.93746004 1.93738996 -1.93746004 0 P 0 ;0
L 1.93468996 -1.93646004 1.93726998 -1.93646004 0 P 0 ;0
L 1.93451004 -1.93546004 1.93716004 -1.93546004 0 P 0 ;0
L 1.93433002 -1.93446004 1.93703996 -1.93446004 0 P 0 ;0
L 1.93408996 -1.93346004 1.93685 -1.93346004 0 P 0 ;0
L 1.93383002 -1.93246004 1.93666004 -1.93246004 0 P 0 ;0
L 1.93353002 -1.93146004 1.93638996 -1.93146004 0 P 0 ;0
L 1.9332 -1.93046004 1.93611998 -1.93046004 0 P 0 ;0
L 1.93283996 -1.92946004 1.93576998 -1.92946004 0 P 0 ;0
L 1.93241004 -1.92846004 1.93541004 -1.92846004 0 P 0 ;0
L 1.93198996 -1.92746004 1.93498002 -1.92746004 0 P 0 ;0
L 1.93146998 -1.92646004 1.93451004 -1.92646004 0 P 0 ;0
L 1.93096004 -1.92546004 1.93398002 -1.92546004 0 P 0 ;0
L 1.93035 -1.92446998 1.93338002 -1.92446998 0 P 0 ;0
L 1.92973002 -1.92346004 1.93275 -1.92346004 0 P 0 ;0
L 1.92903002 -1.92246004 1.93201004 -1.92246004 0 P 0 ;0
L 1.92831004 -1.92146004 1.93125 -1.92146004 0 P 0 ;0
L 1.92746998 -1.92046004 1.93041004 -1.92046004 0 P 0 ;0
L 1.92661004 -1.91946004 1.92948996 -1.91946004 0 P 0 ;0
L 1.92558996 -1.91846004 1.92851004 -1.91846004 0 P 0 ;0
L 1.9245 -1.91746004 1.92741998 -1.91746004 0 P 0 ;0
L 1.92328996 -1.91646004 1.92621998 -1.91646004 0 P 0 ;0
L 1.92188002 -1.91546004 1.92491998 -1.91546004 0 P 0 ;0
L 1.92026004 -1.91446004 1.92358996 -1.91446004 0 P 0 ;0
L 1.91835 -1.91346004 1.92208002 -1.91346004 0 P 0 ;0
L 1.82446998 -2.08323996 1.87608002 -2.08323996 0 P 0 ;0
L 1.82403002 -2.08223996 1.87601004 -2.08223996 0 P 0 ;0
L 1.8234 -2.08123996 1.87591004 -2.08123996 0 P 0 ;0
L 1.82256004 -2.08023996 1.87578002 -2.08023996 0 P 0 ;0
L 1.82166004 -2.07923996 1.87558996 -2.07923996 0 P 0 ;0
L 1.82061998 -2.07823996 1.87533002 -2.07823996 0 P 0 ;0
L 1.81946004 -2.07723996 1.87498996 -2.07723996 0 P 0 ;0
L 1.81818002 -2.07623996 1.8746 -2.07623996 0 P 0 ;0
L 1.8168 -2.07523996 1.87416998 -2.07523996 0 P 0 ;0
L 1.81541998 -2.07423996 1.87371004 -2.07423996 0 P 0 ;0
L 1.81403002 -2.07323996 1.87316998 -2.07323996 0 P 0 ;0
L 1.81265 -2.07223996 1.87261004 -2.07223996 0 P 0 ;0
L 1.81126998 -2.07123996 1.87196004 -2.07123996 0 P 0 ;0
L 1.80986004 -2.07023996 1.87128002 -2.07023996 0 P 0 ;0
L 1.80843996 -2.06923996 1.87051998 -2.06923996 0 P 0 ;0
L 1.80703002 -2.06823996 1.8697 -2.06823996 0 P 0 ;0
L 1.80561004 -2.06723996 1.86883002 -2.06723996 0 P 0 ;0
L 1.8042 -2.06623996 1.86796004 -2.06623996 0 P 0 ;0
L 1.80278002 -2.06523996 1.86705 -2.06523996 0 P 0 ;0
L 1.80136004 -2.06423996 1.86608002 -2.06423996 0 P 0 ;0
L 1.79995 -2.06323996 1.8651 -2.06323996 0 P 0 ;0
L 1.79865 -2.06223996 1.86411004 -2.06223996 0 P 0 ;0
L 1.79735 -2.06123996 1.86301998 -2.06123996 0 P 0 ;0
L 1.79605 -2.06023996 1.86193002 -2.06023996 0 P 0 ;0
L 1.79475 -2.05923996 1.86083996 -2.05923996 0 P 0 ;0
L 1.79345 -2.05823996 1.85966998 -2.05823996 0 P 0 ;0
L 1.79215 -2.05723996 1.85846004 -2.05723996 0 P 0 ;0
L 1.79088002 -2.05623996 1.85726004 -2.05623996 0 P 0 ;0
L 1.78971998 -2.05523996 1.85598996 -2.05523996 0 P 0 ;0
L 1.78856004 -2.05423996 1.85461998 -2.05423996 0 P 0 ;0
L 1.7874 -2.05323996 1.85326004 -2.05323996 0 P 0 ;0
L 1.78623002 -2.05223996 1.8519 -2.05223996 0 P 0 ;0
L 1.78506998 -2.05123996 1.85053996 -2.05123996 0 P 0 ;0
L 1.78398002 -2.05023996 1.84918002 -2.05023996 0 P 0 ;0
L 1.783 -2.04923996 1.84781004 -2.04923996 0 P 0 ;0
L 1.87086004 -2.03023996 1.87535 -2.03023996 0 P 0 ;0
L 1.91633002 -1.91473002 1.9183 -1.91565 0 P 0 ;0
L 1.9183 -1.91565 1.92018996 -1.91673002 0 P 0 ;0
L 1.92018996 -1.91673002 1.92196998 -1.91796998 0 P 0 ;0
L 1.92196998 -1.91796998 1.92365 -1.91936004 0 P 0 ;0
L 1.92365 -1.91936004 1.9252 -1.92088002 0 P 0 ;0
L 1.9252 -1.92088002 1.92661004 -1.92253996 0 P 0 ;0
L 1.92661004 -1.92253996 1.92795 -1.92436998 0 P 0 ;0
L 1.92795 -1.92436998 1.92913996 -1.9263 0 P 0 ;0
L 1.92913996 -1.9263 1.93018002 -1.92831998 0 P 0 ;0
L 1.93018002 -1.92831998 1.93106998 -1.93041004 0 P 0 ;0
L 1.93106998 -1.93041004 1.93178996 -1.93256004 0 P 0 ;0
L 1.93178996 -1.93256004 1.93236004 -1.93476004 0 P 0 ;0
L 1.93236004 -1.93476004 1.93276004 -1.93703996 0 P 0 ;0
L 1.93276004 -1.93703996 1.93298996 -1.93933996 0 P 0 ;0
L 1.93298996 -1.93933996 1.93306004 -1.94165 0 P 0 ;0
L 1.93306004 -1.94165 1.93295 -1.94396998 0 P 0 ;0
L 1.93295 -1.94396998 1.93268002 -1.94626004 0 P 0 ;0
L 1.93268002 -1.94626004 1.93223002 -1.94853996 0 P 0 ;0
L 1.93223002 -1.94853996 1.93161998 -1.95071998 0 P 0 ;0
L 1.93161998 -1.95071998 1.93085 -1.95285 0 P 0 ;0
L 1.93085 -1.95285 1.92991004 -1.95491004 0 P 0 ;0
L 1.92991004 -1.95491004 1.92881004 -1.95688996 0 P 0 ;0
L 1.92881004 -1.95688996 1.92756004 -1.95878002 0 P 0 ;0
L 1.92756004 -1.95878002 1.92616004 -1.96056998 0 P 0 ;0
L 1.92616004 -1.96056998 1.92493996 -1.9619 0 P 0 ;0
L 1.92493996 -1.9619 1.92361998 -1.96313996 0 P 0 ;0
L 1.92361998 -1.96313996 1.9222 -1.96426004 0 P 0 ;0
L 1.9222 -1.96426004 1.9207 -1.96526998 0 P 0 ;0
L 1.9207 -1.96526998 1.91911004 -1.96616998 0 P 0 ;0
L 1.91911004 -1.96616998 1.91686998 -1.96721004 0 P 0 ;0
L 1.91686998 -1.96721004 1.91456004 -1.96806998 0 P 0 ;0
L 1.91456004 -1.96806998 1.91218996 -1.96876004 0 P 0 ;0
L 1.91218996 -1.96876004 1.90975 -1.96926998 0 P 0 ;0
L 1.90975 -1.96926998 1.90725 -1.9696 0 P 0 ;0
L 1.90725 -1.9696 1.90473002 -1.96973996 0 P 0 ;0
L 1.90473002 -1.96973996 1.9022 -1.96968996 0 P 0 ;0
L 1.9022 -1.96968996 1.89966998 -1.96945 0 P 0 ;0
L 1.89966998 -1.96945 1.89778002 -1.96913002 0 P 0 ;0
L 1.89778002 -1.96913002 1.89591998 -1.96868996 0 P 0 ;0
L 1.89591998 -1.96868996 1.8941 -1.96811004 0 P 0 ;0
L 1.8941 -1.96811004 1.89231004 -1.96741004 0 P 0 ;0
L 1.89231004 -1.96741004 1.89058002 -1.96658002 0 P 0 ;0
L 1.89058002 -1.96658002 1.88875 -1.96553996 0 P 0 ;0
L 1.88875 -1.96553996 1.88698996 -1.96435 0 P 0 ;0
L 1.88698996 -1.96435 1.88533996 -1.96303002 0 P 0 ;0
L 1.88533996 -1.96303002 1.88378996 -1.9616 0 P 0 ;0
L 1.88378996 -1.9616 1.88235 -1.96003996 0 P 0 ;0
L 1.88235 -1.96003996 1.88103002 -1.95838996 0 P 0 ;0
L 1.88103002 -1.95838996 1.87983996 -1.95663002 0 P 0 ;0
L 1.87983996 -1.95663002 1.87861998 -1.95446998 0 P 0 ;0
L 1.87861998 -1.95446998 1.87758002 -1.9522 0 P 0 ;0
L 1.87758002 -1.9522 1.87673996 -1.94986004 0 P 0 ;0
L 1.87673996 -1.94986004 1.8761 -1.94745 0 P 0 ;0
L 1.8761 -1.94745 1.87568002 -1.945 0 P 0 ;0
L 1.87568002 -1.945 1.87546004 -1.94248996 0 P 0 ;0
L 1.87546004 -1.94248996 1.87546004 -1.93998996 0 P 0 ;0
L 1.87546004 -1.93998996 1.87566998 -1.93748996 0 P 0 ;0
L 1.87566998 -1.93748996 1.87608996 -1.93501998 0 P 0 ;0
L 1.87608996 -1.93501998 1.87671998 -1.9326 0 P 0 ;0
L 1.87671998 -1.9326 1.87755 -1.93023002 0 P 0 ;0
L 1.87755 -1.93023002 1.8786 -1.92793002 0 P 0 ;0
L 1.8786 -1.92793002 1.87981998 -1.92575 0 P 0 ;0
L 1.87981998 -1.92575 1.88123002 -1.92368002 0 P 0 ;0
L 1.88123002 -1.92368002 1.88281004 -1.92175 0 P 0 ;0
L 1.88281004 -1.92175 1.88455 -1.91996004 0 P 0 ;0
L 1.88455 -1.91996004 1.88643002 -1.91831998 0 P 0 ;0
L 1.88643002 -1.91831998 1.88845 -1.91686004 0 P 0 ;0
L 1.88845 -1.91686004 1.88986998 -1.91598996 0 P 0 ;0
L 1.88986998 -1.91598996 1.89135 -1.91523002 0 P 0 ;0
L 1.89135 -1.91523002 1.89288002 -1.91458996 0 P 0 ;0
L 1.89288002 -1.91458996 1.89446998 -1.91406004 0 P 0 ;0
L 1.89446998 -1.91406004 1.89688996 -1.91343996 0 P 0 ;0
L 1.89688996 -1.91343996 1.89935 -1.91298996 0 P 0 ;0
L 1.89935 -1.91298996 1.90183996 -1.91271004 0 P 0 ;0
L 1.90183996 -1.91271004 1.9044 -1.91261004 0 P 0 ;0
L 1.9044 -1.91261004 1.90695 -1.91268002 0 P 0 ;0
L 1.90695 -1.91268002 1.90948996 -1.91291998 0 P 0 ;0
L 1.90948996 -1.91291998 1.91181998 -1.91331998 0 P 0 ;0
L 1.91181998 -1.91331998 1.91408996 -1.91393002 0 P 0 ;0
L 1.91408996 -1.91393002 1.91633002 -1.91473002 0 P 0 ;0
L 1.89498002 -1.90801998 1.8922 -1.90893002 0 P 0 ;0
L 1.8922 -1.90893002 1.88948002 -1.91003002 0 P 0 ;0
L 1.88948002 -1.91003002 1.88686004 -1.91133002 0 P 0 ;0
L 1.88686004 -1.91133002 1.88431004 -1.91283996 0 P 0 ;0
L 1.88431004 -1.91283996 1.88201004 -1.91446004 0 P 0 ;0
L 1.88201004 -1.91446004 1.87985 -1.91626998 0 P 0 ;0
L 1.87985 -1.91626998 1.87785 -1.91826004 0 P 0 ;0
L 1.87785 -1.91826004 1.87601998 -1.92041004 0 P 0 ;0
L 1.87601998 -1.92041004 1.87441004 -1.92266998 0 P 0 ;0
L 1.87441004 -1.92266998 1.87298996 -1.92505 0 P 0 ;0
L 1.87298996 -1.92505 1.87178002 -1.92756004 0 P 0 ;0
L 1.87178002 -1.92756004 1.87078996 -1.93015 0 P 0 ;0
L 1.87078996 -1.93015 1.87 -1.93286998 0 P 0 ;0
L 1.87 -1.93286998 1.86943996 -1.93563996 0 P 0 ;0
L 1.86943996 -1.93563996 1.86908996 -1.93845 0 P 0 ;0
L 1.86908996 -1.93845 1.86898002 -1.94128996 0 P 0 ;0
L 1.86898002 -1.94128996 1.86911998 -1.94485 0 P 0 ;0
L 1.86911998 -1.94485 1.86953996 -1.94841004 0 P 0 ;0
L 1.86953996 -1.94841004 1.86996004 -1.95048996 0 P 0 ;0
L 1.86996004 -1.95048996 1.87053002 -1.95251998 0 P 0 ;0
L 1.87053002 -1.95251998 1.87125 -1.95451998 0 P 0 ;0
L 1.87125 -1.95451998 1.87211004 -1.95643002 0 P 0 ;0
L 1.87211004 -1.95643002 1.8731 -1.95826004 0 P 0 ;0
L 1.8731 -1.95826004 1.87423996 -1.96001998 0 P 0 ;0
L 1.87423996 -1.96001998 1.87636998 -1.96278996 0 P 0 ;0
L 1.87636998 -1.96278996 1.87871998 -1.96536998 0 P 0 ;0
L 1.87871998 -1.96536998 1.88145 -1.96788002 0 P 0 ;0
L 1.88145 -1.96788002 1.88436998 -1.97015 0 P 0 ;0
L 1.88436998 -1.97015 1.88621004 -1.97135 0 P 0 ;0
L 1.88621004 -1.97135 1.88813002 -1.97238002 0 P 0 ;0
L 1.88813002 -1.97238002 1.89013002 -1.97326004 0 P 0 ;0
L 1.89013002 -1.97326004 1.89228002 -1.97398996 0 P 0 ;0
L 1.89228002 -1.97398996 1.89446998 -1.97455 0 P 0 ;0
L 1.89446998 -1.97455 1.89671004 -1.97493996 0 P 0 ;0
L 1.89671004 -1.97493996 1.90076998 -1.97533996 0 P 0 ;0
L 1.90076998 -1.97533996 1.90485 -1.97546998 0 P 0 ;0
L 1.90485 -1.97546998 1.90821004 -1.97531998 0 P 0 ;0
L 1.90821004 -1.97531998 1.91153996 -1.97488996 0 P 0 ;0
L 1.91153996 -1.97488996 1.91481998 -1.97418996 0 P 0 ;0
L 1.91481998 -1.97418996 1.9171 -1.9735 0 P 0 ;0
L 1.9171 -1.9735 1.91933002 -1.97266004 0 P 0 ;0
L 1.91933002 -1.97266004 1.92148002 -1.97166004 0 P 0 ;0
L 1.92148002 -1.97166004 1.92356998 -1.97048996 0 P 0 ;0
L 1.92356998 -1.97048996 1.92553996 -1.96918996 0 P 0 ;0
L 1.92553996 -1.96918996 1.92741004 -1.96773996 0 P 0 ;0
L 1.92741004 -1.96773996 1.92916004 -1.96616998 0 P 0 ;0
L 1.92916004 -1.96616998 1.93081004 -1.96446004 0 P 0 ;0
L 1.93081004 -1.96446004 1.93236998 -1.96256998 0 P 0 ;0
L 1.93236998 -1.96256998 1.93381004 -1.96058996 0 P 0 ;0
L 1.93381004 -1.96058996 1.93511998 -1.95851004 0 P 0 ;0
L 1.93511998 -1.95851004 1.93628996 -1.95633996 0 P 0 ;0
L 1.93628996 -1.95633996 1.93803996 -1.95251998 0 P 0 ;0
L 1.93803996 -1.95251998 1.93858002 -1.95101998 0 P 0 ;0
L 1.93858002 -1.95101998 1.93898996 -1.94948002 0 P 0 ;0
L 1.93898996 -1.94948002 1.93928996 -1.94786998 0 P 0 ;0
L 1.93928996 -1.94786998 1.93946004 -1.94625 0 P 0 ;0
L 1.93946004 -1.94625 1.9396 -1.94178002 0 P 0 ;0
L 1.9396 -1.94178002 1.93946004 -1.93803996 0 P 0 ;0
L 1.93946004 -1.93803996 1.93905 -1.9343 0 P 0 ;0
L 1.93905 -1.9343 1.93863996 -1.93213996 0 P 0 ;0
L 1.93863996 -1.93213996 1.93808002 -1.93001998 0 P 0 ;0
L 1.93808002 -1.93001998 1.93736004 -1.92795 0 P 0 ;0
L 1.93736004 -1.92795 1.93653002 -1.92601004 0 P 0 ;0
L 1.93653002 -1.92601004 1.93555 -1.92415 0 P 0 ;0
L 1.93555 -1.92415 1.93441998 -1.92236004 0 P 0 ;0
L 1.93441998 -1.92236004 1.9331 -1.92056004 0 P 0 ;0
L 1.9331 -1.92056004 1.93166998 -1.91885 0 P 0 ;0
L 1.93166998 -1.91885 1.93011998 -1.91723002 0 P 0 ;0
L 1.93011998 -1.91723002 1.92896004 -1.91615 0 P 0 ;0
L 1.92896004 -1.91615 1.92775 -1.91511004 0 P 0 ;0
L 1.92775 -1.91511004 1.92493002 -1.91295 0 P 0 ;0
L 1.92493002 -1.91295 1.9221 -1.91108002 0 P 0 ;0
L 1.9221 -1.91108002 1.92095 -1.91043002 0 P 0 ;0
L 1.92095 -1.91043002 1.91975 -1.90985 0 P 0 ;0
L 1.91975 -1.90985 1.91796004 -1.90913996 0 P 0 ;0
L 1.91796004 -1.90913996 1.91613002 -1.90856004 0 P 0 ;0
L 1.91613002 -1.90856004 1.91423996 -1.9081 0 P 0 ;0
L 1.91423996 -1.9081 1.91086004 -1.90751998 0 P 0 ;0
L 1.91086004 -1.90751998 1.90743002 -1.90716004 0 P 0 ;0
L 1.90743002 -1.90716004 1.90401004 -1.90701004 0 P 0 ;0
L 1.90401004 -1.90701004 1.90058002 -1.90708002 0 P 0 ;0
L 1.90058002 -1.90708002 1.8987 -1.90726004 0 P 0 ;0
L 1.8987 -1.90726004 1.89683002 -1.90756998 0 P 0 ;0
L 1.89683002 -1.90756998 1.89498002 -1.90801998 0 P 0 ;0
L 1.86643002 -2.02923996 1.87525 -2.02923996 0 P 0 ;0
L 1.86176998 -2.02823996 1.87515 -2.02823996 0 P 0 ;0
L 1.85588996 -2.02723996 1.87505 -2.02723996 0 P 0 ;0
L 1.78365 -2.00523996 1.87281004 -2.00523996 0 P 0 ;0
L 1.78451004 -2.00423996 1.87271004 -2.00423996 0 P 0 ;0
L 1.78546998 -2.00323996 1.87261004 -2.00323996 0 P 0 ;0
L 1.78655 -2.00223996 1.8725 -2.00223996 0 P 0 ;0
L 1.78776004 -2.00123996 1.8724 -2.00123996 0 P 0 ;0
L 1.78915 -2.00023996 1.8723 -2.00023996 0 P 0 ;0
L 1.79078996 -1.99923996 1.8722 -1.99923996 0 P 0 ;0
L 1.79263996 -1.99823996 1.87208996 -1.99823996 0 P 0 ;0
L 1.79458996 -1.99723996 1.87198996 -1.99723996 0 P 0 ;0
L 1.79686998 -1.99623996 1.87188002 -1.99623996 0 P 0 ;0
L 1.79946004 -1.99523996 1.87178002 -1.99523996 0 P 0 ;0
L 1.80231004 -1.99423996 1.86961998 -1.99423996 0 P 0 ;0
L 1.80596004 -1.99323996 1.86218002 -1.99323996 0 P 0 ;0
L 1.81051004 -1.99223996 1.85398002 -1.99223996 0 P 0 ;0
L 1.81676004 -1.99123996 1.84395 -1.99123996 0 P 0 ;0
L 1.87786998 -1.96146004 1.88093996 -1.96146004 0 P 0 ;0
L 1.8771 -1.96046004 1.88013002 -1.96046004 0 P 0 ;0
L 1.87633996 -1.95946004 1.87933996 -1.95946004 0 P 0 ;0
L 1.87561998 -1.95846004 1.87866998 -1.95846004 0 P 0 ;0
L 1.87496998 -1.95746004 1.87801998 -1.95746004 0 P 0 ;0
L 1.8744 -1.95646004 1.87745 -1.95646004 0 P 0 ;0
L 1.87386998 -1.95546004 1.87688002 -1.95546004 0 P 0 ;0
L 1.87341998 -1.95446004 1.87641998 -1.95446004 0 P 0 ;0
L 1.87298996 -1.95346004 1.87596004 -1.95346004 0 P 0 ;0
L 1.87263002 -1.95246004 1.87555 -1.95246004 0 P 0 ;0
L 1.87231004 -1.95146004 1.87518996 -1.95146004 0 P 0 ;0
L 1.87203002 -1.95046004 1.87483002 -1.95046004 0 P 0 ;0
L 1.87178996 -1.94946004 1.87456998 -1.94946004 0 P 0 ;0
L 1.87158996 -1.94846004 1.87431004 -1.94846004 0 P 0 ;0
L 1.87143996 -1.94746004 1.87408002 -1.94746004 0 P 0 ;0
L 1.87133002 -1.94646004 1.8739 -1.94646004 0 P 0 ;0
L 1.87121004 -1.94546004 1.87373002 -1.94546004 0 P 0 ;0
L 1.8711 -1.94446998 1.87361998 -1.94446998 0 P 0 ;0
L 1.87106998 -1.94346004 1.87353996 -1.94346004 0 P 0 ;0
L 1.87103002 -1.94246004 1.87346004 -1.94246004 0 P 0 ;0
L 1.87098996 -1.94146998 1.87346004 -1.94146998 0 P 0 ;0
L 1.87101004 -1.94046004 1.87346004 -1.94046004 0 P 0 ;0
L 1.87106004 -1.93946004 1.87348996 -1.93946004 0 P 0 ;0
L 1.87111004 -1.93846004 1.87358002 -1.93846004 0 P 0 ;0
L 1.87123002 -1.93746004 1.87366004 -1.93746004 0 P 0 ;0
L 1.87135 -1.93646004 1.87381998 -1.93646004 0 P 0 ;0
L 1.87151004 -1.93546004 1.87398996 -1.93546004 0 P 0 ;0
L 1.87171998 -1.93446004 1.87416998 -1.93446004 0 P 0 ;0
L 1.87191998 -1.93346004 1.87443002 -1.93346004 0 P 0 ;0
L 1.8722 -1.93246004 1.87468996 -1.93246004 0 P 0 ;0
L 1.87248996 -1.93146004 1.875 -1.93146004 0 P 0 ;0
L 1.87281004 -1.93046004 1.87535 -1.93046004 0 P 0 ;0
L 1.87318996 -1.92946004 1.87571004 -1.92946004 0 P 0 ;0
L 1.87356998 -1.92846004 1.87616004 -1.92846004 0 P 0 ;0
L 1.87405 -1.92746004 1.87661004 -1.92746004 0 P 0 ;0
L 1.87453002 -1.92646004 1.87711998 -1.92646004 0 P 0 ;0
L 1.87506998 -1.92546004 1.87768996 -1.92546004 0 P 0 ;0
L 1.87566004 -1.92446998 1.87826998 -1.92446998 0 P 0 ;0
L 1.87628996 -1.92346004 1.87896004 -1.92346004 0 P 0 ;0
L 1.87701004 -1.92246004 1.87963996 -1.92246004 0 P 0 ;0
L 1.87775 -1.92146004 1.88046004 -1.92146004 0 P 0 ;0
L 1.90483996 -1.97346004 1.9009 -1.97333996 0 P 0 ;0
L 1.9009 -1.97333996 1.89698002 -1.97295 0 P 0 ;0
L 1.89698002 -1.97295 1.89488996 -1.97258996 0 P 0 ;0
L 1.89488996 -1.97258996 1.89285 -1.97206998 0 P 0 ;0
L 1.89285 -1.97206998 1.89086004 -1.97138996 0 P 0 ;0
L 1.89086004 -1.97138996 1.889 -1.97058002 0 P 0 ;0
L 1.889 -1.97058002 1.88723002 -1.96961998 0 P 0 ;0
L 1.88723002 -1.96961998 1.88553002 -1.96851998 0 P 0 ;0
L 1.88553002 -1.96851998 1.88273996 -1.96636004 0 P 0 ;0
L 1.88273996 -1.96636004 1.88013996 -1.96396004 0 P 0 ;0
L 1.88013996 -1.96396004 1.8779 -1.9615 0 P 0 ;0
L 1.8779 -1.9615 1.87588002 -1.95886998 0 P 0 ;0
L 1.87588002 -1.95886998 1.87483002 -1.95723996 0 P 0 ;0
L 1.87483002 -1.95723996 1.8739 -1.95553996 0 P 0 ;0
L 1.8739 -1.95553996 1.87311004 -1.95376998 0 P 0 ;0
L 1.87311004 -1.95376998 1.87243002 -1.95191004 0 P 0 ;0
L 1.87243002 -1.95191004 1.8719 -1.95001998 0 P 0 ;0
L 1.8719 -1.95001998 1.87151998 -1.9481 0 P 0 ;0
L 1.87151998 -1.9481 1.87111004 -1.94468996 0 P 0 ;0
L 1.87111004 -1.94468996 1.87098002 -1.94128996 0 P 0 ;0
L 1.87098002 -1.94128996 1.87108996 -1.93861004 0 P 0 ;0
L 1.87108996 -1.93861004 1.87141004 -1.93596998 0 P 0 ;0
L 1.87141004 -1.93596998 1.87195 -1.93335 0 P 0 ;0
L 1.87195 -1.93335 1.87268996 -1.93078996 0 P 0 ;0
L 1.87268996 -1.93078996 1.87361998 -1.92835 0 P 0 ;0
L 1.87361998 -1.92835 1.87475 -1.926 0 P 0 ;0
L 1.87475 -1.926 1.87608996 -1.92376004 0 P 0 ;0
L 1.87608996 -1.92376004 1.8776 -1.92163996 0 P 0 ;0
L 1.8776 -1.92163996 1.87931998 -1.91961998 0 P 0 ;0
L 1.87931998 -1.91961998 1.8812 -1.91775 0 P 0 ;0
L 1.8812 -1.91775 1.88323002 -1.91605 0 P 0 ;0
L 1.88323002 -1.91605 1.8854 -1.91451998 0 P 0 ;0
L 1.8854 -1.91451998 1.88781004 -1.91308996 0 P 0 ;0
L 1.88781004 -1.91308996 1.89031004 -1.91186004 0 P 0 ;0
L 1.89031004 -1.91186004 1.89288002 -1.9108 0 P 0 ;0
L 1.89288002 -1.9108 1.89553002 -1.90995 0 P 0 ;0
L 1.89553002 -1.90995 1.89723002 -1.90953002 0 P 0 ;0
L 1.89723002 -1.90953002 1.89896004 -1.90923996 0 P 0 ;0
L 1.89896004 -1.90923996 1.90068996 -1.90908002 0 P 0 ;0
L 1.90068996 -1.90908002 1.90398996 -1.90901004 0 P 0 ;0
L 1.90398996 -1.90901004 1.90728002 -1.90915 0 P 0 ;0
L 1.90728002 -1.90915 1.91058996 -1.90951004 0 P 0 ;0
L 1.91058996 -1.90951004 1.91383996 -1.91006004 0 P 0 ;0
L 1.91383996 -1.91006004 1.91558996 -1.91048996 0 P 0 ;0
L 1.91558996 -1.91048996 1.91728996 -1.91101998 0 P 0 ;0
L 1.91728996 -1.91101998 1.91895 -1.91168002 0 P 0 ;0
L 1.91895 -1.91168002 1.92001998 -1.9122 0 P 0 ;0
L 1.92001998 -1.9122 1.92105 -1.91278996 0 P 0 ;0
L 1.92105 -1.91278996 1.92376998 -1.91458002 0 P 0 ;0
L 1.92376998 -1.91458002 1.92648996 -1.91666998 0 P 0 ;0
L 1.92648996 -1.91666998 1.92763002 -1.91763996 0 P 0 ;0
L 1.92763002 -1.91763996 1.92871004 -1.91865 0 P 0 ;0
L 1.92871004 -1.91865 1.93018002 -1.92018996 0 P 0 ;0
L 1.93018002 -1.92018996 1.93153002 -1.9218 0 P 0 ;0
L 1.93153002 -1.9218 1.93276998 -1.92348996 0 P 0 ;0
L 1.93276998 -1.92348996 1.93381004 -1.92515 0 P 0 ;0
L 1.93381004 -1.92515 1.93471998 -1.92686998 0 P 0 ;0
L 1.93471998 -1.92686998 1.9355 -1.92866998 0 P 0 ;0
L 1.9355 -1.92866998 1.93616998 -1.93061004 0 P 0 ;0
L 1.93616998 -1.93061004 1.93668996 -1.93258002 0 P 0 ;0
L 1.93668996 -1.93258002 1.93706998 -1.93458996 0 P 0 ;0
L 1.93706998 -1.93458996 1.93746998 -1.93818996 0 P 0 ;0
L 1.93746998 -1.93818996 1.9376 -1.94178996 0 P 0 ;0
L 1.9376 -1.94178996 1.93746004 -1.94611004 0 P 0 ;0
L 1.93746004 -1.94611004 1.93731004 -1.94758996 0 P 0 ;0
L 1.93731004 -1.94758996 1.93705 -1.94903996 0 P 0 ;0
L 1.93705 -1.94903996 1.93666998 -1.95041998 0 P 0 ;0
L 1.93666998 -1.95041998 1.93618002 -1.95176004 0 P 0 ;0
L 1.93618002 -1.95176004 1.9345 -1.95545 0 P 0 ;0
L 1.9345 -1.95545 1.93338996 -1.9575 0 P 0 ;0
L 1.93338996 -1.9575 1.93216004 -1.95946998 0 P 0 ;0
L 1.93216004 -1.95946998 1.93078996 -1.96133996 0 P 0 ;0
L 1.93078996 -1.96133996 1.92931004 -1.96311998 0 P 0 ;0
L 1.92931004 -1.96311998 1.92776998 -1.96473002 0 P 0 ;0
L 1.92776998 -1.96473002 1.92613002 -1.96621004 0 P 0 ;0
L 1.92613002 -1.96621004 1.92438002 -1.96756004 0 P 0 ;0
L 1.92438002 -1.96756004 1.92253002 -1.96878002 0 P 0 ;0
L 1.92253002 -1.96878002 1.92056998 -1.96986998 0 P 0 ;0
L 1.92056998 -1.96986998 1.91855 -1.97081998 0 P 0 ;0
L 1.91855 -1.97081998 1.91646004 -1.97161004 0 P 0 ;0
L 1.91646004 -1.97161004 1.91433002 -1.97223996 0 P 0 ;0
L 1.91433002 -1.97223996 1.9112 -1.97291004 0 P 0 ;0
L 1.9112 -1.97291004 1.90803996 -1.97331998 0 P 0 ;0
L 1.90803996 -1.97331998 1.90483996 -1.97346004 0 P 0 ;0
L 1.90476004 -1.97173996 1.9048 -1.97173996 0 P 0 ;0
L 1.9048 -1.97173996 1.90483996 -1.97173002 0 P 0 ;0
L 1.90483996 -1.97173002 1.90736004 -1.9716 0 P 0 ;0
L 1.90736004 -1.9716 1.9074 -1.97158996 0 P 0 ;0
L 1.9074 -1.97158996 1.90746998 -1.97158996 0 P 0 ;0
L 1.90746998 -1.97158996 1.90751004 -1.97158002 0 P 0 ;0
L 1.90751004 -1.97158002 1.91001004 -1.97126004 0 P 0 ;0
L 1.91001004 -1.97126004 1.91005 -1.97125 0 P 0 ;0
L 1.91005 -1.97125 1.91008002 -1.97123996 0 P 0 ;0
L 1.91008002 -1.97123996 1.91011998 -1.97123996 0 P 0 ;0
L 1.91011998 -1.97123996 1.91016004 -1.97123002 0 P 0 ;0
L 1.91016004 -1.97123002 1.9126 -1.97071998 0 P 0 ;0
L 1.9126 -1.97071998 1.9126 -1.97071004 0 P 0 ;0
L 1.9126 -1.97071004 1.91266998 -1.97071004 0 P 0 ;0
L 1.91266998 -1.97071004 1.91271004 -1.97068996 0 P 0 ;0
L 1.91271004 -1.97068996 1.91275 -1.97068002 0 P 0 ;0
L 1.91275 -1.97068002 1.91511998 -1.96998996 0 P 0 ;0
L 1.91511998 -1.96998996 1.91515 -1.96998996 0 P 0 ;0
L 1.91515 -1.96998996 1.91518996 -1.96996998 0 P 0 ;0
L 1.91518996 -1.96996998 1.91523002 -1.96996004 0 P 0 ;0
L 1.91523002 -1.96996004 1.91526004 -1.96995 0 P 0 ;0
L 1.91526004 -1.96995 1.91756998 -1.96908002 0 P 0 ;0
L 1.91756998 -1.96908002 1.91761004 -1.96906998 0 P 0 ;0
L 1.91761004 -1.96906998 1.91768002 -1.96903996 0 P 0 ;0
L 1.91768002 -1.96903996 1.91771004 -1.96901998 0 P 0 ;0
L 1.91771004 -1.96901998 1.91995 -1.96798002 0 P 0 ;0
L 1.91995 -1.96798002 1.92001998 -1.96795 0 P 0 ;0
L 1.92001998 -1.96795 1.92005 -1.96793002 0 P 0 ;0
L 1.92005 -1.96793002 1.92008996 -1.96791004 0 P 0 ;0
L 1.92008996 -1.96791004 1.92168002 -1.96701998 0 P 0 ;0
L 1.92168002 -1.96701998 1.92171998 -1.967 0 P 0 ;0
L 1.92171998 -1.967 1.92175 -1.96698002 0 P 0 ;0
L 1.92175 -1.96698002 1.92178996 -1.96695 0 P 0 ;0
L 1.92178996 -1.96695 1.92181998 -1.96693002 0 P 0 ;0
L 1.92181998 -1.96693002 1.92331998 -1.96591998 0 P 0 ;0
L 1.92331998 -1.96591998 1.92336004 -1.9659 0 P 0 ;0
L 1.92336004 -1.9659 1.92341998 -1.96586004 0 P 0 ;0
L 1.92341998 -1.96586004 1.92345 -1.96583002 0 P 0 ;0
L 1.92345 -1.96583002 1.92486004 -1.9647 0 P 0 ;0
L 1.92486004 -1.9647 1.92493002 -1.96465 0 P 0 ;0
L 1.92493002 -1.96465 1.92496004 -1.96463002 0 P 0 ;0
L 1.92496004 -1.96463002 1.92498996 -1.9646 0 P 0 ;0
L 1.92498996 -1.9646 1.92631004 -1.96336998 0 P 0 ;0
L 1.92631004 -1.96336998 1.9264 -1.96328002 0 P 0 ;0
L 1.9264 -1.96328002 1.92641998 -1.96325 0 P 0 ;0
L 1.92641998 -1.96325 1.92763996 -1.96191998 0 P 0 ;0
L 1.92763996 -1.96191998 1.92766998 -1.96188996 0 P 0 ;0
L 1.92766998 -1.96188996 1.92768996 -1.96186004 0 P 0 ;0
L 1.92768996 -1.96186004 1.92771998 -1.96183002 0 P 0 ;0
L 1.92771998 -1.96183002 1.92773996 -1.9618 0 P 0 ;0
L 1.92773996 -1.9618 1.92913996 -1.96001004 0 P 0 ;0
L 1.92913996 -1.96001004 1.92918996 -1.95995 0 P 0 ;0
L 1.92918996 -1.95995 1.92921004 -1.95991004 0 P 0 ;0
L 1.92921004 -1.95991004 1.92923002 -1.95988002 0 P 0 ;0
L 1.92923002 -1.95988002 1.93048002 -1.95798996 0 P 0 ;0
L 1.93048002 -1.95798996 1.93051998 -1.95793002 0 P 0 ;0
L 1.93051998 -1.95793002 1.93053996 -1.95788996 0 P 0 ;0
L 1.93053996 -1.95788996 1.93056004 -1.95786004 0 P 0 ;0
L 1.93056004 -1.95786004 1.93166004 -1.95588002 0 P 0 ;0
L 1.93166004 -1.95588002 1.93171004 -1.95576998 0 P 0 ;0
L 1.93171004 -1.95576998 1.93173002 -1.95573996 0 P 0 ;0
L 1.93173002 -1.95573996 1.93266998 -1.95366998 0 P 0 ;0
L 1.93266998 -1.95366998 1.93271004 -1.95356998 0 P 0 ;0
L 1.93271004 -1.95356998 1.93273002 -1.95353002 0 P 0 ;0
L 1.93273002 -1.95353002 1.9335 -1.9514 0 P 0 ;0
L 1.9335 -1.9514 1.93351004 -1.95136998 0 P 0 ;0
L 1.93351004 -1.95136998 1.93353002 -1.95133002 0 P 0 ;0
L 1.93353002 -1.95133002 1.93355 -1.95125 0 P 0 ;0
L 1.93355 -1.95125 1.93416004 -1.94906998 0 P 0 ;0
L 1.93416004 -1.94906998 1.93416998 -1.94903002 0 P 0 ;0
L 1.93416998 -1.94903002 1.93418002 -1.949 0 P 0 ;0
L 1.93418002 -1.949 1.93418002 -1.94896004 0 P 0 ;0
L 1.93418002 -1.94896004 1.93418996 -1.94891998 0 P 0 ;0
L 1.93418996 -1.94891998 1.93463996 -1.94665 0 P 0 ;0
L 1.93463996 -1.94665 1.93463996 -1.94661004 0 P 0 ;0
L 1.93463996 -1.94661004 1.93465 -1.94656998 0 P 0 ;0
L 1.93465 -1.94656998 1.93466004 -1.9465 0 P 0 ;0
L 1.93466004 -1.9465 1.93493996 -1.9442 0 P 0 ;0
L 1.93493996 -1.9442 1.93493996 -1.94413002 0 P 0 ;0
L 1.93493996 -1.94413002 1.93495 -1.94408996 0 P 0 ;0
L 1.93495 -1.94408996 1.93495 -1.94406004 0 P 0 ;0
L 1.93495 -1.94406004 1.93505 -1.94173996 0 P 0 ;0
L 1.93505 -1.94173996 1.93506004 -1.94171004 0 P 0 ;0
L 1.93506004 -1.94171004 1.93506004 -1.9416 0 P 0 ;0
L 1.93506004 -1.9416 1.93498996 -1.93928996 0 P 0 ;0
L 1.93498996 -1.93928996 1.93498996 -1.93921004 0 P 0 ;0
L 1.93498996 -1.93921004 1.93498002 -1.93913996 0 P 0 ;0
L 1.93498002 -1.93913996 1.93475 -1.93683996 0 P 0 ;0
L 1.93475 -1.93683996 1.93473996 -1.93676998 0 P 0 ;0
L 1.93473996 -1.93676998 1.93473002 -1.93673002 0 P 0 ;0
L 1.93473002 -1.93673002 1.93473002 -1.93668996 0 P 0 ;0
L 1.93473002 -1.93668996 1.93433002 -1.93441004 0 P 0 ;0
L 1.93433002 -1.93441004 1.93431998 -1.93436998 0 P 0 ;0
L 1.93431998 -1.93436998 1.93431004 -1.93433996 0 P 0 ;0
L 1.93431004 -1.93433996 1.93428996 -1.93426004 0 P 0 ;0
L 1.93428996 -1.93426004 1.93373002 -1.93206004 0 P 0 ;0
L 1.93373002 -1.93206004 1.93368996 -1.93191998 0 P 0 ;0
L 1.93368996 -1.93191998 1.93296004 -1.92976998 0 P 0 ;0
L 1.93296004 -1.92976998 1.93293996 -1.9297 0 P 0 ;0
L 1.93293996 -1.9297 1.93291004 -1.92963002 0 P 0 ;0
L 1.93291004 -1.92963002 1.93201998 -1.92753996 0 P 0 ;0
L 1.93201998 -1.92753996 1.93196998 -1.92743002 0 P 0 ;0
L 1.93196998 -1.92743002 1.93196004 -1.9274 0 P 0 ;0
L 1.93196004 -1.9274 1.93091998 -1.92538996 0 P 0 ;0
L 1.93091998 -1.92538996 1.9309 -1.92536004 0 P 0 ;0
L 1.9309 -1.92536004 1.93088002 -1.92531998 0 P 0 ;0
L 1.93088002 -1.92531998 1.93086004 -1.92528996 0 P 0 ;0
L 1.93086004 -1.92528996 1.93083996 -1.92525 0 P 0 ;0
L 1.93083996 -1.92525 1.92965 -1.92331998 0 P 0 ;0
L 1.92965 -1.92331998 1.92956998 -1.9232 0 P 0 ;0
L 1.92956998 -1.9232 1.92823002 -1.92136004 0 P 0 ;0
L 1.92823002 -1.92136004 1.92818002 -1.9213 0 P 0 ;0
L 1.92818002 -1.9213 1.92816004 -1.92126998 0 P 0 ;0
L 1.92816004 -1.92126998 1.92813002 -1.92123996 0 P 0 ;0
L 1.92813002 -1.92123996 1.92671998 -1.91958002 0 P 0 ;0
L 1.92671998 -1.91958002 1.9266 -1.91946004 0 P 0 ;0
L 1.9266 -1.91946004 1.92505 -1.91793002 0 P 0 ;0
L 1.92505 -1.91793002 1.92498996 -1.91786998 0 P 0 ;0
L 1.92498996 -1.91786998 1.92493002 -1.91781998 0 P 0 ;0
L 1.92493002 -1.91781998 1.92325 -1.91643002 0 P 0 ;0
L 1.92325 -1.91643002 1.92318996 -1.91636998 0 P 0 ;0
L 1.92318996 -1.91636998 1.92311998 -1.91631998 0 P 0 ;0
L 1.92311998 -1.91631998 1.92133002 -1.91508002 0 P 0 ;0
L 1.92133002 -1.91508002 1.92126004 -1.91503996 0 P 0 ;0
L 1.92126004 -1.91503996 1.92121998 -1.91501004 0 P 0 ;0
L 1.92121998 -1.91501004 1.92118002 -1.91498996 0 P 0 ;0
L 1.92118002 -1.91498996 1.91928996 -1.91391004 0 P 0 ;0
L 1.91928996 -1.91391004 1.91926004 -1.91388996 0 P 0 ;0
L 1.91926004 -1.91388996 1.91913996 -1.91383002 0 P 0 ;0
L 1.91913996 -1.91383002 1.91716998 -1.91291004 0 P 0 ;0
L 1.91716998 -1.91291004 1.91711998 -1.91288996 0 P 0 ;0
L 1.91711998 -1.91288996 1.91705 -1.91286004 0 P 0 ;0
L 1.91705 -1.91286004 1.917 -1.91285 0 P 0 ;0
L 1.917 -1.91285 1.91476998 -1.91203996 0 P 0 ;0
L 1.91476998 -1.91203996 1.91468996 -1.91201998 0 P 0 ;0
L 1.91468996 -1.91201998 1.91465 -1.912 0 P 0 ;0
L 1.91465 -1.912 1.9146 -1.91198996 0 P 0 ;0
L 1.9146 -1.91198996 1.91233002 -1.91138996 0 P 0 ;0
L 1.91233002 -1.91138996 1.91228002 -1.91138002 0 P 0 ;0
L 1.91228002 -1.91138002 1.91223996 -1.91136998 0 P 0 ;0
L 1.91223996 -1.91136998 1.91216004 -1.91136004 0 P 0 ;0
L 1.91216004 -1.91136004 1.90983002 -1.91095 0 P 0 ;0
L 1.90983002 -1.91095 1.9098 -1.91093996 0 P 0 ;0
L 1.9098 -1.91093996 1.90976004 -1.91093996 0 P 0 ;0
L 1.90976004 -1.91093996 1.90971998 -1.91093002 0 P 0 ;0
L 1.90971998 -1.91093002 1.90968002 -1.91093002 0 P 0 ;0
L 1.90968002 -1.91093002 1.90713996 -1.91068996 0 P 0 ;0
L 1.90713996 -1.91068996 1.9071 -1.91068002 0 P 0 ;0
L 1.9071 -1.91068002 1.907 -1.91068002 0 P 0 ;0
L 1.907 -1.91068002 1.90445 -1.91061004 0 P 0 ;0
L 1.90445 -1.91061004 1.90431004 -1.91061004 0 P 0 ;0
L 1.90431004 -1.91061004 1.90176004 -1.91071004 0 P 0 ;0
L 1.90176004 -1.91071004 1.90173002 -1.91071998 0 P 0 ;0
L 1.90173002 -1.91071998 1.90166004 -1.91071998 0 P 0 ;0
L 1.90166004 -1.91071998 1.90161998 -1.91073002 0 P 0 ;0
L 1.90161998 -1.91073002 1.89913002 -1.911 0 P 0 ;0
L 1.89913002 -1.911 1.89906004 -1.91101004 0 P 0 ;0
L 1.89906004 -1.91101004 1.89901998 -1.91101998 0 P 0 ;0
L 1.89901998 -1.91101998 1.89898996 -1.91101998 0 P 0 ;0
L 1.89898996 -1.91101998 1.89653002 -1.91146998 0 P 0 ;0
L 1.89653002 -1.91146998 1.8965 -1.91148002 0 P 0 ;0
L 1.8965 -1.91148002 1.89646004 -1.91148002 0 P 0 ;0
L 1.89646004 -1.91148002 1.8964 -1.9115 0 P 0 ;0
L 1.8964 -1.9115 1.89396998 -1.91211998 0 P 0 ;0
L 1.89396998 -1.91211998 1.89393996 -1.91213002 0 P 0 ;0
L 1.89393996 -1.91213002 1.89383002 -1.91216004 0 P 0 ;0
L 1.89383002 -1.91216004 1.89225 -1.91268996 0 P 0 ;0
L 1.89225 -1.91268996 1.89218002 -1.91271998 0 P 0 ;0
L 1.89218002 -1.91271998 1.89211004 -1.91273996 0 P 0 ;0
L 1.89211004 -1.91273996 1.8921 -1.91273996 0 P 0 ;0
L 1.8921 -1.91273996 1.89058002 -1.91338996 0 P 0 ;0
L 1.89058002 -1.91338996 1.89043996 -1.91345 0 P 0 ;0
L 1.89043996 -1.91345 1.88896004 -1.91421004 0 P 0 ;0
L 1.88896004 -1.91421004 1.88893002 -1.91423002 0 P 0 ;0
L 1.88893002 -1.91423002 1.8889 -1.91423996 0 P 0 ;0
L 1.8889 -1.91423996 1.88886004 -1.91426004 0 P 0 ;0
L 1.88886004 -1.91426004 1.88883002 -1.91428002 0 P 0 ;0
L 1.88883002 -1.91428002 1.88741004 -1.91515 0 P 0 ;0
L 1.88741004 -1.91515 1.88733996 -1.91518996 0 P 0 ;0
L 1.88733996 -1.91518996 1.88728002 -1.91523996 0 P 0 ;0
L 1.88728002 -1.91523996 1.88526004 -1.9167 0 P 0 ;0
L 1.88526004 -1.9167 1.88521998 -1.91673002 0 P 0 ;0
L 1.88521998 -1.91673002 1.88518996 -1.91675 0 P 0 ;0
L 1.88518996 -1.91675 1.88516004 -1.91678002 0 P 0 ;0
L 1.88516004 -1.91678002 1.88511998 -1.91681004 0 P 0 ;0
L 1.88511998 -1.91681004 1.88323002 -1.91845 0 P 0 ;0
L 1.88323002 -1.91845 1.8832 -1.91846998 0 P 0 ;0
L 1.8832 -1.91846998 1.88311004 -1.91856004 0 P 0 ;0
L 1.88311004 -1.91856004 1.88136998 -1.92036004 0 P 0 ;0
L 1.88136998 -1.92036004 1.88128002 -1.92045 0 P 0 ;0
L 1.88128002 -1.92045 1.88125 -1.92048996 0 P 0 ;0
L 1.88125 -1.92048996 1.87968002 -1.92241998 0 P 0 ;0
L 1.87968002 -1.92241998 1.87965 -1.92245 0 P 0 ;0
L 1.87965 -1.92245 1.87961998 -1.92248996 0 P 0 ;0
L 1.87961998 -1.92248996 1.87956998 -1.92256004 0 P 0 ;0
L 1.87956998 -1.92256004 1.87816998 -1.92461998 0 P 0 ;0
L 1.87816998 -1.92461998 1.8781 -1.92473002 0 P 0 ;0
L 1.8781 -1.92473002 1.87808002 -1.92476998 0 P 0 ;0
L 1.87808002 -1.92476998 1.87685 -1.92695 0 P 0 ;0
L 1.87685 -1.92695 1.87683002 -1.92698996 0 P 0 ;0
L 1.87683002 -1.92698996 1.87681004 -1.92701998 0 P 0 ;0
L 1.87681004 -1.92701998 1.87678996 -1.92706998 0 P 0 ;0
L 1.87678996 -1.92706998 1.87676998 -1.92711004 0 P 0 ;0
L 1.87676998 -1.92711004 1.87573002 -1.92941004 0 P 0 ;0
L 1.87573002 -1.92941004 1.87571004 -1.92945 0 P 0 ;0
L 1.87571004 -1.92945 1.8757 -1.92948996 0 P 0 ;0
L 1.8757 -1.92948996 1.87568002 -1.92951998 0 P 0 ;0
L 1.87568002 -1.92951998 1.87566998 -1.92956998 0 P 0 ;0
L 1.87566998 -1.92956998 1.87483996 -1.93193002 0 P 0 ;0
L 1.87483996 -1.93193002 1.87481004 -1.93201004 0 P 0 ;0
L 1.87481004 -1.93201004 1.87478996 -1.93208996 0 P 0 ;0
L 1.87478996 -1.93208996 1.87416004 -1.93451998 0 P 0 ;0
L 1.87416004 -1.93451998 1.87413996 -1.93456004 0 P 0 ;0
L 1.87413996 -1.93456004 1.87413002 -1.9346 0 P 0 ;0
L 1.87413002 -1.9346 1.87413002 -1.93463996 0 P 0 ;0
L 1.87413002 -1.93463996 1.87411998 -1.93468002 0 P 0 ;0
L 1.87411998 -1.93468002 1.8737 -1.93715 0 P 0 ;0
L 1.8737 -1.93715 1.87368996 -1.93718996 0 P 0 ;0
L 1.87368996 -1.93718996 1.87368002 -1.93723996 0 P 0 ;0
L 1.87368002 -1.93723996 1.87368002 -1.93731998 0 P 0 ;0
L 1.87368002 -1.93731998 1.87346998 -1.93981998 0 P 0 ;0
L 1.87346998 -1.93981998 1.87346004 -1.93986004 0 P 0 ;0
L 1.87346004 -1.93986004 1.87346004 -1.94258002 0 P 0 ;0
L 1.87346004 -1.94258002 1.87346998 -1.94266004 0 P 0 ;0
L 1.87346998 -1.94266004 1.87368002 -1.94516998 0 P 0 ;0
L 1.87368002 -1.94516998 1.87368996 -1.94521004 0 P 0 ;0
L 1.87368996 -1.94521004 1.87368996 -1.94525 0 P 0 ;0
L 1.87368996 -1.94525 1.87371004 -1.94533996 0 P 0 ;0
L 1.87371004 -1.94533996 1.87413996 -1.94778996 0 P 0 ;0
L 1.87413996 -1.94778996 1.87413996 -1.94783996 0 P 0 ;0
L 1.87413996 -1.94783996 1.87416998 -1.94796004 0 P 0 ;0
L 1.87416998 -1.94796004 1.87481004 -1.95036998 0 P 0 ;0
L 1.87481004 -1.95036998 1.87483996 -1.95048996 0 P 0 ;0
L 1.87483996 -1.95048996 1.87486004 -1.95053002 0 P 0 ;0
L 1.87486004 -1.95053002 1.8757 -1.95288002 0 P 0 ;0
L 1.8757 -1.95288002 1.87571004 -1.95291998 0 P 0 ;0
L 1.87571004 -1.95291998 1.87575 -1.953 0 P 0 ;0
L 1.87575 -1.953 1.87576004 -1.95303996 0 P 0 ;0
L 1.87576004 -1.95303996 1.8768 -1.9553 0 P 0 ;0
L 1.8768 -1.9553 1.87686004 -1.95541998 0 P 0 ;0
L 1.87686004 -1.95541998 1.87688002 -1.95545 0 P 0 ;0
L 1.87688002 -1.95545 1.8781 -1.95761004 0 P 0 ;0
L 1.8781 -1.95761004 1.87811998 -1.95761004 0 P 0 ;0
L 1.87811998 -1.95761004 1.8781 -1.95761998 0 P 0 ;0
L 1.8781 -1.95761998 1.87813996 -1.95768996 0 P 0 ;0
L 1.87813996 -1.95768996 1.87816998 -1.95771998 0 P 0 ;0
L 1.87816998 -1.95771998 1.87818996 -1.95775 0 P 0 ;0
L 1.87818996 -1.95775 1.87938002 -1.95951004 0 P 0 ;0
L 1.87938002 -1.95951004 1.87943996 -1.9596 0 P 0 ;0
L 1.87943996 -1.9596 1.87946998 -1.95963002 0 P 0 ;0
L 1.87946998 -1.95963002 1.88078002 -1.96128996 0 P 0 ;0
L 1.88078002 -1.96128996 1.88081004 -1.96131998 0 P 0 ;0
L 1.88081004 -1.96131998 1.88083002 -1.96135 0 P 0 ;0
L 1.88083002 -1.96135 1.88086004 -1.96136998 0 P 0 ;0
L 1.88086004 -1.96136998 1.88088002 -1.9614 0 P 0 ;0
L 1.88088002 -1.9614 1.88231998 -1.96295 0 P 0 ;0
L 1.88231998 -1.96295 1.88233996 -1.96298002 0 P 0 ;0
L 1.88233996 -1.96298002 1.8824 -1.96303996 0 P 0 ;0
L 1.8824 -1.96303996 1.88243002 -1.96306004 0 P 0 ;0
L 1.88243002 -1.96306004 1.88398002 -1.9645 0 P 0 ;0
L 1.88398002 -1.9645 1.88401004 -1.96451998 0 P 0 ;0
L 1.88401004 -1.96451998 1.88403002 -1.96455 0 P 0 ;0
L 1.88403002 -1.96455 1.88406998 -1.96458002 0 P 0 ;0
L 1.88406998 -1.96458002 1.88408996 -1.9646 0 P 0 ;0
L 1.88408996 -1.9646 1.88575 -1.96591004 0 P 0 ;0
L 1.88575 -1.96591004 1.88578002 -1.96593996 0 P 0 ;0
L 1.88578002 -1.96593996 1.88586998 -1.966 0 P 0 ;0
L 1.88586998 -1.966 1.88761998 -1.96718996 0 P 0 ;0
L 1.88761998 -1.96718996 1.88766004 -1.96721004 0 P 0 ;0
L 1.88766004 -1.96721004 1.88775 -1.96726998 0 P 0 ;0
L 1.88775 -1.96726998 1.88958996 -1.96831998 0 P 0 ;0
L 1.88958996 -1.96831998 1.88965 -1.96836004 0 P 0 ;0
L 1.88965 -1.96836004 1.88968002 -1.96836998 0 P 0 ;0
L 1.88968002 -1.96836998 1.88971998 -1.96838996 0 P 0 ;0
L 1.88971998 -1.96838996 1.89145 -1.96921998 0 P 0 ;0
L 1.89145 -1.96921998 1.89151004 -1.96925 0 P 0 ;0
L 1.89151004 -1.96925 1.89155 -1.96926004 0 P 0 ;0
L 1.89155 -1.96926004 1.89158002 -1.96926998 0 P 0 ;0
L 1.89158002 -1.96926998 1.89336004 -1.96996998 0 P 0 ;0
L 1.89336004 -1.96996998 1.89336004 -1.96998002 0 P 0 ;0
L 1.89336004 -1.96998002 1.89346004 -1.97001004 0 P 0 ;0
L 1.89346004 -1.97001004 1.89348996 -1.97001998 0 P 0 ;0
L 1.89348996 -1.97001998 1.89531998 -1.9706 0 P 0 ;0
L 1.89531998 -1.9706 1.89536004 -1.97061004 0 P 0 ;0
L 1.89536004 -1.97061004 1.89541998 -1.97063002 0 P 0 ;0
L 1.89541998 -1.97063002 1.89546004 -1.97063002 0 P 0 ;0
L 1.89546004 -1.97063002 1.89731998 -1.97108002 0 P 0 ;0
L 1.89731998 -1.97108002 1.89741998 -1.9711 0 P 0 ;0
L 1.89741998 -1.9711 1.89746004 -1.9711 0 P 0 ;0
L 1.89746004 -1.9711 1.89746004 -1.97111004 0 P 0 ;0
L 1.89746004 -1.97111004 1.89933996 -1.97141998 0 P 0 ;0
L 1.89933996 -1.97141998 1.89936998 -1.97143002 0 P 0 ;0
L 1.89936998 -1.97143002 1.89941004 -1.97143002 0 P 0 ;0
L 1.89941004 -1.97143002 1.89945 -1.97143996 0 P 0 ;0
L 1.89945 -1.97143996 1.89948002 -1.97143996 0 P 0 ;0
L 1.89948002 -1.97143996 1.90201004 -1.97168002 0 P 0 ;0
L 1.90201004 -1.97168002 1.90205 -1.97168002 0 P 0 ;0
L 1.90205 -1.97168002 1.90208996 -1.97168996 0 P 0 ;0
L 1.90208996 -1.97168996 1.90216004 -1.97168996 0 P 0 ;0
L 1.90216004 -1.97168996 1.90468996 -1.97173996 0 P 0 ;0
L 1.90468996 -1.97173996 1.90476004 -1.97173996 0 P 0 ;0
L 1.80616004 -2.12823996 1.83348996 -2.12823996 0 P 0 ;0
L 1.79591998 -2.12723996 1.8396 -2.12723996 0 P 0 ;0
L 1.78818002 -2.12623996 1.84465 -2.12623996 0 P 0 ;0
L 1.82003996 -2.09123996 1.87618996 -2.09123996 0 P 0 ;0
L 1.82198996 -2.09023996 1.8762 -2.09023996 0 P 0 ;0
L 1.82325 -2.08923996 1.8762 -2.08923996 0 P 0 ;0
L 1.82411998 -2.08823996 1.87618996 -2.08823996 0 P 0 ;0
L 1.82463002 -2.08723996 1.87616998 -2.08723996 0 P 0 ;0
L 1.82488002 -2.08623996 1.87615 -2.08623996 0 P 0 ;0
L 1.82493002 -2.08523996 1.87613002 -2.08523996 0 P 0 ;0
L 1.82476998 -2.08423996 1.87611004 -2.08423996 0 P 0 ;0
L 1.64846004 -2.08295 1.73316998 -2.08295 0 P 0 ;0
L 1.64811998 -2.08195 1.73356998 -2.08195 0 P 0 ;0
L 1.64776998 -2.08095 1.73398002 -2.08095 0 P 0 ;0
L 1.64743002 -2.07995 1.73438002 -2.07995 0 P 0 ;0
L 1.64708996 -2.07895 1.73478996 -2.07895 0 P 0 ;0
L 1.64673996 -2.07795 1.7352 -2.07795 0 P 0 ;0
L 1.6464 -2.07695 1.7356 -2.07695 0 P 0 ;0
L 1.64605 -2.07595 1.73601004 -2.07595 0 P 0 ;0
L 1.64571004 -2.07495 1.73641004 -2.07495 0 P 0 ;0
L 1.64536004 -2.07395 1.73681004 -2.07395 0 P 0 ;0
L 1.64501998 -2.07295 1.73721998 -2.07295 0 P 0 ;0
L 1.64466998 -2.07195 1.73761998 -2.07195 0 P 0 ;0
L 1.64433002 -2.07095 1.73803002 -2.07095 0 P 0 ;0
L 1.64398002 -2.06995 1.69251004 -2.06995 0 P 0 ;0
L 1.69583002 -2.06995 1.73843996 -2.06995 0 P 0 ;0
L 1.64363002 -2.06895 1.69168002 -2.06895 0 P 0 ;0
L 1.69671998 -2.06895 1.73883996 -2.06895 0 P 0 ;0
L 1.64328996 -2.06795 1.69136004 -2.06795 0 P 0 ;0
L 1.69708996 -2.06795 1.73925 -2.06795 0 P 0 ;0
L 1.64293996 -2.06695 1.69108002 -2.06695 0 P 0 ;0
L 1.69738002 -2.06695 1.73965 -2.06695 0 P 0 ;0
L 1.64258996 -2.06595 1.6908 -2.06595 0 P 0 ;0
L 1.69768002 -2.06595 1.74006004 -2.06595 0 P 0 ;0
L 1.64223996 -2.06495 1.69051998 -2.06495 0 P 0 ;0
L 1.69796998 -2.06495 1.74046004 -2.06495 0 P 0 ;0
L 1.6419 -2.06395 1.69023002 -2.06395 0 P 0 ;0
L 1.69826998 -2.06395 1.74086004 -2.06395 0 P 0 ;0
L 1.64155 -2.06295 1.68996004 -2.06295 0 P 0 ;0
L 1.69856004 -2.06295 1.74126998 -2.06295 0 P 0 ;0
L 1.6412 -2.06195 1.68966998 -2.06195 0 P 0 ;0
L 1.69886004 -2.06195 1.74168002 -2.06195 0 P 0 ;0
L 1.64085 -2.06095 1.68938996 -2.06095 0 P 0 ;0
L 1.69915 -2.06095 1.74208002 -2.06095 0 P 0 ;0
L 1.6405 -2.05995 1.68911004 -2.05995 0 P 0 ;0
L 1.69945 -2.05995 1.74248002 -2.05995 0 P 0 ;0
L 1.64016004 -2.05895 1.68883002 -2.05895 0 P 0 ;0
L 1.69973996 -2.05895 1.74288996 -2.05895 0 P 0 ;0
L 1.63981004 -2.05795 1.68855 -2.05795 0 P 0 ;0
L 1.70003996 -2.05795 1.74328996 -2.05795 0 P 0 ;0
L 1.63946004 -2.05695 1.68826998 -2.05695 0 P 0 ;0
L 1.70033002 -2.05695 1.7437 -2.05695 0 P 0 ;0
L 1.63911004 -2.05595 1.68798996 -2.05595 0 P 0 ;0
L 1.70063002 -2.05595 1.7441 -2.05595 0 P 0 ;0
L 1.63876998 -2.05495 1.68771004 -2.05495 0 P 0 ;0
L 1.70091998 -2.05495 1.74451004 -2.05495 0 P 0 ;0
L 1.63841998 -2.05395 1.68741998 -2.05395 0 P 0 ;0
L 1.70121998 -2.05395 1.74491004 -2.05395 0 P 0 ;0
L 1.63806998 -2.05295 1.68713996 -2.05295 0 P 0 ;0
L 1.70151004 -2.05295 1.74531004 -2.05295 0 P 0 ;0
L 1.63771998 -2.05195 1.68686004 -2.05195 0 P 0 ;0
L 1.70181004 -2.05195 1.74571998 -2.05195 0 P 0 ;0
L 1.63738002 -2.05095 1.68658002 -2.05095 0 P 0 ;0
L 1.7021 -2.05095 1.74611998 -2.05095 0 P 0 ;0
L 1.63703002 -2.04995 1.6863 -2.04995 0 P 0 ;0
L 1.7024 -2.04995 1.74653002 -2.04995 0 P 0 ;0
L 1.63668002 -2.04895 1.68601998 -2.04895 0 P 0 ;0
L 1.70268996 -2.04895 1.74693002 -2.04895 0 P 0 ;0
L 1.63633002 -2.04795 1.68573996 -2.04795 0 P 0 ;0
L 1.70298996 -2.04795 1.74733002 -2.04795 0 P 0 ;0
L 1.63598002 -2.04695 1.68546004 -2.04695 0 P 0 ;0
L 1.70328002 -2.04695 1.74773996 -2.04695 0 P 0 ;0
L 1.63563996 -2.04595 1.68518002 -2.04595 0 P 0 ;0
L 1.70358002 -2.04595 1.74813996 -2.04595 0 P 0 ;0
L 1.63528996 -2.04495 1.6849 -2.04495 0 P 0 ;0
L 1.70386998 -2.04495 1.74855 -2.04495 0 P 0 ;0
L 1.63493996 -2.04395 1.68461004 -2.04395 0 P 0 ;0
L 1.70416998 -2.04395 1.74895 -2.04395 0 P 0 ;0
L 1.63458996 -2.04295 1.68433002 -2.04295 0 P 0 ;0
L 1.70446004 -2.04295 1.74936004 -2.04295 0 P 0 ;0
L 1.63425 -2.04195 1.68405 -2.04195 0 P 0 ;0
L 1.70475 -2.04195 1.74976004 -2.04195 0 P 0 ;0
L 1.6339 -2.04095 1.68376998 -2.04095 0 P 0 ;0
L 1.70503002 -2.04095 1.75016004 -2.04095 0 P 0 ;0
L 1.63355 -2.03995 1.68348996 -2.03995 0 P 0 ;0
L 1.70531998 -2.03995 1.75056998 -2.03995 0 P 0 ;0
L 1.6332 -2.03895 1.68321004 -2.03895 0 P 0 ;0
L 1.7056 -2.03895 1.75096998 -2.03895 0 P 0 ;0
L 1.63286004 -2.03795 1.68293002 -2.03795 0 P 0 ;0
L 1.70588996 -2.03795 1.75138002 -2.03795 0 P 0 ;0
L 1.63251004 -2.03695 1.68266004 -2.03695 0 P 0 ;0
L 1.70618002 -2.03695 1.75178002 -2.03695 0 P 0 ;0
L 1.63216004 -2.03595 1.68238002 -2.03595 0 P 0 ;0
L 1.70646998 -2.03595 1.75218996 -2.03595 0 P 0 ;0
L 1.63181004 -2.03495 1.6821 -2.03495 0 P 0 ;0
L 1.70675 -2.03495 1.75258996 -2.03495 0 P 0 ;0
L 1.63146998 -2.03395 1.68183002 -2.03395 0 P 0 ;0
L 1.70703996 -2.03395 1.75298996 -2.03395 0 P 0 ;0
L 1.63111998 -2.03295 1.68155 -2.03295 0 P 0 ;0
L 1.70733002 -2.03295 1.7534 -2.03295 0 P 0 ;0
L 1.63076998 -2.03195 1.68126998 -2.03195 0 P 0 ;0
L 1.70761004 -2.03195 1.75381004 -2.03195 0 P 0 ;0
L 1.63041998 -2.03095 1.68098996 -2.03095 0 P 0 ;0
L 1.7079 -2.03095 1.75421004 -2.03095 0 P 0 ;0
L 1.63006998 -2.02995 1.68071004 -2.02995 0 P 0 ;0
L 1.70818996 -2.02995 1.75461004 -2.02995 0 P 0 ;0
L 1.62973002 -2.02895 1.68043996 -2.02895 0 P 0 ;0
L 1.70846998 -2.02895 1.75501998 -2.02895 0 P 0 ;0
L 1.62938002 -2.02795 1.68016004 -2.02795 0 P 0 ;0
L 1.70876004 -2.02795 1.75541998 -2.02795 0 P 0 ;0
L 1.62903002 -2.02695 1.67988002 -2.02695 0 P 0 ;0
L 1.70905 -2.02695 1.75583002 -2.02695 0 P 0 ;0
L 1.62868002 -2.02595 1.6796 -2.02595 0 P 0 ;0
L 1.70933996 -2.02595 1.75623002 -2.02595 0 P 0 ;0
L 1.62831004 -2.02495 1.67933002 -2.02495 0 P 0 ;0
L 1.70961998 -2.02495 1.75663996 -2.02495 0 P 0 ;0
L 1.62793996 -2.02395 1.67905 -2.02395 0 P 0 ;0
L 1.70991004 -2.02395 1.75703996 -2.02395 0 P 0 ;0
L 1.62756998 -2.02295 1.67876998 -2.02295 0 P 0 ;0
L 1.7102 -2.02295 1.75743996 -2.02295 0 P 0 ;0
L 1.6272 -2.02195 1.6785 -2.02195 0 P 0 ;0
L 1.71048002 -2.02195 1.75785 -2.02195 0 P 0 ;0
L 1.62683002 -2.02095 1.67821998 -2.02095 0 P 0 ;0
L 1.71076004 -2.02095 1.75825 -2.02095 0 P 0 ;0
L 1.62646998 -2.01995 1.67793996 -2.01995 0 P 0 ;0
L 1.71101004 -2.01995 1.75866004 -2.01995 0 P 0 ;0
L 1.6261 -2.01895 1.67766004 -2.01895 0 P 0 ;0
L 1.71126998 -2.01895 1.75906004 -2.01895 0 P 0 ;0
L 1.62573002 -2.01795 1.67738996 -2.01795 0 P 0 ;0
L 1.71151998 -2.01795 1.75946998 -2.01795 0 P 0 ;0
L 1.62536004 -2.01695 1.67711004 -2.01695 0 P 0 ;0
L 1.71176998 -2.01695 1.75986998 -2.01695 0 P 0 ;0
L 1.62498996 -2.01595 1.67683002 -2.01595 0 P 0 ;0
L 1.71203002 -2.01595 1.76026998 -2.01595 0 P 0 ;0
L 1.62461998 -2.01495 1.67656004 -2.01495 0 P 0 ;0
L 1.71228002 -2.01495 1.76068002 -2.01495 0 P 0 ;0
L 1.62425 -2.01395 1.67628002 -2.01395 0 P 0 ;0
L 1.71253996 -2.01395 1.76108002 -2.01395 0 P 0 ;0
L 1.62388002 -2.01295 1.67601998 -2.01295 0 P 0 ;0
L 1.71278996 -2.01295 1.76148996 -2.01295 0 P 0 ;0
L 1.62351004 -2.01195 1.67576998 -2.01195 0 P 0 ;0
L 1.71305 -2.01195 1.76188996 -2.01195 0 P 0 ;0
L 1.62313996 -2.01095 1.67551998 -2.01095 0 P 0 ;0
L 1.7133 -2.01095 1.76228996 -2.01095 0 P 0 ;0
L 1.62276998 -2.00995 1.67528002 -2.00995 0 P 0 ;0
L 1.71355 -2.00995 1.7627 -2.00995 0 P 0 ;0
L 1.6224 -2.00895 1.67503002 -2.00895 0 P 0 ;0
L 1.71381004 -2.00895 1.7631 -2.00895 0 P 0 ;0
L 1.62203002 -2.00795 1.67478996 -2.00795 0 P 0 ;0
L 1.71406004 -2.00795 1.76351004 -2.00795 0 P 0 ;0
L 1.62166004 -2.00695 1.67453996 -2.00695 0 P 0 ;0
L 1.71431004 -2.00695 1.76391004 -2.00695 0 P 0 ;0
L 1.62128996 -2.00595 1.67428996 -2.00595 0 P 0 ;0
L 1.71453996 -2.00595 1.76431998 -2.00595 0 P 0 ;0
L 1.62091004 -2.00495 1.67405 -2.00495 0 P 0 ;0
L 1.71476998 -2.00495 1.76471998 -2.00495 0 P 0 ;0
L 1.62051998 -2.00395 1.6738 -2.00395 0 P 0 ;0
L 1.715 -2.00395 1.76511998 -2.00395 0 P 0 ;0
L 1.62013002 -2.00295 1.67355 -2.00295 0 P 0 ;0
L 1.71523002 -2.00295 1.76553002 -2.00295 0 P 0 ;0
L 1.61973996 -2.00195 1.67331004 -2.00195 0 P 0 ;0
L 1.71546004 -2.00195 1.76593996 -2.00195 0 P 0 ;0
L 1.61935 -2.00095 1.67306004 -2.00095 0 P 0 ;0
L 1.71568996 -2.00095 1.76633996 -2.00095 0 P 0 ;0
L 1.61896004 -1.99995 1.67283996 -1.99995 0 P 0 ;0
L 1.71591998 -1.99995 1.76673996 -1.99995 0 P 0 ;0
L 1.61856998 -1.99895 1.67261998 -1.99895 0 P 0 ;0
L 1.71613996 -1.99895 1.76715 -1.99895 0 P 0 ;0
L 1.71638002 -1.99795 1.76755 -1.99795 0 P 0 ;0
L 1.7166 -1.99695 1.76796004 -1.99695 0 P 0 ;0
L 1.71683002 -1.99595 1.76836004 -1.99595 0 P 0 ;0
L 1.71866998 -1.99495 1.76876998 -1.99495 0 P 0 ;0
L 1.78213996 -2.04823996 1.84641998 -2.04823996 0 P 0 ;0
L 1.78138002 -2.04723996 1.84498996 -2.04723996 0 P 0 ;0
L 1.78071004 -2.04623996 1.84356004 -2.04623996 0 P 0 ;0
L 1.7801 -2.04523996 1.84213996 -2.04523996 0 P 0 ;0
L 1.77956004 -2.04423996 1.84071004 -2.04423996 0 P 0 ;0
L 1.77908996 -2.04323996 1.83928002 -2.04323996 0 P 0 ;0
L 1.77866004 -2.04223996 1.83786004 -2.04223996 0 P 0 ;0
L 1.77831004 -2.04123996 1.83658996 -2.04123996 0 P 0 ;0
L 1.77796004 -2.04023996 1.83536004 -2.04023996 0 P 0 ;0
L 1.77761004 -2.03923996 1.83428002 -2.03923996 0 P 0 ;0
L 1.77733996 -2.03823996 1.83321998 -2.03823996 0 P 0 ;0
L 1.77706998 -2.03723996 1.83236998 -2.03723996 0 P 0 ;0
L 1.7768 -2.03623996 1.83171004 -2.03623996 0 P 0 ;0
L 1.7766 -2.03523996 1.83121004 -2.03523996 0 P 0 ;0
L 1.77641004 -2.03423996 1.83085 -2.03423996 0 P 0 ;0
L 1.77621004 -2.03323996 1.83071004 -2.03323996 0 P 0 ;0
L 1.77608002 -2.03223996 1.83076998 -2.03223996 0 P 0 ;0
L 1.77596004 -2.03123996 1.83106004 -2.03123996 0 P 0 ;0
L 1.77583996 -2.03023996 1.83158996 -2.03023996 0 P 0 ;0
L 1.77576004 -2.02923996 1.83238002 -2.02923996 0 P 0 ;0
L 1.7757 -2.02823996 1.83356998 -2.02823996 0 P 0 ;0
L 1.7757 -2.02723996 1.83591998 -2.02723996 0 P 0 ;0
L 1.77571998 -2.02623996 1.87495 -2.02623996 0 P 0 ;0
L 1.7758 -2.02523996 1.87485 -2.02523996 0 P 0 ;0
L 1.77588996 -2.02423996 1.87475 -2.02423996 0 P 0 ;0
L 1.77605 -2.02323996 1.87465 -2.02323996 0 P 0 ;0
L 1.77621004 -2.02223996 1.87455 -2.02223996 0 P 0 ;0
L 1.7764 -2.02123996 1.87445 -2.02123996 0 P 0 ;0
L 1.77665 -2.02023996 1.87433996 -2.02023996 0 P 0 ;0
L 1.7769 -2.01923996 1.87425 -2.01923996 0 P 0 ;0
L 1.7772 -2.01823996 1.87413996 -2.01823996 0 P 0 ;0
L 1.77753002 -2.01723996 1.87405 -2.01723996 0 P 0 ;0
L 1.77786004 -2.01623996 1.87393996 -2.01623996 0 P 0 ;0
L 1.77823002 -2.01523996 1.87383996 -2.01523996 0 P 0 ;0
L 1.77863996 -2.01423996 1.87373996 -2.01423996 0 P 0 ;0
L 1.77903996 -2.01323996 1.87363996 -2.01323996 0 P 0 ;0
L 1.7795 -2.01223996 1.87353996 -2.01223996 0 P 0 ;0
L 1.77998996 -2.01123996 1.87343996 -2.01123996 0 P 0 ;0
L 1.78046998 -2.01023996 1.87333002 -2.01023996 0 P 0 ;0
L 1.78103996 -2.00923996 1.87323002 -2.00923996 0 P 0 ;0
L 1.78161004 -2.00823996 1.87311998 -2.00823996 0 P 0 ;0
L 1.78221004 -2.00723996 1.87301998 -2.00723996 0 P 0 ;0
L 1.78288002 -2.00623996 1.87291998 -2.00623996 0 P 0 ;0
L 1.64213996 -2.14795 1.70566004 -2.14795 0 P 0 ;0
L 1.64518996 -2.14695 1.7062 -2.14695 0 P 0 ;0
L 1.64728996 -2.14595 1.70673996 -2.14595 0 P 0 ;0
L 1.64906998 -2.14495 1.70728002 -2.14495 0 P 0 ;0
L 1.65058002 -2.14395 1.70783002 -2.14395 0 P 0 ;0
L 1.6519 -2.14295 1.70836998 -2.14295 0 P 0 ;0
L 1.65311998 -2.14195 1.70881998 -2.14195 0 P 0 ;0
L 1.65416998 -2.14095 1.70926998 -2.14095 0 P 0 ;0
L 1.65508996 -2.13995 1.70973002 -2.13995 0 P 0 ;0
L 1.65588002 -2.13895 1.71018002 -2.13895 0 P 0 ;0
L 1.65658002 -2.13795 1.71063002 -2.13795 0 P 0 ;0
L 1.65726998 -2.13695 1.71108996 -2.13695 0 P 0 ;0
L 1.65791998 -2.13595 1.71153996 -2.13595 0 P 0 ;0
L 1.65853002 -2.13495 1.71198996 -2.13495 0 P 0 ;0
L 1.65913002 -2.13395 1.71245 -2.13395 0 P 0 ;0
L 1.65968002 -2.13295 1.7129 -2.13295 0 P 0 ;0
L 1.66021998 -2.13195 1.71331004 -2.13195 0 P 0 ;0
L 1.66071998 -2.13095 1.71371998 -2.13095 0 P 0 ;0
L 1.66121004 -2.12995 1.71411998 -2.12995 0 P 0 ;0
L 1.66166998 -2.12895 1.71453002 -2.12895 0 P 0 ;0
L 1.66201004 -2.12795 1.71493996 -2.12795 0 P 0 ;0
L 1.66223996 -2.12695 1.71533996 -2.12695 0 P 0 ;0
L 1.66235 -2.12595 1.71575 -2.12595 0 P 0 ;0
L 1.66236004 -2.12495 1.71615 -2.12495 0 P 0 ;0
L 1.66228002 -2.12395 1.71656004 -2.12395 0 P 0 ;0
L 1.66211998 -2.12295 1.71696004 -2.12295 0 P 0 ;0
L 1.66188002 -2.12195 1.71736004 -2.12195 0 P 0 ;0
L 1.66156004 -2.12095 1.71776998 -2.12095 0 P 0 ;0
L 1.66121004 -2.11995 1.71818002 -2.11995 0 P 0 ;0
L 1.66086998 -2.11895 1.71858002 -2.11895 0 P 0 ;0
L 1.66053002 -2.11795 1.71898996 -2.11795 0 P 0 ;0
L 1.66018002 -2.11695 1.71938996 -2.11695 0 P 0 ;0
L 1.65983996 -2.11595 1.7198 -2.11595 0 P 0 ;0
L 1.65948996 -2.11495 1.7202 -2.11495 0 P 0 ;0
L 1.65913996 -2.11395 1.72061004 -2.11395 0 P 0 ;0
L 1.6588 -2.11295 1.72101004 -2.11295 0 P 0 ;0
L 1.65846004 -2.11195 1.72141998 -2.11195 0 P 0 ;0
L 1.65811004 -2.11095 1.72181998 -2.11095 0 P 0 ;0
L 1.65776998 -2.10995 1.72223002 -2.10995 0 P 0 ;0
L 1.65741998 -2.10895 1.72263002 -2.10895 0 P 0 ;0
L 1.65708002 -2.10795 1.72303996 -2.10795 0 P 0 ;0
L 1.65673002 -2.10695 1.72343996 -2.10695 0 P 0 ;0
L 1.65638996 -2.10595 1.72385 -2.10595 0 P 0 ;0
L 1.65605 -2.10495 1.72425 -2.10495 0 P 0 ;0
L 1.6557 -2.10395 1.72466004 -2.10395 0 P 0 ;0
L 1.65536004 -2.10295 1.72506998 -2.10295 0 P 0 ;0
L 1.65501004 -2.10195 1.72546998 -2.10195 0 P 0 ;0
L 1.65466998 -2.10095 1.72588002 -2.10095 0 P 0 ;0
L 1.65431998 -2.09995 1.72628002 -2.09995 0 P 0 ;0
L 1.65398002 -2.09895 1.72668996 -2.09895 0 P 0 ;0
L 1.65363002 -2.09795 1.72708996 -2.09795 0 P 0 ;0
L 1.65328996 -2.09695 1.72748996 -2.09695 0 P 0 ;0
L 1.65293996 -2.09595 1.7279 -2.09595 0 P 0 ;0
L 1.6526 -2.09495 1.72831004 -2.09495 0 P 0 ;0
L 1.65225 -2.09395 1.72871004 -2.09395 0 P 0 ;0
L 1.65191004 -2.09295 1.72911998 -2.09295 0 P 0 ;0
L 1.65156998 -2.09195 1.72951998 -2.09195 0 P 0 ;0
L 1.65121998 -2.09095 1.72993002 -2.09095 0 P 0 ;0
L 1.65088002 -2.08995 1.73033002 -2.08995 0 P 0 ;0
L 1.65053002 -2.08895 1.73073996 -2.08895 0 P 0 ;0
L 1.65018996 -2.08795 1.73113996 -2.08795 0 P 0 ;0
L 1.64983996 -2.08695 1.73155 -2.08695 0 P 0 ;0
L 1.6495 -2.08595 1.73195 -2.08595 0 P 0 ;0
L 1.64915 -2.08495 1.73236004 -2.08495 0 P 0 ;0
L 1.64881004 -2.08395 1.73276004 -2.08395 0 P 0 ;0
L 1.81726998 -1.98915 1.81196004 -1.9899 0 P 0 ;0
L 1.81196004 -1.9899 1.80668996 -1.99096998 0 P 0 ;0
L 1.80668996 -1.99096998 1.8019 -1.99226004 0 P 0 ;0
L 1.8019 -1.99226004 1.79718996 -1.99391004 0 P 0 ;0
L 1.79718996 -1.99391004 1.79316004 -1.99568002 0 P 0 ;0
L 1.79316004 -1.99568002 1.78926998 -1.99778002 0 P 0 ;0
L 1.78926998 -1.99778002 1.78771004 -1.99878002 0 P 0 ;0
L 1.78771004 -1.99878002 1.78623002 -1.99988002 0 P 0 ;0
L 1.78623002 -1.99988002 1.78481004 -2.00108002 0 P 0 ;0
L 1.78481004 -2.00108002 1.78346998 -2.00238996 0 P 0 ;0
L 1.78346998 -2.00238996 1.78228996 -2.00371998 0 P 0 ;0
L 1.78228996 -2.00371998 1.78121004 -2.00513002 0 P 0 ;0
L 1.78121004 -2.00513002 1.78023002 -2.00661004 0 P 0 ;0
L 1.78023002 -2.00661004 1.77868002 -2.00933996 0 P 0 ;0
L 1.77868002 -2.00933996 1.77731998 -2.01216998 0 P 0 ;0
L 1.77731998 -2.01216998 1.77611004 -2.01516004 0 P 0 ;0
L 1.77611004 -2.01516004 1.77508996 -2.01823002 0 P 0 ;0
L 1.77508996 -2.01823002 1.77436998 -2.02111004 0 P 0 ;0
L 1.77436998 -2.02111004 1.77388996 -2.02406004 0 P 0 ;0
L 1.77388996 -2.02406004 1.77371998 -2.02603996 0 P 0 ;0
L 1.77371998 -2.02603996 1.77368996 -2.02801998 0 P 0 ;0
L 1.77368996 -2.02801998 1.7738 -2.03001998 0 P 0 ;0
L 1.7738 -2.03001998 1.7742 -2.03338996 0 P 0 ;0
L 1.7742 -2.03338996 1.77485 -2.03671004 0 P 0 ;0
L 1.77485 -2.03671004 1.77573002 -2.03993996 0 P 0 ;0
L 1.77573002 -2.03993996 1.77683996 -2.04308002 0 P 0 ;0
L 1.77683996 -2.04308002 1.7776 -2.04481998 0 P 0 ;0
L 1.7776 -2.04481998 1.7785 -2.04648996 0 P 0 ;0
L 1.7785 -2.04648996 1.77953002 -2.04808996 0 P 0 ;0
L 1.77953002 -2.04808996 1.78061004 -2.04953996 0 P 0 ;0
L 1.78061004 -2.04953996 1.78181004 -2.05091004 0 P 0 ;0
L 1.78181004 -2.05091004 1.78311004 -2.05218996 0 P 0 ;0
L 1.78311004 -2.05218996 1.78988996 -2.05801998 0 P 0 ;0
L 1.78988996 -2.05801998 1.79883996 -2.06491004 0 P 0 ;0
L 1.79883996 -2.06491004 1.80976998 -2.07261004 0 P 0 ;0
L 1.80976998 -2.07261004 1.81753002 -2.07823002 0 P 0 ;0
L 1.81753002 -2.07823002 1.81896998 -2.07943002 0 P 0 ;0
L 1.81896998 -2.07943002 1.82033002 -2.08073002 0 P 0 ;0
L 1.82033002 -2.08073002 1.82156998 -2.08213996 0 P 0 ;0
L 1.82156998 -2.08213996 1.82186004 -2.08251004 0 P 0 ;0
L 1.82186004 -2.08251004 1.82211004 -2.0829 0 P 0 ;0
L 1.82211004 -2.0829 1.82233002 -2.08331004 0 P 0 ;0
L 1.82233002 -2.08331004 1.82253002 -2.08373996 0 P 0 ;0
L 1.82253002 -2.08373996 1.82268002 -2.08418002 0 P 0 ;0
L 1.82268002 -2.08418002 1.82281004 -2.08463002 0 P 0 ;0
L 1.82281004 -2.08463002 1.8229 -2.0851 0 P 0 ;0
L 1.8229 -2.0851 1.82293002 -2.08533996 0 P 0 ;0
L 1.82293002 -2.08533996 1.82293996 -2.08558996 0 P 0 ;0
L 1.82293996 -2.08558996 1.82291998 -2.08583996 0 P 0 ;0
L 1.82291998 -2.08583996 1.82288002 -2.08608002 0 P 0 ;0
L 1.82288002 -2.08608002 1.82283002 -2.08631998 0 P 0 ;0
L 1.82283002 -2.08631998 1.82275 -2.08656004 0 P 0 ;0
L 1.82275 -2.08656004 1.82265 -2.08678996 0 P 0 ;0
L 1.82265 -2.08678996 1.82253996 -2.087 0 P 0 ;0
L 1.82253996 -2.087 1.8224 -2.08721004 0 P 0 ;0
L 1.8224 -2.08721004 1.82225 -2.08741004 0 P 0 ;0
L 1.82225 -2.08741004 1.82208996 -2.08758996 0 P 0 ;0
L 1.82208996 -2.08758996 1.8216 -2.08803996 0 P 0 ;0
L 1.8216 -2.08803996 1.82106998 -2.08845 0 P 0 ;0
L 1.82106998 -2.08845 1.82051004 -2.08881004 0 P 0 ;0
L 1.82051004 -2.08881004 1.81991998 -2.08911998 0 P 0 ;0
L 1.81991998 -2.08911998 1.81931004 -2.08936998 0 P 0 ;0
L 1.81931004 -2.08936998 1.81868002 -2.08958002 0 P 0 ;0
L 1.81868002 -2.08958002 1.81803002 -2.08973002 0 P 0 ;0
L 1.81803002 -2.08973002 1.81736004 -2.08981998 0 P 0 ;0
L 1.81736004 -2.08981998 1.81293002 -2.09001998 0 P 0 ;0
L 1.81293002 -2.09001998 1.80846998 -2.08986004 0 P 0 ;0
L 1.80846998 -2.08986004 1.80256998 -2.08923002 0 P 0 ;0
L 1.80256998 -2.08923002 1.79668002 -2.08818996 0 P 0 ;0
L 1.79668002 -2.08818996 1.78223002 -2.08458002 0 P 0 ;0
L 1.78223002 -2.08458002 1.77788996 -2.08338002 0 P 0 ;0
L 1.77788996 -2.08338002 1.77415 -2.08246004 0 P 0 ;0
L 1.77415 -2.08246004 1.77095 -2.08175 0 P 0 ;0
L 1.77095 -2.08175 1.7709 -2.08173996 0 P 0 ;0
L 1.7709 -2.08173996 1.77076998 -2.08173996 0 P 0 ;0
L 1.77076998 -2.08173996 1.77068996 -2.08176004 0 P 0 ;0
L 1.77068996 -2.08176004 1.77053002 -2.08183996 0 P 0 ;0
L 1.77053002 -2.08183996 1.77043002 -2.08193996 0 P 0 ;0
L 1.77043002 -2.08193996 1.77036998 -2.08201998 0 P 0 ;0
L 1.77036998 -2.08201998 1.77031998 -2.08211998 0 P 0 ;0
L 1.77031998 -2.08211998 1.7703 -2.08216998 0 P 0 ;0
L 1.7703 -2.08216998 1.77028996 -2.08223002 0 P 0 ;0
L 1.77028996 -2.08223002 1.77028002 -2.08228002 0 P 0 ;0
L 1.77028002 -2.08228002 1.77028002 -2.08238996 0 P 0 ;0
L 1.77028002 -2.08238996 1.77056998 -2.08838996 0 P 0 ;0
L 1.77056998 -2.08838996 1.77096004 -2.09526004 0 P 0 ;0
L 1.77096004 -2.09526004 1.77153996 -2.1033 0 P 0 ;0
L 1.77153996 -2.1033 1.77236004 -2.11291004 0 P 0 ;0
L 1.77236004 -2.11291004 1.77311004 -2.1194 0 P 0 ;0
L 1.77311004 -2.1194 1.77383002 -2.12398002 0 P 0 ;0
L 1.77383002 -2.12398002 1.77386004 -2.12411004 0 P 0 ;0
L 1.77386004 -2.12411004 1.7739 -2.12423002 0 P 0 ;0
L 1.7739 -2.12423002 1.77395 -2.12436004 0 P 0 ;0
L 1.77395 -2.12436004 1.77401004 -2.12448002 0 P 0 ;0
L 1.77401004 -2.12448002 1.77408002 -2.12458996 0 P 0 ;0
L 1.77408002 -2.12458996 1.77416004 -2.1247 0 P 0 ;0
L 1.77416004 -2.1247 1.77425 -2.1248 0 P 0 ;0
L 1.77425 -2.1248 1.77435 -2.12488996 0 P 0 ;0
L 1.77435 -2.12488996 1.77445 -2.12496998 0 P 0 ;0
L 1.77445 -2.12496998 1.77456998 -2.12505 0 P 0 ;0
L 1.77456998 -2.12505 1.77571004 -2.12568996 0 P 0 ;0
L 1.77571004 -2.12568996 1.7769 -2.12623996 0 P 0 ;0
L 1.7769 -2.12623996 1.77813002 -2.12668996 0 P 0 ;0
L 1.77813002 -2.12668996 1.7794 -2.12703996 0 P 0 ;0
L 1.7794 -2.12703996 1.78068996 -2.12728996 0 P 0 ;0
L 1.78068996 -2.12728996 1.79791998 -2.12951004 0 P 0 ;0
L 1.79791998 -2.12951004 1.81536004 -2.13106004 0 P 0 ;0
L 1.81536004 -2.13106004 1.82125 -2.13123996 0 P 0 ;0
L 1.82125 -2.13123996 1.82716004 -2.13098996 0 P 0 ;0
L 1.82716004 -2.13098996 1.83583996 -2.12998002 0 P 0 ;0
L 1.83583996 -2.12998002 1.84445 -2.12836004 0 P 0 ;0
L 1.84445 -2.12836004 1.84911998 -2.12711004 0 P 0 ;0
L 1.84911998 -2.12711004 1.85366004 -2.12548002 0 P 0 ;0
L 1.85366004 -2.12548002 1.85806998 -2.12348002 0 P 0 ;0
L 1.85806998 -2.12348002 1.86078996 -2.12196998 0 P 0 ;0
L 1.86078996 -2.12196998 1.8634 -2.12026998 0 P 0 ;0
L 1.8634 -2.12026998 1.86586998 -2.11836998 0 P 0 ;0
L 1.86586998 -2.11836998 1.86821004 -2.11628002 0 P 0 ;0
L 1.86821004 -2.11628002 1.87026004 -2.11413002 0 P 0 ;0
L 1.87026004 -2.11413002 1.8721 -2.11181998 0 P 0 ;0
L 1.8721 -2.11181998 1.87375 -2.10936004 0 P 0 ;0
L 1.87375 -2.10936004 1.87516998 -2.10673996 0 P 0 ;0
L 1.87516998 -2.10673996 1.87605 -2.10483996 0 P 0 ;0
L 1.87605 -2.10483996 1.87683996 -2.10291004 0 P 0 ;0
L 1.87683996 -2.10291004 1.8772 -2.10188002 0 P 0 ;0
L 1.8772 -2.10188002 1.87748996 -2.10083002 0 P 0 ;0
L 1.87748996 -2.10083002 1.87771004 -2.09976998 0 P 0 ;0
L 1.87771004 -2.09976998 1.87798002 -2.09788996 0 P 0 ;0
L 1.87798002 -2.09788996 1.87811998 -2.09601004 0 P 0 ;0
L 1.87811998 -2.09601004 1.87821004 -2.08966998 0 P 0 ;0
L 1.87821004 -2.08966998 1.8781 -2.08353996 0 P 0 ;0
L 1.8781 -2.08353996 1.87798002 -2.08166004 0 P 0 ;0
L 1.87798002 -2.08166004 1.87773002 -2.07976998 0 P 0 ;0
L 1.87773002 -2.07976998 1.87753002 -2.07873996 0 P 0 ;0
L 1.87753002 -2.07873996 1.87726998 -2.07773996 0 P 0 ;0
L 1.87726998 -2.07773996 1.87695 -2.07673996 0 P 0 ;0
L 1.87695 -2.07673996 1.87628996 -2.07505 0 P 0 ;0
L 1.87628996 -2.07505 1.87553002 -2.07338002 0 P 0 ;0
L 1.87553002 -2.07338002 1.87441004 -2.07133996 0 P 0 ;0
L 1.87441004 -2.07133996 1.87313996 -2.06938002 0 P 0 ;0
L 1.87313996 -2.06938002 1.87171004 -2.06751004 0 P 0 ;0
L 1.87171004 -2.06751004 1.8688 -2.06416004 0 P 0 ;0
L 1.8688 -2.06416004 1.86566998 -2.06095 0 P 0 ;0
L 1.86566998 -2.06095 1.86181998 -2.05741998 0 P 0 ;0
L 1.86181998 -2.05741998 1.85778002 -2.05406998 0 P 0 ;0
L 1.85778002 -2.05406998 1.84833996 -2.04715 0 P 0 ;0
L 1.84833996 -2.04715 1.83913996 -2.0407 0 P 0 ;0
L 1.83913996 -2.0407 1.83686004 -2.0389 0 P 0 ;0
L 1.83686004 -2.0389 1.83471998 -2.03691998 0 P 0 ;0
L 1.83471998 -2.03691998 1.83428002 -2.03643002 0 P 0 ;0
L 1.83428002 -2.03643002 1.83386998 -2.0359 0 P 0 ;0
L 1.83386998 -2.0359 1.83351004 -2.03535 0 P 0 ;0
L 1.83351004 -2.03535 1.83318996 -2.03476004 0 P 0 ;0
L 1.83318996 -2.03476004 1.83291998 -2.03415 0 P 0 ;0
L 1.83291998 -2.03415 1.83283996 -2.03393996 0 P 0 ;0
L 1.83283996 -2.03393996 1.83278002 -2.03371004 0 P 0 ;0
L 1.83278002 -2.03371004 1.83273002 -2.03348996 0 P 0 ;0
L 1.83273002 -2.03348996 1.83271004 -2.03326004 0 P 0 ;0
L 1.83271004 -2.03326004 1.8327 -2.03303002 0 P 0 ;0
L 1.8327 -2.03303002 1.83271004 -2.0328 0 P 0 ;0
L 1.83271004 -2.0328 1.83275 -2.03258002 0 P 0 ;0
L 1.83275 -2.03258002 1.83278996 -2.03235 0 P 0 ;0
L 1.83278996 -2.03235 1.83286004 -2.03213002 0 P 0 ;0
L 1.83286004 -2.03213002 1.83293996 -2.03191998 0 P 0 ;0
L 1.83293996 -2.03191998 1.83305 -2.03171004 0 P 0 ;0
L 1.83305 -2.03171004 1.83325 -2.03135 0 P 0 ;0
L 1.83325 -2.03135 1.83348996 -2.03101998 0 P 0 ;0
L 1.83348996 -2.03101998 1.83375 -2.03071004 0 P 0 ;0
L 1.83375 -2.03071004 1.83403002 -2.03041004 0 P 0 ;0
L 1.83403002 -2.03041004 1.83433996 -2.03015 0 P 0 ;0
L 1.83433996 -2.03015 1.83466998 -2.02991004 0 P 0 ;0
L 1.83466998 -2.02991004 1.83501998 -2.02968996 0 P 0 ;0
L 1.83501998 -2.02968996 1.83538002 -2.02951004 0 P 0 ;0
L 1.83538002 -2.02951004 1.83576004 -2.02936004 0 P 0 ;0
L 1.83576004 -2.02936004 1.83615 -2.02923996 0 P 0 ;0
L 1.83615 -2.02923996 1.83655 -2.02915 0 P 0 ;0
L 1.83655 -2.02915 1.8392 -2.02873996 0 P 0 ;0
L 1.8392 -2.02873996 1.84188002 -2.0285 0 P 0 ;0
L 1.84188002 -2.0285 1.84458002 -2.02841004 0 P 0 ;0
L 1.84458002 -2.02841004 1.84993996 -2.02858002 0 P 0 ;0
L 1.84993996 -2.02858002 1.85526998 -2.02916004 0 P 0 ;0
L 1.85526998 -2.02916004 1.86155 -2.03023002 0 P 0 ;0
L 1.86155 -2.03023002 1.86778002 -2.03158002 0 P 0 ;0
L 1.86778002 -2.03158002 1.8713 -2.03238996 0 P 0 ;0
L 1.8713 -2.03238996 1.87428996 -2.03303002 0 P 0 ;0
L 1.87428996 -2.03303002 1.8769 -2.03356004 0 P 0 ;0
L 1.8769 -2.03356004 1.87691998 -2.03356998 0 P 0 ;0
L 1.87691998 -2.03356998 1.87696004 -2.03356998 0 P 0 ;0
L 1.87696004 -2.03356998 1.87696998 -2.03356004 0 P 0 ;0
L 1.87696998 -2.03356004 1.87701004 -2.03356004 0 P 0 ;0
L 1.87701004 -2.03356004 1.87703996 -2.03353996 0 P 0 ;0
L 1.87703996 -2.03353996 1.87706004 -2.03353002 0 P 0 ;0
L 1.87706004 -2.03353002 1.87706998 -2.03351998 0 P 0 ;0
L 1.87706998 -2.03351998 1.87708996 -2.03351004 0 P 0 ;0
L 1.87708996 -2.03351004 1.8771 -2.03348996 0 P 0 ;0
L 1.8771 -2.03348996 1.87711004 -2.03348002 0 P 0 ;0
L 1.87711004 -2.03348002 1.87721998 -2.0333 0 P 0 ;0
L 1.87721998 -2.0333 1.87731998 -2.0331 0 P 0 ;0
L 1.87731998 -2.0331 1.8774 -2.0329 0 P 0 ;0
L 1.8774 -2.0329 1.87746004 -2.03268996 0 P 0 ;0
L 1.87746004 -2.03268996 1.87751004 -2.03248002 0 P 0 ;0
L 1.87751004 -2.03248002 1.87753002 -2.03226998 0 P 0 ;0
L 1.87753002 -2.03226998 1.87753996 -2.03205 0 P 0 ;0
L 1.87753996 -2.03205 1.87753002 -2.03183002 0 P 0 ;0
L 1.87753002 -2.03183002 1.87565 -2.01323996 0 P 0 ;0
L 1.87565 -2.01323996 1.87371004 -1.99451998 0 P 0 ;0
L 1.87371004 -1.99451998 1.8737 -1.99438996 0 P 0 ;0
L 1.8737 -1.99438996 1.87366998 -1.99426998 0 P 0 ;0
L 1.87366998 -1.99426998 1.87363002 -1.99415 0 P 0 ;0
L 1.87363002 -1.99415 1.87358002 -1.99403002 0 P 0 ;0
L 1.87358002 -1.99403002 1.87351998 -1.99391004 0 P 0 ;0
L 1.87351998 -1.99391004 1.87346004 -1.9938 0 P 0 ;0
L 1.87346004 -1.9938 1.87338002 -1.9937 0 P 0 ;0
L 1.87338002 -1.9937 1.87328996 -1.9936 0 P 0 ;0
L 1.87328996 -1.9936 1.8732 -1.99351004 0 P 0 ;0
L 1.8732 -1.99351004 1.8731 -1.99343002 0 P 0 ;0
L 1.8731 -1.99343002 1.87298996 -1.99335 0 P 0 ;0
L 1.87298996 -1.99335 1.87248002 -1.99305 0 P 0 ;0
L 1.87248002 -1.99305 1.87193996 -1.99278002 0 P 0 ;0
L 1.87193996 -1.99278002 1.87136998 -1.99256998 0 P 0 ;0
L 1.87136998 -1.99256998 1.87078996 -1.99241004 0 P 0 ;0
L 1.87078996 -1.99241004 1.8702 -1.9923 0 P 0 ;0
L 1.8702 -1.9923 1.85876004 -1.99076004 0 P 0 ;0
L 1.85876004 -1.99076004 1.84691998 -1.98943002 0 P 0 ;0
L 1.84691998 -1.98943002 1.83693002 -1.98876004 0 P 0 ;0
L 1.83693002 -1.98876004 1.8318 -1.98863002 0 P 0 ;0
L 1.8318 -1.98863002 1.82623002 -1.98866998 0 P 0 ;0
L 1.82623002 -1.98866998 1.82106004 -1.98883996 0 P 0 ;0
L 1.82106004 -1.98883996 1.81726998 -1.98915 0 P 0 ;0
L 1.78061004 -2.12523996 1.84838002 -2.12523996 0 P 0 ;0
L 1.77733002 -2.12423996 1.85121004 -2.12423996 0 P 0 ;0
L 1.77573996 -2.12323996 1.85376998 -2.12323996 0 P 0 ;0
L 1.77558002 -2.12223996 1.85596998 -2.12223996 0 P 0 ;0
L 1.77541998 -2.12123996 1.85798996 -2.12123996 0 P 0 ;0
L 1.77526998 -2.12023996 1.85978996 -2.12023996 0 P 0 ;0
L 1.77511004 -2.11923996 1.86131998 -2.11923996 0 P 0 ;0
L 1.77498996 -2.11823996 1.86276004 -2.11823996 0 P 0 ;0
L 1.77486998 -2.11723996 1.86406998 -2.11723996 0 P 0 ;0
L 1.77475 -2.11623996 1.86526004 -2.11623996 0 P 0 ;0
L 1.77463996 -2.11523996 1.86638002 -2.11523996 0 P 0 ;0
L 1.77451998 -2.11423996 1.8674 -2.11423996 0 P 0 ;0
L 1.77441004 -2.11323996 1.86835 -2.11323996 0 P 0 ;0
L 1.77431004 -2.11223996 1.86921004 -2.11223996 0 P 0 ;0
L 1.77421998 -2.11123996 1.87001004 -2.11123996 0 P 0 ;0
L 1.77413996 -2.11023996 1.87075 -2.11023996 0 P 0 ;0
L 1.77405 -2.10923996 1.87141998 -2.10923996 0 P 0 ;0
L 1.77396998 -2.10823996 1.87208002 -2.10823996 0 P 0 ;0
L 1.77388002 -2.10723996 1.87261998 -2.10723996 0 P 0 ;0
L 1.7738 -2.10623996 1.87316998 -2.10623996 0 P 0 ;0
L 1.77371004 -2.10523996 1.87366004 -2.10523996 0 P 0 ;0
L 1.77363002 -2.10423996 1.87411998 -2.10423996 0 P 0 ;0
L 1.77353996 -2.10323996 1.87453996 -2.10323996 0 P 0 ;0
L 1.77346998 -2.10223996 1.87495 -2.10223996 0 P 0 ;0
L 1.7734 -2.10123996 1.8753 -2.10123996 0 P 0 ;0
L 1.77333002 -2.10023996 1.87556998 -2.10023996 0 P 0 ;0
L 1.77325 -2.09923996 1.87576998 -2.09923996 0 P 0 ;0
L 1.77318002 -2.09823996 1.87591998 -2.09823996 0 P 0 ;0
L 1.77311004 -2.09723996 1.87603002 -2.09723996 0 P 0 ;0
L 1.77303996 -2.09623996 1.8761 -2.09623996 0 P 0 ;0
L 1.77296998 -2.09523996 1.87613002 -2.09523996 0 P 0 ;0
L 1.77291004 -2.09423996 1.87613996 -2.09423996 0 P 0 ;0
L 1.77285 -2.09323996 1.87616004 -2.09323996 0 P 0 ;0
L 1.77278996 -2.09223996 1.87616998 -2.09223996 0 P 0 ;0
L 1.77273002 -2.09123996 1.80256998 -2.09123996 0 P 0 ;0
L 1.77268002 -2.09023996 1.7968 -2.09023996 0 P 0 ;0
L 1.77261998 -2.08923996 1.79263002 -2.08923996 0 P 0 ;0
L 1.77256004 -2.08823996 1.78861998 -2.08823996 0 P 0 ;0
L 1.77251004 -2.08723996 1.7846 -2.08723996 0 P 0 ;0
L 1.77246004 -2.08623996 1.7807 -2.08623996 0 P 0 ;0
L 1.77241998 -2.08523996 1.77705 -2.08523996 0 P 0 ;0
L 1.77236998 -2.08423996 1.77293996 -2.08423996 0 P 0 ;0
L 1.62463996 -2.18195 1.65948996 -2.18195 0 P 0 ;0
L 1.61963996 -2.18095 1.66483002 -2.18095 0 P 0 ;0
L 1.61818002 -1.99795 1.6724 -1.99795 0 P 0 ;0
L 1.61778996 -1.99695 1.67218002 -1.99695 0 P 0 ;0
L 1.6174 -1.99595 1.67196004 -1.99595 0 P 0 ;0
L 1.61701004 -1.99495 1.67173996 -1.99495 0 P 0 ;0
L 1.61391998 -2.15695 1.70026004 -2.15695 0 P 0 ;0
L 1.61386004 -2.15595 1.70088002 -2.15595 0 P 0 ;0
L 1.61381004 -2.15495 1.70151004 -2.15495 0 P 0 ;0
L 1.61375 -2.15395 1.70213996 -2.15395 0 P 0 ;0
L 1.6137 -2.15295 1.70276004 -2.15295 0 P 0 ;0
L 1.61365 -2.15195 1.70338996 -2.15195 0 P 0 ;0
L 1.6136 -2.15095 1.70401004 -2.15095 0 P 0 ;0
L 1.61355 -2.14995 1.70456998 -2.14995 0 P 0 ;0
L 1.61348996 -2.14895 1.70511998 -2.14895 0 P 0 ;0
L 1.61343996 -2.14795 1.61738002 -2.14795 0 P 0 ;0
L 1.55341004 -2.08286998 1.60538002 -2.08286998 0 P 0 ;0
L 1.55286004 -2.08186998 1.60526998 -2.08186998 0 P 0 ;0
L 1.5521 -2.08086998 1.6051 -2.08086998 0 P 0 ;0
L 1.55126998 -2.07986998 1.6049 -2.07986998 0 P 0 ;0
L 1.55033996 -2.07886998 1.60463996 -2.07886998 0 P 0 ;0
L 1.54928996 -2.07786998 1.60433002 -2.07786998 0 P 0 ;0
L 1.54806998 -2.07686998 1.60398996 -2.07686998 0 P 0 ;0
L 1.5467 -2.07586998 1.60356998 -2.07586998 0 P 0 ;0
L 1.54531004 -2.07486998 1.6031 -2.07486998 0 P 0 ;0
L 1.54391004 -2.07386998 1.60258996 -2.07386998 0 P 0 ;0
L 1.54251004 -2.07286998 1.60201004 -2.07286998 0 P 0 ;0
L 1.54111998 -2.07186998 1.60138002 -2.07186998 0 P 0 ;0
L 1.53971998 -2.07086998 1.60068002 -2.07086998 0 P 0 ;0
L 1.53833002 -2.06986998 1.59993002 -2.06986998 0 P 0 ;0
L 1.53693002 -2.06886998 1.59908002 -2.06886998 0 P 0 ;0
L 1.53556004 -2.06786998 1.59821004 -2.06786998 0 P 0 ;0
L 1.53418996 -2.06686998 1.59733996 -2.06686998 0 P 0 ;0
L 1.53281998 -2.06586998 1.59646998 -2.06586998 0 P 0 ;0
L 1.53145 -2.06486998 1.5955 -2.06486998 0 P 0 ;0
L 1.53008002 -2.06386998 1.59453002 -2.06386998 0 P 0 ;0
L 1.52871004 -2.06286998 1.59356004 -2.06286998 0 P 0 ;0
L 1.52733996 -2.06186998 1.59253002 -2.06186998 0 P 0 ;0
L 1.52596998 -2.06086998 1.59145 -2.06086998 0 P 0 ;0
L 1.5246 -2.05986998 1.59038002 -2.05986998 0 P 0 ;0
L 1.52323002 -2.05886998 1.5893 -2.05886998 0 P 0 ;0
L 1.52186004 -2.05786998 1.58813996 -2.05786998 0 P 0 ;0
L 1.52053996 -2.05686998 1.58696004 -2.05686998 0 P 0 ;0
L 1.51935 -2.05586998 1.58576998 -2.05586998 0 P 0 ;0
L 1.51816004 -2.05486998 1.58456998 -2.05486998 0 P 0 ;0
L 1.51706998 -2.05386998 1.58321004 -2.05386998 0 P 0 ;0
L 1.51603996 -2.05286998 1.58185 -2.05286998 0 P 0 ;0
L 1.51501998 -2.05186998 1.58048996 -2.05186998 0 P 0 ;0
L 1.51408996 -2.05086998 1.57913002 -2.05086998 0 P 0 ;0
L 1.5132 -2.04986998 1.57776998 -2.04986998 0 P 0 ;0
L 1.51231998 -2.04886998 1.57641998 -2.04886998 0 P 0 ;0
L 1.51151004 -2.04786998 1.57505 -2.04786998 0 P 0 ;0
L 1.51075 -2.04686998 1.57365 -2.04686998 0 P 0 ;0
L 1.51008002 -2.04586998 1.57223002 -2.04586998 0 P 0 ;0
L 1.50945 -2.04486998 1.57081004 -2.04486998 0 P 0 ;0
L 1.50888002 -2.04386998 1.56938996 -2.04386998 0 P 0 ;0
L 1.50836004 -2.04286998 1.56796998 -2.04286998 0 P 0 ;0
L 1.5079 -2.04186998 1.56655 -2.04186998 0 P 0 ;0
L 1.50748002 -2.04086998 1.56518996 -2.04086998 0 P 0 ;0
L 1.50708996 -2.03986998 1.564 -2.03986998 0 P 0 ;0
L 1.50676004 -2.03886998 1.56296998 -2.03886998 0 P 0 ;0
L 1.50641998 -2.03786998 1.56206004 -2.03786998 0 P 0 ;0
L 1.50616998 -2.03686998 1.56125 -2.03686998 0 P 0 ;0
L 1.50591004 -2.03586998 1.56066998 -2.03586998 0 P 0 ;0
L 1.5057 -2.03486998 1.56031998 -2.03486998 0 P 0 ;0
L 1.50551998 -2.03386998 1.56016004 -2.03386998 0 P 0 ;0
L 1.50533996 -2.03286998 1.56016998 -2.03286998 0 P 0 ;0
L 1.50523996 -2.03186998 1.56036004 -2.03186998 0 P 0 ;0
L 1.50513002 -2.03086998 1.56071998 -2.03086998 0 P 0 ;0
L 1.50506998 -2.02986998 1.56131004 -2.02986998 0 P 0 ;0
L 1.50503996 -2.02886998 1.5622 -2.02886998 0 P 0 ;0
L 1.50501004 -2.02786998 1.56355 -2.02786998 0 P 0 ;0
L 1.50501998 -2.02686998 1.5657 -2.02686998 0 P 0 ;0
L 1.50506998 -2.02586998 1.60378996 -2.02586998 0 P 0 ;0
L 1.50511998 -2.02486998 1.60371004 -2.02486998 0 P 0 ;0
L 1.50521004 -2.02386998 1.60363996 -2.02386998 0 P 0 ;0
L 1.50533996 -2.02286998 1.60356998 -2.02286998 0 P 0 ;0
L 1.50546998 -2.02186998 1.6035 -2.02186998 0 P 0 ;0
L 1.50563996 -2.02086998 1.60343002 -2.02086998 0 P 0 ;0
L 1.50585 -2.01986998 1.60336004 -2.01986998 0 P 0 ;0
L 1.50606004 -2.01886998 1.60328996 -2.01886998 0 P 0 ;0
L 1.50633002 -2.01786998 1.60321998 -2.01786998 0 P 0 ;0
L 1.50661998 -2.01686998 1.60315 -2.01686998 0 P 0 ;0
L 1.50691004 -2.01586998 1.60308002 -2.01586998 0 P 0 ;0
L 1.50726998 -2.01486998 1.603 -2.01486998 0 P 0 ;0
L 1.50766004 -2.01386998 1.60293002 -2.01386998 0 P 0 ;0
L 1.50808996 -2.01286998 1.60285 -2.01286998 0 P 0 ;0
L 1.50856998 -2.01186998 1.60278002 -2.01186998 0 P 0 ;0
L 1.50908996 -2.01086998 1.6027 -2.01086998 0 P 0 ;0
L 1.50966004 -2.00986998 1.60261998 -2.00986998 0 P 0 ;0
L 1.51028996 -2.00886998 1.60255 -2.00886998 0 P 0 ;0
L 1.51096998 -2.00786998 1.60246998 -2.00786998 0 P 0 ;0
L 1.51171998 -2.00686998 1.6024 -2.00686998 0 P 0 ;0
L 1.51253996 -2.00586998 1.60233002 -2.00586998 0 P 0 ;0
L 1.51343996 -2.00486998 1.60225 -2.00486998 0 P 0 ;0
L 1.5144 -2.00386998 1.60218002 -2.00386998 0 P 0 ;0
L 1.51551998 -2.00286998 1.6021 -2.00286998 0 P 0 ;0
L 1.51663996 -2.00186998 1.60203002 -2.00186998 0 P 0 ;0
L 1.51795 -2.00086998 1.60195 -2.00086998 0 P 0 ;0
L 1.51928996 -1.99986998 1.60183996 -1.99986998 0 P 0 ;0
L 1.52086998 -1.99886998 1.60173002 -1.99886998 0 P 0 ;0
L 1.52258996 -1.99786998 1.60156998 -1.99786998 0 P 0 ;0
L 1.52451004 -1.99686998 1.60138996 -1.99686998 0 P 0 ;0
L 1.52686998 -1.99586998 1.60106998 -1.99586998 0 P 0 ;0
L 1.52976004 -1.99486998 1.59943996 -1.99486998 0 P 0 ;0
L 1.53283002 -1.99386998 1.59543002 -1.99386998 0 P 0 ;0
L 1.53678996 -1.99286998 1.59003996 -1.99286998 0 P 0 ;0
L 1.54173996 -1.99186998 1.58073996 -1.99186998 0 P 0 ;0
L 1.55036998 -1.99086998 1.56493002 -1.99086998 0 P 0 ;0
L 1.6036 -2.03086998 1.60413996 -2.03086998 0 P 0 ;0
L 1.59891004 -2.02986998 1.60406998 -2.02986998 0 P 0 ;0
L 1.59435 -2.02886998 1.604 -2.02886998 0 P 0 ;0
L 1.58838996 -2.02786998 1.60393002 -2.02786998 0 P 0 ;0
L 1.57981004 -2.02686998 1.60386004 -2.02686998 0 P 0 ;0
L 1.54575 -1.98923996 1.53931998 -1.99021998 0 P 0 ;0
L 1.53931998 -1.99021998 1.53298996 -1.99171998 0 P 0 ;0
L 1.53298996 -1.99171998 1.52678996 -1.99373996 0 P 0 ;0
L 1.52678996 -1.99373996 1.52376998 -1.995 0 P 0 ;0
L 1.52376998 -1.995 1.52086998 -1.99651004 0 P 0 ;0
L 1.52086998 -1.99651004 1.5181 -1.99826004 0 P 0 ;0
L 1.5181 -1.99826004 1.51548002 -2.00023002 0 P 0 ;0
L 1.51548002 -2.00023002 1.51301004 -2.00243002 0 P 0 ;0
L 1.51301004 -2.00243002 1.51128996 -2.00423002 0 P 0 ;0
L 1.51128996 -2.00423002 1.50971998 -2.00616004 0 P 0 ;0
L 1.50971998 -2.00616004 1.50831004 -2.00821004 0 P 0 ;0
L 1.50831004 -2.00821004 1.50706998 -2.01036998 0 P 0 ;0
L 1.50706998 -2.01036998 1.50598996 -2.01261998 0 P 0 ;0
L 1.50598996 -2.01261998 1.50508996 -2.01496998 0 P 0 ;0
L 1.50508996 -2.01496998 1.5042 -2.01801004 0 P 0 ;0
L 1.5042 -2.01801004 1.50355 -2.02111004 0 P 0 ;0
L 1.50355 -2.02111004 1.50313996 -2.02426004 0 P 0 ;0
L 1.50313996 -2.02426004 1.50298996 -2.02743002 0 P 0 ;0
L 1.50298996 -2.02743002 1.50308996 -2.03063002 0 P 0 ;0
L 1.50308996 -2.03063002 1.50338002 -2.03326998 0 P 0 ;0
L 1.50338002 -2.03326998 1.50385 -2.03588002 0 P 0 ;0
L 1.50385 -2.03588002 1.50451004 -2.03845 0 P 0 ;0
L 1.50451004 -2.03845 1.50535 -2.04096998 0 P 0 ;0
L 1.50535 -2.04096998 1.50633002 -2.0433 0 P 0 ;0
L 1.50633002 -2.0433 1.5075 -2.04553002 0 P 0 ;0
L 1.5075 -2.04553002 1.50883996 -2.04766998 0 P 0 ;0
L 1.50883996 -2.04766998 1.51036998 -2.04968996 0 P 0 ;0
L 1.51036998 -2.04968996 1.51323002 -2.05291998 0 P 0 ;0
L 1.51323002 -2.05291998 1.51631998 -2.05593996 0 P 0 ;0
L 1.51631998 -2.05593996 1.51961998 -2.05871004 0 P 0 ;0
L 1.51961998 -2.05871004 1.53591004 -2.0706 0 P 0 ;0
L 1.53591004 -2.0706 1.54668002 -2.07831004 0 P 0 ;0
L 1.54668002 -2.07831004 1.54793996 -2.07933996 0 P 0 ;0
L 1.54793996 -2.07933996 1.54911998 -2.08046998 0 P 0 ;0
L 1.54911998 -2.08046998 1.55021004 -2.08168002 0 P 0 ;0
L 1.55021004 -2.08168002 1.5512 -2.08298996 0 P 0 ;0
L 1.5512 -2.08298996 1.55136004 -2.08323002 0 P 0 ;0
L 1.55136004 -2.08323002 1.5515 -2.08348002 0 P 0 ;0
L 1.5515 -2.08348002 1.55161004 -2.08373996 0 P 0 ;0
L 1.55161004 -2.08373996 1.5517 -2.08401998 0 P 0 ;0
L 1.5517 -2.08401998 1.55176998 -2.0843 0 P 0 ;0
L 1.55176998 -2.0843 1.55181004 -2.08458002 0 P 0 ;0
L 1.55181004 -2.08458002 1.55183002 -2.08486998 0 P 0 ;0
L 1.55183002 -2.08486998 1.55181998 -2.08516004 0 P 0 ;0
L 1.55181998 -2.08516004 1.55178996 -2.08545 0 P 0 ;0
L 1.55178996 -2.08545 1.55173996 -2.08573002 0 P 0 ;0
L 1.55173996 -2.08573002 1.55166004 -2.086 0 P 0 ;0
L 1.55166004 -2.086 1.55156004 -2.08628002 0 P 0 ;0
L 1.55156004 -2.08628002 1.55136998 -2.08666998 0 P 0 ;0
L 1.55136998 -2.08666998 1.55115 -2.08703996 0 P 0 ;0
L 1.55115 -2.08703996 1.5509 -2.08738996 0 P 0 ;0
L 1.5509 -2.08738996 1.55063002 -2.08771998 0 P 0 ;0
L 1.55063002 -2.08771998 1.55033002 -2.08803002 0 P 0 ;0
L 1.55033002 -2.08803002 1.55 -2.08831004 0 P 0 ;0
L 1.55 -2.08831004 1.54966004 -2.08856004 0 P 0 ;0
L 1.54966004 -2.08856004 1.54928996 -2.08878996 0 P 0 ;0
L 1.54928996 -2.08878996 1.5489 -2.08898996 0 P 0 ;0
L 1.5489 -2.08898996 1.54786004 -2.08941004 0 P 0 ;0
L 1.54786004 -2.08941004 1.54678996 -2.08973996 0 P 0 ;0
L 1.54678996 -2.08973996 1.54568002 -2.08998002 0 P 0 ;0
L 1.54568002 -2.08998002 1.54456998 -2.09011998 0 P 0 ;0
L 1.54456998 -2.09011998 1.54343996 -2.09016998 0 P 0 ;0
L 1.54343996 -2.09016998 1.53906998 -2.09003002 0 P 0 ;0
L 1.53906998 -2.09003002 1.53468002 -2.08961998 0 P 0 ;0
L 1.53468002 -2.08961998 1.52908996 -2.08878996 0 P 0 ;0
L 1.52908996 -2.08878996 1.52351004 -2.08766004 0 P 0 ;0
L 1.52351004 -2.08766004 1.51005 -2.08418996 0 P 0 ;0
L 1.51005 -2.08418996 1.50631004 -2.08318002 0 P 0 ;0
L 1.50631004 -2.08318002 1.50308002 -2.08238996 0 P 0 ;0
L 1.50308002 -2.08238996 1.50033996 -2.08183002 0 P 0 ;0
L 1.50033996 -2.08183002 1.5003 -2.08181998 0 P 0 ;0
L 1.5003 -2.08181998 1.50016004 -2.08181998 0 P 0 ;0
L 1.50016004 -2.08181998 1.50011998 -2.08183002 0 P 0 ;0
L 1.50011998 -2.08183002 1.50006998 -2.08183996 0 P 0 ;0
L 1.50006998 -2.08183996 1.50003002 -2.08186004 0 P 0 ;0
L 1.50003002 -2.08186004 1.49998996 -2.08186998 0 P 0 ;0
L 1.49998996 -2.08186998 1.49995 -2.08188996 0 P 0 ;0
L 1.49995 -2.08188996 1.49991004 -2.08191998 0 P 0 ;0
L 1.49991004 -2.08191998 1.49988002 -2.08195 0 P 0 ;0
L 1.49988002 -2.08195 1.49983996 -2.08198002 0 P 0 ;0
L 1.49983996 -2.08198002 1.4997 -2.08213996 0 P 0 ;0
L 1.4997 -2.08213996 1.49956004 -2.08231998 0 P 0 ;0
L 1.49956004 -2.08231998 1.49943996 -2.0825 0 P 0 ;0
L 1.49943996 -2.0825 1.49933996 -2.0827 0 P 0 ;0
L 1.49933996 -2.0827 1.49925 -2.0829 0 P 0 ;0
L 1.49925 -2.0829 1.49918996 -2.08311004 0 P 0 ;0
L 1.49918996 -2.08311004 1.49913996 -2.08333002 0 P 0 ;0
L 1.49913996 -2.08333002 1.49911004 -2.08355 0 P 0 ;0
L 1.49911004 -2.08355 1.4991 -2.08376998 0 P 0 ;0
L 1.4991 -2.08376998 1.49911004 -2.08398996 0 P 0 ;0
L 1.49911004 -2.08398996 1.50071004 -2.10395 0 P 0 ;0
L 1.50071004 -2.10395 1.5024 -2.12403996 0 P 0 ;0
L 1.5024 -2.12403996 1.50241998 -2.12418002 0 P 0 ;0
L 1.50241998 -2.12418002 1.50246004 -2.12431004 0 P 0 ;0
L 1.50246004 -2.12431004 1.50248996 -2.12445 0 P 0 ;0
L 1.50248996 -2.12445 1.50255 -2.12456998 0 P 0 ;0
L 1.50255 -2.12456998 1.50261004 -2.1247 0 P 0 ;0
L 1.50261004 -2.1247 1.50276998 -2.12491998 0 P 0 ;0
L 1.50276998 -2.12491998 1.50286004 -2.12501998 0 P 0 ;0
L 1.50286004 -2.12501998 1.50296998 -2.12511998 0 P 0 ;0
L 1.50296998 -2.12511998 1.50308002 -2.12521004 0 P 0 ;0
L 1.50308002 -2.12521004 1.50318996 -2.12528002 0 P 0 ;0
L 1.50318996 -2.12528002 1.50331998 -2.12535 0 P 0 ;0
L 1.50331998 -2.12535 1.50343996 -2.1254 0 P 0 ;0
L 1.50343996 -2.1254 1.50391998 -2.12556004 0 P 0 ;0
L 1.50391998 -2.12556004 1.5044 -2.12568996 0 P 0 ;0
L 1.5044 -2.12568996 1.50848002 -2.12648996 0 P 0 ;0
L 1.50848002 -2.12648996 1.51328996 -2.12738002 0 P 0 ;0
L 1.51328996 -2.12738002 1.51873996 -2.12833996 0 P 0 ;0
L 1.51873996 -2.12833996 1.52606004 -2.12945 0 P 0 ;0
L 1.52606004 -2.12945 1.53343996 -2.13023002 0 P 0 ;0
L 1.53343996 -2.13023002 1.54886998 -2.13086998 0 P 0 ;0
L 1.54886998 -2.13086998 1.56305 -2.1303 0 P 0 ;0
L 1.56305 -2.1303 1.56666004 -2.12988996 0 P 0 ;0
L 1.56666004 -2.12988996 1.57023002 -2.12926998 0 P 0 ;0
L 1.57023002 -2.12926998 1.5738 -2.12843002 0 P 0 ;0
L 1.5738 -2.12843002 1.57945 -2.12668996 0 P 0 ;0
L 1.57945 -2.12668996 1.58498002 -2.12456998 0 P 0 ;0
L 1.58498002 -2.12456998 1.58793996 -2.12318002 0 P 0 ;0
L 1.58793996 -2.12318002 1.59078996 -2.12156004 0 P 0 ;0
L 1.59078996 -2.12156004 1.59348996 -2.11971998 0 P 0 ;0
L 1.59348996 -2.11971998 1.59525 -2.11833002 0 P 0 ;0
L 1.59525 -2.11833002 1.5969 -2.11681998 0 P 0 ;0
L 1.5969 -2.11681998 1.59846004 -2.11521004 0 P 0 ;0
L 1.59846004 -2.11521004 1.59991004 -2.11348002 0 P 0 ;0
L 1.59991004 -2.11348002 1.60175 -2.11093996 0 P 0 ;0
L 1.60175 -2.11093996 1.60338002 -2.10826998 0 P 0 ;0
L 1.60338002 -2.10826998 1.60481004 -2.10548002 0 P 0 ;0
L 1.60481004 -2.10548002 1.60573002 -2.10321004 0 P 0 ;0
L 1.60573002 -2.10321004 1.60646004 -2.10088002 0 P 0 ;0
L 1.60646004 -2.10088002 1.60698002 -2.09848996 0 P 0 ;0
L 1.60698002 -2.09848996 1.60756004 -2.09421998 0 P 0 ;0
L 1.60756004 -2.09421998 1.6078 -2.08991004 0 P 0 ;0
L 1.6078 -2.08991004 1.60768996 -2.08565 0 P 0 ;0
L 1.60768996 -2.08565 1.60723002 -2.08141998 0 P 0 ;0
L 1.60723002 -2.08141998 1.60691998 -2.07968002 0 P 0 ;0
L 1.60691998 -2.07968002 1.60646998 -2.07796998 0 P 0 ;0
L 1.60646998 -2.07796998 1.60591998 -2.0763 0 P 0 ;0
L 1.60591998 -2.0763 1.60523002 -2.07466998 0 P 0 ;0
L 1.60523002 -2.07466998 1.60411998 -2.07246998 0 P 0 ;0
L 1.60411998 -2.07246998 1.60281004 -2.07038002 0 P 0 ;0
L 1.60281004 -2.07038002 1.60131998 -2.06838996 0 P 0 ;0
L 1.60131998 -2.06838996 1.59803996 -2.06461998 0 P 0 ;0
L 1.59803996 -2.06461998 1.59455 -2.06101998 0 P 0 ;0
L 1.59455 -2.06101998 1.59031998 -2.05708996 0 P 0 ;0
L 1.59031998 -2.05708996 1.58586004 -2.05333996 0 P 0 ;0
L 1.58586004 -2.05333996 1.57588002 -2.04598996 0 P 0 ;0
L 1.57588002 -2.04598996 1.56685 -2.03963996 0 P 0 ;0
L 1.56685 -2.03963996 1.56578002 -2.03878996 0 P 0 ;0
L 1.56578002 -2.03878996 1.56476998 -2.03786004 0 P 0 ;0
L 1.56476998 -2.03786004 1.56383002 -2.03686998 0 P 0 ;0
L 1.56383002 -2.03686998 1.56295 -2.0358 0 P 0 ;0
L 1.56295 -2.0358 1.56276998 -2.03555 0 P 0 ;0
L 1.56276998 -2.03555 1.56261004 -2.03528002 0 P 0 ;0
L 1.56261004 -2.03528002 1.56246998 -2.035 0 P 0 ;0
L 1.56246998 -2.035 1.56236004 -2.03471998 0 P 0 ;0
L 1.56236004 -2.03471998 1.56226998 -2.03441998 0 P 0 ;0
L 1.56226998 -2.03441998 1.5622 -2.03411998 0 P 0 ;0
L 1.5622 -2.03411998 1.56216004 -2.03381998 0 P 0 ;0
L 1.56216004 -2.03381998 1.56213996 -2.03351004 0 P 0 ;0
L 1.56213996 -2.03351004 1.56215 -2.0332 0 P 0 ;0
L 1.56215 -2.0332 1.56218002 -2.03288996 0 P 0 ;0
L 1.56218002 -2.03288996 1.56225 -2.03253996 0 P 0 ;0
L 1.56225 -2.03253996 1.56233996 -2.03221004 0 P 0 ;0
L 1.56233996 -2.03221004 1.56246004 -2.03186998 0 P 0 ;0
L 1.56246004 -2.03186998 1.56261004 -2.03156004 0 P 0 ;0
L 1.56261004 -2.03156004 1.56278996 -2.03125 0 P 0 ;0
L 1.56278996 -2.03125 1.56298002 -2.03096004 0 P 0 ;0
L 1.56298002 -2.03096004 1.56321004 -2.03068996 0 P 0 ;0
L 1.56321004 -2.03068996 1.56345 -2.03043996 0 P 0 ;0
L 1.56345 -2.03043996 1.56371004 -2.0302 0 P 0 ;0
L 1.56371004 -2.0302 1.56416004 -2.02986004 0 P 0 ;0
L 1.56416004 -2.02986004 1.56463002 -2.02955 0 P 0 ;0
L 1.56463002 -2.02955 1.56511998 -2.02928002 0 P 0 ;0
L 1.56511998 -2.02928002 1.56561998 -2.02903002 0 P 0 ;0
L 1.56561998 -2.02903002 1.56611998 -2.02883996 0 P 0 ;0
L 1.56611998 -2.02883996 1.56663996 -2.02866998 0 P 0 ;0
L 1.56663996 -2.02866998 1.56716004 -2.02855 0 P 0 ;0
L 1.56716004 -2.02855 1.5677 -2.02846998 0 P 0 ;0
L 1.5677 -2.02846998 1.56926998 -2.02835 0 P 0 ;0
L 1.56926998 -2.02835 1.57085 -2.02833996 0 P 0 ;0
L 1.57085 -2.02833996 1.57725 -2.02866998 0 P 0 ;0
L 1.57725 -2.02866998 1.58205 -2.02906004 0 P 0 ;0
L 1.58205 -2.02906004 1.58746998 -2.02975 0 P 0 ;0
L 1.58746998 -2.02975 1.59271004 -2.03056998 0 P 0 ;0
L 1.59271004 -2.03056998 1.59681004 -2.03143002 0 P 0 ;0
L 1.59681004 -2.03143002 1.60016004 -2.03221998 0 P 0 ;0
L 1.60016004 -2.03221998 1.60308002 -2.03281004 0 P 0 ;0
L 1.60308002 -2.03281004 1.60553996 -2.03323996 0 P 0 ;0
L 1.60553996 -2.03323996 1.60568996 -2.03323996 0 P 0 ;0
L 1.60568996 -2.03323996 1.60576998 -2.03321998 0 P 0 ;0
L 1.60576998 -2.03321998 1.60586004 -2.03316004 0 P 0 ;0
L 1.60586004 -2.03316004 1.6059 -2.03313996 0 P 0 ;0
L 1.6059 -2.03313996 1.60591998 -2.03311004 0 P 0 ;0
L 1.60591998 -2.03311004 1.60598996 -2.03303996 0 P 0 ;0
L 1.60598996 -2.03303996 1.60605 -2.03296998 0 P 0 ;0
L 1.60605 -2.03296998 1.6061 -2.03288996 0 P 0 ;0
L 1.6061 -2.03288996 1.60618002 -2.03273002 0 P 0 ;0
L 1.60618002 -2.03273002 1.60621004 -2.03263002 0 P 0 ;0
L 1.60621004 -2.03263002 1.60623002 -2.03253996 0 P 0 ;0
L 1.60623002 -2.03253996 1.60625 -2.03236004 0 P 0 ;0
L 1.60625 -2.03236004 1.60623996 -2.03226004 0 P 0 ;0
L 1.60623996 -2.03226004 1.60508002 -2.01578002 0 P 0 ;0
L 1.60508002 -2.01578002 1.60393996 -2.00068002 0 P 0 ;0
L 1.60393996 -2.00068002 1.60368002 -1.99833996 0 P 0 ;0
L 1.60368002 -1.99833996 1.60326998 -1.99601004 0 P 0 ;0
L 1.60326998 -1.99601004 1.60321004 -1.99576998 0 P 0 ;0
L 1.60321004 -1.99576998 1.60313996 -1.99553002 0 P 0 ;0
L 1.60313996 -1.99553002 1.60303996 -1.9953 0 P 0 ;0
L 1.60303996 -1.9953 1.60293002 -1.99508002 0 P 0 ;0
L 1.60293002 -1.99508002 1.60281004 -1.99486004 0 P 0 ;0
L 1.60281004 -1.99486004 1.60261998 -1.9946 0 P 0 ;0
L 1.60261998 -1.9946 1.60241004 -1.99435 0 P 0 ;0
L 1.60241004 -1.99435 1.60218002 -1.99411998 0 P 0 ;0
L 1.60218002 -1.99411998 1.60191998 -1.99391004 0 P 0 ;0
L 1.60191998 -1.99391004 1.60161004 -1.99368996 0 P 0 ;0
L 1.60161004 -1.99368996 1.60128996 -1.99348996 0 P 0 ;0
L 1.60128996 -1.99348996 1.60095 -1.99331998 0 P 0 ;0
L 1.60095 -1.99331998 1.6006 -1.99316004 0 P 0 ;0
L 1.6006 -1.99316004 1.59966004 -1.99283002 0 P 0 ;0
L 1.59966004 -1.99283002 1.59871004 -1.99255 0 P 0 ;0
L 1.59871004 -1.99255 1.5933 -1.99135 0 P 0 ;0
L 1.5933 -1.99135 1.5878 -1.9905 0 P 0 ;0
L 1.5878 -1.9905 1.57285 -1.98915 0 P 0 ;0
L 1.57285 -1.98915 1.55763996 -1.98861004 0 P 0 ;0
L 1.55763996 -1.98861004 1.55171004 -1.98876004 0 P 0 ;0
L 1.55171004 -1.98876004 1.54575 -1.98923996 0 P 0 ;0
L 1.53011998 -2.12786998 1.5666 -2.12786998 0 P 0 ;0
L 1.52236004 -2.12686998 1.57168002 -2.12686998 0 P 0 ;0
L 1.51621998 -2.12586998 1.5753 -2.12586998 0 P 0 ;0
L 1.51071004 -2.12486998 1.57856004 -2.12486998 0 P 0 ;0
L 1.50553002 -2.12386998 1.58121004 -2.12386998 0 P 0 ;0
L 1.50431004 -2.12286998 1.58381998 -2.12286998 0 P 0 ;0
L 1.50423002 -2.12186998 1.58601998 -2.12186998 0 P 0 ;0
L 1.50413996 -2.12086998 1.58796004 -2.12086998 0 P 0 ;0
L 1.50406004 -2.11986998 1.58971004 -2.11986998 0 P 0 ;0
L 1.50396998 -2.11886998 1.59118002 -2.11886998 0 P 0 ;0
L 1.50388996 -2.11786998 1.5926 -2.11786998 0 P 0 ;0
L 1.50381004 -2.11686998 1.59386004 -2.11686998 0 P 0 ;0
L 1.50371998 -2.11586998 1.59496998 -2.11586998 0 P 0 ;0
L 1.50363996 -2.11486998 1.59601004 -2.11486998 0 P 0 ;0
L 1.50355 -2.11386998 1.59696998 -2.11386998 0 P 0 ;0
L 1.50346998 -2.11286998 1.59781004 -2.11286998 0 P 0 ;0
L 1.50338002 -2.11186998 1.5986 -2.11186998 0 P 0 ;0
L 1.5033 -2.11086998 1.59933002 -2.11086998 0 P 0 ;0
L 1.50321004 -2.10986998 1.60005 -2.10986998 0 P 0 ;0
L 1.50313002 -2.10886998 1.60066998 -2.10886998 0 P 0 ;0
L 1.50305 -2.10786998 1.60128002 -2.10786998 0 P 0 ;0
L 1.50296004 -2.10686998 1.60185 -2.10686998 0 P 0 ;0
L 1.50288002 -2.10586998 1.60236004 -2.10586998 0 P 0 ;0
L 1.50278996 -2.10486998 1.60286998 -2.10486998 0 P 0 ;0
L 1.50271004 -2.10386998 1.6033 -2.10386998 0 P 0 ;0
L 1.50263002 -2.10286998 1.60371004 -2.10286998 0 P 0 ;0
L 1.50255 -2.10186998 1.60405 -2.10186998 0 P 0 ;0
L 1.50246998 -2.10086998 1.60436004 -2.10086998 0 P 0 ;0
L 1.50238996 -2.09986998 1.60463002 -2.09986998 0 P 0 ;0
L 1.50231004 -2.09886998 1.60485 -2.09886998 0 P 0 ;0
L 1.50223002 -2.09786998 1.60505 -2.09786998 0 P 0 ;0
L 1.50215 -2.09686998 1.60518002 -2.09686998 0 P 0 ;0
L 1.50206998 -2.09586998 1.60531998 -2.09586998 0 P 0 ;0
L 1.50198996 -2.09486998 1.60545 -2.09486998 0 P 0 ;0
L 1.50191004 -2.09386998 1.60558002 -2.09386998 0 P 0 ;0
L 1.50183002 -2.09286998 1.60563002 -2.09286998 0 P 0 ;0
L 1.50175 -2.09186998 1.53725 -2.09186998 0 P 0 ;0
L 1.54638996 -2.09186998 1.60568996 -2.09186998 0 P 0 ;0
L 1.50166998 -2.09086998 1.5295 -2.09086998 0 P 0 ;0
L 1.54956998 -2.09086998 1.60573996 -2.09086998 0 P 0 ;0
L 1.50158996 -2.08986998 1.52436004 -2.08986998 0 P 0 ;0
L 1.55125 -2.08986998 1.60578996 -2.08986998 0 P 0 ;0
L 1.50151004 -2.08886998 1.52021004 -2.08886998 0 P 0 ;0
L 1.55226998 -2.08886998 1.60576998 -2.08886998 0 P 0 ;0
L 1.50143002 -2.08786998 1.51633002 -2.08786998 0 P 0 ;0
L 1.55298002 -2.08786998 1.60573996 -2.08786998 0 P 0 ;0
L 1.50133996 -2.08686998 1.51246004 -2.08686998 0 P 0 ;0
L 1.55346998 -2.08686998 1.60571998 -2.08686998 0 P 0 ;0
L 1.50126998 -2.08586998 1.50861998 -2.08586998 0 P 0 ;0
L 1.55375 -2.08586998 1.60568996 -2.08586998 0 P 0 ;0
L 1.50118002 -2.08486998 1.50481004 -2.08486998 0 P 0 ;0
L 1.55383002 -2.08486998 1.60558996 -2.08486998 0 P 0 ;0
L 1.55371998 -2.08386998 1.60548996 -2.08386998 0 P 0 ;0
L 1.54886998 -2.12886998 1.53358996 -2.12823996 0 P 0 ;0
L 1.53358996 -2.12823996 1.52631998 -2.12746998 0 P 0 ;0
L 1.52631998 -2.12746998 1.51906004 -2.12636998 0 P 0 ;0
L 1.51906004 -2.12636998 1.51363002 -2.12541004 0 P 0 ;0
L 1.51363002 -2.12541004 1.50886998 -2.12451998 0 P 0 ;0
L 1.50886998 -2.12451998 1.50483996 -2.12373996 0 P 0 ;0
L 1.50483996 -2.12373996 1.50448996 -2.12365 0 P 0 ;0
L 1.50448996 -2.12365 1.50438002 -2.12361004 0 P 0 ;0
L 1.50438002 -2.12361004 1.5027 -2.10378002 0 P 0 ;0
L 1.5027 -2.10378002 1.50111998 -2.08403002 0 P 0 ;0
L 1.50111998 -2.08403002 1.50263996 -2.08433996 0 P 0 ;0
L 1.50263996 -2.08433996 1.50581004 -2.08511004 0 P 0 ;0
L 1.50581004 -2.08511004 1.50955 -2.08611998 0 P 0 ;0
L 1.50955 -2.08611998 1.52306004 -2.08961004 0 P 0 ;0
L 1.52306004 -2.08961004 1.52311004 -2.08961998 0 P 0 ;0
L 1.52311004 -2.08961998 1.52875 -2.09076004 0 P 0 ;0
L 1.52875 -2.09076004 1.5288 -2.09076004 0 P 0 ;0
L 1.5288 -2.09076004 1.53443996 -2.09161004 0 P 0 ;0
L 1.53443996 -2.09161004 1.53893996 -2.09203002 0 P 0 ;0
L 1.53893996 -2.09203002 1.54346004 -2.09216998 0 P 0 ;0
L 1.54346004 -2.09216998 1.54473996 -2.09211004 0 P 0 ;0
L 1.54473996 -2.09211004 1.54603002 -2.09195 0 P 0 ;0
L 1.54603002 -2.09195 1.54728996 -2.09166998 0 P 0 ;0
L 1.54728996 -2.09166998 1.54853002 -2.09128996 0 P 0 ;0
L 1.54853002 -2.09128996 1.54973002 -2.09081004 0 P 0 ;0
L 1.54973002 -2.09081004 1.55026998 -2.09053996 0 P 0 ;0
L 1.55026998 -2.09053996 1.55076998 -2.09023002 0 P 0 ;0
L 1.55076998 -2.09023002 1.55118002 -2.08991998 0 P 0 ;0
L 1.55118002 -2.08991998 1.55118002 -2.08991004 0 P 0 ;0
L 1.55118002 -2.08991004 1.5512 -2.08991004 0 P 0 ;0
L 1.5512 -2.08991004 1.55125 -2.08986998 0 P 0 ;0
L 1.55125 -2.08986998 1.55131004 -2.08981998 0 P 0 ;0
L 1.55131004 -2.08981998 1.55126998 -2.08978002 0 P 0 ;0
L 1.55126998 -2.08978002 1.55136004 -2.08978002 0 P 0 ;0
L 1.55136004 -2.08978002 1.5517 -2.08948996 0 P 0 ;0
L 1.5517 -2.08948996 1.55206004 -2.08911998 0 P 0 ;0
L 1.55206004 -2.08911998 1.55205 -2.08911004 0 P 0 ;0
L 1.55205 -2.08911004 1.55206004 -2.08911004 0 P 0 ;0
L 1.55206004 -2.08911004 1.55211998 -2.08906004 0 P 0 ;0
L 1.55211998 -2.08906004 1.55248996 -2.08861004 0 P 0 ;0
L 1.55248996 -2.08861004 1.55283996 -2.08811998 0 P 0 ;0
L 1.55283996 -2.08811998 1.55313996 -2.08761004 0 P 0 ;0
L 1.55313996 -2.08761004 1.5534 -2.08706998 0 P 0 ;0
L 1.5534 -2.08706998 1.55356004 -2.08663002 0 P 0 ;0
L 1.55356004 -2.08663002 1.55368996 -2.08618996 0 P 0 ;0
L 1.55368996 -2.08618996 1.55376998 -2.08573996 0 P 0 ;0
L 1.55376998 -2.08573996 1.55378002 -2.08565 0 P 0 ;0
L 1.55378002 -2.08565 1.55381998 -2.08528002 0 P 0 ;0
L 1.55381998 -2.08528002 1.55383002 -2.08481998 0 P 0 ;0
L 1.55383002 -2.08481998 1.5538 -2.08436998 0 P 0 ;0
L 1.5538 -2.08436998 1.55373002 -2.08391998 0 P 0 ;0
L 1.55373002 -2.08391998 1.55361998 -2.08346998 0 P 0 ;0
L 1.55361998 -2.08346998 1.55348002 -2.08303996 0 P 0 ;0
L 1.55348002 -2.08303996 1.5533 -2.08261004 0 P 0 ;0
L 1.5533 -2.08261004 1.55308996 -2.08221004 0 P 0 ;0
L 1.55308996 -2.08221004 1.55283996 -2.08183002 0 P 0 ;0
L 1.55283996 -2.08183002 1.55175 -2.0804 0 P 0 ;0
L 1.55175 -2.0804 1.55055 -2.07908002 0 P 0 ;0
L 1.55055 -2.07908002 1.54926004 -2.07783996 0 P 0 ;0
L 1.54926004 -2.07783996 1.54788996 -2.07671998 0 P 0 ;0
L 1.54788996 -2.07671998 1.53706998 -2.06898002 0 P 0 ;0
L 1.53706998 -2.06898002 1.52085 -2.05713996 0 P 0 ;0
L 1.52085 -2.05713996 1.51766004 -2.05445 0 P 0 ;0
L 1.51766004 -2.05445 1.51468002 -2.05153996 0 P 0 ;0
L 1.51468002 -2.05153996 1.51191998 -2.04841998 0 P 0 ;0
L 1.51191998 -2.04841998 1.51048996 -2.04651998 0 P 0 ;0
L 1.51048996 -2.04651998 1.50923002 -2.04453002 0 P 0 ;0
L 1.50923002 -2.04453002 1.50813996 -2.04245 0 P 0 ;0
L 1.50813996 -2.04245 1.50721998 -2.04026004 0 P 0 ;0
L 1.50721998 -2.04026004 1.50643002 -2.03788002 0 P 0 ;0
L 1.50643002 -2.03788002 1.50581004 -2.03545 0 P 0 ;0
L 1.50581004 -2.03545 1.50536004 -2.03298996 0 P 0 ;0
L 1.50536004 -2.03298996 1.50508996 -2.0305 0 P 0 ;0
L 1.50508996 -2.0305 1.50498996 -2.02745 0 P 0 ;0
L 1.50498996 -2.02745 1.50513996 -2.02443996 0 P 0 ;0
L 1.50513996 -2.02443996 1.50551998 -2.02145 0 P 0 ;0
L 1.50551998 -2.02145 1.50613996 -2.0185 0 P 0 ;0
L 1.50613996 -2.0185 1.50698996 -2.01561004 0 P 0 ;0
L 1.50698996 -2.01561004 1.50783002 -2.01341004 0 P 0 ;0
L 1.50783002 -2.01341004 1.50883002 -2.0113 0 P 0 ;0
L 1.50883002 -2.0113 1.51 -2.00928002 0 P 0 ;0
L 1.51 -2.00928002 1.51133002 -2.00736004 0 P 0 ;0
L 1.51133002 -2.00736004 1.5128 -2.00555 0 P 0 ;0
L 1.5128 -2.00555 1.5144 -2.00386004 0 P 0 ;0
L 1.5144 -2.00386004 1.51675 -2.00176998 0 P 0 ;0
L 1.51675 -2.00176998 1.51923002 -1.9999 0 P 0 ;0
L 1.51923002 -1.9999 1.52186004 -1.99823996 0 P 0 ;0
L 1.52186004 -1.99823996 1.52461998 -1.99681004 0 P 0 ;0
L 1.52461998 -1.99681004 1.52748996 -1.99561004 0 P 0 ;0
L 1.52748996 -1.99561004 1.53353002 -1.99363996 0 P 0 ;0
L 1.53353002 -1.99363996 1.5397 -1.99218002 0 P 0 ;0
L 1.5397 -1.99218002 1.54598002 -1.99123002 0 P 0 ;0
L 1.54598002 -1.99123002 1.55181004 -1.99075 0 P 0 ;0
L 1.55181004 -1.99075 1.55763002 -1.99061998 0 P 0 ;0
L 1.55763002 -1.99061998 1.57273002 -1.99113996 0 P 0 ;0
L 1.57273002 -1.99113996 1.58755 -1.99248996 0 P 0 ;0
L 1.58755 -1.99248996 1.59293002 -1.99331998 0 P 0 ;0
L 1.59293002 -1.99331998 1.59821004 -1.99448996 0 P 0 ;0
L 1.59821004 -1.99448996 1.59905 -1.99473002 0 P 0 ;0
L 1.59905 -1.99473002 1.59986004 -1.99501998 0 P 0 ;0
L 1.59986004 -1.99501998 1.60008002 -1.99511998 0 P 0 ;0
L 1.60008002 -1.99511998 1.6003 -1.99523002 0 P 0 ;0
L 1.6003 -1.99523002 1.60051004 -1.99536004 0 P 0 ;0
L 1.60051004 -1.99536004 1.60071004 -1.9955 0 P 0 ;0
L 1.60071004 -1.9955 1.60083002 -1.99561004 0 P 0 ;0
L 1.60083002 -1.99561004 1.60093996 -1.99571004 0 P 0 ;0
L 1.60093996 -1.99571004 1.60103996 -1.99583002 0 P 0 ;0
L 1.60103996 -1.99583002 1.60111998 -1.99595 0 P 0 ;0
L 1.60111998 -1.99595 1.60116998 -1.99601998 0 P 0 ;0
L 1.60116998 -1.99601998 1.60121004 -1.99611004 0 P 0 ;0
L 1.60121004 -1.99611004 1.60125 -1.99621004 0 P 0 ;0
L 1.60125 -1.99621004 1.60128002 -1.9963 0 P 0 ;0
L 1.60128002 -1.9963 1.60131004 -1.99641004 0 P 0 ;0
L 1.60131004 -1.99641004 1.6017 -1.99861998 0 P 0 ;0
L 1.6017 -1.99861998 1.60195 -2.00086998 0 P 0 ;0
L 1.60195 -2.00086998 1.60308002 -2.01593002 0 P 0 ;0
L 1.60308002 -2.01593002 1.60415 -2.03096998 0 P 0 ;0
L 1.60415 -2.03096998 1.60345 -2.03083996 0 P 0 ;0
L 1.60345 -2.03083996 1.60058996 -2.03026004 0 P 0 ;0
L 1.60058996 -2.03026004 1.59723002 -2.02948002 0 P 0 ;0
L 1.59723002 -2.02948002 1.59721998 -2.02948002 0 P 0 ;0
L 1.59721998 -2.02948002 1.59306998 -2.0286 0 P 0 ;0
L 1.59306998 -2.0286 1.58776004 -2.02776998 0 P 0 ;0
L 1.58776004 -2.02776998 1.58226004 -2.02708002 0 P 0 ;0
L 1.58226004 -2.02708002 1.57738002 -2.02666998 0 P 0 ;0
L 1.57738002 -2.02666998 1.5709 -2.02633996 0 P 0 ;0
L 1.5709 -2.02633996 1.56918996 -2.02635 0 P 0 ;0
L 1.56918996 -2.02635 1.56746998 -2.02648996 0 P 0 ;0
L 1.56746998 -2.02648996 1.56678996 -2.02658996 0 P 0 ;0
L 1.56678996 -2.02658996 1.56611998 -2.02673996 0 P 0 ;0
L 1.56611998 -2.02673996 1.56546004 -2.02695 0 P 0 ;0
L 1.56546004 -2.02695 1.56481998 -2.0272 0 P 0 ;0
L 1.56481998 -2.0272 1.56418996 -2.0275 0 P 0 ;0
L 1.56418996 -2.0275 1.56358002 -2.02785 0 P 0 ;0
L 1.56358002 -2.02785 1.563 -2.02823002 0 P 0 ;0
L 1.563 -2.02823002 1.56245 -2.02865 0 P 0 ;0
L 1.56245 -2.02865 1.56206998 -2.02898996 0 P 0 ;0
L 1.56206998 -2.02898996 1.56171004 -2.02936004 0 P 0 ;0
L 1.56171004 -2.02936004 1.56138002 -2.02976004 0 P 0 ;0
L 1.56138002 -2.02976004 1.56108996 -2.03018996 0 P 0 ;0
L 1.56108996 -2.03018996 1.56083002 -2.03063996 0 P 0 ;0
L 1.56083002 -2.03063996 1.56061998 -2.0311 0 P 0 ;0
L 1.56061998 -2.0311 1.56043996 -2.03158996 0 P 0 ;0
L 1.56043996 -2.03158996 1.5603 -2.03208002 0 P 0 ;0
L 1.5603 -2.03208002 1.5602 -2.0326 0 P 0 ;0
L 1.5602 -2.0326 1.56015 -2.03308002 0 P 0 ;0
L 1.56015 -2.03308002 1.56013996 -2.03353996 0 P 0 ;0
L 1.56013996 -2.03353996 1.56016004 -2.03391004 0 P 0 ;0
L 1.56016004 -2.03391004 1.56048002 -2.03391004 0 P 0 ;0
L 1.56048002 -2.03391004 1.56016004 -2.03393002 0 P 0 ;0
L 1.56016004 -2.03393002 1.56016998 -2.03401004 0 P 0 ;0
L 1.56016998 -2.03401004 1.56023002 -2.03448002 0 P 0 ;0
L 1.56023002 -2.03448002 1.56025 -2.03456004 0 P 0 ;0
L 1.56025 -2.03456004 1.56033002 -2.03493002 0 P 0 ;0
L 1.56033002 -2.03493002 1.56046998 -2.03538002 0 P 0 ;0
L 1.56046998 -2.03538002 1.56063996 -2.03581998 0 P 0 ;0
L 1.56063996 -2.03581998 1.56085 -2.03623996 0 P 0 ;0
L 1.56085 -2.03623996 1.56108996 -2.03663996 0 P 0 ;0
L 1.56108996 -2.03663996 1.56136004 -2.03701998 0 P 0 ;0
L 1.56136004 -2.03701998 1.56233002 -2.03818996 0 P 0 ;0
L 1.56233002 -2.03818996 1.56336998 -2.03928996 0 P 0 ;0
L 1.56336998 -2.03928996 1.56448002 -2.04031004 0 P 0 ;0
L 1.56448002 -2.04031004 1.56566004 -2.04123996 0 P 0 ;0
L 1.56566004 -2.04123996 1.57471004 -2.04761998 0 P 0 ;0
L 1.57471004 -2.04761998 1.58461998 -2.05491004 0 P 0 ;0
L 1.58461998 -2.05491004 1.58898996 -2.05858996 0 P 0 ;0
L 1.58898996 -2.05858996 1.59315 -2.06245 0 P 0 ;0
L 1.59315 -2.06245 1.59656998 -2.06596998 0 P 0 ;0
L 1.59656998 -2.06596998 1.59976004 -2.06965 0 P 0 ;0
L 1.59976004 -2.06965 1.60116004 -2.07151004 0 P 0 ;0
L 1.60116004 -2.07151004 1.60238002 -2.07346004 0 P 0 ;0
L 1.60238002 -2.07346004 1.60341998 -2.0755 0 P 0 ;0
L 1.60341998 -2.0755 1.60403996 -2.077 0 P 0 ;0
L 1.60403996 -2.077 1.60456004 -2.07853996 0 P 0 ;0
L 1.60456004 -2.07853996 1.60496004 -2.08011004 0 P 0 ;0
L 1.60496004 -2.08011004 1.60525 -2.0817 0 P 0 ;0
L 1.60525 -2.0817 1.60568996 -2.08578002 0 P 0 ;0
L 1.60568996 -2.08578002 1.60578996 -2.08988002 0 P 0 ;0
L 1.60578996 -2.08988002 1.60556998 -2.09403002 0 P 0 ;0
L 1.60556998 -2.09403002 1.60501004 -2.09813996 0 P 0 ;0
L 1.60501004 -2.09813996 1.60451998 -2.10036998 0 P 0 ;0
L 1.60451998 -2.10036998 1.60383996 -2.10253996 0 P 0 ;0
L 1.60383996 -2.10253996 1.60298996 -2.10465 0 P 0 ;0
L 1.60298996 -2.10465 1.60163996 -2.1073 0 P 0 ;0
L 1.60163996 -2.1073 1.60008002 -2.10983002 0 P 0 ;0
L 1.60008002 -2.10983002 1.59833002 -2.11225 0 P 0 ;0
L 1.59833002 -2.11225 1.59696998 -2.11386998 0 P 0 ;0
L 1.59696998 -2.11386998 1.59551004 -2.11538996 0 P 0 ;0
L 1.59551004 -2.11538996 1.59395 -2.1168 0 P 0 ;0
L 1.59395 -2.1168 1.59231004 -2.11811004 0 P 0 ;0
L 1.59231004 -2.11811004 1.58973002 -2.11986004 0 P 0 ;0
L 1.58973002 -2.11986004 1.58701998 -2.1214 0 P 0 ;0
L 1.58701998 -2.1214 1.5842 -2.12273002 0 P 0 ;0
L 1.5842 -2.12273002 1.5788 -2.1248 0 P 0 ;0
L 1.5788 -2.1248 1.57326998 -2.12648996 0 P 0 ;0
L 1.57326998 -2.12648996 1.56983002 -2.12731004 0 P 0 ;0
L 1.56983002 -2.12731004 1.56638002 -2.12791004 0 P 0 ;0
L 1.56638002 -2.12791004 1.56288996 -2.1283 0 P 0 ;0
L 1.56288996 -2.1283 1.54886998 -2.12886998 0 P 0 ;0
L 1.35851998 -2.06545 1.47866004 -2.06545 0 P 0 ;0
L 1.35936004 -2.06445 1.47871004 -2.06445 0 P 0 ;0
L 1.36041004 -2.06345 1.47875 -2.06345 0 P 0 ;0
L 1.36163996 -2.06245 1.4788 -2.06245 0 P 0 ;0
L 1.36293996 -2.06145 1.47883996 -2.06145 0 P 0 ;0
L 1.36436004 -2.06045 1.47888996 -2.06045 0 P 0 ;0
L 1.36598002 -2.05945 1.47893996 -2.05945 0 P 0 ;0
L 1.36776004 -2.05845 1.47898996 -2.05845 0 P 0 ;0
L 1.36971004 -2.05745 1.47903002 -2.05745 0 P 0 ;0
L 1.37166004 -2.05645 1.47908002 -2.05645 0 P 0 ;0
L 1.37391004 -2.05545 1.47911998 -2.05545 0 P 0 ;0
L 1.37616998 -2.05445 1.47916998 -2.05445 0 P 0 ;0
L 1.37873002 -2.05345 1.47921004 -2.05345 0 P 0 ;0
L 1.38136004 -2.05245 1.47926004 -2.05245 0 P 0 ;0
L 1.36875 -2.03345 1.37108996 -2.03345 0 P 0 ;0
L 1.36886004 -2.03245 1.37385 -2.03245 0 P 0 ;0
L 1.36896998 -2.03145 1.37678002 -2.03145 0 P 0 ;0
L 1.36908996 -2.03045 1.3797 -2.03045 0 P 0 ;0
L 1.36921004 -2.02945 1.38261998 -2.02945 0 P 0 ;0
L 1.36933002 -2.02845 1.38638996 -2.02845 0 P 0 ;0
L 1.36946004 -2.02745 1.39023996 -2.02745 0 P 0 ;0
L 1.36958002 -2.02645 1.39503002 -2.02645 0 P 0 ;0
L 1.3697 -2.02545 1.40068002 -2.02545 0 P 0 ;0
L 1.36981998 -2.02445 1.41053996 -2.02445 0 P 0 ;0
L 1.36993996 -2.02345 1.47993996 -2.02345 0 P 0 ;0
L 1.37008002 -2.02245 1.47988002 -2.02245 0 P 0 ;0
L 1.37021004 -2.02145 1.47978002 -2.02145 0 P 0 ;0
L 1.37033996 -2.02045 1.47968002 -2.02045 0 P 0 ;0
L 1.37046998 -2.01945 1.47953002 -2.01945 0 P 0 ;0
L 1.3706 -2.01845 1.47936004 -2.01845 0 P 0 ;0
L 1.37073002 -2.01745 1.47918002 -2.01745 0 P 0 ;0
L 1.37086004 -2.01645 1.47893002 -2.01645 0 P 0 ;0
L 1.37098996 -2.01545 1.47868002 -2.01545 0 P 0 ;0
L 1.37113002 -2.01445 1.4784 -2.01445 0 P 0 ;0
L 1.37126998 -2.01345 1.47806004 -2.01345 0 P 0 ;0
L 1.3714 -2.01245 1.47773002 -2.01245 0 P 0 ;0
L 1.37153996 -2.01145 1.47733002 -2.01145 0 P 0 ;0
L 1.37168002 -2.01045 1.47691004 -2.01045 0 P 0 ;0
L 1.37181004 -2.00945 1.47641004 -2.00945 0 P 0 ;0
L 1.37195 -2.00845 1.47588996 -2.00845 0 P 0 ;0
L 1.37208002 -2.00745 1.47528002 -2.00745 0 P 0 ;0
L 1.37221004 -2.00645 1.47463996 -2.00645 0 P 0 ;0
L 1.37235 -2.00545 1.47391998 -2.00545 0 P 0 ;0
L 1.37248996 -2.00445 1.47311004 -2.00445 0 P 0 ;0
L 1.37261998 -2.00345 1.47225 -2.00345 0 P 0 ;0
L 1.37276004 -2.00245 1.47126998 -2.00245 0 P 0 ;0
L 1.3729 -2.00145 1.4702 -2.00145 0 P 0 ;0
L 1.37303002 -2.00045 1.46903996 -2.00045 0 P 0 ;0
L 1.37316998 -1.99945 1.46775 -1.99945 0 P 0 ;0
L 1.3733 -1.99845 1.46625 -1.99845 0 P 0 ;0
L 1.37343996 -1.99745 1.46455 -1.99745 0 P 0 ;0
L 1.37356998 -1.99645 1.46253996 -1.99645 0 P 0 ;0
L 1.37753002 -1.99545 1.46041004 -1.99545 0 P 0 ;0
L 1.38218996 -1.99445 1.45781004 -1.99445 0 P 0 ;0
L 1.42925 -2.08345 1.47785 -2.08345 0 P 0 ;0
L 1.42931998 -2.08245 1.47788996 -2.08245 0 P 0 ;0
L 1.42938002 -2.08145 1.47793002 -2.08145 0 P 0 ;0
L 1.42945 -2.08045 1.47796998 -2.08045 0 P 0 ;0
L 1.42951004 -2.07945 1.47801004 -2.07945 0 P 0 ;0
L 1.42958002 -2.07845 1.47806004 -2.07845 0 P 0 ;0
L 1.42963996 -2.07745 1.4781 -2.07745 0 P 0 ;0
L 1.4297 -2.07645 1.47815 -2.07645 0 P 0 ;0
L 1.42976998 -2.07545 1.4782 -2.07545 0 P 0 ;0
L 1.42983002 -2.07445 1.47825 -2.07445 0 P 0 ;0
L 1.4299 -2.07345 1.47828996 -2.07345 0 P 0 ;0
L 1.42963996 -2.07245 1.47833996 -2.07245 0 P 0 ;0
L 1.42918996 -2.07145 1.47838002 -2.07145 0 P 0 ;0
L 1.38425 -2.05145 1.47931004 -2.05145 0 P 0 ;0
L 1.38731998 -2.05045 1.47933996 -2.05045 0 P 0 ;0
L 1.39088002 -2.04945 1.47938002 -2.04945 0 P 0 ;0
L 1.3947 -2.04845 1.47941004 -2.04845 0 P 0 ;0
L 1.39851004 -2.04745 1.47945 -2.04745 0 P 0 ;0
L 1.40233002 -2.04645 1.47948002 -2.04645 0 P 0 ;0
L 1.40608002 -2.04545 1.47951004 -2.04545 0 P 0 ;0
L 1.40983002 -2.04445 1.47955 -2.04445 0 P 0 ;0
L 1.41306998 -2.04345 1.47958996 -2.04345 0 P 0 ;0
L 1.41591998 -2.04245 1.47961998 -2.04245 0 P 0 ;0
L 1.41876998 -2.04145 1.47965 -2.04145 0 P 0 ;0
L 1.42133996 -2.04045 1.47968996 -2.04045 0 P 0 ;0
L 1.42361998 -2.03945 1.47971998 -2.03945 0 P 0 ;0
L 1.42591004 -2.03845 1.47975 -2.03845 0 P 0 ;0
L 1.42805 -2.03745 1.47978002 -2.03745 0 P 0 ;0
L 1.42936004 -2.03645 1.47981004 -2.03645 0 P 0 ;0
L 1.43003002 -2.03545 1.47983002 -2.03545 0 P 0 ;0
L 1.43081998 -2.03445 1.47986004 -2.03445 0 P 0 ;0
L 1.43121004 -2.03345 1.47988002 -2.03345 0 P 0 ;0
L 1.43141998 -2.03245 1.4799 -2.03245 0 P 0 ;0
L 1.43146998 -2.03145 1.47993002 -2.03145 0 P 0 ;0
L 1.43136004 -2.03045 1.47996004 -2.03045 0 P 0 ;0
L 1.43108002 -2.02945 1.47998002 -2.02945 0 P 0 ;0
L 1.4306 -2.02845 1.48001004 -2.02845 0 P 0 ;0
L 1.42986998 -2.02745 1.48001004 -2.02745 0 P 0 ;0
L 1.42875 -2.02645 1.47998996 -2.02645 0 P 0 ;0
L 1.42658996 -2.02545 1.47996998 -2.02545 0 P 0 ;0
L 1.42203996 -2.02445 1.47996004 -2.02445 0 P 0 ;0
L 1.38748002 -1.99345 1.45483002 -1.99345 0 P 0 ;0
L 1.39331998 -1.99245 1.45108996 -1.99245 0 P 0 ;0
L 1.40051004 -1.99145 1.44503002 -1.99145 0 P 0 ;0
L 1.38096998 -2.12745 1.4051 -2.12745 0 P 0 ;0
L 1.37671004 -2.12645 1.41113996 -2.12645 0 P 0 ;0
L 1.3736 -2.12545 1.41238996 -2.12545 0 P 0 ;0
L 1.37096998 -2.12445 1.41268002 -2.12445 0 P 0 ;0
L 1.36876998 -2.12345 1.41296998 -2.12345 0 P 0 ;0
L 1.36685 -2.12245 1.41326998 -2.12245 0 P 0 ;0
L 1.36516004 -2.12145 1.41356004 -2.12145 0 P 0 ;0
L 1.36366004 -2.12045 1.41385 -2.12045 0 P 0 ;0
L 1.36225 -2.11945 1.41413996 -2.11945 0 P 0 ;0
L 1.361 -2.11845 1.41443002 -2.11845 0 P 0 ;0
L 1.35983002 -2.11745 1.41471998 -2.11745 0 P 0 ;0
L 1.35876004 -2.11645 1.41501004 -2.11645 0 P 0 ;0
L 1.42661998 -2.12445 1.47693002 -2.12445 0 P 0 ;0
L 1.42665 -2.12345 1.47693002 -2.12345 0 P 0 ;0
L 1.4267 -2.12245 1.47693002 -2.12245 0 P 0 ;0
L 1.42675 -2.12145 1.47693002 -2.12145 0 P 0 ;0
L 1.42681004 -2.12045 1.47693002 -2.12045 0 P 0 ;0
L 1.42686998 -2.11945 1.47693002 -2.11945 0 P 0 ;0
L 1.42691998 -2.11845 1.47693002 -2.11845 0 P 0 ;0
L 1.42698996 -2.11745 1.47693002 -2.11745 0 P 0 ;0
L 1.42705 -2.11645 1.47693002 -2.11645 0 P 0 ;0
L 1.42711004 -2.11545 1.47693002 -2.11545 0 P 0 ;0
L 1.42716998 -2.11445 1.47693002 -2.11445 0 P 0 ;0
L 1.42723002 -2.11345 1.47693996 -2.11345 0 P 0 ;0
L 1.4273 -2.11245 1.47695 -2.11245 0 P 0 ;0
L 1.42736998 -2.11145 1.47696004 -2.11145 0 P 0 ;0
L 1.42743996 -2.11045 1.47698002 -2.11045 0 P 0 ;0
L 1.42751004 -2.10945 1.47698996 -2.10945 0 P 0 ;0
L 1.42758002 -2.10845 1.47701004 -2.10845 0 P 0 ;0
L 1.42765 -2.10745 1.47703002 -2.10745 0 P 0 ;0
L 1.42771004 -2.10645 1.47703996 -2.10645 0 P 0 ;0
L 1.42778002 -2.10545 1.47706998 -2.10545 0 P 0 ;0
L 1.42783996 -2.10445 1.4771 -2.10445 0 P 0 ;0
L 1.42791004 -2.10345 1.47713002 -2.10345 0 P 0 ;0
L 1.42798002 -2.10245 1.47716004 -2.10245 0 P 0 ;0
L 1.42805 -2.10145 1.4772 -2.10145 0 P 0 ;0
L 1.42811004 -2.10045 1.47723002 -2.10045 0 P 0 ;0
L 1.40953002 -2.09945 1.41973002 -2.09945 0 P 0 ;0
L 1.42818002 -2.09945 1.47726004 -2.09945 0 P 0 ;0
L 1.41618002 -2.09845 1.41996998 -2.09845 0 P 0 ;0
L 1.42825 -2.09845 1.47728996 -2.09845 0 P 0 ;0
L 1.42831998 -2.09745 1.47733002 -2.09745 0 P 0 ;0
L 1.42838996 -2.09645 1.47736004 -2.09645 0 P 0 ;0
L 1.42846004 -2.09545 1.47738996 -2.09545 0 P 0 ;0
L 1.42851998 -2.09445 1.47741998 -2.09445 0 P 0 ;0
L 1.42858996 -2.09345 1.47746004 -2.09345 0 P 0 ;0
L 1.42866004 -2.09245 1.4775 -2.09245 0 P 0 ;0
L 1.42873002 -2.09145 1.47753996 -2.09145 0 P 0 ;0
L 1.42878996 -2.09045 1.47758002 -2.09045 0 P 0 ;0
L 1.42886004 -2.08945 1.47761998 -2.08945 0 P 0 ;0
L 1.42893002 -2.08845 1.47766004 -2.08845 0 P 0 ;0
L 1.42898996 -2.08745 1.4777 -2.08745 0 P 0 ;0
L 1.42906004 -2.08645 1.47773002 -2.08645 0 P 0 ;0
L 1.42911998 -2.08545 1.47776998 -2.08545 0 P 0 ;0
L 1.42918996 -2.08445 1.47781004 -2.08445 0 P 0 ;0
L 1.61686004 -2.17995 1.66846004 -2.17995 0 P 0 ;0
L 1.61591004 -2.17895 1.67158996 -2.17895 0 P 0 ;0
L 1.61553996 -2.17795 1.67431998 -2.17795 0 P 0 ;0
L 1.61526998 -2.17695 1.67675 -2.17695 0 P 0 ;0
L 1.61508002 -2.17595 1.67903996 -2.17595 0 P 0 ;0
L 1.61496998 -2.17495 1.68108002 -2.17495 0 P 0 ;0
L 1.61491004 -2.17395 1.68295 -2.17395 0 P 0 ;0
L 1.61485 -2.17295 1.68458996 -2.17295 0 P 0 ;0
L 1.61478996 -2.17195 1.6861 -2.17195 0 P 0 ;0
L 1.61473002 -2.17095 1.6875 -2.17095 0 P 0 ;0
L 1.61466998 -2.16995 1.68876998 -2.16995 0 P 0 ;0
L 1.61461004 -2.16895 1.68998002 -2.16895 0 P 0 ;0
L 1.61455 -2.16795 1.69108002 -2.16795 0 P 0 ;0
L 1.61448996 -2.16695 1.69211998 -2.16695 0 P 0 ;0
L 1.61443002 -2.16595 1.69316004 -2.16595 0 P 0 ;0
L 1.61436998 -2.16495 1.69411998 -2.16495 0 P 0 ;0
L 1.61431004 -2.16395 1.69498996 -2.16395 0 P 0 ;0
L 1.61425 -2.16295 1.69586004 -2.16295 0 P 0 ;0
L 1.61418996 -2.16195 1.69673002 -2.16195 0 P 0 ;0
L 1.61413002 -2.16095 1.69746998 -2.16095 0 P 0 ;0
L 1.61406998 -2.15995 1.6982 -2.15995 0 P 0 ;0
L 1.61401998 -2.15895 1.69893996 -2.15895 0 P 0 ;0
L 1.61396998 -2.15795 1.69963002 -2.15795 0 P 0 ;0
L 1.64433002 -2.18295 1.63151004 -2.18271004 0 P 0 ;0
L 1.63151004 -2.18271004 1.62658002 -2.18226998 0 P 0 ;0
L 1.62658002 -2.18226998 1.62168996 -2.18146998 0 P 0 ;0
L 1.62168996 -2.18146998 1.6201 -2.1811 0 P 0 ;0
L 1.6201 -2.1811 1.61853996 -2.18061004 0 P 0 ;0
L 1.61853996 -2.18061004 1.61701004 -2.18001998 0 P 0 ;0
L 1.61701004 -2.18001998 1.61686004 -2.17995 0 P 0 ;0
L 1.61686004 -2.17995 1.61671004 -2.17986998 0 P 0 ;0
L 1.61671004 -2.17986998 1.61656998 -2.17976998 0 P 0 ;0
L 1.61656998 -2.17976998 1.61643996 -2.17966998 0 P 0 ;0
L 1.61643996 -2.17966998 1.61631998 -2.17955 0 P 0 ;0
L 1.61631998 -2.17955 1.61621004 -2.17943002 0 P 0 ;0
L 1.61621004 -2.17943002 1.6161 -2.1793 0 P 0 ;0
L 1.6161 -2.1793 1.61601004 -2.17915 0 P 0 ;0
L 1.61601004 -2.17915 1.61593002 -2.179 0 P 0 ;0
L 1.61593002 -2.179 1.61586004 -2.17885 0 P 0 ;0
L 1.61586004 -2.17885 1.61553002 -2.17791004 0 P 0 ;0
L 1.61553002 -2.17791004 1.61526998 -2.17696004 0 P 0 ;0
L 1.61526998 -2.17696004 1.61508996 -2.17598996 0 P 0 ;0
L 1.61508996 -2.17598996 1.61496998 -2.17496998 0 P 0 ;0
L 1.61496998 -2.17496998 1.61408002 -2.16011004 0 P 0 ;0
L 1.61408002 -2.16011004 1.61341998 -2.14758996 0 P 0 ;0
L 1.61341998 -2.14758996 1.6202 -2.14821004 0 P 0 ;0
L 1.6202 -2.14821004 1.62023002 -2.14821004 0 P 0 ;0
L 1.62023002 -2.14821004 1.63216998 -2.14893996 0 P 0 ;0
L 1.63216998 -2.14893996 1.6349 -2.14893002 0 P 0 ;0
L 1.6349 -2.14893002 1.63761998 -2.14873002 0 P 0 ;0
L 1.63761998 -2.14873002 1.64031998 -2.14835 0 P 0 ;0
L 1.64031998 -2.14835 1.64198996 -2.14798996 0 P 0 ;0
L 1.64198996 -2.14798996 1.64363002 -2.14751998 0 P 0 ;0
L 1.64363002 -2.14751998 1.64523002 -2.14693002 0 P 0 ;0
L 1.64523002 -2.14693002 1.64678996 -2.14623002 0 P 0 ;0
L 1.64678996 -2.14623002 1.64888002 -2.14506998 0 P 0 ;0
L 1.64888002 -2.14506998 1.65086998 -2.14376004 0 P 0 ;0
L 1.65086998 -2.14376004 1.65093996 -2.14371004 0 P 0 ;0
L 1.65093996 -2.14371004 1.65275 -2.14228996 0 P 0 ;0
L 1.65275 -2.14228996 1.6539 -2.14123996 0 P 0 ;0
L 1.6539 -2.14123996 1.65496004 -2.14011004 0 P 0 ;0
L 1.65496004 -2.14011004 1.65591998 -2.13891004 0 P 0 ;0
L 1.65591998 -2.13891004 1.65755 -2.13653996 0 P 0 ;0
L 1.65755 -2.13653996 1.65901998 -2.13415 0 P 0 ;0
L 1.65901998 -2.13415 1.65903002 -2.13413002 0 P 0 ;0
L 1.65903002 -2.13413002 1.66035 -2.13171998 0 P 0 ;0
L 1.66035 -2.13171998 1.66155 -2.12925 0 P 0 ;0
L 1.66155 -2.12925 1.66183996 -2.12851998 0 P 0 ;0
L 1.66183996 -2.12851998 1.66206998 -2.12776004 0 P 0 ;0
L 1.66206998 -2.12776004 1.66223996 -2.12696998 0 P 0 ;0
L 1.66223996 -2.12696998 1.66233996 -2.12618002 0 P 0 ;0
L 1.66233996 -2.12618002 1.66236998 -2.12538996 0 P 0 ;0
L 1.66236998 -2.12538996 1.66233002 -2.12436004 0 P 0 ;0
L 1.66233002 -2.12436004 1.66221004 -2.12335 0 P 0 ;0
L 1.66221004 -2.12335 1.662 -2.12235 0 P 0 ;0
L 1.662 -2.12235 1.66171004 -2.12141004 0 P 0 ;0
L 1.66171004 -2.12141004 1.64438996 -2.07113002 0 P 0 ;0
L 1.64438996 -2.07113002 1.62871998 -2.02606004 0 P 0 ;0
L 1.62871998 -2.02606004 1.62116004 -2.00558996 0 P 0 ;0
L 1.62116004 -2.00558996 1.62116004 -2.00556998 0 P 0 ;0
L 1.62116004 -2.00556998 1.61681004 -1.99443996 0 P 0 ;0
L 1.61681004 -1.99443996 1.67163002 -1.99443996 0 P 0 ;0
L 1.67163002 -1.99443996 1.67301004 -2.00076004 0 P 0 ;0
L 1.67301004 -2.00076004 1.67613002 -2.01341998 0 P 0 ;0
L 1.67613002 -2.01341998 1.68331004 -2.03931998 0 P 0 ;0
L 1.68331004 -2.03931998 1.69153002 -2.06856998 0 P 0 ;0
L 1.69153002 -2.06856998 1.6916 -2.06876004 0 P 0 ;0
L 1.6916 -2.06876004 1.69168996 -2.06896998 0 P 0 ;0
L 1.69168996 -2.06896998 1.69181004 -2.06918002 0 P 0 ;0
L 1.69181004 -2.06918002 1.69193002 -2.06936998 0 P 0 ;0
L 1.69193002 -2.06936998 1.69208002 -2.06956004 0 P 0 ;0
L 1.69208002 -2.06956004 1.69223996 -2.06973002 0 P 0 ;0
L 1.69223996 -2.06973002 1.69241998 -2.06988002 0 P 0 ;0
L 1.69241998 -2.06988002 1.6926 -2.07001998 0 P 0 ;0
L 1.6926 -2.07001998 1.6928 -2.07015 0 P 0 ;0
L 1.6928 -2.07015 1.69301004 -2.07025 0 P 0 ;0
L 1.69301004 -2.07025 1.69323002 -2.07033996 0 P 0 ;0
L 1.69323002 -2.07033996 1.69346004 -2.07041004 0 P 0 ;0
L 1.69346004 -2.07041004 1.69368002 -2.07045 0 P 0 ;0
L 1.69368002 -2.07045 1.69391998 -2.07048002 0 P 0 ;0
L 1.69391998 -2.07048002 1.69413996 -2.07048996 0 P 0 ;0
L 1.69413996 -2.07048996 1.6944 -2.07048002 0 P 0 ;0
L 1.6944 -2.07048002 1.69465 -2.07045 0 P 0 ;0
L 1.69465 -2.07045 1.69488996 -2.07038996 0 P 0 ;0
L 1.69488996 -2.07038996 1.69513996 -2.07031998 0 P 0 ;0
L 1.69513996 -2.07031998 1.69536998 -2.07021998 0 P 0 ;0
L 1.69536998 -2.07021998 1.69558996 -2.0701 0 P 0 ;0
L 1.69558996 -2.0701 1.69581004 -2.06996998 0 P 0 ;0
L 1.69581004 -2.06996998 1.69601004 -2.06981998 0 P 0 ;0
L 1.69601004 -2.06981998 1.6962 -2.06965 0 P 0 ;0
L 1.6962 -2.06965 1.69636998 -2.06946004 0 P 0 ;0
L 1.69636998 -2.06946004 1.69653002 -2.06926004 0 P 0 ;0
L 1.69653002 -2.06926004 1.69666004 -2.06905 0 P 0 ;0
L 1.69666004 -2.06905 1.69678996 -2.06883002 0 P 0 ;0
L 1.69678996 -2.06883002 1.69688002 -2.0686 0 P 0 ;0
L 1.69688002 -2.0686 1.69695 -2.0684 0 P 0 ;0
L 1.69695 -2.0684 1.70426004 -2.04365 0 P 0 ;0
L 1.70426004 -2.04365 1.70426004 -2.04363002 0 P 0 ;0
L 1.70426004 -2.04363002 1.71066998 -2.0213 0 P 0 ;0
L 1.71066998 -2.0213 1.71068002 -2.02126004 0 P 0 ;0
L 1.71068002 -2.02126004 1.71431998 -2.00693996 0 P 0 ;0
L 1.71431998 -2.00693996 1.71706004 -1.99496998 0 P 0 ;0
L 1.71706004 -1.99496998 1.74335 -1.9947 0 P 0 ;0
L 1.74335 -1.9947 1.75403002 -1.99461004 0 P 0 ;0
L 1.75403002 -1.99461004 1.76301004 -1.99465 0 P 0 ;0
L 1.76301004 -1.99465 1.76886004 -1.99471004 0 P 0 ;0
L 1.76886004 -1.99471004 1.76883996 -1.99476004 0 P 0 ;0
L 1.76883996 -1.99476004 1.74021004 -2.06556004 0 P 0 ;0
L 1.74021004 -2.06556004 1.71298002 -2.13276998 0 P 0 ;0
L 1.71298002 -2.13276998 1.70836998 -2.14293996 0 P 0 ;0
L 1.70836998 -2.14293996 1.70413996 -2.15076004 0 P 0 ;0
L 1.70413996 -2.15076004 1.69941998 -2.15828996 0 P 0 ;0
L 1.69941998 -2.15828996 1.6967 -2.16198996 0 P 0 ;0
L 1.6967 -2.16198996 1.6937 -2.16541998 0 P 0 ;0
L 1.6937 -2.16541998 1.69041998 -2.1686 0 P 0 ;0
L 1.69041998 -2.1686 1.68793996 -2.17063002 0 P 0 ;0
L 1.68793996 -2.17063002 1.68535 -2.17248002 0 P 0 ;0
L 1.68535 -2.17248002 1.68263996 -2.17413996 0 P 0 ;0
L 1.68263996 -2.17413996 1.67981004 -2.17561004 0 P 0 ;0
L 1.67981004 -2.17561004 1.67525 -2.17761004 0 P 0 ;0
L 1.67525 -2.17761004 1.6706 -2.17931998 0 P 0 ;0
L 1.6706 -2.17931998 1.66586004 -2.18073002 0 P 0 ;0
L 1.66586004 -2.18073002 1.66141998 -2.1817 0 P 0 ;0
L 1.66141998 -2.1817 1.65691998 -2.18228996 0 P 0 ;0
L 1.65691998 -2.18228996 1.64433002 -2.18295 0 P 0 ;0
L 1.61928996 -2.00628002 1.62683996 -2.02673002 0 P 0 ;0
L 1.62683996 -2.02673002 1.6425 -2.07178002 0 P 0 ;0
L 1.6425 -2.07178002 1.65981004 -2.12201998 0 P 0 ;0
L 1.65981004 -2.12201998 1.66006004 -2.12283996 0 P 0 ;0
L 1.66006004 -2.12283996 1.66023002 -2.12368002 0 P 0 ;0
L 1.66023002 -2.12368002 1.66033996 -2.12451998 0 P 0 ;0
L 1.66033996 -2.12451998 1.66036998 -2.12538002 0 P 0 ;0
L 1.66036998 -2.12538002 1.66033996 -2.12601004 0 P 0 ;0
L 1.66033996 -2.12601004 1.66026998 -2.12663996 0 P 0 ;0
L 1.66026998 -2.12663996 1.66013996 -2.12725 0 P 0 ;0
L 1.66013996 -2.12725 1.65995 -2.12786004 0 P 0 ;0
L 1.65995 -2.12786004 1.65971004 -2.12843996 0 P 0 ;0
L 1.65971004 -2.12843996 1.65856998 -2.1308 0 P 0 ;0
L 1.65856998 -2.1308 1.6573 -2.13313002 0 P 0 ;0
L 1.6573 -2.13313002 1.65586998 -2.13545 0 P 0 ;0
L 1.65586998 -2.13545 1.65431004 -2.13771998 0 P 0 ;0
L 1.65431004 -2.13771998 1.65343996 -2.1388 0 P 0 ;0
L 1.65343996 -2.1388 1.65248996 -2.13981998 0 P 0 ;0
L 1.65248996 -2.13981998 1.65146004 -2.14076004 0 P 0 ;0
L 1.65146004 -2.14076004 1.64971004 -2.14213002 0 P 0 ;0
L 1.64971004 -2.14213002 1.64785 -2.14336004 0 P 0 ;0
L 1.64785 -2.14336004 1.64588996 -2.14443996 0 P 0 ;0
L 1.64588996 -2.14443996 1.64446998 -2.14508002 0 P 0 ;0
L 1.64446998 -2.14508002 1.64301004 -2.14561998 0 P 0 ;0
L 1.64301004 -2.14561998 1.64151004 -2.14605 0 P 0 ;0
L 1.64151004 -2.14605 1.63996998 -2.14636998 0 P 0 ;0
L 1.63996998 -2.14636998 1.63741004 -2.14673996 0 P 0 ;0
L 1.63741004 -2.14673996 1.63483002 -2.14693002 0 P 0 ;0
L 1.63483002 -2.14693002 1.63223002 -2.14693996 0 P 0 ;0
L 1.63223002 -2.14693996 1.62036004 -2.14621998 0 P 0 ;0
L 1.62036004 -2.14621998 1.6113 -2.14538002 0 P 0 ;0
L 1.6113 -2.14538002 1.61208996 -2.16023002 0 P 0 ;0
L 1.61208996 -2.16023002 1.61298002 -2.17515 0 P 0 ;0
L 1.61298002 -2.17515 1.6131 -2.17628002 0 P 0 ;0
L 1.6131 -2.17628002 1.61331998 -2.17741004 0 P 0 ;0
L 1.61331998 -2.17741004 1.61361998 -2.17851004 0 P 0 ;0
L 1.61361998 -2.17851004 1.614 -2.17958996 0 P 0 ;0
L 1.614 -2.17958996 1.61413996 -2.17988996 0 P 0 ;0
L 1.61413996 -2.17988996 1.61428996 -2.18018002 0 P 0 ;0
L 1.61428996 -2.18018002 1.61446998 -2.18045 0 P 0 ;0
L 1.61446998 -2.18045 1.61466998 -2.18071004 0 P 0 ;0
L 1.61466998 -2.18071004 1.61488996 -2.18095 0 P 0 ;0
L 1.61488996 -2.18095 1.61511998 -2.18116998 0 P 0 ;0
L 1.61511998 -2.18116998 1.61538002 -2.18138002 0 P 0 ;0
L 1.61538002 -2.18138002 1.61565 -2.18156004 0 P 0 ;0
L 1.61565 -2.18156004 1.61593002 -2.18173002 0 P 0 ;0
L 1.61593002 -2.18173002 1.61623002 -2.18186004 0 P 0 ;0
L 1.61623002 -2.18186004 1.61788002 -2.1825 0 P 0 ;0
L 1.61788002 -2.1825 1.61956998 -2.18301998 0 P 0 ;0
L 1.61956998 -2.18301998 1.6213 -2.18343002 0 P 0 ;0
L 1.6213 -2.18343002 1.62633002 -2.18426004 0 P 0 ;0
L 1.62633002 -2.18426004 1.6314 -2.18471004 0 P 0 ;0
L 1.6314 -2.18471004 1.64436004 -2.18495 0 P 0 ;0
L 1.64436004 -2.18495 1.65711004 -2.18428002 0 P 0 ;0
L 1.65711004 -2.18428002 1.66176998 -2.18366998 0 P 0 ;0
L 1.66176998 -2.18366998 1.66636004 -2.18266998 0 P 0 ;0
L 1.66636004 -2.18266998 1.67123002 -2.18121004 0 P 0 ;0
L 1.67123002 -2.18121004 1.676 -2.17946998 0 P 0 ;0
L 1.676 -2.17946998 1.68068002 -2.17741998 0 P 0 ;0
L 1.68068002 -2.17741998 1.68361998 -2.17588002 0 P 0 ;0
L 1.68361998 -2.17588002 1.68646004 -2.17415 0 P 0 ;0
L 1.68646004 -2.17415 1.68916004 -2.17221998 0 P 0 ;0
L 1.68916004 -2.17221998 1.69175 -2.17008996 0 P 0 ;0
L 1.69175 -2.17008996 1.69515 -2.1668 0 P 0 ;0
L 1.69515 -2.1668 1.69826004 -2.16323996 0 P 0 ;0
L 1.69826004 -2.16323996 1.70108002 -2.15941998 0 P 0 ;0
L 1.70108002 -2.15941998 1.70586004 -2.15176998 0 P 0 ;0
L 1.70586004 -2.15176998 1.71016004 -2.14383002 0 P 0 ;0
L 1.71016004 -2.14383002 1.71481998 -2.13356004 0 P 0 ;0
L 1.71481998 -2.13356004 1.74206998 -2.06631004 0 P 0 ;0
L 1.74206998 -2.06631004 1.77071004 -1.99548002 0 P 0 ;0
L 1.77071004 -1.99548002 1.77088002 -1.99498996 0 P 0 ;0
L 1.77088002 -1.99498996 1.77101998 -1.99448996 0 P 0 ;0
L 1.77101998 -1.99448996 1.77111998 -1.99398996 0 P 0 ;0
L 1.77111998 -1.99398996 1.77118002 -1.99346998 0 P 0 ;0
L 1.77118002 -1.99346998 1.7712 -1.99295 0 P 0 ;0
L 1.7712 -1.99295 1.7712 -1.99293002 0 P 0 ;0
L 1.7712 -1.99293002 1.77118996 -1.99286998 0 P 0 ;0
L 1.77118996 -1.99286998 1.77118002 -1.99286004 0 P 0 ;0
L 1.77118002 -1.99286004 1.77118002 -1.99283996 0 P 0 ;0
L 1.77118002 -1.99283996 1.77111004 -1.99276998 0 P 0 ;0
L 1.77111004 -1.99276998 1.77106998 -1.99275 0 P 0 ;0
L 1.77106998 -1.99275 1.77106004 -1.99273996 0 P 0 ;0
L 1.77106004 -1.99273996 1.771 -1.99273002 0 P 0 ;0
L 1.771 -1.99273002 1.77098002 -1.99273002 0 P 0 ;0
L 1.77098002 -1.99273002 1.76301004 -1.99265 0 P 0 ;0
L 1.76301004 -1.99265 1.75401998 -1.99261004 0 P 0 ;0
L 1.75401998 -1.99261004 1.74333002 -1.9927 0 P 0 ;0
L 1.74333002 -1.9927 1.71546004 -1.99298996 0 P 0 ;0
L 1.71546004 -1.99298996 1.71236998 -2.00646998 0 P 0 ;0
L 1.71236998 -2.00646998 1.70873996 -2.02078002 0 P 0 ;0
L 1.70873996 -2.02078002 1.70233996 -2.04308002 0 P 0 ;0
L 1.70233996 -2.04308002 1.69505 -2.0678 0 P 0 ;0
L 1.69505 -2.0678 1.69501998 -2.06788002 0 P 0 ;0
L 1.69501998 -2.06788002 1.69498996 -2.06795 0 P 0 ;0
L 1.69498996 -2.06795 1.69495 -2.06801998 0 P 0 ;0
L 1.69495 -2.06801998 1.69485 -2.06816004 0 P 0 ;0
L 1.69485 -2.06816004 1.69478996 -2.06821998 0 P 0 ;0
L 1.69478996 -2.06821998 1.69466998 -2.06831998 0 P 0 ;0
L 1.69466998 -2.06831998 1.69453002 -2.0684 0 P 0 ;0
L 1.69453002 -2.0684 1.69445 -2.06843002 0 P 0 ;0
L 1.69445 -2.06843002 1.69438002 -2.06846004 0 P 0 ;0
L 1.69438002 -2.06846004 1.69428996 -2.06846998 0 P 0 ;0
L 1.69428996 -2.06846998 1.69421004 -2.06848996 0 P 0 ;0
L 1.69421004 -2.06848996 1.69406998 -2.06848996 0 P 0 ;0
L 1.69406998 -2.06848996 1.69395 -2.06846998 0 P 0 ;0
L 1.69395 -2.06846998 1.69383002 -2.06843002 0 P 0 ;0
L 1.69383002 -2.06843002 1.69373002 -2.06836998 0 P 0 ;0
L 1.69373002 -2.06836998 1.69363002 -2.06828996 0 P 0 ;0
L 1.69363002 -2.06828996 1.69358996 -2.06823996 0 P 0 ;0
L 1.69358996 -2.06823996 1.69355 -2.0682 0 P 0 ;0
L 1.69355 -2.0682 1.69351998 -2.06815 0 P 0 ;0
L 1.69351998 -2.06815 1.69346004 -2.06803996 0 P 0 ;0
L 1.69346004 -2.06803996 1.69343996 -2.06798002 0 P 0 ;0
L 1.69343996 -2.06798002 1.68523002 -2.03878002 0 P 0 ;0
L 1.68523002 -2.03878002 1.67806998 -2.01291998 0 P 0 ;0
L 1.67806998 -2.01291998 1.67496004 -2.00031004 0 P 0 ;0
L 1.67496004 -2.00031004 1.67323002 -1.99243996 0 P 0 ;0
L 1.67323002 -1.99243996 1.61388002 -1.99243996 0 P 0 ;0
L 1.61388002 -1.99243996 1.61928996 -2.00628002 0 P 0 ;0
L 1.35018002 -2.08345 1.39488996 -2.08345 0 P 0 ;0
L 1.35026004 -2.08245 1.39586004 -2.08245 0 P 0 ;0
L 1.35041004 -2.08145 1.39708996 -2.08145 0 P 0 ;0
L 1.35058996 -2.08045 1.39853002 -2.08045 0 P 0 ;0
L 1.35083996 -2.07945 1.40031998 -2.07945 0 P 0 ;0
L 1.35116998 -2.07845 1.40271004 -2.07845 0 P 0 ;0
L 1.35158002 -2.07745 1.40561998 -2.07745 0 P 0 ;0
L 1.35203002 -2.07645 1.4092 -2.07645 0 P 0 ;0
L 1.35248002 -2.07545 1.41288996 -2.07545 0 P 0 ;0
L 1.35293002 -2.07445 1.4164 -2.07445 0 P 0 ;0
L 1.35338996 -2.07345 1.41975 -2.07345 0 P 0 ;0
L 1.35393996 -2.07245 1.42293996 -2.07245 0 P 0 ;0
L 1.35448996 -2.07145 1.42606998 -2.07145 0 P 0 ;0
L 1.35505 -2.07045 1.47843002 -2.07045 0 P 0 ;0
L 1.3557 -2.06945 1.47846998 -2.06945 0 P 0 ;0
L 1.35635 -2.06845 1.47851998 -2.06845 0 P 0 ;0
L 1.35701998 -2.06745 1.47856998 -2.06745 0 P 0 ;0
L 1.35776998 -2.06645 1.47861004 -2.06645 0 P 0 ;0
L 1.29346998 -2.00516004 1.33388996 -2.00516004 0 P 0 ;0
L 1.29448996 -2.00416004 1.33385 -2.00416004 0 P 0 ;0
L 1.29551004 -2.00316004 1.33381004 -2.00316004 0 P 0 ;0
L 1.29653996 -2.00216004 1.33376004 -2.00216004 0 P 0 ;0
L 1.29756004 -2.00116004 1.33371004 -2.00116004 0 P 0 ;0
L 1.29861998 -2.00016004 1.33366004 -2.00016004 0 P 0 ;0
L 1.29973002 -1.99916004 1.3336 -1.99916004 0 P 0 ;0
L 1.30101004 -1.99816004 1.33355 -1.99816004 0 P 0 ;0
L 1.30238996 -1.99716004 1.3335 -1.99716004 0 P 0 ;0
L 1.30393996 -1.99616004 1.33345 -1.99616004 0 P 0 ;0
L 1.30571004 -1.99516004 1.33338996 -1.99516004 0 P 0 ;0
L 1.3077 -1.99416004 1.33333002 -1.99416004 0 P 0 ;0
L 1.31001004 -1.99316004 1.33328002 -1.99316004 0 P 0 ;0
L 1.31288002 -1.99216004 1.33321998 -1.99216004 0 P 0 ;0
L 1.31688996 -1.99116004 1.33316004 -1.99116004 0 P 0 ;0
L 1.39798996 -1.98971998 1.39326998 -1.99043002 0 P 0 ;0
L 1.39326998 -1.99043002 1.38806998 -1.9913 0 P 0 ;0
L 1.38806998 -1.9913 1.38316004 -1.9922 0 P 0 ;0
L 1.38316004 -1.9922 1.37946004 -1.99296998 0 P 0 ;0
L 1.37946004 -1.99296998 1.3718 -1.99466998 0 P 0 ;0
L 1.3718 -1.99466998 1.36896004 -2.01553996 0 P 0 ;0
L 1.36896004 -2.01553996 1.36791004 -2.02358996 0 P 0 ;0
L 1.36791004 -2.02358996 1.36708002 -2.03043002 0 P 0 ;0
L 1.36708002 -2.03043002 1.36638996 -2.03646004 0 P 0 ;0
L 1.36638996 -2.03646004 1.36638002 -2.03648996 0 P 0 ;0
L 1.36638002 -2.03648996 1.36638996 -2.03653002 0 P 0 ;0
L 1.36638996 -2.03653002 1.36638996 -2.03656998 0 P 0 ;0
L 1.36638996 -2.03656998 1.3664 -2.03663996 0 P 0 ;0
L 1.3664 -2.03663996 1.36641998 -2.03666998 0 P 0 ;0
L 1.36641998 -2.03666998 1.36643002 -2.03671004 0 P 0 ;0
L 1.36643002 -2.03671004 1.36648996 -2.0368 0 P 0 ;0
L 1.36648996 -2.0368 1.36656004 -2.03686004 0 P 0 ;0
L 1.36656004 -2.03686004 1.3666 -2.03688996 0 P 0 ;0
L 1.3666 -2.03688996 1.36663002 -2.03691004 0 P 0 ;0
L 1.36663002 -2.03691004 1.36666004 -2.03691004 0 P 0 ;0
L 1.36666004 -2.03691004 1.36671004 -2.03693002 0 P 0 ;0
L 1.36671004 -2.03693002 1.36676998 -2.03693002 0 P 0 ;0
L 1.36676998 -2.03693002 1.36685 -2.03691998 0 P 0 ;0
L 1.36685 -2.03691998 1.36895 -2.03628002 0 P 0 ;0
L 1.36895 -2.03628002 1.37143002 -2.03545 0 P 0 ;0
L 1.37143002 -2.03545 1.37428996 -2.03441004 0 P 0 ;0
L 1.37428996 -2.03441004 1.38346004 -2.03126998 0 P 0 ;0
L 1.38346004 -2.03126998 1.39251998 -2.02891998 0 P 0 ;0
L 1.39251998 -2.02891998 1.40156004 -2.02731998 0 P 0 ;0
L 1.40156004 -2.02731998 1.41068002 -2.02643996 0 P 0 ;0
L 1.41068002 -2.02643996 1.41566998 -2.02628002 0 P 0 ;0
L 1.41566998 -2.02628002 1.42066004 -2.02633996 0 P 0 ;0
L 1.42066004 -2.02633996 1.42221004 -2.02646998 0 P 0 ;0
L 1.42221004 -2.02646998 1.42375 -2.02671998 0 P 0 ;0
L 1.42375 -2.02671998 1.42525 -2.0271 0 P 0 ;0
L 1.42525 -2.0271 1.42671998 -2.02761004 0 P 0 ;0
L 1.42671998 -2.02761004 1.42706004 -2.02776004 0 P 0 ;0
L 1.42706004 -2.02776004 1.42738002 -2.02793002 0 P 0 ;0
L 1.42738002 -2.02793002 1.42768002 -2.02813996 0 P 0 ;0
L 1.42768002 -2.02813996 1.42796998 -2.02836004 0 P 0 ;0
L 1.42796998 -2.02836004 1.42823002 -2.02861004 0 P 0 ;0
L 1.42823002 -2.02861004 1.42848002 -2.02888996 0 P 0 ;0
L 1.42848002 -2.02888996 1.4287 -2.02918002 0 P 0 ;0
L 1.4287 -2.02918002 1.42888996 -2.02948996 0 P 0 ;0
L 1.42888996 -2.02948996 1.42906004 -2.02981004 0 P 0 ;0
L 1.42906004 -2.02981004 1.4292 -2.03015 0 P 0 ;0
L 1.4292 -2.03015 1.42931998 -2.0305 0 P 0 ;0
L 1.42931998 -2.0305 1.4294 -2.03086004 0 P 0 ;0
L 1.4294 -2.03086004 1.42945 -2.03121998 0 P 0 ;0
L 1.42945 -2.03121998 1.42946998 -2.03158002 0 P 0 ;0
L 1.42946998 -2.03158002 1.42946004 -2.03195 0 P 0 ;0
L 1.42946004 -2.03195 1.42941998 -2.03231004 0 P 0 ;0
L 1.42941998 -2.03231004 1.42935 -2.03266998 0 P 0 ;0
L 1.42935 -2.03266998 1.42925 -2.03301998 0 P 0 ;0
L 1.42925 -2.03301998 1.42911998 -2.03336004 0 P 0 ;0
L 1.42911998 -2.03336004 1.42896004 -2.03368996 0 P 0 ;0
L 1.42896004 -2.03368996 1.42875 -2.03405 0 P 0 ;0
L 1.42875 -2.03405 1.42851004 -2.03438996 0 P 0 ;0
L 1.42851004 -2.03438996 1.42825 -2.03471004 0 P 0 ;0
L 1.42825 -2.03471004 1.42796004 -2.03501004 0 P 0 ;0
L 1.42796004 -2.03501004 1.42765 -2.03528996 0 P 0 ;0
L 1.42765 -2.03528996 1.42731998 -2.03553996 0 P 0 ;0
L 1.42731998 -2.03553996 1.42696998 -2.03576004 0 P 0 ;0
L 1.42696998 -2.03576004 1.4266 -2.03596004 0 P 0 ;0
L 1.4266 -2.03596004 1.41951004 -2.03906004 0 P 0 ;0
L 1.41951004 -2.03906004 1.4109 -2.04208996 0 P 0 ;0
L 1.4109 -2.04208996 1.40178002 -2.04451998 0 P 0 ;0
L 1.40178002 -2.04451998 1.3878 -2.04818996 0 P 0 ;0
L 1.3878 -2.04818996 1.38176998 -2.05015 0 P 0 ;0
L 1.38176998 -2.05015 1.3758 -2.05243002 0 P 0 ;0
L 1.3758 -2.05243002 1.37086998 -2.0546 0 P 0 ;0
L 1.37086998 -2.0546 1.36603996 -2.05708002 0 P 0 ;0
L 1.36603996 -2.05708002 1.36356004 -2.05856004 0 P 0 ;0
L 1.36356004 -2.05856004 1.36118996 -2.06023002 0 P 0 ;0
L 1.36118996 -2.06023002 1.35895 -2.06206004 0 P 0 ;0
L 1.35895 -2.06206004 1.35805 -2.06291004 0 P 0 ;0
L 1.35805 -2.06291004 1.35721998 -2.06385 0 P 0 ;0
L 1.35721998 -2.06385 1.35518996 -2.06655 0 P 0 ;0
L 1.35518996 -2.06655 1.3532 -2.06961998 0 P 0 ;0
L 1.3532 -2.06961998 1.35156004 -2.07263002 0 P 0 ;0
L 1.35156004 -2.07263002 1.34951004 -2.07718002 0 P 0 ;0
L 1.34951004 -2.07718002 1.34911004 -2.07825 0 P 0 ;0
L 1.34911004 -2.07825 1.34878996 -2.07935 0 P 0 ;0
L 1.34878996 -2.07935 1.34853002 -2.08046998 0 P 0 ;0
L 1.34853002 -2.08046998 1.34825 -2.08238002 0 P 0 ;0
L 1.34825 -2.08238002 1.34811998 -2.08431004 0 P 0 ;0
L 1.34811998 -2.08431004 1.348 -2.09128996 0 P 0 ;0
L 1.348 -2.09128996 1.3481 -2.09761004 0 P 0 ;0
L 1.3481 -2.09761004 1.34823002 -2.09961004 0 P 0 ;0
L 1.34823002 -2.09961004 1.34846998 -2.10161004 0 P 0 ;0
L 1.34846998 -2.10161004 1.34876998 -2.10321998 0 P 0 ;0
L 1.34876998 -2.10321998 1.3492 -2.10478996 0 P 0 ;0
L 1.3492 -2.10478996 1.3498 -2.10648996 0 P 0 ;0
L 1.3498 -2.10648996 1.3505 -2.10815 0 P 0 ;0
L 1.3505 -2.10815 1.35178996 -2.11066004 0 P 0 ;0
L 1.35178996 -2.11066004 1.35328002 -2.11305 0 P 0 ;0
L 1.35328002 -2.11305 1.35496998 -2.1153 0 P 0 ;0
L 1.35496998 -2.1153 1.35685 -2.1174 0 P 0 ;0
L 1.35685 -2.1174 1.35891998 -2.11933996 0 P 0 ;0
L 1.35891998 -2.11933996 1.36126998 -2.12121998 0 P 0 ;0
L 1.36126998 -2.12121998 1.36373996 -2.12293002 0 P 0 ;0
L 1.36373996 -2.12293002 1.36633002 -2.12446004 0 P 0 ;0
L 1.36633002 -2.12446004 1.36901004 -2.1258 0 P 0 ;0
L 1.36901004 -2.1258 1.3718 -2.12695 0 P 0 ;0
L 1.3718 -2.12695 1.37578996 -2.12828002 0 P 0 ;0
L 1.37578996 -2.12828002 1.37986998 -2.12928996 0 P 0 ;0
L 1.37986998 -2.12928996 1.38401998 -2.12998996 0 P 0 ;0
L 1.38401998 -2.12998996 1.3882 -2.13036004 0 P 0 ;0
L 1.3882 -2.13036004 1.39443002 -2.13045 0 P 0 ;0
L 1.39443002 -2.13045 1.40066004 -2.13006998 0 P 0 ;0
L 1.40066004 -2.13006998 1.40685 -2.12923002 0 P 0 ;0
L 1.40685 -2.12923002 1.41371004 -2.12801998 0 P 0 ;0
L 1.41371004 -2.12801998 1.41583002 -2.12081004 0 P 0 ;0
L 1.41583002 -2.12081004 1.41953996 -2.10798996 0 P 0 ;0
L 1.41953996 -2.10798996 1.42135 -2.10126998 0 P 0 ;0
L 1.42135 -2.10126998 1.42236998 -2.097 0 P 0 ;0
L 1.42236998 -2.097 1.42238996 -2.09691004 0 P 0 ;0
L 1.42238996 -2.09691004 1.4224 -2.09681998 0 P 0 ;0
L 1.4224 -2.09681998 1.4224 -2.09673996 0 P 0 ;0
L 1.4224 -2.09673996 1.42238002 -2.09656004 0 P 0 ;0
L 1.42238002 -2.09656004 1.42235 -2.09648002 0 P 0 ;0
L 1.42235 -2.09648002 1.42233002 -2.09638996 0 P 0 ;0
L 1.42233002 -2.09638996 1.42225 -2.09623002 0 P 0 ;0
L 1.42225 -2.09623002 1.4222 -2.09616004 0 P 0 ;0
L 1.4222 -2.09616004 1.42213996 -2.09608996 0 P 0 ;0
L 1.42213996 -2.09608996 1.42208996 -2.09601998 0 P 0 ;0
L 1.42208996 -2.09601998 1.42203996 -2.09598996 0 P 0 ;0
L 1.42203996 -2.09598996 1.42198996 -2.09595 0 P 0 ;0
L 1.42198996 -2.09595 1.42188996 -2.09588996 0 P 0 ;0
L 1.42188996 -2.09588996 1.42183002 -2.09586004 0 P 0 ;0
L 1.42183002 -2.09586004 1.42178002 -2.09585 0 P 0 ;0
L 1.42178002 -2.09585 1.42171998 -2.09583002 0 P 0 ;0
L 1.42171998 -2.09583002 1.42166004 -2.09581998 0 P 0 ;0
L 1.42166004 -2.09581998 1.42153996 -2.09581998 0 P 0 ;0
L 1.42153996 -2.09581998 1.41978002 -2.09591004 0 P 0 ;0
L 1.41978002 -2.09591004 1.41763996 -2.09615 0 P 0 ;0
L 1.41763996 -2.09615 1.41521998 -2.09658002 0 P 0 ;0
L 1.41521998 -2.09658002 1.4107 -2.09733002 0 P 0 ;0
L 1.4107 -2.09733002 1.40613002 -2.09775 0 P 0 ;0
L 1.40613002 -2.09775 1.40481004 -2.09778002 0 P 0 ;0
L 1.40481004 -2.09778002 1.40348996 -2.09771998 0 P 0 ;0
L 1.40348996 -2.09771998 1.40216998 -2.09756004 0 P 0 ;0
L 1.40216998 -2.09756004 1.40086998 -2.0973 0 P 0 ;0
L 1.40086998 -2.0973 1.39958996 -2.09695 0 P 0 ;0
L 1.39958996 -2.09695 1.39895 -2.09671998 0 P 0 ;0
L 1.39895 -2.09671998 1.39831998 -2.09643002 0 P 0 ;0
L 1.39831998 -2.09643002 1.39773002 -2.0961 0 P 0 ;0
L 1.39773002 -2.0961 1.39716004 -2.09571004 0 P 0 ;0
L 1.39716004 -2.09571004 1.39663002 -2.09528002 0 P 0 ;0
L 1.39663002 -2.09528002 1.39613996 -2.0948 0 P 0 ;0
L 1.39613996 -2.0948 1.39568002 -2.09428002 0 P 0 ;0
L 1.39568002 -2.09428002 1.39533996 -2.09381998 0 P 0 ;0
L 1.39533996 -2.09381998 1.39505 -2.09333996 0 P 0 ;0
L 1.39505 -2.09333996 1.39478996 -2.09281998 0 P 0 ;0
L 1.39478996 -2.09281998 1.39456998 -2.09228996 0 P 0 ;0
L 1.39456998 -2.09228996 1.3944 -2.09173996 0 P 0 ;0
L 1.3944 -2.09173996 1.39428002 -2.09118996 0 P 0 ;0
L 1.39428002 -2.09118996 1.39421004 -2.09061998 0 P 0 ;0
L 1.39421004 -2.09061998 1.39418002 -2.09003996 0 P 0 ;0
L 1.39418002 -2.09003996 1.39421004 -2.08943002 0 P 0 ;0
L 1.39421004 -2.08943002 1.39428002 -2.08883002 0 P 0 ;0
L 1.39428002 -2.08883002 1.39441004 -2.08823002 0 P 0 ;0
L 1.39441004 -2.08823002 1.3946 -2.08765 0 P 0 ;0
L 1.3946 -2.08765 1.39483002 -2.08708002 0 P 0 ;0
L 1.39483002 -2.08708002 1.39511004 -2.08653996 0 P 0 ;0
L 1.39511004 -2.08653996 1.39555 -2.08583996 0 P 0 ;0
L 1.39555 -2.08583996 1.39603996 -2.08518002 0 P 0 ;0
L 1.39603996 -2.08518002 1.39658002 -2.08456004 0 P 0 ;0
L 1.39658002 -2.08456004 1.39716004 -2.08396998 0 P 0 ;0
L 1.39716004 -2.08396998 1.39778002 -2.08343002 0 P 0 ;0
L 1.39778002 -2.08343002 1.39878996 -2.08266998 0 P 0 ;0
L 1.39878996 -2.08266998 1.39985 -2.08196998 0 P 0 ;0
L 1.39985 -2.08196998 1.40096004 -2.08135 0 P 0 ;0
L 1.40096004 -2.08135 1.40211998 -2.08081004 0 P 0 ;0
L 1.40211998 -2.08081004 1.40503002 -2.07971004 0 P 0 ;0
L 1.40503002 -2.07971004 1.40801998 -2.07881998 0 P 0 ;0
L 1.40801998 -2.07881998 1.41128996 -2.07796004 0 P 0 ;0
L 1.41128996 -2.07796004 1.41506004 -2.07691998 0 P 0 ;0
L 1.41506004 -2.07691998 1.41871998 -2.07585 0 P 0 ;0
L 1.41871998 -2.07585 1.42165 -2.07495 0 P 0 ;0
L 1.42165 -2.07495 1.42791998 -2.07295 0 P 0 ;0
L 1.42791998 -2.07295 1.42731998 -2.08241004 0 P 0 ;0
L 1.42731998 -2.08241004 1.42701004 -2.08708002 0 P 0 ;0
L 1.42701004 -2.08708002 1.42658002 -2.09353996 0 P 0 ;0
L 1.42658002 -2.09353996 1.4261 -2.10055 0 P 0 ;0
L 1.4261 -2.10055 1.42566998 -2.10706004 0 P 0 ;0
L 1.42566998 -2.10706004 1.42525 -2.11306004 0 P 0 ;0
L 1.42525 -2.11306004 1.42491998 -2.11851998 0 P 0 ;0
L 1.42491998 -2.11851998 1.42466004 -2.1231 0 P 0 ;0
L 1.42466004 -2.1231 1.42461004 -2.12471004 0 P 0 ;0
L 1.42461004 -2.12471004 1.4246 -2.12716004 0 P 0 ;0
L 1.4246 -2.12716004 1.47893002 -2.12716004 0 P 0 ;0
L 1.47893002 -2.12716004 1.47893002 -2.11358002 0 P 0 ;0
L 1.47893002 -2.11358002 1.47905 -2.10616998 0 P 0 ;0
L 1.47905 -2.10616998 1.47943996 -2.09385 0 P 0 ;0
L 1.47943996 -2.09385 1.48 -2.07968996 0 P 0 ;0
L 1.48 -2.07968996 1.48066004 -2.0655 0 P 0 ;0
L 1.48066004 -2.0655 1.4813 -2.05168996 0 P 0 ;0
L 1.4813 -2.05168996 1.48175 -2.03873996 0 P 0 ;0
L 1.48175 -2.03873996 1.48201998 -2.02785 0 P 0 ;0
L 1.48201998 -2.02785 1.48191998 -2.02286004 0 P 0 ;0
L 1.48191998 -2.02286004 1.48165 -2.01995 0 P 0 ;0
L 1.48165 -2.01995 1.48115 -2.01708002 0 P 0 ;0
L 1.48115 -2.01708002 1.48043996 -2.01425 0 P 0 ;0
L 1.48043996 -2.01425 1.47951004 -2.01146998 0 P 0 ;0
L 1.47951004 -2.01146998 1.47866998 -2.00946998 0 P 0 ;0
L 1.47866998 -2.00946998 1.47768002 -2.00753996 0 P 0 ;0
L 1.47768002 -2.00753996 1.47655 -2.00568002 0 P 0 ;0
L 1.47655 -2.00568002 1.47528002 -2.00391998 0 P 0 ;0
L 1.47528002 -2.00391998 1.47388002 -2.00225 0 P 0 ;0
L 1.47388002 -2.00225 1.47228996 -2.00063002 0 P 0 ;0
L 1.47228996 -2.00063002 1.4706 -1.99911998 0 P 0 ;0
L 1.4706 -1.99911998 1.4688 -1.99773002 0 P 0 ;0
L 1.4688 -1.99773002 1.46691004 -1.99648002 0 P 0 ;0
L 1.46691004 -1.99648002 1.46491998 -1.99535 0 P 0 ;0
L 1.46491998 -1.99535 1.46098996 -1.99351004 0 P 0 ;0
L 1.46098996 -1.99351004 1.45693002 -1.99196998 0 P 0 ;0
L 1.45693002 -1.99196998 1.45276004 -1.99076004 0 P 0 ;0
L 1.45276004 -1.99076004 1.44953996 -1.99006004 0 P 0 ;0
L 1.44953996 -1.99006004 1.44628996 -1.98956004 0 P 0 ;0
L 1.44628996 -1.98956004 1.44298002 -1.98923996 0 P 0 ;0
L 1.44298002 -1.98923996 1.42695 -1.98856998 0 P 0 ;0
L 1.42695 -1.98856998 1.41038996 -1.98865 0 P 0 ;0
L 1.41038996 -1.98865 1.4042 -1.98901004 0 P 0 ;0
L 1.4042 -1.98901004 1.39798996 -1.98971998 0 P 0 ;0
L 1.35778996 -2.11545 1.4153 -2.11545 0 P 0 ;0
L 1.35688996 -2.11445 1.41558996 -2.11445 0 P 0 ;0
L 1.35608002 -2.11345 1.41588002 -2.11345 0 P 0 ;0
L 1.35533002 -2.11245 1.41616998 -2.11245 0 P 0 ;0
L 1.35463996 -2.11145 1.41646004 -2.11145 0 P 0 ;0
L 1.35401004 -2.11045 1.41675 -2.11045 0 P 0 ;0
L 1.35341004 -2.10945 1.41703996 -2.10945 0 P 0 ;0
L 1.3529 -2.10845 1.41733002 -2.10845 0 P 0 ;0
L 1.35238002 -2.10745 1.41761998 -2.10745 0 P 0 ;0
L 1.35195 -2.10645 1.41788002 -2.10645 0 P 0 ;0
L 1.35155 -2.10545 1.41816004 -2.10545 0 P 0 ;0
L 1.3512 -2.10445 1.41841998 -2.10445 0 P 0 ;0
L 1.35091004 -2.10345 1.41868996 -2.10345 0 P 0 ;0
L 1.35066004 -2.10245 1.41896004 -2.10245 0 P 0 ;0
L 1.35046998 -2.10145 1.41923002 -2.10145 0 P 0 ;0
L 1.35033996 -2.10045 1.41948996 -2.10045 0 P 0 ;0
L 1.35021998 -2.09945 1.40141004 -2.09945 0 P 0 ;0
L 1.35016004 -2.09845 1.39791004 -2.09845 0 P 0 ;0
L 1.3501 -2.09745 1.39616004 -2.09745 0 P 0 ;0
L 1.35008002 -2.09645 1.39496004 -2.09645 0 P 0 ;0
L 1.35006998 -2.09545 1.39406004 -2.09545 0 P 0 ;0
L 1.35005 -2.09445 1.39338002 -2.09445 0 P 0 ;0
L 1.35003996 -2.09345 1.39288002 -2.09345 0 P 0 ;0
L 1.35001998 -2.09245 1.39253002 -2.09245 0 P 0 ;0
L 1.35001004 -2.09145 1.3923 -2.09145 0 P 0 ;0
L 1.35001998 -2.09045 1.3922 -2.09045 0 P 0 ;0
L 1.35003002 -2.08945 1.3922 -2.08945 0 P 0 ;0
L 1.35005 -2.08845 1.39231998 -2.08845 0 P 0 ;0
L 1.35006998 -2.08745 1.39256004 -2.08745 0 P 0 ;0
L 1.35008002 -2.08645 1.39293002 -2.08645 0 P 0 ;0
L 1.3501 -2.08545 1.39343002 -2.08545 0 P 0 ;0
L 1.35011004 -2.08445 1.39408996 -2.08445 0 P 0 ;0
L 1.39438002 -2.12845 1.3883 -2.12836004 0 P 0 ;0
L 1.3883 -2.12836004 1.38426998 -2.128 0 P 0 ;0
L 1.38426998 -2.128 1.38028002 -2.12733002 0 P 0 ;0
L 1.38028002 -2.12733002 1.37635 -2.12636004 0 P 0 ;0
L 1.37635 -2.12636004 1.37248996 -2.12508002 0 P 0 ;0
L 1.37248996 -2.12508002 1.36983996 -2.12398002 0 P 0 ;0
L 1.36983996 -2.12398002 1.36728996 -2.1227 0 P 0 ;0
L 1.36728996 -2.1227 1.36481998 -2.12123996 0 P 0 ;0
L 1.36481998 -2.12123996 1.36246004 -2.11961004 0 P 0 ;0
L 1.36246004 -2.11961004 1.36023002 -2.11781998 0 P 0 ;0
L 1.36023002 -2.11781998 1.35828996 -2.116 0 P 0 ;0
L 1.35828996 -2.116 1.35651998 -2.11403002 0 P 0 ;0
L 1.35651998 -2.11403002 1.35493002 -2.11191004 0 P 0 ;0
L 1.35493002 -2.11191004 1.35353002 -2.10966998 0 P 0 ;0
L 1.35353002 -2.10966998 1.35231004 -2.10731004 0 P 0 ;0
L 1.35231004 -2.10731004 1.35166998 -2.10576998 0 P 0 ;0
L 1.35166998 -2.10576998 1.35111004 -2.1042 0 P 0 ;0
L 1.35111004 -2.1042 1.35071998 -2.10276004 0 P 0 ;0
L 1.35071998 -2.10276004 1.35045 -2.1013 0 P 0 ;0
L 1.35045 -2.1013 1.35021998 -2.09943002 0 P 0 ;0
L 1.35021998 -2.09943002 1.3501 -2.09753002 0 P 0 ;0
L 1.3501 -2.09753002 1.35001004 -2.09128002 0 P 0 ;0
L 1.35001004 -2.09128002 1.35011998 -2.0844 0 P 0 ;0
L 1.35011998 -2.0844 1.35023996 -2.08258996 0 P 0 ;0
L 1.35023996 -2.08258996 1.3505 -2.08083996 0 P 0 ;0
L 1.3505 -2.08083996 1.35071998 -2.07985 0 P 0 ;0
L 1.35071998 -2.07985 1.35101004 -2.07888002 0 P 0 ;0
L 1.35101004 -2.07888002 1.35136004 -2.07793002 0 P 0 ;0
L 1.35136004 -2.07793002 1.35335 -2.07351998 0 P 0 ;0
L 1.35335 -2.07351998 1.35491998 -2.07065 0 P 0 ;0
L 1.35491998 -2.07065 1.35683002 -2.0677 0 P 0 ;0
L 1.35683002 -2.0677 1.35876998 -2.06511004 0 P 0 ;0
L 1.35876998 -2.06511004 1.35948996 -2.0643 0 P 0 ;0
L 1.35948996 -2.0643 1.36026998 -2.06356004 0 P 0 ;0
L 1.36026998 -2.06356004 1.3624 -2.06181998 0 P 0 ;0
L 1.3624 -2.06181998 1.36465 -2.06023996 0 P 0 ;0
L 1.36465 -2.06023996 1.36701004 -2.05883002 0 P 0 ;0
L 1.36701004 -2.05883002 1.37173002 -2.05641004 0 P 0 ;0
L 1.37173002 -2.05641004 1.37656004 -2.05426998 0 P 0 ;0
L 1.37656004 -2.05426998 1.38243002 -2.05203996 0 P 0 ;0
L 1.38243002 -2.05203996 1.38836004 -2.0501 0 P 0 ;0
L 1.38836004 -2.0501 1.4023 -2.04645 0 P 0 ;0
L 1.4023 -2.04645 1.41148996 -2.044 0 P 0 ;0
L 1.41148996 -2.044 1.42016998 -2.04095 0 P 0 ;0
L 1.42016998 -2.04095 1.42016998 -2.04093996 0 P 0 ;0
L 1.42016998 -2.04093996 1.42021004 -2.04093996 0 P 0 ;0
L 1.42021004 -2.04093996 1.42023996 -2.04093002 0 P 0 ;0
L 1.42023996 -2.04093002 1.42746998 -2.03776004 0 P 0 ;0
L 1.42746998 -2.03776004 1.42753002 -2.03773002 0 P 0 ;0
L 1.42753002 -2.03773002 1.42796998 -2.03748996 0 P 0 ;0
L 1.42796998 -2.03748996 1.42846004 -2.03718996 0 P 0 ;0
L 1.42846004 -2.03718996 1.42891998 -2.03683996 0 P 0 ;0
L 1.42891998 -2.03683996 1.42935 -2.03646004 0 P 0 ;0
L 1.42935 -2.03646004 1.42975 -2.03603996 0 P 0 ;0
L 1.42975 -2.03603996 1.43011004 -2.0356 0 P 0 ;0
L 1.43011004 -2.0356 1.43016004 -2.03553002 0 P 0 ;0
L 1.43016004 -2.03553002 1.4299 -2.03535 0 P 0 ;0
L 1.4299 -2.03535 1.43028002 -2.03535 0 P 0 ;0
L 1.43028002 -2.03535 1.43043996 -2.03513002 0 P 0 ;0
L 1.43043996 -2.03513002 1.43048002 -2.03506004 0 P 0 ;0
L 1.43048002 -2.03506004 1.43041998 -2.03501998 0 P 0 ;0
L 1.43041998 -2.03501998 1.4305 -2.03501998 0 P 0 ;0
L 1.4305 -2.03501998 1.43073002 -2.03463002 0 P 0 ;0
L 1.43073002 -2.03463002 1.43096004 -2.03415 0 P 0 ;0
L 1.43096004 -2.03415 1.43115 -2.03365 0 P 0 ;0
L 1.43115 -2.03365 1.4313 -2.03313002 0 P 0 ;0
L 1.4313 -2.03313002 1.4314 -2.03261004 0 P 0 ;0
L 1.4314 -2.03261004 1.43146004 -2.03208002 0 P 0 ;0
L 1.43146004 -2.03208002 1.43146998 -2.03155 0 P 0 ;0
L 1.43146998 -2.03155 1.43143996 -2.03101004 0 P 0 ;0
L 1.43143996 -2.03101004 1.43143002 -2.03093002 0 P 0 ;0
L 1.43143002 -2.03093002 1.43136004 -2.03048996 0 P 0 ;0
L 1.43136004 -2.03048996 1.43125 -2.02996998 0 P 0 ;0
L 1.43125 -2.02996998 1.43108002 -2.02946004 0 P 0 ;0
L 1.43108002 -2.02946004 1.43086998 -2.02896004 0 P 0 ;0
L 1.43086998 -2.02896004 1.43063002 -2.02848996 0 P 0 ;0
L 1.43063002 -2.02848996 1.43033996 -2.02803996 0 P 0 ;0
L 1.43033996 -2.02803996 1.43001998 -2.02761004 0 P 0 ;0
L 1.43001998 -2.02761004 1.42966004 -2.02721004 0 P 0 ;0
L 1.42966004 -2.02721004 1.42928002 -2.02685 0 P 0 ;0
L 1.42928002 -2.02685 1.42886004 -2.02651998 0 P 0 ;0
L 1.42886004 -2.02651998 1.42841998 -2.02623002 0 P 0 ;0
L 1.42841998 -2.02623002 1.42795 -2.02596998 0 P 0 ;0
L 1.42795 -2.02596998 1.42746004 -2.02575 0 P 0 ;0
L 1.42746004 -2.02575 1.42583002 -2.02518002 0 P 0 ;0
L 1.42583002 -2.02518002 1.42416004 -2.02476004 0 P 0 ;0
L 1.42416004 -2.02476004 1.42245 -2.02448002 0 P 0 ;0
L 1.42245 -2.02448002 1.42075 -2.02435 0 P 0 ;0
L 1.42075 -2.02435 1.41565 -2.02428002 0 P 0 ;0
L 1.41565 -2.02428002 1.4156 -2.02428002 0 P 0 ;0
L 1.4156 -2.02428002 1.41055 -2.02445 0 P 0 ;0
L 1.41055 -2.02445 1.41048002 -2.02445 0 P 0 ;0
L 1.41048002 -2.02445 1.40128996 -2.02533996 0 P 0 ;0
L 1.40128996 -2.02533996 1.39208996 -2.02696998 0 P 0 ;0
L 1.39208996 -2.02696998 1.38288002 -2.02936004 0 P 0 ;0
L 1.38288002 -2.02936004 1.37363002 -2.03251998 0 P 0 ;0
L 1.37363002 -2.03251998 1.37076998 -2.03356004 0 P 0 ;0
L 1.37076998 -2.03356004 1.36865 -2.03426998 0 P 0 ;0
L 1.36865 -2.03426998 1.36906004 -2.03066998 0 P 0 ;0
L 1.36906004 -2.03066998 1.36988996 -2.02383996 0 P 0 ;0
L 1.36988996 -2.02383996 1.37095 -2.01581004 0 P 0 ;0
L 1.37095 -2.01581004 1.37358996 -1.99631998 0 P 0 ;0
L 1.37358996 -1.99631998 1.37988002 -1.99491998 0 P 0 ;0
L 1.37988002 -1.99491998 1.38353996 -1.99416998 0 P 0 ;0
L 1.38353996 -1.99416998 1.38841998 -1.99326998 0 P 0 ;0
L 1.38841998 -1.99326998 1.39358002 -1.9924 0 P 0 ;0
L 1.39358002 -1.9924 1.39825 -1.9917 0 P 0 ;0
L 1.39825 -1.9917 1.40436998 -1.991 0 P 0 ;0
L 1.40436998 -1.991 1.41045 -1.99065 0 P 0 ;0
L 1.41045 -1.99065 1.42691004 -1.99056998 0 P 0 ;0
L 1.42691004 -1.99056998 1.44283996 -1.99123996 0 P 0 ;0
L 1.44283996 -1.99123996 1.44603996 -1.99153996 0 P 0 ;0
L 1.44603996 -1.99153996 1.44918002 -1.99203002 0 P 0 ;0
L 1.44918002 -1.99203002 1.45226004 -1.9927 0 P 0 ;0
L 1.45226004 -1.9927 1.4563 -1.99386998 0 P 0 ;0
L 1.4563 -1.99386998 1.46021004 -1.99535 0 P 0 ;0
L 1.46021004 -1.99535 1.464 -1.99713002 0 P 0 ;0
L 1.464 -1.99713002 1.46586004 -1.99818996 0 P 0 ;0
L 1.46586004 -1.99818996 1.46763996 -1.99936004 0 P 0 ;0
L 1.46763996 -1.99936004 1.46931998 -2.00066004 0 P 0 ;0
L 1.46931998 -2.00066004 1.47091004 -2.00206998 0 P 0 ;0
L 1.47091004 -2.00206998 1.47238996 -2.00358996 0 P 0 ;0
L 1.47238996 -2.00358996 1.4737 -2.00515 0 P 0 ;0
L 1.4737 -2.00515 1.47488002 -2.00678996 0 P 0 ;0
L 1.47488002 -2.00678996 1.47593996 -2.00851004 0 P 0 ;0
L 1.47593996 -2.00851004 1.47686004 -2.01031004 0 P 0 ;0
L 1.47686004 -2.01031004 1.47763996 -2.01216998 0 P 0 ;0
L 1.47763996 -2.01216998 1.47851998 -2.01481004 0 P 0 ;0
L 1.47851998 -2.01481004 1.47918996 -2.01748996 0 P 0 ;0
L 1.47918996 -2.01748996 1.47966004 -2.02021998 0 P 0 ;0
L 1.47966004 -2.02021998 1.47993002 -2.02296998 0 P 0 ;0
L 1.47993002 -2.02296998 1.48001998 -2.02783996 0 P 0 ;0
L 1.48001998 -2.02783996 1.47975 -2.03868996 0 P 0 ;0
L 1.47975 -2.03868996 1.4793 -2.05161004 0 P 0 ;0
L 1.4793 -2.05161004 1.47866004 -2.06543002 0 P 0 ;0
L 1.47866004 -2.06543002 1.47801004 -2.07961004 0 P 0 ;0
L 1.47801004 -2.07961004 1.47743996 -2.09378996 0 P 0 ;0
L 1.47743996 -2.09378996 1.47705 -2.10613002 0 P 0 ;0
L 1.47705 -2.10613002 1.47693002 -2.11356004 0 P 0 ;0
L 1.47693002 -2.11356004 1.47693002 -2.12516004 0 P 0 ;0
L 1.47693002 -2.12516004 1.42661004 -2.12516004 0 P 0 ;0
L 1.42661004 -2.12516004 1.42661004 -2.12473996 0 P 0 ;0
L 1.42661004 -2.12473996 1.42666004 -2.12318002 0 P 0 ;0
L 1.42666004 -2.12318002 1.42691004 -2.11863996 0 P 0 ;0
L 1.42691004 -2.11863996 1.42725 -2.1132 0 P 0 ;0
L 1.42725 -2.1132 1.42766004 -2.1072 0 P 0 ;0
L 1.42766004 -2.1072 1.42766004 -2.10718996 0 P 0 ;0
L 1.42766004 -2.10718996 1.4281 -2.10068996 0 P 0 ;0
L 1.4281 -2.10068996 1.42858002 -2.09368002 0 P 0 ;0
L 1.42858002 -2.09368002 1.42901004 -2.08721004 0 P 0 ;0
L 1.42901004 -2.08721004 1.42901004 -2.0872 0 P 0 ;0
L 1.42901004 -2.0872 1.42931004 -2.08256004 0 P 0 ;0
L 1.42931004 -2.08256004 1.42991998 -2.07308002 0 P 0 ;0
L 1.42991998 -2.07308002 1.42916004 -2.07136998 0 P 0 ;0
L 1.42916004 -2.07136998 1.42731998 -2.07105 0 P 0 ;0
L 1.42731998 -2.07105 1.42105 -2.07303996 0 P 0 ;0
L 1.42105 -2.07303996 1.41815 -2.07393002 0 P 0 ;0
L 1.41815 -2.07393002 1.41451004 -2.075 0 P 0 ;0
L 1.41451004 -2.075 1.41076004 -2.07603002 0 P 0 ;0
L 1.41076004 -2.07603002 1.40748002 -2.0769 0 P 0 ;0
L 1.40748002 -2.0769 1.40438996 -2.07781004 0 P 0 ;0
L 1.40438996 -2.07781004 1.40431998 -2.07783996 0 P 0 ;0
L 1.40431998 -2.07783996 1.40133996 -2.07896998 0 P 0 ;0
L 1.40133996 -2.07896998 1.40005 -2.07956998 0 P 0 ;0
L 1.40005 -2.07956998 1.39881998 -2.08026004 0 P 0 ;0
L 1.39881998 -2.08026004 1.39763996 -2.08103002 0 P 0 ;0
L 1.39763996 -2.08103002 1.39651998 -2.08188002 0 P 0 ;0
L 1.39651998 -2.08188002 1.39578996 -2.08251004 0 P 0 ;0
L 1.39578996 -2.08251004 1.39573996 -2.08256004 0 P 0 ;0
L 1.39573996 -2.08256004 1.3951 -2.08318996 0 P 0 ;0
L 1.3951 -2.08318996 1.39446998 -2.08393002 0 P 0 ;0
L 1.39446998 -2.08393002 1.3939 -2.08471004 0 P 0 ;0
L 1.3939 -2.08471004 1.39336998 -2.08553996 0 P 0 ;0
L 1.39336998 -2.08553996 1.39301004 -2.08623996 0 P 0 ;0
L 1.39301004 -2.08623996 1.39271004 -2.08696998 0 P 0 ;0
L 1.39271004 -2.08696998 1.39248002 -2.08771998 0 P 0 ;0
L 1.39248002 -2.08771998 1.39231004 -2.08848996 0 P 0 ;0
L 1.39231004 -2.08848996 1.39221004 -2.08926004 0 P 0 ;0
L 1.39221004 -2.08926004 1.39218002 -2.09003996 0 P 0 ;0
L 1.39218002 -2.09003996 1.39221004 -2.0908 0 P 0 ;0
L 1.39221004 -2.0908 1.39231004 -2.09153002 0 P 0 ;0
L 1.39231004 -2.09153002 1.39246998 -2.09226004 0 P 0 ;0
L 1.39246998 -2.09226004 1.39268996 -2.09296998 0 P 0 ;0
L 1.39268996 -2.09296998 1.39296004 -2.09365 0 P 0 ;0
L 1.39296004 -2.09365 1.3933 -2.09431004 0 P 0 ;0
L 1.3933 -2.09431004 1.39368996 -2.09493996 0 P 0 ;0
L 1.39368996 -2.09493996 1.39411998 -2.09553996 0 P 0 ;0
L 1.39411998 -2.09553996 1.39468996 -2.09618002 0 P 0 ;0
L 1.39468996 -2.09618002 1.3953 -2.09678002 0 P 0 ;0
L 1.3953 -2.09678002 1.39596004 -2.09731998 0 P 0 ;0
L 1.39596004 -2.09731998 1.39666998 -2.0978 0 P 0 ;0
L 1.39666998 -2.0978 1.39673996 -2.09783996 0 P 0 ;0
L 1.39673996 -2.09783996 1.39741004 -2.09821998 0 P 0 ;0
L 1.39741004 -2.09821998 1.39748996 -2.09825 0 P 0 ;0
L 1.39748996 -2.09825 1.39818996 -2.09856998 0 P 0 ;0
L 1.39818996 -2.09856998 1.39898996 -2.09886004 0 P 0 ;0
L 1.39898996 -2.09886004 1.39906998 -2.09888002 0 P 0 ;0
L 1.39906998 -2.09888002 1.40043996 -2.09888002 0 P 0 ;0
L 1.40043996 -2.09888002 1.40033996 -2.09923002 0 P 0 ;0
L 1.40033996 -2.09923002 1.40041998 -2.09925 0 P 0 ;0
L 1.40041998 -2.09925 1.40186004 -2.09953002 0 P 0 ;0
L 1.40186004 -2.09953002 1.40331004 -2.09971004 0 P 0 ;0
L 1.40331004 -2.09971004 1.40478002 -2.09978002 0 P 0 ;0
L 1.40478002 -2.09978002 1.40625 -2.09975 0 P 0 ;0
L 1.40625 -2.09975 1.41096004 -2.09931004 0 P 0 ;0
L 1.41096004 -2.09931004 1.41556998 -2.09855 0 P 0 ;0
L 1.41556998 -2.09855 1.41791998 -2.09813002 0 P 0 ;0
L 1.41791998 -2.09813002 1.41995 -2.09791004 0 P 0 ;0
L 1.41995 -2.09791004 1.4201 -2.0979 0 P 0 ;0
L 1.4201 -2.0979 1.41941004 -2.10078002 0 P 0 ;0
L 1.41941004 -2.10078002 1.41761004 -2.10745 0 P 0 ;0
L 1.41761004 -2.10745 1.41391004 -2.12025 0 P 0 ;0
L 1.41391004 -2.12025 1.41215 -2.12626998 0 P 0 ;0
L 1.41215 -2.12626998 1.40655 -2.12725 0 P 0 ;0
L 1.40655 -2.12725 1.40046004 -2.12808002 0 P 0 ;0
L 1.40046004 -2.12808002 1.39438002 -2.12845 0 P 0 ;0
L 1.15303002 -2.08283002 1.20788996 -2.08283002 0 P 0 ;0
L 1.15398996 -2.08183002 1.20795 -2.08183002 0 P 0 ;0
L 1.15483002 -2.08083002 1.208 -2.08083002 0 P 0 ;0
L 1.15555 -2.07983002 1.20805 -2.07983002 0 P 0 ;0
L 1.15621998 -2.07883002 1.2081 -2.07883002 0 P 0 ;0
L 1.15681998 -2.07783002 1.20816004 -2.07783002 0 P 0 ;0
L 1.15733002 -2.07683002 1.20821004 -2.07683002 0 P 0 ;0
L 1.15778996 -2.07583002 1.20826004 -2.07583002 0 P 0 ;0
L 1.15818002 -2.07483002 1.20831004 -2.07483002 0 P 0 ;0
L 1.15853996 -2.07383002 1.20836998 -2.07383002 0 P 0 ;0
L 1.15881998 -2.07283002 1.20841998 -2.07283002 0 P 0 ;0
L 1.1591 -2.07183002 1.20846998 -2.07183002 0 P 0 ;0
L 1.15938002 -2.07083002 1.20853002 -2.07083002 0 P 0 ;0
L 1.1596 -2.06983002 1.20858002 -2.06983002 0 P 0 ;0
L 1.15981004 -2.06883002 1.20863996 -2.06883002 0 P 0 ;0
L 1.16001004 -2.06783002 1.20868996 -2.06783002 0 P 0 ;0
L 1.1602 -2.06683002 1.20875 -2.06683002 0 P 0 ;0
L 1.16033996 -2.06583002 1.2088 -2.06583002 0 P 0 ;0
L 1.16048996 -2.06483002 1.20886004 -2.06483002 0 P 0 ;0
L 1.16063996 -2.06383002 1.20891998 -2.06383002 0 P 0 ;0
L 1.16078002 -2.06283002 1.20896998 -2.06283002 0 P 0 ;0
L 1.16088996 -2.06183002 1.20903002 -2.06183002 0 P 0 ;0
L 1.16098996 -2.06083002 1.20908002 -2.06083002 0 P 0 ;0
L 1.16108996 -2.05983002 1.20913996 -2.05983002 0 P 0 ;0
L 1.16118002 -2.05883002 1.20918996 -2.05883002 0 P 0 ;0
L 1.16128002 -2.05783002 1.20925 -2.05783002 0 P 0 ;0
L 1.16133996 -2.05683002 1.2093 -2.05683002 0 P 0 ;0
L 1.1614 -2.05583002 1.20936004 -2.05583002 0 P 0 ;0
L 1.16146004 -2.05483002 1.20941004 -2.05483002 0 P 0 ;0
L 1.16151998 -2.05383002 1.20946998 -2.05383002 0 P 0 ;0
L 1.16158002 -2.05283002 1.20951998 -2.05283002 0 P 0 ;0
L 1.16163996 -2.05183002 1.20958002 -2.05183002 0 P 0 ;0
L 1.1617 -2.05083002 1.20963996 -2.05083002 0 P 0 ;0
L 1.16175 -2.04983002 1.2097 -2.04983002 0 P 0 ;0
L 1.16181004 -2.04883002 1.20975 -2.04883002 0 P 0 ;0
L 1.16186998 -2.04783002 1.20981004 -2.04783002 0 P 0 ;0
L 1.16193002 -2.04683002 1.20986998 -2.04683002 0 P 0 ;0
L 1.16198996 -2.04583002 1.20993002 -2.04583002 0 P 0 ;0
L 1.16205 -2.04483002 1.20998996 -2.04483002 0 P 0 ;0
L 1.16211004 -2.04383002 1.21005 -2.04383002 0 P 0 ;0
L 1.16215 -2.04283002 1.2101 -2.04283002 0 P 0 ;0
L 1.1622 -2.04183002 1.21016004 -2.04183002 0 P 0 ;0
L 1.16225 -2.04083002 1.21021998 -2.04083002 0 P 0 ;0
L 1.16228996 -2.03983002 1.21028002 -2.03983002 0 P 0 ;0
L 1.16233996 -2.03883002 1.21033996 -2.03883002 0 P 0 ;0
L 1.16238002 -2.03783002 1.2104 -2.03783002 0 P 0 ;0
L 1.16243002 -2.03683002 1.21046004 -2.03683002 0 P 0 ;0
L 1.16246998 -2.03583002 1.21051004 -2.03583002 0 P 0 ;0
L 1.16251998 -2.03483002 1.21056998 -2.03483002 0 P 0 ;0
L 1.16256998 -2.03383002 1.21063996 -2.03383002 0 P 0 ;0
L 1.16261004 -2.03283002 1.2107 -2.03283002 0 P 0 ;0
L 1.16266004 -2.03183002 1.21076004 -2.03183002 0 P 0 ;0
L 1.1627 -2.03083002 1.21083002 -2.03083002 0 P 0 ;0
L 1.16015 -1.97631004 1.17066004 -1.97631004 0 P 0 ;0
L 1.15961998 -1.97531004 1.17026004 -1.97531004 0 P 0 ;0
L 1.1591 -1.97431004 1.16986998 -1.97431004 0 P 0 ;0
L 1.15856998 -1.97331004 1.16946998 -1.97331004 0 P 0 ;0
L 1.15803996 -1.97231004 1.16903002 -1.97231004 0 P 0 ;0
L 1.15746998 -1.97131004 1.16858996 -1.97131004 0 P 0 ;0
L 1.1569 -1.97031004 1.16815 -1.97031004 0 P 0 ;0
L 1.15631998 -1.96931004 1.16771004 -1.96931004 0 P 0 ;0
L 1.15573996 -1.96831004 1.16726998 -1.96831004 0 P 0 ;0
L 1.15516004 -1.96731004 1.16681998 -1.96731004 0 P 0 ;0
L 1.15458996 -1.96631004 1.16638002 -1.96631004 0 P 0 ;0
L 1.15398002 -1.96531004 1.16593996 -1.96531004 0 P 0 ;0
L 1.1533 -1.96431004 1.16548996 -1.96431004 0 P 0 ;0
L 1.15261998 -1.96331004 1.16503002 -1.96331004 0 P 0 ;0
L 1.15193996 -1.96231004 1.16448002 -1.96231004 0 P 0 ;0
L 1.15126004 -1.96131004 1.16393002 -1.96131004 0 P 0 ;0
L 1.15058002 -1.96031004 1.16338002 -1.96031004 0 P 0 ;0
L 1.1499 -1.95931004 1.16283002 -1.95931004 0 P 0 ;0
L 1.1491 -1.95831004 1.16228996 -1.95831004 0 P 0 ;0
L 1.14831004 -1.95731004 1.16173996 -1.95731004 0 P 0 ;0
L 1.14751004 -1.95631004 1.16118996 -1.95631004 0 P 0 ;0
L 1.14671004 -1.95531004 1.16063996 -1.95531004 0 P 0 ;0
L 1.14591998 -1.95431004 1.16008996 -1.95431004 0 P 0 ;0
L 1.14511998 -1.95331004 1.15943996 -1.95331004 0 P 0 ;0
L 1.1442 -1.95231004 1.15878002 -1.95231004 0 P 0 ;0
L 1.14326998 -1.95131004 1.15811004 -1.95131004 0 P 0 ;0
L 1.14233996 -1.95031004 1.15745 -1.95031004 0 P 0 ;0
L 1.14141004 -1.94931004 1.15678002 -1.94931004 0 P 0 ;0
L 1.14048996 -1.94831004 1.15611998 -1.94831004 0 P 0 ;0
L 1.1395 -1.94731004 1.15545 -1.94731004 0 P 0 ;0
L 1.13843002 -1.94631004 1.15478996 -1.94631004 0 P 0 ;0
L 1.13736004 -1.94531004 1.15411998 -1.94531004 0 P 0 ;0
L 1.13628996 -1.94431004 1.15333002 -1.94431004 0 P 0 ;0
L 1.13521004 -1.94331004 1.15253002 -1.94331004 0 P 0 ;0
L 1.13413996 -1.94231004 1.15173996 -1.94231004 0 P 0 ;0
L 1.13306998 -1.94131004 1.15093996 -1.94131004 0 P 0 ;0
L 1.132 -1.94031004 1.15013996 -1.94031004 0 P 0 ;0
L 1.13081004 -1.93931004 1.14935 -1.93931004 0 P 0 ;0
L 1.12958002 -1.93831004 1.14855 -1.93831004 0 P 0 ;0
L 1.12833996 -1.93731004 1.14775 -1.93731004 0 P 0 ;0
L 1.1271 -1.93631004 1.14688996 -1.93631004 0 P 0 ;0
L 1.12586004 -1.93531004 1.14593996 -1.93531004 0 P 0 ;0
L 1.12461998 -1.93431004 1.14498996 -1.93431004 0 P 0 ;0
L 1.12338002 -1.93331004 1.14405 -1.93331004 0 P 0 ;0
L 1.12203002 -1.93231004 1.1431 -1.93231004 0 P 0 ;0
L 1.1206 -1.93131004 1.14216004 -1.93131004 0 P 0 ;0
L 1.11916004 -1.93031004 1.14121004 -1.93031004 0 P 0 ;0
L 1.11771998 -1.92931004 1.14026998 -1.92931004 0 P 0 ;0
L 1.11628996 -1.92831004 1.13931998 -1.92831004 0 P 0 ;0
L 1.11483996 -1.92731004 1.13838002 -1.92731004 0 P 0 ;0
L 1.11338996 -1.92631004 1.13743002 -1.92631004 0 P 0 ;0
L 1.11171998 -1.92531004 1.13648996 -1.92531004 0 P 0 ;0
L 1.11005 -1.92431004 1.13538002 -1.92431004 0 P 0 ;0
L 1.10838002 -1.92331004 1.13426998 -1.92331004 0 P 0 ;0
L 1.1067 -1.92231004 1.13315 -1.92231004 0 P 0 ;0
L 1.10503002 -1.92131004 1.13203002 -1.92131004 0 P 0 ;0
L 1.10336004 -1.92031004 1.13091998 -1.92031004 0 P 0 ;0
L 1.1015 -1.91931004 1.1298 -1.91931004 0 P 0 ;0
L 1.09955 -1.91831004 1.12868002 -1.91831004 0 P 0 ;0
L 1.16275 -2.02983002 1.21088996 -2.02983002 0 P 0 ;0
L 1.16278996 -2.02883002 1.21095 -2.02883002 0 P 0 ;0
L 1.16283996 -2.02783002 1.21101004 -2.02783002 0 P 0 ;0
L 1.16226998 -2.02683002 1.21108002 -2.02683002 0 P 0 ;0
L 1.16153996 -2.02583002 1.21113996 -2.02583002 0 P 0 ;0
L 1.15846004 -2.02483002 1.2112 -2.02483002 0 P 0 ;0
L 1.10036004 -2.00383002 1.21255 -2.00383002 0 P 0 ;0
L 1.10226004 -2.00283002 1.2126 -2.00283002 0 P 0 ;0
L 1.10433996 -2.00183002 1.21266998 -2.00183002 0 P 0 ;0
L 1.1065 -2.00083002 1.21273002 -2.00083002 0 P 0 ;0
L 1.10886998 -1.99983002 1.21278996 -1.99983002 0 P 0 ;0
L 1.11138002 -1.99883002 1.21285 -1.99883002 0 P 0 ;0
L 1.11436998 -1.99783002 1.21288002 -1.99783002 0 P 0 ;0
L 1.11748996 -1.99683002 1.21255 -1.99683002 0 P 0 ;0
L 1.12061998 -1.99583002 1.2089 -1.99583002 0 P 0 ;0
L 1.12433996 -1.99483002 1.2036 -1.99483002 0 P 0 ;0
L 1.12863996 -1.99383002 1.19728002 -1.99383002 0 P 0 ;0
L 1.13295 -1.99283002 1.19096998 -1.99283002 0 P 0 ;0
L 1.13985 -1.99183002 1.18111998 -1.99183002 0 P 0 ;0
L 1.14948002 -1.99083002 1.1651 -1.99083002 0 P 0 ;0
L 1.24218002 -2.08316004 1.29143996 -2.08316004 0 P 0 ;0
L 1.24223002 -2.08216004 1.29151004 -2.08216004 0 P 0 ;0
L 1.24228002 -2.08116004 1.29158996 -2.08116004 0 P 0 ;0
L 1.24233996 -2.08016004 1.29166004 -2.08016004 0 P 0 ;0
L 1.24238996 -2.07916004 1.29173002 -2.07916004 0 P 0 ;0
L 1.24245 -2.07816004 1.29181004 -2.07816004 0 P 0 ;0
L 1.2425 -2.07716004 1.29188002 -2.07716004 0 P 0 ;0
L 1.24256004 -2.07616004 1.29195 -2.07616004 0 P 0 ;0
L 1.24261004 -2.07516004 1.29203002 -2.07516004 0 P 0 ;0
L 1.24266998 -2.07416004 1.2921 -2.07416004 0 P 0 ;0
L 1.24271998 -2.07316004 1.29216998 -2.07316004 0 P 0 ;0
L 1.24278002 -2.07216004 1.29223996 -2.07216004 0 P 0 ;0
L 1.24283002 -2.07116004 1.29231998 -2.07116004 0 P 0 ;0
L 1.24288002 -2.07016004 1.29238996 -2.07016004 0 P 0 ;0
L 1.24293002 -2.06916004 1.29246004 -2.06916004 0 P 0 ;0
L 1.24296998 -2.06816004 1.29253002 -2.06816004 0 P 0 ;0
L 1.24301998 -2.06716004 1.29261004 -2.06716004 0 P 0 ;0
L 1.24306004 -2.06616004 1.2927 -2.06616004 0 P 0 ;0
L 1.24311004 -2.06516004 1.29281004 -2.06516004 0 P 0 ;0
L 1.24315 -2.06416004 1.29291998 -2.06416004 0 P 0 ;0
L 1.2432 -2.06316004 1.29303002 -2.06316004 0 P 0 ;0
L 1.24323996 -2.06216004 1.29315 -2.06216004 0 P 0 ;0
L 1.24328996 -2.06116004 1.29331998 -2.06116004 0 P 0 ;0
L 1.24333002 -2.06016004 1.2935 -2.06016004 0 P 0 ;0
L 1.24338002 -2.05916004 1.29366998 -2.05916004 0 P 0 ;0
L 1.24341998 -2.05816004 1.29385 -2.05816004 0 P 0 ;0
L 1.24346998 -2.05716004 1.29408996 -2.05716004 0 P 0 ;0
L 1.24351004 -2.05616004 1.29433996 -2.05616004 0 P 0 ;0
L 1.24355 -2.05516004 1.29458996 -2.05516004 0 P 0 ;0
L 1.2436 -2.05416004 1.29485 -2.05416004 0 P 0 ;0
L 1.24363996 -2.05316004 1.29516998 -2.05316004 0 P 0 ;0
L 1.24368996 -2.05216004 1.29551998 -2.05216004 0 P 0 ;0
L 1.24373002 -2.05116004 1.29586004 -2.05116004 0 P 0 ;0
L 1.24378002 -2.05016004 1.29621004 -2.05016004 0 P 0 ;0
L 1.24383002 -2.04916004 1.29663996 -2.04916004 0 P 0 ;0
L 1.24386998 -2.04816004 1.29708002 -2.04816004 0 P 0 ;0
L 1.24391004 -2.04716004 1.29753002 -2.04716004 0 P 0 ;0
L 1.24396004 -2.04616004 1.29796998 -2.04616004 0 P 0 ;0
L 1.244 -2.04516004 1.29851004 -2.04516004 0 P 0 ;0
L 1.24405 -2.04416004 1.2991 -2.04416004 0 P 0 ;0
L 1.24408996 -2.04316004 1.29975 -2.04316004 0 P 0 ;0
L 1.24413996 -2.04216004 1.3005 -2.04216004 0 P 0 ;0
L 1.24418002 -2.04116004 1.30131998 -2.04116004 0 P 0 ;0
L 1.24423002 -2.04016004 1.30223002 -2.04016004 0 P 0 ;0
L 1.24426998 -2.03916004 1.30326998 -2.03916004 0 P 0 ;0
L 1.24431998 -2.03816004 1.30446004 -2.03816004 0 P 0 ;0
L 1.24436004 -2.03716004 1.30581998 -2.03716004 0 P 0 ;0
L 1.24441004 -2.03616004 1.30738002 -2.03616004 0 P 0 ;0
L 1.24445 -2.03516004 1.30923002 -2.03516004 0 P 0 ;0
L 1.24448996 -2.03416004 1.31156004 -2.03416004 0 P 0 ;0
L 1.24453996 -2.03316004 1.31478996 -2.03316004 0 P 0 ;0
L 1.24458996 -2.03216004 1.32013002 -2.03216004 0 P 0 ;0
L 1.24461998 -2.03116004 1.33481004 -2.03116004 0 P 0 ;0
L 1.24463996 -2.03016004 1.33478002 -2.03016004 0 P 0 ;0
L 1.24466004 -2.02916004 1.33473996 -2.02916004 0 P 0 ;0
L 1.24468002 -2.02816004 1.33471004 -2.02816004 0 P 0 ;0
L 1.2447 -2.02716004 1.33468002 -2.02716004 0 P 0 ;0
L 1.24471998 -2.02616004 1.33463996 -2.02616004 0 P 0 ;0
L 1.24473996 -2.02516004 1.3346 -2.02516004 0 P 0 ;0
L 1.24476004 -2.02416004 1.33456998 -2.02416004 0 P 0 ;0
L 1.24478002 -2.02316004 1.33453002 -2.02316004 0 P 0 ;0
L 1.2448 -2.02216004 1.3345 -2.02216004 0 P 0 ;0
L 1.24481998 -2.02116004 1.33446998 -2.02116004 0 P 0 ;0
L 1.24483996 -2.02016004 1.33443002 -2.02016004 0 P 0 ;0
L 1.24486004 -2.01916004 1.3344 -2.01916004 0 P 0 ;0
L 1.24488002 -2.01816004 1.33436004 -2.01816004 0 P 0 ;0
L 1.2449 -2.01716004 1.33433002 -2.01716004 0 P 0 ;0
L 1.24491998 -2.01616004 1.33428996 -2.01616004 0 P 0 ;0
L 1.24493996 -2.01516004 1.33426004 -2.01516004 0 P 0 ;0
L 1.24496004 -2.01416004 1.33421998 -2.01416004 0 P 0 ;0
L 1.24498002 -2.01316004 1.33418996 -2.01316004 0 P 0 ;0
L 1.245 -2.01216004 1.33415 -2.01216004 0 P 0 ;0
L 1.24501998 -2.01116004 1.33411998 -2.01116004 0 P 0 ;0
L 1.24503996 -2.01016004 1.33408002 -2.01016004 0 P 0 ;0
L 1.24506004 -2.00916004 1.33403996 -2.00916004 0 P 0 ;0
L 1.24508002 -2.00816004 1.334 -2.00816004 0 P 0 ;0
L 1.2451 -2.00716004 1.33396004 -2.00716004 0 P 0 ;0
L 1.24511998 -2.00616004 1.33393002 -2.00616004 0 P 0 ;0
L 1.24513996 -2.00516004 1.29098996 -2.00516004 0 P 0 ;0
L 1.24513996 -2.00416004 1.29033002 -2.00416004 0 P 0 ;0
L 1.24513996 -2.00316004 1.29005 -2.00316004 0 P 0 ;0
L 1.24513996 -2.00216004 1.29005 -2.00216004 0 P 0 ;0
L 1.24513996 -2.00116004 1.29005 -2.00116004 0 P 0 ;0
L 1.24515 -2.00016004 1.29005 -2.00016004 0 P 0 ;0
L 1.24515 -1.99916004 1.29005 -1.99916004 0 P 0 ;0
L 1.24515 -1.99816004 1.29005 -1.99816004 0 P 0 ;0
L 1.24515 -1.99716004 1.29005 -1.99716004 0 P 0 ;0
L 1.24515 -1.99616004 1.29005 -1.99616004 0 P 0 ;0
L 1.24515 -1.99516004 1.29005 -1.99516004 0 P 0 ;0
L 1.16085 -2.02753002 1.1601 -2.04393002 0 P 0 ;0
L 1.1601 -2.04393002 1.15928996 -2.05771998 0 P 0 ;0
L 1.15928996 -2.05771998 1.15883996 -2.06228002 0 P 0 ;0
L 1.15883996 -2.06228002 1.15818002 -2.06681998 0 P 0 ;0
L 1.15818002 -2.06681998 1.15751004 -2.07006998 0 P 0 ;0
L 1.15751004 -2.07006998 1.15661004 -2.07328996 0 P 0 ;0
L 1.15661004 -2.07328996 1.15616004 -2.07453996 0 P 0 ;0
L 1.15616004 -2.07453996 1.15563002 -2.07576998 0 P 0 ;0
L 1.15563002 -2.07576998 1.15501998 -2.07696004 0 P 0 ;0
L 1.15501998 -2.07696004 1.15433002 -2.0781 0 P 0 ;0
L 1.15433002 -2.0781 1.1534 -2.07941998 0 P 0 ;0
L 1.1534 -2.07941998 1.15236004 -2.08066004 0 P 0 ;0
L 1.15236004 -2.08066004 1.15123002 -2.08181998 0 P 0 ;0
L 1.15123002 -2.08181998 1.15001004 -2.08286998 0 P 0 ;0
L 1.15001004 -2.08286998 1.14871004 -2.08383002 0 P 0 ;0
L 1.14871004 -2.08383002 1.14733002 -2.08468002 0 P 0 ;0
L 1.14733002 -2.08468002 1.14591004 -2.0854 0 P 0 ;0
L 1.14591004 -2.0854 1.14443996 -2.086 0 P 0 ;0
L 1.14443996 -2.086 1.14291004 -2.08648002 0 P 0 ;0
L 1.14291004 -2.08648002 1.14136004 -2.08683002 0 P 0 ;0
L 1.14136004 -2.08683002 1.13976998 -2.08703996 0 P 0 ;0
L 1.13976998 -2.08703996 1.13816004 -2.08713002 0 P 0 ;0
L 1.13816004 -2.08713002 1.13656998 -2.08708002 0 P 0 ;0
L 1.13656998 -2.08708002 1.13498996 -2.0869 0 P 0 ;0
L 1.13498996 -2.0869 1.13341998 -2.08658996 0 P 0 ;0
L 1.13341998 -2.08658996 1.13188996 -2.08615 0 P 0 ;0
L 1.13188996 -2.08615 1.1304 -2.08558996 0 P 0 ;0
L 1.1304 -2.08558996 1.12895 -2.08488996 0 P 0 ;0
L 1.12895 -2.08488996 1.12756998 -2.08408002 0 P 0 ;0
L 1.12756998 -2.08408002 1.12625 -2.08315 0 P 0 ;0
L 1.12625 -2.08315 1.12501004 -2.08211998 0 P 0 ;0
L 1.12501004 -2.08211998 1.12386004 -2.081 0 P 0 ;0
L 1.12386004 -2.081 1.12281004 -2.07978002 0 P 0 ;0
L 1.12281004 -2.07978002 1.12183996 -2.07846998 0 P 0 ;0
L 1.12183996 -2.07846998 1.1211 -2.07726004 0 P 0 ;0
L 1.1211 -2.07726004 1.12046998 -2.07598996 0 P 0 ;0
L 1.12046998 -2.07598996 1.11996004 -2.07466998 0 P 0 ;0
L 1.11996004 -2.07466998 1.11955 -2.07331004 0 P 0 ;0
L 1.11955 -2.07331004 1.11926998 -2.07191004 0 P 0 ;0
L 1.11926998 -2.07191004 1.11868002 -2.06693996 0 P 0 ;0
L 1.11868002 -2.06693996 1.11848002 -2.06191004 0 P 0 ;0
L 1.11848002 -2.06191004 1.11871004 -2.05668002 0 P 0 ;0
L 1.11871004 -2.05668002 1.11936004 -2.05148002 0 P 0 ;0
L 1.11936004 -2.05148002 1.11978996 -2.04936998 0 P 0 ;0
L 1.11978996 -2.04936998 1.12036998 -2.0473 0 P 0 ;0
L 1.12036998 -2.0473 1.12108996 -2.04528002 0 P 0 ;0
L 1.12108996 -2.04528002 1.12196004 -2.04331998 0 P 0 ;0
L 1.12196004 -2.04331998 1.1229 -2.04153996 0 P 0 ;0
L 1.1229 -2.04153996 1.12396998 -2.03985 0 P 0 ;0
L 1.12396998 -2.03985 1.12516998 -2.03823002 0 P 0 ;0
L 1.12516998 -2.03823002 1.12735 -2.03573996 0 P 0 ;0
L 1.12735 -2.03573996 1.12973002 -2.03345 0 P 0 ;0
L 1.12973002 -2.03345 1.13223996 -2.03141998 0 P 0 ;0
L 1.13223996 -2.03141998 1.13491998 -2.02961004 0 P 0 ;0
L 1.13491998 -2.02961004 1.13611004 -2.02893002 0 P 0 ;0
L 1.13611004 -2.02893002 1.13735 -2.02833996 0 P 0 ;0
L 1.13735 -2.02833996 1.13861998 -2.02781998 0 P 0 ;0
L 1.13861998 -2.02781998 1.13993996 -2.0274 0 P 0 ;0
L 1.13993996 -2.0274 1.14191004 -2.02693002 0 P 0 ;0
L 1.14191004 -2.02693002 1.14391004 -2.02663002 0 P 0 ;0
L 1.14391004 -2.02663002 1.14935 -2.02626004 0 P 0 ;0
L 1.14935 -2.02626004 1.15471004 -2.0263 0 P 0 ;0
L 1.15471004 -2.0263 1.15591004 -2.02638996 0 P 0 ;0
L 1.15591004 -2.02638996 1.1571 -2.02656998 0 P 0 ;0
L 1.1571 -2.02656998 1.15828002 -2.02683996 0 P 0 ;0
L 1.15828002 -2.02683996 1.16085 -2.02753002 0 P 0 ;0
L 1.13876998 -2.14783002 1.20233002 -2.14783002 0 P 0 ;0
L 1.14236998 -2.14683002 1.20266004 -2.14683002 0 P 0 ;0
L 1.14481004 -2.14583002 1.20296004 -2.14583002 0 P 0 ;0
L 1.1467 -2.14483002 1.20325 -2.14483002 0 P 0 ;0
L 1.14826004 -2.14383002 1.20353002 -2.14383002 0 P 0 ;0
L 1.1496 -2.14283002 1.20373996 -2.14283002 0 P 0 ;0
L 1.15078996 -2.14183002 1.20395 -2.14183002 0 P 0 ;0
L 1.15186004 -2.14083002 1.20415 -2.14083002 0 P 0 ;0
L 1.15278996 -2.13983002 1.20431998 -2.13983002 0 P 0 ;0
L 1.15361998 -2.13883002 1.20446004 -2.13883002 0 P 0 ;0
L 1.15436004 -2.13783002 1.20458002 -2.13783002 0 P 0 ;0
L 1.155 -2.13683002 1.20466998 -2.13683002 0 P 0 ;0
L 1.15556998 -2.13583002 1.20475 -2.13583002 0 P 0 ;0
L 1.15608996 -2.13483002 1.20481998 -2.13483002 0 P 0 ;0
L 1.15653996 -2.13383002 1.20488996 -2.13383002 0 P 0 ;0
L 1.15691004 -2.13283002 1.20496004 -2.13283002 0 P 0 ;0
L 1.15723996 -2.13183002 1.20503002 -2.13183002 0 P 0 ;0
L 1.15751998 -2.13083002 1.2051 -2.13083002 0 P 0 ;0
L 1.15773002 -2.12983002 1.20516004 -2.12983002 0 P 0 ;0
L 1.15793002 -2.12883002 1.20523002 -2.12883002 0 P 0 ;0
L 1.15806004 -2.12783002 1.2053 -2.12783002 0 P 0 ;0
L 1.15816998 -2.12683002 1.20536998 -2.12683002 0 P 0 ;0
L 1.15821004 -2.12583002 1.20543996 -2.12583002 0 P 0 ;0
L 1.11716004 -2.12483002 1.12726004 -2.12483002 0 P 0 ;0
L 1.15823996 -2.12483002 1.20551004 -2.12483002 0 P 0 ;0
L 1.10911998 -2.12383002 1.1352 -2.12383002 0 P 0 ;0
L 1.15821998 -2.12383002 1.20556998 -2.12383002 0 P 0 ;0
L 1.10468996 -2.12283002 1.14018996 -2.12283002 0 P 0 ;0
L 1.1582 -2.12283002 1.20563996 -2.12283002 0 P 0 ;0
L 1.10131004 -2.12183002 1.14366998 -2.12183002 0 P 0 ;0
L 1.15818002 -2.12183002 1.2057 -2.12183002 0 P 0 ;0
L 1.15808996 -2.12083002 1.20576004 -2.12083002 0 P 0 ;0
L 1.15781004 -2.11983002 1.20583002 -2.11983002 0 P 0 ;0
L 1.15721004 -2.11883002 1.20588002 -2.11883002 0 P 0 ;0
L 1.14146004 -2.08883002 1.20758002 -2.08883002 0 P 0 ;0
L 1.14525 -2.08783002 1.20763002 -2.08783002 0 P 0 ;0
L 1.14751004 -2.08683002 1.20768002 -2.08683002 0 P 0 ;0
L 1.14928002 -2.08583002 1.20773002 -2.08583002 0 P 0 ;0
L 1.15073002 -2.08483002 1.20778996 -2.08483002 0 P 0 ;0
L 1.15196004 -2.08383002 1.20783996 -2.08383002 0 P 0 ;0
L 1.13818996 -2.08913002 1.13826998 -2.08913002 0 P 0 ;0
L 1.13826998 -2.08913002 1.13988002 -2.08903996 0 P 0 ;0
L 1.13988002 -2.08903996 1.13996004 -2.08903996 0 P 0 ;0
L 1.13996004 -2.08903996 1.14001004 -2.08903002 0 P 0 ;0
L 1.14001004 -2.08903002 1.14005 -2.08901998 0 P 0 ;0
L 1.14005 -2.08901998 1.14163002 -2.08881004 0 P 0 ;0
L 1.14163002 -2.08881004 1.14166998 -2.0888 0 P 0 ;0
L 1.14166998 -2.0888 1.14171004 -2.0888 0 P 0 ;0
L 1.14171004 -2.0888 1.14178996 -2.08878002 0 P 0 ;0
L 1.14178996 -2.08878002 1.14335 -2.08843002 0 P 0 ;0
L 1.14335 -2.08843002 1.14351004 -2.08838996 0 P 0 ;0
L 1.14351004 -2.08838996 1.14503002 -2.08791004 0 P 0 ;0
L 1.14503002 -2.08791004 1.14511004 -2.08788996 0 P 0 ;0
L 1.14511004 -2.08788996 1.14515 -2.08786998 0 P 0 ;0
L 1.14515 -2.08786998 1.14518996 -2.08786004 0 P 0 ;0
L 1.14518996 -2.08786004 1.14666004 -2.08725 0 P 0 ;0
L 1.14666004 -2.08725 1.14673996 -2.08721998 0 P 0 ;0
L 1.14673996 -2.08721998 1.14678002 -2.0872 0 P 0 ;0
L 1.14678002 -2.0872 1.14681998 -2.08718996 0 P 0 ;0
L 1.14681998 -2.08718996 1.14823996 -2.08646998 0 P 0 ;0
L 1.14823996 -2.08646998 1.14826998 -2.08645 0 P 0 ;0
L 1.14826998 -2.08645 1.14835 -2.08641004 0 P 0 ;0
L 1.14835 -2.08641004 1.14838002 -2.08638002 0 P 0 ;0
L 1.14838002 -2.08638002 1.14976004 -2.08553002 0 P 0 ;0
L 1.14976004 -2.08553002 1.14978996 -2.08551004 0 P 0 ;0
L 1.14978996 -2.08551004 1.14983002 -2.08548996 0 P 0 ;0
L 1.14983002 -2.08548996 1.14988996 -2.08543996 0 P 0 ;0
L 1.14988996 -2.08543996 1.1512 -2.08448996 0 P 0 ;0
L 1.1512 -2.08448996 1.15126004 -2.08443996 0 P 0 ;0
L 1.15126004 -2.08443996 1.15128996 -2.08441004 0 P 0 ;0
L 1.15128996 -2.08441004 1.15131998 -2.08438996 0 P 0 ;0
L 1.15131998 -2.08438996 1.15253996 -2.08333002 0 P 0 ;0
L 1.15253996 -2.08333002 1.15256998 -2.0833 0 P 0 ;0
L 1.15256998 -2.0833 1.1526 -2.08328002 0 P 0 ;0
L 1.1526 -2.08328002 1.15263002 -2.08323996 0 P 0 ;0
L 1.15263002 -2.08323996 1.15266004 -2.08321998 0 P 0 ;0
L 1.15266004 -2.08321998 1.15378996 -2.08206004 0 P 0 ;0
L 1.15378996 -2.08206004 1.15376004 -2.08203996 0 P 0 ;0
L 1.15376004 -2.08203996 1.15381998 -2.08203996 0 P 0 ;0
L 1.15381998 -2.08203996 1.15383996 -2.082 0 P 0 ;0
L 1.15383996 -2.082 1.15386998 -2.08196998 0 P 0 ;0
L 1.15386998 -2.08196998 1.1539 -2.08195 0 P 0 ;0
L 1.1539 -2.08195 1.15493002 -2.08071004 0 P 0 ;0
L 1.15493002 -2.08071004 1.15493002 -2.0807 0 P 0 ;0
L 1.15493002 -2.0807 1.15496004 -2.08066998 0 P 0 ;0
L 1.15496004 -2.08066998 1.15498002 -2.08063996 0 P 0 ;0
L 1.15498002 -2.08063996 1.15501004 -2.08061004 0 P 0 ;0
L 1.15501004 -2.08061004 1.15503002 -2.08058002 0 P 0 ;0
L 1.15503002 -2.08058002 1.15596004 -2.07926004 0 P 0 ;0
L 1.15596004 -2.07926004 1.15603996 -2.07913996 0 P 0 ;0
L 1.15603996 -2.07913996 1.15673002 -2.07798996 0 P 0 ;0
L 1.15673002 -2.07798996 1.15676998 -2.07793002 0 P 0 ;0
L 1.15676998 -2.07793002 1.15678996 -2.07786998 0 P 0 ;0
L 1.15678996 -2.07786998 1.15741004 -2.07668996 0 P 0 ;0
L 1.15741004 -2.07668996 1.15743996 -2.07663002 0 P 0 ;0
L 1.15743996 -2.07663002 1.15746004 -2.07656998 0 P 0 ;0
L 1.15746004 -2.07656998 1.15746998 -2.07656998 0 P 0 ;0
L 1.15746998 -2.07656998 1.158 -2.07533996 0 P 0 ;0
L 1.158 -2.07533996 1.15801004 -2.07531004 0 P 0 ;0
L 1.15801004 -2.07531004 1.15803002 -2.07528002 0 P 0 ;0
L 1.15803002 -2.07528002 1.15805 -2.07521998 0 P 0 ;0
L 1.15805 -2.07521998 1.15848996 -2.07396004 0 P 0 ;0
L 1.15848996 -2.07396004 1.15841004 -2.07393002 0 P 0 ;0
L 1.15841004 -2.07393002 1.15851004 -2.07393002 0 P 0 ;0
L 1.15851004 -2.07393002 1.15851998 -2.0739 0 P 0 ;0
L 1.15851998 -2.0739 1.15853002 -2.07386004 0 P 0 ;0
L 1.15853002 -2.07386004 1.15853996 -2.07383002 0 P 0 ;0
L 1.15853996 -2.07383002 1.15943996 -2.07061004 0 P 0 ;0
L 1.15943996 -2.07061004 1.15945 -2.07058002 0 P 0 ;0
L 1.15945 -2.07058002 1.15946004 -2.07053996 0 P 0 ;0
L 1.15946004 -2.07053996 1.15946998 -2.07051004 0 P 0 ;0
L 1.15946998 -2.07051004 1.15946998 -2.07046998 0 P 0 ;0
L 1.15946998 -2.07046998 1.16013996 -2.06723002 0 P 0 ;0
L 1.16013996 -2.06723002 1.16013996 -2.0672 0 P 0 ;0
L 1.16013996 -2.0672 1.16016004 -2.06713996 0 P 0 ;0
L 1.16016004 -2.06713996 1.16016004 -2.06711004 0 P 0 ;0
L 1.16016004 -2.06711004 1.16081998 -2.06256004 0 P 0 ;0
L 1.16081998 -2.06256004 1.16081998 -2.06253996 0 P 0 ;0
L 1.16081998 -2.06253996 1.16083002 -2.0625 0 P 0 ;0
L 1.16083002 -2.0625 1.16083002 -2.06246998 0 P 0 ;0
L 1.16083002 -2.06246998 1.16126998 -2.05791004 0 P 0 ;0
L 1.16126998 -2.05791004 1.16128002 -2.0579 0 P 0 ;0
L 1.16128002 -2.0579 1.16128002 -2.05783996 0 P 0 ;0
L 1.16128002 -2.05783996 1.1621 -2.04405 0 P 0 ;0
L 1.1621 -2.04405 1.1621 -2.04401998 0 P 0 ;0
L 1.1621 -2.04401998 1.16285 -2.02761998 0 P 0 ;0
L 1.16285 -2.02761998 1.16136998 -2.0256 0 P 0 ;0
L 1.16136998 -2.0256 1.15878996 -2.02491004 0 P 0 ;0
L 1.15878996 -2.02491004 1.15878002 -2.0249 0 P 0 ;0
L 1.15878002 -2.0249 1.15871998 -2.02488996 0 P 0 ;0
L 1.15871998 -2.02488996 1.15755 -2.02461998 0 P 0 ;0
L 1.15755 -2.02461998 1.15746998 -2.0246 0 P 0 ;0
L 1.15746998 -2.0246 1.1574 -2.0246 0 P 0 ;0
L 1.1574 -2.0246 1.15621004 -2.02441004 0 P 0 ;0
L 1.15621004 -2.02441004 1.15616998 -2.02441004 0 P 0 ;0
L 1.15616998 -2.02441004 1.1561 -2.0244 0 P 0 ;0
L 1.1561 -2.0244 1.15606004 -2.02438996 0 P 0 ;0
L 1.15606004 -2.02438996 1.15486004 -2.0243 0 P 0 ;0
L 1.15486004 -2.0243 1.15471998 -2.0243 0 P 0 ;0
L 1.15471998 -2.0243 1.14936004 -2.02426004 0 P 0 ;0
L 1.14936004 -2.02426004 1.14928996 -2.02426004 0 P 0 ;0
L 1.14928996 -2.02426004 1.14925 -2.02426998 0 P 0 ;0
L 1.14925 -2.02426998 1.14921004 -2.02426998 0 P 0 ;0
L 1.14921004 -2.02426998 1.14376998 -2.02463996 0 P 0 ;0
L 1.14376998 -2.02463996 1.1437 -2.02463996 0 P 0 ;0
L 1.1437 -2.02463996 1.14365 -2.02465 0 P 0 ;0
L 1.14365 -2.02465 1.14361004 -2.02465 0 P 0 ;0
L 1.14361004 -2.02465 1.14161998 -2.02495 0 P 0 ;0
L 1.14161998 -2.02495 1.14161004 -2.02495 0 P 0 ;0
L 1.14161004 -2.02495 1.14153002 -2.02496998 0 P 0 ;0
L 1.14153002 -2.02496998 1.14148996 -2.02496998 0 P 0 ;0
L 1.14148996 -2.02496998 1.14143996 -2.02498996 0 P 0 ;0
L 1.14143996 -2.02498996 1.13946998 -2.02545 0 P 0 ;0
L 1.13946998 -2.02545 1.13943996 -2.02546998 0 P 0 ;0
L 1.13943996 -2.02546998 1.1394 -2.02546998 0 P 0 ;0
L 1.1394 -2.02546998 1.13933002 -2.0255 0 P 0 ;0
L 1.13933002 -2.0255 1.13801004 -2.02591998 0 P 0 ;0
L 1.13801004 -2.02591998 1.13798002 -2.02593002 0 P 0 ;0
L 1.13798002 -2.02593002 1.13793996 -2.02593996 0 P 0 ;0
L 1.13793996 -2.02593996 1.13788002 -2.02596998 0 P 0 ;0
L 1.13788002 -2.02596998 1.1366 -2.02648002 0 P 0 ;0
L 1.1366 -2.02648002 1.13653996 -2.0265 0 P 0 ;0
L 1.13653996 -2.0265 1.13648002 -2.02653002 0 P 0 ;0
L 1.13648002 -2.02653002 1.13523996 -2.02713002 0 P 0 ;0
L 1.13523996 -2.02713002 1.13518002 -2.02716004 0 P 0 ;0
L 1.13518002 -2.02716004 1.13515 -2.02716998 0 P 0 ;0
L 1.13515 -2.02716998 1.13511998 -2.02718996 0 P 0 ;0
L 1.13511998 -2.02718996 1.13393002 -2.02786998 0 P 0 ;0
L 1.13393002 -2.02786998 1.13388996 -2.02788996 0 P 0 ;0
L 1.13388996 -2.02788996 1.1338 -2.02795 0 P 0 ;0
L 1.1338 -2.02795 1.13111998 -2.02976004 0 P 0 ;0
L 1.13111998 -2.02976004 1.13105 -2.02981004 0 P 0 ;0
L 1.13105 -2.02981004 1.13101004 -2.02983996 0 P 0 ;0
L 1.13101004 -2.02983996 1.13098002 -2.02986004 0 P 0 ;0
L 1.13098002 -2.02986004 1.12846998 -2.03188996 0 P 0 ;0
L 1.12846998 -2.03188996 1.12838002 -2.03198002 0 P 0 ;0
L 1.12838002 -2.03198002 1.12833996 -2.03201004 0 P 0 ;0
L 1.12833996 -2.03201004 1.12596004 -2.0343 0 P 0 ;0
L 1.12596004 -2.0343 1.12593996 -2.03433002 0 P 0 ;0
L 1.12593996 -2.03433002 1.1259 -2.03436004 0 P 0 ;0
L 1.1259 -2.03436004 1.12588002 -2.03438996 0 P 0 ;0
L 1.12588002 -2.03438996 1.12585 -2.03443002 0 P 0 ;0
L 1.12585 -2.03443002 1.12366998 -2.03691004 0 P 0 ;0
L 1.12366998 -2.03691004 1.12363996 -2.03695 0 P 0 ;0
L 1.12363996 -2.03695 1.12361998 -2.03698002 0 P 0 ;0
L 1.12361998 -2.03698002 1.12358996 -2.03701004 0 P 0 ;0
L 1.12358996 -2.03701004 1.12356998 -2.03703996 0 P 0 ;0
L 1.12356998 -2.03703996 1.12236998 -2.03865 0 P 0 ;0
L 1.12236998 -2.03865 1.12233996 -2.03868996 0 P 0 ;0
L 1.12233996 -2.03868996 1.12233002 -2.03871004 0 P 0 ;0
L 1.12233002 -2.03871004 1.12228996 -2.03878002 0 P 0 ;0
L 1.12228996 -2.03878002 1.12121004 -2.04046998 0 P 0 ;0
L 1.12121004 -2.04046998 1.12118996 -2.0405 0 P 0 ;0
L 1.12118996 -2.0405 1.12116998 -2.04053996 0 P 0 ;0
L 1.12116998 -2.04053996 1.12115 -2.04056998 0 P 0 ;0
L 1.12115 -2.04056998 1.12113996 -2.04061004 0 P 0 ;0
L 1.12113996 -2.04061004 1.12018996 -2.04238002 0 P 0 ;0
L 1.12018996 -2.04238002 1.12016004 -2.04245 0 P 0 ;0
L 1.12016004 -2.04245 1.12013996 -2.04248002 0 P 0 ;0
L 1.12013996 -2.04248002 1.12013002 -2.04251004 0 P 0 ;0
L 1.12013002 -2.04251004 1.11926004 -2.04446998 0 P 0 ;0
L 1.11926004 -2.04446998 1.11925 -2.0445 0 P 0 ;0
L 1.11925 -2.0445 1.11923002 -2.04453996 0 P 0 ;0
L 1.11923002 -2.04453996 1.11921998 -2.04458002 0 P 0 ;0
L 1.11921998 -2.04458002 1.11921004 -2.04461004 0 P 0 ;0
L 1.11921004 -2.04461004 1.11848002 -2.04663002 0 P 0 ;0
L 1.11848002 -2.04663002 1.11846998 -2.04666004 0 P 0 ;0
L 1.11846998 -2.04666004 1.11846004 -2.0467 0 P 0 ;0
L 1.11846004 -2.0467 1.11843996 -2.04676998 0 P 0 ;0
L 1.11843996 -2.04676998 1.11786004 -2.04883996 0 P 0 ;0
L 1.11786004 -2.04883996 1.11785 -2.04886998 0 P 0 ;0
L 1.11785 -2.04886998 1.11783996 -2.04891004 0 P 0 ;0
L 1.11783996 -2.04891004 1.11783996 -2.04893996 0 P 0 ;0
L 1.11783996 -2.04893996 1.11783002 -2.04896998 0 P 0 ;0
L 1.11783002 -2.04896998 1.11783002 -2.04898002 0 P 0 ;0
L 1.11783002 -2.04898002 1.1174 -2.05108002 0 P 0 ;0
L 1.1174 -2.05108002 1.1174 -2.05111998 0 P 0 ;0
L 1.1174 -2.05111998 1.11738996 -2.05116004 0 P 0 ;0
L 1.11738996 -2.05116004 1.11738002 -2.05118996 0 P 0 ;0
L 1.11738002 -2.05118996 1.11738002 -2.05123002 0 P 0 ;0
L 1.11738002 -2.05123002 1.11673002 -2.05643002 0 P 0 ;0
L 1.11673002 -2.05643002 1.11671998 -2.05646998 0 P 0 ;0
L 1.11671998 -2.05646998 1.11671998 -2.05655 0 P 0 ;0
L 1.11671998 -2.05655 1.11671004 -2.05658996 0 P 0 ;0
L 1.11671004 -2.05658996 1.11648996 -2.06181998 0 P 0 ;0
L 1.11648996 -2.06181998 1.11648002 -2.06186998 0 P 0 ;0
L 1.11648002 -2.06186998 1.11648002 -2.06195 0 P 0 ;0
L 1.11648002 -2.06195 1.11648996 -2.06198996 0 P 0 ;0
L 1.11648996 -2.06198996 1.11668002 -2.06696998 0 P 0 ;0
L 1.11668002 -2.06696998 1.11768002 -2.06696998 0 P 0 ;0
L 1.11768002 -2.06696998 1.11668002 -2.06701004 0 P 0 ;0
L 1.11668002 -2.06701004 1.11668002 -2.06713002 0 P 0 ;0
L 1.11668002 -2.06713002 1.11668996 -2.06716998 0 P 0 ;0
L 1.11668996 -2.06716998 1.11728002 -2.07215 0 P 0 ;0
L 1.11728002 -2.07215 1.11728996 -2.07218996 0 P 0 ;0
L 1.11728996 -2.07218996 1.11728996 -2.07223002 0 P 0 ;0
L 1.11728996 -2.07223002 1.11731004 -2.07231004 0 P 0 ;0
L 1.11731004 -2.07231004 1.11758996 -2.07371004 0 P 0 ;0
L 1.11758996 -2.07371004 1.1176 -2.07375 0 P 0 ;0
L 1.1176 -2.07375 1.11761004 -2.0738 0 P 0 ;0
L 1.11761004 -2.0738 1.11761998 -2.07383996 0 P 0 ;0
L 1.11761998 -2.07383996 1.11763996 -2.07388002 0 P 0 ;0
L 1.11763996 -2.07388002 1.11803996 -2.07523996 0 P 0 ;0
L 1.11803996 -2.07523996 1.11806004 -2.07531998 0 P 0 ;0
L 1.11806004 -2.07531998 1.11808002 -2.07536004 0 P 0 ;0
L 1.11808002 -2.07536004 1.11808996 -2.07541004 0 P 0 ;0
L 1.11808996 -2.07541004 1.11861004 -2.07673002 0 P 0 ;0
L 1.11861004 -2.07673002 1.11863996 -2.07681004 0 P 0 ;0
L 1.11863996 -2.07681004 1.11866004 -2.07683996 0 P 0 ;0
L 1.11866004 -2.07683996 1.11868002 -2.07688002 0 P 0 ;0
L 1.11868002 -2.07688002 1.11931004 -2.07815 0 P 0 ;0
L 1.11931004 -2.07815 1.11935 -2.07823002 0 P 0 ;0
L 1.11935 -2.07823002 1.1194 -2.0783 0 P 0 ;0
L 1.1194 -2.0783 1.12013996 -2.07951998 0 P 0 ;0
L 1.12013996 -2.07951998 1.12021004 -2.07961998 0 P 0 ;0
L 1.12021004 -2.07961998 1.12023002 -2.07965 0 P 0 ;0
L 1.12023002 -2.07965 1.12023002 -2.07966004 0 P 0 ;0
L 1.12023002 -2.07966004 1.1212 -2.08096998 0 P 0 ;0
L 1.1212 -2.08096998 1.12123996 -2.08103002 0 P 0 ;0
L 1.12123996 -2.08103002 1.12126998 -2.08106004 0 P 0 ;0
L 1.12126998 -2.08106004 1.12128996 -2.08108996 0 P 0 ;0
L 1.12128996 -2.08108996 1.12235 -2.08231004 0 P 0 ;0
L 1.12235 -2.08231004 1.12238002 -2.08233996 0 P 0 ;0
L 1.12238002 -2.08233996 1.1224 -2.08236998 0 P 0 ;0
L 1.1224 -2.08236998 1.12246004 -2.08243002 0 P 0 ;0
L 1.12246004 -2.08243002 1.12361004 -2.08355 0 P 0 ;0
L 1.12361004 -2.08355 1.12366998 -2.08361004 0 P 0 ;0
L 1.12366998 -2.08361004 1.1237 -2.08363002 0 P 0 ;0
L 1.1237 -2.08363002 1.12373002 -2.08366004 0 P 0 ;0
L 1.12373002 -2.08366004 1.12496998 -2.08468996 0 P 0 ;0
L 1.12496998 -2.08468996 1.125 -2.08471004 0 P 0 ;0
L 1.125 -2.08471004 1.12503002 -2.08473996 0 P 0 ;0
L 1.12503002 -2.08473996 1.12506998 -2.08476004 0 P 0 ;0
L 1.12506998 -2.08476004 1.1251 -2.08478996 0 P 0 ;0
L 1.1251 -2.08478996 1.12641998 -2.08571004 0 P 0 ;0
L 1.12641998 -2.08571004 1.12645 -2.08573002 0 P 0 ;0
L 1.12645 -2.08573002 1.12648002 -2.08576004 0 P 0 ;0
L 1.12648002 -2.08576004 1.12651004 -2.08578002 0 P 0 ;0
L 1.12651004 -2.08578002 1.12655 -2.0858 0 P 0 ;0
L 1.12655 -2.0858 1.12793996 -2.08661004 0 P 0 ;0
L 1.12793996 -2.08661004 1.12801004 -2.08665 0 P 0 ;0
L 1.12801004 -2.08665 1.12805 -2.08666998 0 P 0 ;0
L 1.12805 -2.08666998 1.12808002 -2.08668996 0 P 0 ;0
L 1.12808002 -2.08668996 1.12808996 -2.08668996 0 P 0 ;0
L 1.12808996 -2.08668996 1.12953996 -2.08738996 0 P 0 ;0
L 1.12953996 -2.08738996 1.12961998 -2.08743002 0 P 0 ;0
L 1.12961998 -2.08743002 1.12965 -2.08743996 0 P 0 ;0
L 1.12965 -2.08743996 1.1297 -2.08746004 0 P 0 ;0
L 1.1297 -2.08746004 1.13118002 -2.08801998 0 P 0 ;0
L 1.13118002 -2.08801998 1.13133996 -2.08808002 0 P 0 ;0
L 1.13133996 -2.08808002 1.13286998 -2.08851004 0 P 0 ;0
L 1.13286998 -2.08851004 1.13295 -2.08853996 0 P 0 ;0
L 1.13295 -2.08853996 1.13303996 -2.08855 0 P 0 ;0
L 1.13303996 -2.08855 1.1346 -2.08886004 0 P 0 ;0
L 1.1346 -2.08886004 1.13471998 -2.08888996 0 P 0 ;0
L 1.13471998 -2.08888996 1.13476004 -2.08888996 0 P 0 ;0
L 1.13476004 -2.08888996 1.13633996 -2.08906998 0 P 0 ;0
L 1.13633996 -2.08906998 1.13638996 -2.08908002 0 P 0 ;0
L 1.13638996 -2.08908002 1.13651004 -2.08908002 0 P 0 ;0
L 1.13651004 -2.08908002 1.1381 -2.08913002 0 P 0 ;0
L 1.1381 -2.08913002 1.13818996 -2.08913002 0 P 0 ;0
L 1.31623996 -1.98923996 1.3135 -1.98988002 0 P 0 ;0
L 1.3135 -1.98988002 1.31078996 -1.99071004 0 P 0 ;0
L 1.31078996 -1.99071004 1.30813002 -1.99175 0 P 0 ;0
L 1.30813002 -1.99175 1.30553996 -1.99296998 0 P 0 ;0
L 1.30553996 -1.99296998 1.30308996 -1.99431998 0 P 0 ;0
L 1.30308996 -1.99431998 1.30073996 -1.99585 0 P 0 ;0
L 1.30073996 -1.99585 1.29863996 -1.99746004 0 P 0 ;0
L 1.29863996 -1.99746004 1.29666004 -1.99923996 0 P 0 ;0
L 1.29666004 -1.99923996 1.29205 -2.00375 0 P 0 ;0
L 1.29205 -2.00375 1.29205 -1.99243996 0 P 0 ;0
L 1.29205 -1.99243996 1.24316004 -1.99243996 0 P 0 ;0
L 1.24316004 -1.99243996 1.24313996 -2.00521004 0 P 0 ;0
L 1.24313996 -2.00521004 1.24261004 -2.03151004 0 P 0 ;0
L 1.24261004 -2.03151004 1.24086998 -2.07046004 0 P 0 ;0
L 1.24086998 -2.07046004 1.23873996 -2.10921004 0 P 0 ;0
L 1.23873996 -2.10921004 1.23811998 -2.11641998 0 P 0 ;0
L 1.23811998 -2.11641998 1.23711998 -2.12361998 0 P 0 ;0
L 1.23711998 -2.12361998 1.23655 -2.12716004 0 P 0 ;0
L 1.23655 -2.12716004 1.29205 -2.12716004 0 P 0 ;0
L 1.29205 -2.12716004 1.29206998 -2.11766004 0 P 0 ;0
L 1.29206998 -2.11766004 1.29238996 -2.10283996 0 P 0 ;0
L 1.29238996 -2.10283996 1.29336004 -2.08431004 0 P 0 ;0
L 1.29336004 -2.08431004 1.29463996 -2.06673002 0 P 0 ;0
L 1.29463996 -2.06673002 1.29511004 -2.06253002 0 P 0 ;0
L 1.29511004 -2.06253002 1.29583996 -2.05836004 0 P 0 ;0
L 1.29583996 -2.05836004 1.29683002 -2.05446998 0 P 0 ;0
L 1.29683002 -2.05446998 1.29813996 -2.05068996 0 P 0 ;0
L 1.29813996 -2.05068996 1.29978002 -2.04701998 0 P 0 ;0
L 1.29978002 -2.04701998 1.30056998 -2.04556998 0 P 0 ;0
L 1.30056998 -2.04556998 1.30146998 -2.04418996 0 P 0 ;0
L 1.30146998 -2.04418996 1.30246998 -2.04288002 0 P 0 ;0
L 1.30246998 -2.04288002 1.30356998 -2.04165 0 P 0 ;0
L 1.30356998 -2.04165 1.30475 -2.0405 0 P 0 ;0
L 1.30475 -2.0405 1.30603996 -2.03945 0 P 0 ;0
L 1.30603996 -2.03945 1.30773996 -2.03826004 0 P 0 ;0
L 1.30773996 -2.03826004 1.30953002 -2.03723002 0 P 0 ;0
L 1.30953002 -2.03723002 1.31141004 -2.03635 0 P 0 ;0
L 1.31141004 -2.03635 1.31335 -2.03563002 0 P 0 ;0
L 1.31335 -2.03563002 1.31535 -2.03508002 0 P 0 ;0
L 1.31535 -2.03508002 1.31973996 -2.03423002 0 P 0 ;0
L 1.31973996 -2.03423002 1.32416004 -2.03366998 0 P 0 ;0
L 1.32416004 -2.03366998 1.32863002 -2.0334 0 P 0 ;0
L 1.32863002 -2.0334 1.33688002 -2.03318002 0 P 0 ;0
L 1.33688002 -2.03318002 1.33613002 -2.01151004 0 P 0 ;0
L 1.33613002 -2.01151004 1.33581004 -2.00315 0 P 0 ;0
L 1.33581004 -2.00315 1.33543996 -1.99596004 0 P 0 ;0
L 1.33543996 -1.99596004 1.33508002 -1.98971004 0 P 0 ;0
L 1.33508002 -1.98971004 1.33503996 -1.98945 0 P 0 ;0
L 1.33503996 -1.98945 1.335 -1.98931998 0 P 0 ;0
L 1.335 -1.98931998 1.33496004 -1.9892 0 P 0 ;0
L 1.33496004 -1.9892 1.3349 -1.98908002 0 P 0 ;0
L 1.3349 -1.98908002 1.33483996 -1.98896998 0 P 0 ;0
L 1.33483996 -1.98896998 1.33476998 -1.98886004 0 P 0 ;0
L 1.33476998 -1.98886004 1.33468996 -1.98876004 0 P 0 ;0
L 1.33468996 -1.98876004 1.3346 -1.98866998 0 P 0 ;0
L 1.3346 -1.98866998 1.33451004 -1.98858996 0 P 0 ;0
L 1.33451004 -1.98858996 1.3344 -1.98851998 0 P 0 ;0
L 1.3344 -1.98851998 1.3343 -1.98845 0 P 0 ;0
L 1.3343 -1.98845 1.33418002 -1.98838996 0 P 0 ;0
L 1.33418002 -1.98838996 1.33406998 -1.98833996 0 P 0 ;0
L 1.33406998 -1.98833996 1.33395 -1.9883 0 P 0 ;0
L 1.33395 -1.9883 1.33383002 -1.98828002 0 P 0 ;0
L 1.33383002 -1.98828002 1.3337 -1.98826004 0 P 0 ;0
L 1.3337 -1.98826004 1.33356998 -1.98825 0 P 0 ;0
L 1.33356998 -1.98825 1.32756998 -1.98823002 0 P 0 ;0
L 1.32756998 -1.98823002 1.32135 -1.98853996 0 P 0 ;0
L 1.32135 -1.98853996 1.31878996 -1.98881998 0 P 0 ;0
L 1.31878996 -1.98881998 1.31623996 -1.98923996 0 P 0 ;0
L 1.2389 -2.12516004 1.29006004 -2.12516004 0 P 0 ;0
L 1.23906998 -2.12416004 1.29006004 -2.12416004 0 P 0 ;0
L 1.23921004 -2.12316004 1.29006004 -2.12316004 0 P 0 ;0
L 1.23933996 -2.12216004 1.29006004 -2.12216004 0 P 0 ;0
L 1.23948996 -2.12116004 1.29006004 -2.12116004 0 P 0 ;0
L 1.23961998 -2.12016004 1.29006998 -2.12016004 0 P 0 ;0
L 1.23976004 -2.11916004 1.29006998 -2.11916004 0 P 0 ;0
L 1.2399 -2.11816004 1.29006998 -2.11816004 0 P 0 ;0
L 1.24003996 -2.11716004 1.29008002 -2.11716004 0 P 0 ;0
L 1.24015 -2.11616004 1.2901 -2.11616004 0 P 0 ;0
L 1.24023996 -2.11516004 1.29011998 -2.11516004 0 P 0 ;0
L 1.24033002 -2.11416004 1.29013996 -2.11416004 0 P 0 ;0
L 1.24041004 -2.11316004 1.29016004 -2.11316004 0 P 0 ;0
L 1.24048996 -2.11216004 1.29018996 -2.11216004 0 P 0 ;0
L 1.24058002 -2.11116004 1.29021004 -2.11116004 0 P 0 ;0
L 1.24066998 -2.11016004 1.29023002 -2.11016004 0 P 0 ;0
L 1.24075 -2.10916004 1.29025 -2.10916004 0 P 0 ;0
L 1.2408 -2.10816004 1.29026998 -2.10816004 0 P 0 ;0
L 1.24086004 -2.10716004 1.29028996 -2.10716004 0 P 0 ;0
L 1.24091004 -2.10616004 1.29031998 -2.10616004 0 P 0 ;0
L 1.24096998 -2.10516004 1.29033996 -2.10516004 0 P 0 ;0
L 1.24101998 -2.10416004 1.29036004 -2.10416004 0 P 0 ;0
L 1.24108002 -2.10316004 1.29038002 -2.10316004 0 P 0 ;0
L 1.24113002 -2.10216004 1.29041998 -2.10216004 0 P 0 ;0
L 1.24118002 -2.10116004 1.29046998 -2.10116004 0 P 0 ;0
L 1.24123996 -2.10016004 1.29053002 -2.10016004 0 P 0 ;0
L 1.24128996 -2.09916004 1.29058002 -2.09916004 0 P 0 ;0
L 1.24135 -2.09816004 1.29063002 -2.09816004 0 P 0 ;0
L 1.2414 -2.09716004 1.29068002 -2.09716004 0 P 0 ;0
L 1.24146004 -2.09616004 1.29073996 -2.09616004 0 P 0 ;0
L 1.24151004 -2.09516004 1.29078996 -2.09516004 0 P 0 ;0
L 1.24156998 -2.09416004 1.29083996 -2.09416004 0 P 0 ;0
L 1.24161998 -2.09316004 1.2909 -2.09316004 0 P 0 ;0
L 1.24168002 -2.09216004 1.29095 -2.09216004 0 P 0 ;0
L 1.24173002 -2.09116004 1.291 -2.09116004 0 P 0 ;0
L 1.24178996 -2.09016004 1.29105 -2.09016004 0 P 0 ;0
L 1.24183996 -2.08916004 1.2911 -2.08916004 0 P 0 ;0
L 1.2419 -2.08816004 1.29116004 -2.08816004 0 P 0 ;0
L 1.24196004 -2.08716004 1.29121004 -2.08716004 0 P 0 ;0
L 1.24201004 -2.08616004 1.29126998 -2.08616004 0 P 0 ;0
L 1.24206998 -2.08516004 1.29131998 -2.08516004 0 P 0 ;0
L 1.24211998 -2.08416004 1.29136998 -2.08416004 0 P 0 ;0
L 1.2389 -2.12516004 1.2391 -2.12393002 0 P 0 ;0
L 1.2391 -2.12393002 1.2391 -2.1239 0 P 0 ;0
L 1.2391 -2.1239 1.24011004 -2.11665 0 P 0 ;0
L 1.24011004 -2.11665 1.24073002 -2.10935 0 P 0 ;0
L 1.24073002 -2.10935 1.24073996 -2.10931998 0 P 0 ;0
L 1.24073996 -2.10931998 1.24286004 -2.07056004 0 P 0 ;0
L 1.24286004 -2.07056004 1.24461004 -2.03158002 0 P 0 ;0
L 1.24461004 -2.03158002 1.24513996 -2.00523002 0 P 0 ;0
L 1.24513996 -2.00523002 1.24515 -1.99443996 0 P 0 ;0
L 1.24515 -1.99443996 1.29005 -1.99443996 0 P 0 ;0
L 1.29005 -1.99443996 1.29005 -2.00375 0 P 0 ;0
L 1.29005 -2.00375 1.29128002 -2.0056 0 P 0 ;0
L 1.29128002 -2.0056 1.29345 -2.00518002 0 P 0 ;0
L 1.29345 -2.00518002 1.29803002 -2.0007 0 P 0 ;0
L 1.29803002 -2.0007 1.29991998 -1.999 0 P 0 ;0
L 1.29991998 -1.999 1.30188996 -1.99748996 0 P 0 ;0
L 1.30188996 -1.99748996 1.30411998 -1.99603996 0 P 0 ;0
L 1.30411998 -1.99603996 1.30645 -1.99475 0 P 0 ;0
L 1.30645 -1.99475 1.30891998 -1.99358996 0 P 0 ;0
L 1.30891998 -1.99358996 1.31145 -1.9926 0 P 0 ;0
L 1.31145 -1.9926 1.31401998 -1.99181004 0 P 0 ;0
L 1.31401998 -1.99181004 1.31663996 -1.9912 0 P 0 ;0
L 1.31663996 -1.9912 1.31906004 -1.9908 0 P 0 ;0
L 1.31906004 -1.9908 1.32151004 -1.99053002 0 P 0 ;0
L 1.32151004 -1.99053002 1.32761998 -1.99023002 0 P 0 ;0
L 1.32761998 -1.99023002 1.3331 -1.99025 0 P 0 ;0
L 1.3331 -1.99025 1.33345 -1.99608002 0 P 0 ;0
L 1.33345 -1.99608002 1.33381004 -2.00323002 0 P 0 ;0
L 1.33381004 -2.00323002 1.33413002 -2.01158996 0 P 0 ;0
L 1.33413002 -2.01158996 1.33413002 -2.0116 0 P 0 ;0
L 1.33413002 -2.0116 1.33481998 -2.03123002 0 P 0 ;0
L 1.33481998 -2.03123002 1.32853996 -2.0314 0 P 0 ;0
L 1.32853996 -2.0314 1.32398002 -2.03166998 0 P 0 ;0
L 1.32398002 -2.03166998 1.31941998 -2.03225 0 P 0 ;0
L 1.31941998 -2.03225 1.31488996 -2.03313002 0 P 0 ;0
L 1.31488996 -2.03313002 1.31273996 -2.03373002 0 P 0 ;0
L 1.31273996 -2.03373002 1.31063996 -2.0345 0 P 0 ;0
L 1.31063996 -2.0345 1.3086 -2.03545 0 P 0 ;0
L 1.3086 -2.03545 1.30666004 -2.03656998 0 P 0 ;0
L 1.30666004 -2.03656998 1.30658996 -2.03661998 0 P 0 ;0
L 1.30658996 -2.03661998 1.30483002 -2.03786004 0 P 0 ;0
L 1.30483002 -2.03786004 1.30341998 -2.03901004 0 P 0 ;0
L 1.30341998 -2.03901004 1.30336998 -2.03906004 0 P 0 ;0
L 1.30336998 -2.03906004 1.30211998 -2.04026004 0 P 0 ;0
L 1.30211998 -2.04026004 1.30093002 -2.0416 0 P 0 ;0
L 1.30093002 -2.0416 1.29983002 -2.04303996 0 P 0 ;0
L 1.29983002 -2.04303996 1.29978996 -2.0431 0 P 0 ;0
L 1.29978996 -2.0431 1.29885 -2.04453996 0 P 0 ;0
L 1.29885 -2.04453996 1.29798996 -2.04613002 0 P 0 ;0
L 1.29798996 -2.04613002 1.29631998 -2.04986998 0 P 0 ;0
L 1.29631998 -2.04986998 1.29628002 -2.04995 0 P 0 ;0
L 1.29628002 -2.04995 1.29625 -2.05003002 0 P 0 ;0
L 1.29625 -2.05003002 1.29491998 -2.0539 0 P 0 ;0
L 1.29491998 -2.0539 1.29388996 -2.05793996 0 P 0 ;0
L 1.29388996 -2.05793996 1.29386998 -2.05801998 0 P 0 ;0
L 1.29386998 -2.05801998 1.29313996 -2.06221004 0 P 0 ;0
L 1.29313996 -2.06221004 1.29313002 -2.06223996 0 P 0 ;0
L 1.29313002 -2.06223996 1.29311998 -2.0623 0 P 0 ;0
L 1.29311998 -2.0623 1.29265 -2.06655 0 P 0 ;0
L 1.29265 -2.06655 1.29136998 -2.08418996 0 P 0 ;0
L 1.29136998 -2.08418996 1.29038996 -2.10276998 0 P 0 ;0
L 1.29038996 -2.10276998 1.29006998 -2.11763002 0 P 0 ;0
L 1.29006998 -2.11763002 1.29006004 -2.12516004 0 P 0 ;0
L 1.29006004 -2.12516004 1.2389 -2.12516004 0 P 0 ;0
L 1.09846998 -2.00483002 1.21248002 -2.00483002 0 P 0 ;0
L 1.09838002 -2.12083002 1.14708002 -2.12083002 0 P 0 ;0
L 1.11933002 -2.18283002 1.15161998 -2.18283002 0 P 0 ;0
L 1.11001998 -2.18183002 1.15838002 -2.18183002 0 P 0 ;0
L 1.10246998 -2.18083002 1.16333996 -2.18083002 0 P 0 ;0
L 1.04061004 -1.89731004 1.09978002 -1.89731004 0 P 0 ;0
L 1.03565 -1.89631004 1.09821004 -1.89631004 0 P 0 ;0
L 1.03068996 -1.89531004 1.09661004 -1.89531004 0 P 0 ;0
L 1.02573002 -1.89431004 1.09475 -1.89431004 0 P 0 ;0
L 1.019 -1.89331004 1.09288002 -1.89331004 0 P 0 ;0
L 1.01163996 -1.89231004 1.09101998 -1.89231004 0 P 0 ;0
L 0.99518996 -1.89131004 1.08916004 -1.89131004 0 P 0 ;0
L 0.87011998 -1.88331004 1.07278996 -1.88331004 0 P 0 ;0
L 0.86963996 -1.88231004 1.07053002 -1.88231004 0 P 0 ;0
L 0.86916004 -1.88131004 1.06828002 -1.88131004 0 P 0 ;0
L 0.86863002 -1.88031004 1.06603002 -1.88031004 0 P 0 ;0
L 0.86806998 -1.87931004 1.06351004 -1.87931004 0 P 0 ;0
L 0.8675 -1.87831004 1.06076998 -1.87831004 0 P 0 ;0
L 0.86693002 -1.87731004 1.05803996 -1.87731004 0 P 0 ;0
L 0.86631004 -1.87631004 1.05531004 -1.87631004 0 P 0 ;0
L 0.86563996 -1.87531004 1.05256998 -1.87531004 0 P 0 ;0
L 0.86498002 -1.87431004 1.04983996 -1.87431004 0 P 0 ;0
L 0.86431998 -1.87331004 1.0471 -1.87331004 0 P 0 ;0
L 0.86356004 -1.87231004 1.04376004 -1.87231004 0 P 0 ;0
L 0.86278996 -1.87131004 1.04041998 -1.87131004 0 P 0 ;0
L 0.86203002 -1.87031004 1.03708002 -1.87031004 0 P 0 ;0
L 0.86118996 -1.86931004 1.03373996 -1.86931004 0 P 0 ;0
L 0.8603 -1.86831004 1.0304 -1.86831004 0 P 0 ;0
L 0.85941004 -1.86731004 1.02656998 -1.86731004 0 P 0 ;0
L 0.8585 -1.86631004 1.02231998 -1.86631004 0 P 0 ;0
L 0.85756998 -1.86531004 1.01806998 -1.86531004 0 P 0 ;0
L 0.85663002 -1.86431004 1.01381998 -1.86431004 0 P 0 ;0
L 0.85568996 -1.86331004 1.00931998 -1.86331004 0 P 0 ;0
L 0.85481004 -1.86231004 1.00335 -1.86231004 0 P 0 ;0
L 0.85916998 -1.86131004 0.99738002 -1.86131004 0 P 0 ;0
L 0.86716998 -1.86031004 0.99141998 -1.86031004 0 P 0 ;0
L 0.87476998 -1.89731004 0.89943002 -1.89731004 0 P 0 ;0
L 0.87453996 -1.89631004 0.90426004 -1.89631004 0 P 0 ;0
L 0.87431004 -1.89531004 0.9097 -1.89531004 0 P 0 ;0
L 0.87406998 -1.89431004 0.91608002 -1.89431004 0 P 0 ;0
L 0.87383002 -1.89331004 0.92246004 -1.89331004 0 P 0 ;0
L 0.87355 -1.89231004 0.93086004 -1.89231004 0 P 0 ;0
L 0.87323002 -1.89131004 0.95553002 -1.89131004 0 P 0 ;0
L 0.87291004 -1.89031004 1.08728996 -1.89031004 0 P 0 ;0
L 0.87258996 -1.88931004 1.08543002 -1.88931004 0 P 0 ;0
L 0.87223002 -1.88831004 1.08356998 -1.88831004 0 P 0 ;0
L 0.87183002 -1.88731004 1.0817 -1.88731004 0 P 0 ;0
L 0.87143002 -1.88631004 1.07955 -1.88631004 0 P 0 ;0
L 0.87103002 -1.88531004 1.07728996 -1.88531004 0 P 0 ;0
L 0.8706 -1.88431004 1.07503996 -1.88431004 0 P 0 ;0
L 0.87525 -1.85931004 0.98545 -1.85931004 0 P 0 ;0
L 0.88421004 -1.85831004 0.97621004 -1.85831004 0 P 0 ;0
L 0.89393002 -1.85731004 0.96606998 -1.85731004 0 P 0 ;0
L 0.9106 -1.85631004 0.95203002 -1.85631004 0 P 0 ;0
L 1.08716004 -1.91231004 1.12151004 -1.91231004 0 P 0 ;0
L 1.08486004 -1.91131004 1.12018996 -1.91131004 0 P 0 ;0
L 1.08256004 -1.91031004 1.11886004 -1.91031004 0 P 0 ;0
L 1.08023002 -1.90931004 1.11753996 -1.90931004 0 P 0 ;0
L 1.07738002 -1.90831004 1.11621004 -1.90831004 0 P 0 ;0
L 1.07453002 -1.90731004 1.11488996 -1.90731004 0 P 0 ;0
L 1.07168996 -1.90631004 1.11356998 -1.90631004 0 P 0 ;0
L 1.06883996 -1.90531004 1.11223996 -1.90531004 0 P 0 ;0
L 1.066 -1.90431004 1.11076998 -1.90431004 0 P 0 ;0
L 1.06315 -1.90331004 1.1092 -1.90331004 0 P 0 ;0
L 1.0599 -1.90231004 1.10763002 -1.90231004 0 P 0 ;0
L 1.05611998 -1.90131004 1.10606004 -1.90131004 0 P 0 ;0
L 1.05235 -1.90031004 1.10448996 -1.90031004 0 P 0 ;0
L 1.04856998 -1.89931004 1.10291998 -1.89931004 0 P 0 ;0
L 1.04478996 -1.89831004 1.10135 -1.89831004 0 P 0 ;0
L 0.98815 -2.08316004 1.03726998 -2.08316004 0 P 0 ;0
L 0.98818002 -2.08216004 1.03731004 -2.08216004 0 P 0 ;0
L 0.98821998 -2.08116004 1.03735 -2.08116004 0 P 0 ;0
L 0.98825 -2.08016004 1.03738996 -2.08016004 0 P 0 ;0
L 0.98828002 -2.07916004 1.03743002 -2.07916004 0 P 0 ;0
L 0.98831998 -2.07816004 1.03746998 -2.07816004 0 P 0 ;0
L 0.98835 -2.07716004 1.03751004 -2.07716004 0 P 0 ;0
L 0.98838002 -2.07616004 1.03755 -2.07616004 0 P 0 ;0
L 0.98841998 -2.07516004 1.03758002 -2.07516004 0 P 0 ;0
L 0.98845 -2.07416004 1.03761004 -2.07416004 0 P 0 ;0
L 0.98848002 -2.07316004 1.03763996 -2.07316004 0 P 0 ;0
L 0.98851004 -2.07216004 1.03768002 -2.07216004 0 P 0 ;0
L 0.98855 -2.07116004 1.03771004 -2.07116004 0 P 0 ;0
L 0.98858002 -2.07016004 1.03773996 -2.07016004 0 P 0 ;0
L 0.98858996 -2.06916004 1.03776998 -2.06916004 0 P 0 ;0
L 0.98858996 -2.06816004 1.0378 -2.06816004 0 P 0 ;0
L 0.98858996 -2.06716004 1.03783002 -2.06716004 0 P 0 ;0
L 0.98858002 -2.06616004 1.03786004 -2.06616004 0 P 0 ;0
L 0.98856998 -2.06516004 1.0379 -2.06516004 0 P 0 ;0
L 0.98856998 -2.06416004 1.03793002 -2.06416004 0 P 0 ;0
L 0.98856998 -2.06316004 1.03796004 -2.06316004 0 P 0 ;0
L 0.98856004 -2.06216004 1.03798996 -2.06216004 0 P 0 ;0
L 0.98855 -2.06116004 1.03801998 -2.06116004 0 P 0 ;0
L 0.98855 -2.06016004 1.03805 -2.06016004 0 P 0 ;0
L 0.98853996 -2.05916004 1.03808002 -2.05916004 0 P 0 ;0
L 0.98853996 -2.05816004 1.0381 -2.05816004 0 P 0 ;0
L 0.98853002 -2.05716004 1.03811998 -2.05716004 0 P 0 ;0
L 0.98848002 -2.05616004 1.03815 -2.05616004 0 P 0 ;0
L 0.98841004 -2.05516004 1.03818002 -2.05516004 0 P 0 ;0
L 0.98835 -2.05416004 1.0382 -2.05416004 0 P 0 ;0
L 0.98828002 -2.05316004 1.03821998 -2.05316004 0 P 0 ;0
L 0.98821004 -2.05216004 1.03825 -2.05216004 0 P 0 ;0
L 0.98815 -2.05116004 1.03826998 -2.05116004 0 P 0 ;0
L 0.98808996 -2.05016004 1.03828996 -2.05016004 0 P 0 ;0
L 0.98801998 -2.04916004 1.03831998 -2.04916004 0 P 0 ;0
L 0.98796004 -2.04816004 1.03833996 -2.04816004 0 P 0 ;0
L 0.98788996 -2.04716004 1.03836004 -2.04716004 0 P 0 ;0
L 0.98783002 -2.04616004 1.03838996 -2.04616004 0 P 0 ;0
L 0.98768996 -2.04516004 1.0384 -2.04516004 0 P 0 ;0
L 0.98756004 -2.04416004 1.03841004 -2.04416004 0 P 0 ;0
L 0.98738002 -2.04316004 1.03841998 -2.04316004 0 P 0 ;0
L 0.98716004 -2.04216004 1.03843002 -2.04216004 0 P 0 ;0
L 0.98691998 -2.04116004 1.03843996 -2.04116004 0 P 0 ;0
L 0.98661998 -2.04016004 1.03845 -2.04016004 0 P 0 ;0
L 0.98631998 -2.03916004 1.03846004 -2.03916004 0 P 0 ;0
L 0.98593996 -2.03816004 1.03846998 -2.03816004 0 P 0 ;0
L 0.98546998 -2.03716004 1.03848002 -2.03716004 0 P 0 ;0
L 0.98491004 -2.03616004 1.03846998 -2.03616004 0 P 0 ;0
L 0.98425 -2.03516004 1.03846004 -2.03516004 0 P 0 ;0
L 0.98346004 -2.03416004 1.03846004 -2.03416004 0 P 0 ;0
L 0.98251998 -2.03316004 1.03843996 -2.03316004 0 P 0 ;0
L 0.98138002 -2.03216004 1.03843002 -2.03216004 0 P 0 ;0
L 0.97998996 -2.03116004 1.03841998 -2.03116004 0 P 0 ;0
L 0.97813996 -2.03016004 1.03841004 -2.03016004 0 P 0 ;0
L 0.97491004 -2.02916004 1.0384 -2.02916004 0 P 0 ;0
L 0.94763996 -2.00716004 1.03293996 -2.00716004 0 P 0 ;0
L 0.94978996 -2.00616004 1.03231998 -2.00616004 0 P 0 ;0
L 0.95081004 -2.00516004 1.0317 -2.00516004 0 P 0 ;0
L 0.95183002 -2.00416004 1.03098002 -2.00416004 0 P 0 ;0
L 0.95285 -2.00316004 1.03023002 -2.00316004 0 P 0 ;0
L 0.95388996 -2.00216004 1.02936004 -2.00216004 0 P 0 ;0
L 0.95498002 -2.00116004 1.02841998 -2.00116004 0 P 0 ;0
L 0.95621998 -2.00016004 1.02738996 -2.00016004 0 P 0 ;0
L 0.95761998 -1.99916004 1.0262 -1.99916004 0 P 0 ;0
L 0.9592 -1.99816004 1.02486004 -1.99816004 0 P 0 ;0
L 0.96083996 -1.99716004 1.02335 -1.99716004 0 P 0 ;0
L 0.9627 -1.99616004 1.02161004 -1.99616004 0 P 0 ;0
L 0.96468996 -1.99516004 1.01951998 -1.99516004 0 P 0 ;0
L 0.96685 -1.99416004 1.01683002 -1.99416004 0 P 0 ;0
L 0.96936998 -1.99316004 1.01378002 -1.99316004 0 P 0 ;0
L 0.97236998 -1.99216004 1.00981004 -1.99216004 0 P 0 ;0
L 0.97676004 -1.99116004 1.00456998 -1.99116004 0 P 0 ;0
L 1.06713996 -2.08283002 1.12288002 -2.08283002 0 P 0 ;0
L 1.06698996 -2.08183002 1.12193996 -2.08183002 0 P 0 ;0
L 1.06686004 -2.08083002 1.12108996 -2.08083002 0 P 0 ;0
L 1.06673996 -2.07983002 1.12036004 -2.07983002 0 P 0 ;0
L 1.06661998 -2.07883002 1.11971998 -2.07883002 0 P 0 ;0
L 1.06653002 -2.07783002 1.11916004 -2.07783002 0 P 0 ;0
L 1.06648002 -2.07683002 1.11866004 -2.07683002 0 P 0 ;0
L 1.06641998 -2.07583002 1.11826004 -2.07583002 0 P 0 ;0
L 1.06636998 -2.07483002 1.11791998 -2.07483002 0 P 0 ;0
L 1.06631998 -2.07383002 1.11761998 -2.07383002 0 P 0 ;0
L 1.06626004 -2.07283002 1.11741998 -2.07283002 0 P 0 ;0
L 1.06621004 -2.07183002 1.11723996 -2.07183002 0 P 0 ;0
L 1.06616004 -2.07083002 1.11711998 -2.07083002 0 P 0 ;0
L 1.06616004 -2.06983002 1.11701004 -2.06983002 0 P 0 ;0
L 1.06616004 -2.06883002 1.11688996 -2.06883002 0 P 0 ;0
L 1.06616998 -2.06783002 1.11676998 -2.06783002 0 P 0 ;0
L 1.06618002 -2.06683002 1.11666998 -2.06683002 0 P 0 ;0
L 1.06618996 -2.06583002 1.11663002 -2.06583002 0 P 0 ;0
L 1.0662 -2.06483002 1.11658996 -2.06483002 0 P 0 ;0
L 1.06621004 -2.06383002 1.11656004 -2.06383002 0 P 0 ;0
L 1.06623002 -2.06283002 1.11651998 -2.06283002 0 P 0 ;0
L 1.06631004 -2.06183002 1.11648996 -2.06183002 0 P 0 ;0
L 1.06638002 -2.06083002 1.11653002 -2.06083002 0 P 0 ;0
L 1.06645 -2.05983002 1.11656998 -2.05983002 0 P 0 ;0
L 1.06651998 -2.05883002 1.11661998 -2.05883002 0 P 0 ;0
L 1.06658996 -2.05783002 1.11666004 -2.05783002 0 P 0 ;0
L 1.06666998 -2.05683002 1.11671004 -2.05683002 0 P 0 ;0
L 1.06673996 -2.05583002 1.11681004 -2.05583002 0 P 0 ;0
L 1.06686004 -2.05483002 1.11693002 -2.05483002 0 P 0 ;0
L 1.067 -2.05383002 1.11705 -2.05383002 0 P 0 ;0
L 1.06713996 -2.05283002 1.11718002 -2.05283002 0 P 0 ;0
L 1.06728002 -2.05183002 1.11731004 -2.05183002 0 P 0 ;0
L 1.06741998 -2.05083002 1.11746004 -2.05083002 0 P 0 ;0
L 1.06756004 -2.04983002 1.11766004 -2.04983002 0 P 0 ;0
L 1.0677 -2.04883002 1.11786004 -2.04883002 0 P 0 ;0
L 1.06786004 -2.04783002 1.11813996 -2.04783002 0 P 0 ;0
L 1.06806998 -2.04683002 1.11841998 -2.04683002 0 P 0 ;0
L 1.06828002 -2.04583002 1.11876998 -2.04583002 0 P 0 ;0
L 1.06848996 -2.04483002 1.11913002 -2.04483002 0 P 0 ;0
L 1.06871004 -2.04383002 1.11955 -2.04383002 0 P 0 ;0
L 1.06898996 -2.04283002 1.11998996 -2.04283002 0 P 0 ;0
L 1.06928002 -2.04183002 1.12048002 -2.04183002 0 P 0 ;0
L 1.06956004 -2.04083002 1.12101004 -2.04083002 0 P 0 ;0
L 1.06985 -2.03983002 1.12161998 -2.03983002 0 P 0 ;0
L 1.07021004 -2.03883002 1.12225 -2.03883002 0 P 0 ;0
L 1.07056998 -2.03783002 1.12298002 -2.03783002 0 P 0 ;0
L 1.07093002 -2.03683002 1.12373996 -2.03683002 0 P 0 ;0
L 1.07128996 -2.03583002 1.12461998 -2.03583002 0 P 0 ;0
L 1.07173002 -2.03483002 1.12548996 -2.03483002 0 P 0 ;0
L 1.07216998 -2.03383002 1.12646004 -2.03383002 0 P 0 ;0
L 1.07261998 -2.03283002 1.12748996 -2.03283002 0 P 0 ;0
L 1.07308002 -2.03183002 1.12855 -2.03183002 0 P 0 ;0
L 1.07361998 -2.03083002 1.12978996 -2.03083002 0 P 0 ;0
L 1.09761004 -1.91731004 1.12756998 -1.91731004 0 P 0 ;0
L 1.09566004 -1.91631004 1.12645 -1.91631004 0 P 0 ;0
L 1.09371004 -1.91531004 1.12533002 -1.91531004 0 P 0 ;0
L 1.09176004 -1.91431004 1.12416004 -1.91431004 0 P 0 ;0
L 1.08946004 -1.91331004 1.12283996 -1.91331004 0 P 0 ;0
L 1.07415 -2.02983002 1.13101998 -2.02983002 0 P 0 ;0
L 1.07468996 -2.02883002 1.13248996 -2.02883002 0 P 0 ;0
L 1.07528996 -2.02783002 1.134 -2.02783002 0 P 0 ;0
L 1.07591998 -2.02683002 1.13586004 -2.02683002 0 P 0 ;0
L 1.07656004 -2.02583002 1.13828996 -2.02583002 0 P 0 ;0
L 1.07721004 -2.02483002 1.14243002 -2.02483002 0 P 0 ;0
L 1.07795 -2.02383002 1.21126998 -2.02383002 0 P 0 ;0
L 1.07868002 -2.02283002 1.21133002 -2.02283002 0 P 0 ;0
L 1.07941998 -2.02183002 1.2114 -2.02183002 0 P 0 ;0
L 1.08021004 -2.02083002 1.21146004 -2.02083002 0 P 0 ;0
L 1.08103996 -2.01983002 1.21153002 -2.01983002 0 P 0 ;0
L 1.08186998 -2.01883002 1.2116 -2.01883002 0 P 0 ;0
L 1.08273002 -2.01783002 1.21166004 -2.01783002 0 P 0 ;0
L 1.08366998 -2.01683002 1.21173002 -2.01683002 0 P 0 ;0
L 1.0846 -2.01583002 1.2118 -2.01583002 0 P 0 ;0
L 1.08555 -2.01483002 1.21186004 -2.01483002 0 P 0 ;0
L 1.08661004 -2.01383002 1.21193002 -2.01383002 0 P 0 ;0
L 1.08766998 -2.01283002 1.21198996 -2.01283002 0 P 0 ;0
L 1.08873002 -2.01183002 1.21205 -2.01183002 0 P 0 ;0
L 1.0898 -2.01083002 1.21211998 -2.01083002 0 P 0 ;0
L 1.09098996 -2.00983002 1.21218002 -2.00983002 0 P 0 ;0
L 1.09225 -2.00883002 1.21223996 -2.00883002 0 P 0 ;0
L 1.09358996 -2.00783002 1.2123 -2.00783002 0 P 0 ;0
L 1.09506998 -2.00683002 1.21236004 -2.00683002 0 P 0 ;0
L 1.09668996 -2.00583002 1.21241998 -2.00583002 0 P 0 ;0
L 0.98546998 -2.12516004 1.03548996 -2.12516004 0 P 0 ;0
L 0.98558996 -2.12416004 1.03553996 -2.12416004 0 P 0 ;0
L 0.9857 -2.12316004 1.03558002 -2.12316004 0 P 0 ;0
L 0.98581004 -2.12216004 1.03561998 -2.12216004 0 P 0 ;0
L 0.98591004 -2.12116004 1.03566998 -2.12116004 0 P 0 ;0
L 0.98598996 -2.12016004 1.03571004 -2.12016004 0 P 0 ;0
L 0.98608002 -2.11916004 1.03575 -2.11916004 0 P 0 ;0
L 0.98616998 -2.11816004 1.0358 -2.11816004 0 P 0 ;0
L 0.98625 -2.11716004 1.03583996 -2.11716004 0 P 0 ;0
L 0.98633996 -2.11616004 1.03588002 -2.11616004 0 P 0 ;0
L 0.98641998 -2.11516004 1.03593002 -2.11516004 0 P 0 ;0
L 0.98651004 -2.11416004 1.03596998 -2.11416004 0 P 0 ;0
L 0.9866 -2.11316004 1.03601004 -2.11316004 0 P 0 ;0
L 0.98668002 -2.11216004 1.03605 -2.11216004 0 P 0 ;0
L 0.98676998 -2.11116004 1.0361 -2.11116004 0 P 0 ;0
L 0.98685 -2.11016004 1.03613996 -2.11016004 0 P 0 ;0
L 0.98693996 -2.10916004 1.03618002 -2.10916004 0 P 0 ;0
L 0.987 -2.10816004 1.03623002 -2.10816004 0 P 0 ;0
L 0.98705 -2.10716004 1.03626998 -2.10716004 0 P 0 ;0
L 0.9871 -2.10616004 1.03631004 -2.10616004 0 P 0 ;0
L 0.98716004 -2.10516004 1.03636004 -2.10516004 0 P 0 ;0
L 0.9872 -2.10416004 1.0364 -2.10416004 0 P 0 ;0
L 0.98725 -2.10316004 1.03643996 -2.10316004 0 P 0 ;0
L 0.98731004 -2.10216004 1.03648002 -2.10216004 0 P 0 ;0
L 0.98735 -2.10116004 1.03653002 -2.10116004 0 P 0 ;0
L 0.9874 -2.10016004 1.03656998 -2.10016004 0 P 0 ;0
L 0.98746004 -2.09916004 1.03661004 -2.09916004 0 P 0 ;0
L 0.98751004 -2.09816004 1.03666004 -2.09816004 0 P 0 ;0
L 0.98755 -2.09716004 1.0367 -2.09716004 0 P 0 ;0
L 0.9876 -2.09616004 1.03673996 -2.09616004 0 P 0 ;0
L 0.98766004 -2.09516004 1.03678996 -2.09516004 0 P 0 ;0
L 0.9877 -2.09416004 1.03683002 -2.09416004 0 P 0 ;0
L 0.98775 -2.09316004 1.03686998 -2.09316004 0 P 0 ;0
L 0.98781004 -2.09216004 1.03691998 -2.09216004 0 P 0 ;0
L 0.98785 -2.09116004 1.03696004 -2.09116004 0 P 0 ;0
L 0.9879 -2.09016004 1.037 -2.09016004 0 P 0 ;0
L 0.98796004 -2.08916004 1.03703996 -2.08916004 0 P 0 ;0
L 0.98798996 -2.08816004 1.03706998 -2.08816004 0 P 0 ;0
L 0.98801998 -2.08716004 1.03711004 -2.08716004 0 P 0 ;0
L 0.98805 -2.08616004 1.03715 -2.08616004 0 P 0 ;0
L 0.98808996 -2.08516004 1.03718996 -2.08516004 0 P 0 ;0
L 0.98811998 -2.08416004 1.03723002 -2.08416004 0 P 0 ;0
L 1.08216998 -2.15683002 1.19803996 -2.15683002 0 P 0 ;0
L 1.0821 -2.15583002 1.19861004 -2.15583002 0 P 0 ;0
L 1.08201998 -2.15483002 1.19918002 -2.15483002 0 P 0 ;0
L 1.08195 -2.15383002 1.1997 -2.15383002 0 P 0 ;0
L 1.08188996 -2.15283002 1.20018002 -2.15283002 0 P 0 ;0
L 1.08183002 -2.15183002 1.20066004 -2.15183002 0 P 0 ;0
L 1.08176998 -2.15083002 1.20113996 -2.15083002 0 P 0 ;0
L 1.08171998 -2.14983002 1.20153996 -2.14983002 0 P 0 ;0
L 1.08166004 -2.14883002 1.20193002 -2.14883002 0 P 0 ;0
L 1.0816 -2.14783002 1.11538996 -2.14783002 0 P 0 ;0
L 1.08155 -2.14683002 1.10903002 -2.14683002 0 P 0 ;0
L 1.0815 -2.14583002 1.10415 -2.14583002 0 P 0 ;0
L 1.08146004 -2.14483002 1.09953002 -2.14483002 0 P 0 ;0
L 1.08141004 -2.14383002 1.09563996 -2.14383002 0 P 0 ;0
L 1.08136004 -2.14283002 1.09183996 -2.14283002 0 P 0 ;0
L 1.08131004 -2.14183002 1.08821004 -2.14183002 0 P 0 ;0
L 1.08133002 -2.14083002 1.08471998 -2.14083002 0 P 0 ;0
L 1.09586998 -2.11983002 1.14965 -2.11983002 0 P 0 ;0
L 1.09361998 -2.11883002 1.15221998 -2.11883002 0 P 0 ;0
L 1.09158996 -2.11783002 1.20595 -2.11783002 0 P 0 ;0
L 1.08988002 -2.11683002 1.20601004 -2.11683002 0 P 0 ;0
L 1.08823996 -2.11583002 1.20606998 -2.11583002 0 P 0 ;0
L 1.08678996 -2.11483002 1.20613002 -2.11483002 0 P 0 ;0
L 1.08541004 -2.11383002 1.20618996 -2.11383002 0 P 0 ;0
L 1.08416998 -2.11283002 1.20625 -2.11283002 0 P 0 ;0
L 1.08295 -2.11183002 1.20631004 -2.11183002 0 P 0 ;0
L 1.08188002 -2.11083002 1.20638002 -2.11083002 0 P 0 ;0
L 1.08081998 -2.10983002 1.20643996 -2.10983002 0 P 0 ;0
L 1.07986004 -2.10883002 1.2065 -2.10883002 0 P 0 ;0
L 1.07895 -2.10783002 1.20656004 -2.10783002 0 P 0 ;0
L 1.07803002 -2.10683002 1.20661998 -2.10683002 0 P 0 ;0
L 1.07723996 -2.10583002 1.20666998 -2.10583002 0 P 0 ;0
L 1.07646004 -2.10483002 1.20671998 -2.10483002 0 P 0 ;0
L 1.07568002 -2.10383002 1.20678002 -2.10383002 0 P 0 ;0
L 1.075 -2.10283002 1.20683002 -2.10283002 0 P 0 ;0
L 1.07433002 -2.10183002 1.20688002 -2.10183002 0 P 0 ;0
L 1.07366998 -2.10083002 1.20693996 -2.10083002 0 P 0 ;0
L 1.07308996 -2.09983002 1.20698996 -2.09983002 0 P 0 ;0
L 1.07253002 -2.09883002 1.20705 -2.09883002 0 P 0 ;0
L 1.07198002 -2.09783002 1.2071 -2.09783002 0 P 0 ;0
L 1.07146998 -2.09683002 1.20715 -2.09683002 0 P 0 ;0
L 1.07101998 -2.09583002 1.2072 -2.09583002 0 P 0 ;0
L 1.07056998 -2.09483002 1.20726004 -2.09483002 0 P 0 ;0
L 1.07013002 -2.09383002 1.20731004 -2.09383002 0 P 0 ;0
L 1.06976998 -2.09283002 1.20736004 -2.09283002 0 P 0 ;0
L 1.06941998 -2.09183002 1.20741998 -2.09183002 0 P 0 ;0
L 1.06906004 -2.09083002 1.20746998 -2.09083002 0 P 0 ;0
L 1.06876004 -2.08983002 1.20753002 -2.08983002 0 P 0 ;0
L 1.06848996 -2.08883002 1.13443002 -2.08883002 0 P 0 ;0
L 1.06821998 -2.08783002 1.13068002 -2.08783002 0 P 0 ;0
L 1.06795 -2.08683002 1.12836998 -2.08683002 0 P 0 ;0
L 1.06771998 -2.08583002 1.1266 -2.08583002 0 P 0 ;0
L 1.06753002 -2.08483002 1.12516004 -2.08483002 0 P 0 ;0
L 1.06733002 -2.08383002 1.12393996 -2.08383002 0 P 0 ;0
L 0.90273996 -1.85456998 0.89068996 -1.85558002 0 P 0 ;0
L 0.89068996 -1.85558002 0.87421004 -1.85741998 0 P 0 ;0
L 0.87421004 -1.85741998 0.85783002 -1.85946998 0 P 0 ;0
L 0.85783002 -1.85946998 0.85526998 -1.8599 0 P 0 ;0
L 0.85526998 -1.8599 0.85276004 -1.86055 0 P 0 ;0
L 0.85276004 -1.86055 0.85255 -1.86063996 0 P 0 ;0
L 0.85255 -1.86063996 0.85248996 -1.86068996 0 P 0 ;0
L 0.85248996 -1.86068996 0.85243002 -1.86073002 0 P 0 ;0
L 0.85243002 -1.86073002 0.85238002 -1.86078002 0 P 0 ;0
L 0.85238002 -1.86078002 0.85233002 -1.86083996 0 P 0 ;0
L 0.85233002 -1.86083996 0.85225 -1.86096004 0 P 0 ;0
L 0.85225 -1.86096004 0.85218002 -1.8611 0 P 0 ;0
L 0.85218002 -1.8611 0.85216004 -1.86116998 0 P 0 ;0
L 0.85216004 -1.86116998 0.85215 -1.86123996 0 P 0 ;0
L 0.85215 -1.86123996 0.85213996 -1.86136998 0 P 0 ;0
L 0.85213996 -1.86136998 0.85213002 -1.86148996 0 P 0 ;0
L 0.85213002 -1.86148996 0.85213996 -1.86161998 0 P 0 ;0
L 0.85213996 -1.86161998 0.85215 -1.86173996 0 P 0 ;0
L 0.85215 -1.86173996 0.85218002 -1.86186998 0 P 0 ;0
L 0.85218002 -1.86186998 0.85221004 -1.86198996 0 P 0 ;0
L 0.85221004 -1.86198996 0.85225 -1.8621 0 P 0 ;0
L 0.85225 -1.8621 0.85231004 -1.86221998 0 P 0 ;0
L 0.85231004 -1.86221998 0.85236998 -1.86233002 0 P 0 ;0
L 0.85236998 -1.86233002 0.85281998 -1.863 0 P 0 ;0
L 0.85281998 -1.863 0.8533 -1.86363996 0 P 0 ;0
L 0.8533 -1.86363996 0.85383002 -1.86425 0 P 0 ;0
L 0.85383002 -1.86425 0.85736004 -1.86801998 0 P 0 ;0
L 0.85736004 -1.86801998 0.86013002 -1.87113002 0 P 0 ;0
L 0.86013002 -1.87113002 0.86266004 -1.87443002 0 P 0 ;0
L 0.86266004 -1.87443002 0.86501004 -1.87798996 0 P 0 ;0
L 0.86501004 -1.87798996 0.86711998 -1.88171004 0 P 0 ;0
L 0.86711998 -1.88171004 0.86896998 -1.88553996 0 P 0 ;0
L 0.86896998 -1.88553996 0.87055 -1.8895 0 P 0 ;0
L 0.87055 -1.8895 0.8718 -1.89343002 0 P 0 ;0
L 0.8718 -1.89343002 0.87276004 -1.89745 0 P 0 ;0
L 0.87276004 -1.89745 0.87371004 -1.90195 0 P 0 ;0
L 0.87371004 -1.90195 0.87383002 -1.90236004 0 P 0 ;0
L 0.87383002 -1.90236004 0.87396998 -1.90276004 0 P 0 ;0
L 0.87396998 -1.90276004 0.87416004 -1.90313996 0 P 0 ;0
L 0.87416004 -1.90313996 0.87436998 -1.90351004 0 P 0 ;0
L 0.87436998 -1.90351004 0.87443002 -1.9036 0 P 0 ;0
L 0.87443002 -1.9036 0.87456998 -1.90376004 0 P 0 ;0
L 0.87456998 -1.90376004 0.87465 -1.90381998 0 P 0 ;0
L 0.87465 -1.90381998 0.87473002 -1.90388996 0 P 0 ;0
L 0.87473002 -1.90388996 0.87481998 -1.90393996 0 P 0 ;0
L 0.87481998 -1.90393996 0.87491998 -1.90398996 0 P 0 ;0
L 0.87491998 -1.90398996 0.87501004 -1.90403002 0 P 0 ;0
L 0.87501004 -1.90403002 0.87521004 -1.90408996 0 P 0 ;0
L 0.87521004 -1.90408996 0.87531998 -1.9041 0 P 0 ;0
L 0.87531998 -1.9041 0.87573002 -1.90413002 0 P 0 ;0
L 0.87573002 -1.90413002 0.87613996 -1.90411998 0 P 0 ;0
L 0.87613996 -1.90411998 0.87653996 -1.90408002 0 P 0 ;0
L 0.87653996 -1.90408002 0.87695 -1.90401004 0 P 0 ;0
L 0.87695 -1.90401004 0.90756004 -1.89766998 0 P 0 ;0
L 0.90756004 -1.89766998 0.92603996 -1.89478002 0 P 0 ;0
L 0.92603996 -1.89478002 0.93486004 -1.89393996 0 P 0 ;0
L 0.93486004 -1.89393996 0.94371004 -1.8935 0 P 0 ;0
L 0.94371004 -1.8935 0.97045 -1.89308002 0 P 0 ;0
L 0.97045 -1.89308002 0.99468996 -1.89328996 0 P 0 ;0
L 0.99468996 -1.89328996 1.01021004 -1.89413996 0 P 0 ;0
L 1.01021004 -1.89413996 1.0241 -1.89601998 0 P 0 ;0
L 1.0241 -1.89601998 1.04188002 -1.89961004 0 P 0 ;0
L 1.04188002 -1.89961004 1.06095 -1.90466004 0 P 0 ;0
L 1.06095 -1.90466004 1.07963996 -1.91123002 0 P 0 ;0
L 1.07963996 -1.91123002 1.09093996 -1.91613002 0 P 0 ;0
L 1.09093996 -1.91613002 1.10186998 -1.92175 0 P 0 ;0
L 1.10186998 -1.92175 1.11243996 -1.92806998 0 P 0 ;0
L 1.11243996 -1.92806998 1.12163002 -1.93446998 0 P 0 ;0
L 1.12163002 -1.93446998 1.13033002 -1.94148996 0 P 0 ;0
L 1.13033002 -1.94148996 1.1385 -1.94911004 0 P 0 ;0
L 1.1385 -1.94911004 1.14358996 -1.9546 0 P 0 ;0
L 1.14358996 -1.9546 1.14825 -1.96045 0 P 0 ;0
L 1.14825 -1.96045 1.15246998 -1.96663002 0 P 0 ;0
L 1.15246998 -1.96663002 1.15623002 -1.97316004 0 P 0 ;0
L 1.15623002 -1.97316004 1.15895 -1.97831004 0 P 0 ;0
L 1.15895 -1.97831004 1.17358996 -1.97831004 0 P 0 ;0
L 1.17358996 -1.97831004 1.17135 -1.9726 0 P 0 ;0
L 1.17135 -1.9726 1.16696004 -1.96266998 0 P 0 ;0
L 1.16696004 -1.96266998 1.16171998 -1.95313002 0 P 0 ;0
L 1.16171998 -1.95313002 1.1557 -1.94406998 0 P 0 ;0
L 1.1557 -1.94406998 1.14885 -1.93548002 0 P 0 ;0
L 1.14885 -1.93548002 1.13778996 -1.92378002 0 P 0 ;0
L 1.13778996 -1.92378002 1.12576998 -1.91301998 0 P 0 ;0
L 1.12576998 -1.91301998 1.11283996 -1.90326004 0 P 0 ;0
L 1.11283996 -1.90326004 1.09783002 -1.89368996 0 P 0 ;0
L 1.09783002 -1.89368996 1.08213002 -1.88526998 0 P 0 ;0
L 1.08213002 -1.88526998 1.06576998 -1.87801004 0 P 0 ;0
L 1.06576998 -1.87801004 1.04776004 -1.87141998 0 P 0 ;0
L 1.04776004 -1.87141998 1.02938002 -1.86591998 0 P 0 ;0
L 1.02938002 -1.86591998 1.01058002 -1.8615 0 P 0 ;0
L 1.01058002 -1.8615 0.98441998 -1.85711004 0 P 0 ;0
L 0.98441998 -1.85711004 0.95781004 -1.85448996 0 P 0 ;0
L 0.95781004 -1.85448996 0.93061004 -1.85366004 0 P 0 ;0
L 0.93061004 -1.85366004 0.90273996 -1.85456998 0 P 0 ;0
L 1.16015 -1.97631004 1.15798002 -1.97218996 0 P 0 ;0
L 1.15798002 -1.97218996 1.15796004 -1.97216004 0 P 0 ;0
L 1.15796004 -1.97216004 1.15416004 -1.96556998 0 P 0 ;0
L 1.15416004 -1.96556998 1.15411998 -1.96551004 0 P 0 ;0
L 1.15411998 -1.96551004 1.14986004 -1.95926004 0 P 0 ;0
L 1.14986004 -1.95926004 1.14981998 -1.95921004 0 P 0 ;0
L 1.14981998 -1.95921004 1.14511004 -1.9533 0 P 0 ;0
L 1.14511004 -1.9533 1.13991998 -1.9477 0 P 0 ;0
L 1.13991998 -1.9477 1.13986004 -1.94765 0 P 0 ;0
L 1.13986004 -1.94765 1.13163996 -1.93998002 0 P 0 ;0
L 1.13163996 -1.93998002 1.12283002 -1.93286004 0 P 0 ;0
L 1.12283002 -1.93286004 1.11351998 -1.92638996 0 P 0 ;0
L 1.11351998 -1.92638996 1.10283996 -1.92 0 P 0 ;0
L 1.10283996 -1.92 1.0918 -1.91433002 0 P 0 ;0
L 1.0918 -1.91433002 1.08036998 -1.90936004 0 P 0 ;0
L 1.08036998 -1.90936004 1.06153002 -1.90273996 0 P 0 ;0
L 1.06153002 -1.90273996 1.06146004 -1.90273002 0 P 0 ;0
L 1.06146004 -1.90273002 1.04233002 -1.89766004 0 P 0 ;0
L 1.04233002 -1.89766004 1.02443002 -1.89405 0 P 0 ;0
L 1.02443002 -1.89405 1.0104 -1.89213996 0 P 0 ;0
L 1.0104 -1.89213996 0.99475 -1.89128996 0 P 0 ;0
L 0.99475 -1.89128996 0.97045 -1.89108002 0 P 0 ;0
L 0.97045 -1.89108002 0.94365 -1.8915 0 P 0 ;0
L 0.94365 -1.8915 0.94361998 -1.8915 0 P 0 ;0
L 0.94361998 -1.8915 0.93471998 -1.89195 0 P 0 ;0
L 0.93471998 -1.89195 0.92578996 -1.89278996 0 P 0 ;0
L 0.92578996 -1.89278996 0.9072 -1.89571004 0 P 0 ;0
L 0.9072 -1.89571004 0.87656998 -1.90203996 0 P 0 ;0
L 0.87656998 -1.90203996 0.87626998 -1.9021 0 P 0 ;0
L 0.87626998 -1.9021 0.87601998 -1.90211998 0 P 0 ;0
L 0.87601998 -1.90211998 0.87588996 -1.90213002 0 P 0 ;0
L 0.87588996 -1.90213002 0.87583002 -1.90198996 0 P 0 ;0
L 0.87583002 -1.90198996 0.87573002 -1.90175 0 P 0 ;0
L 0.87573002 -1.90175 0.87566004 -1.90146998 0 P 0 ;0
L 0.87566004 -1.90146998 0.87471004 -1.89701004 0 P 0 ;0
L 0.87471004 -1.89701004 0.8747 -1.89698996 0 P 0 ;0
L 0.8747 -1.89698996 0.87373002 -1.89288996 0 P 0 ;0
L 0.87373002 -1.89288996 0.87243002 -1.88881998 0 P 0 ;0
L 0.87243002 -1.88881998 0.8724 -1.88876004 0 P 0 ;0
L 0.8724 -1.88876004 0.8708 -1.88473996 0 P 0 ;0
L 0.8708 -1.88473996 0.8689 -1.88078002 0 P 0 ;0
L 0.8689 -1.88078002 0.86671998 -1.87693996 0 P 0 ;0
L 0.86671998 -1.87693996 0.86428996 -1.87326004 0 P 0 ;0
L 0.86428996 -1.87326004 0.86166998 -1.86985 0 P 0 ;0
L 0.86166998 -1.86985 0.85883996 -1.86668002 0 P 0 ;0
L 0.85883996 -1.86668002 0.85883002 -1.86666004 0 P 0 ;0
L 0.85883002 -1.86666004 0.85531998 -1.86291004 0 P 0 ;0
L 0.85531998 -1.86291004 0.85486004 -1.86238002 0 P 0 ;0
L 0.85486004 -1.86238002 0.85466004 -1.86211998 0 P 0 ;0
L 0.85466004 -1.86211998 0.8557 -1.86186004 0 P 0 ;0
L 0.8557 -1.86186004 0.85811998 -1.86145 0 P 0 ;0
L 0.85811998 -1.86145 0.87443996 -1.85941004 0 P 0 ;0
L 0.87443996 -1.85941004 0.89088996 -1.85756998 0 P 0 ;0
L 0.89088996 -1.85756998 0.90286004 -1.85656998 0 P 0 ;0
L 0.90286004 -1.85656998 0.93061004 -1.85566004 0 P 0 ;0
L 0.93061004 -1.85566004 0.95768002 -1.85648996 0 P 0 ;0
L 0.95768002 -1.85648996 0.98416004 -1.8591 0 P 0 ;0
L 0.98416004 -1.8591 1.01018996 -1.86346004 0 P 0 ;0
L 1.01018996 -1.86346004 1.02886004 -1.86785 0 P 0 ;0
L 1.02886004 -1.86785 1.04711998 -1.87331998 0 P 0 ;0
L 1.04711998 -1.87331998 1.06501004 -1.87986004 0 P 0 ;0
L 1.06501004 -1.87986004 1.08125 -1.88706998 0 P 0 ;0
L 1.08125 -1.88706998 1.09681004 -1.89541998 0 P 0 ;0
L 1.09681004 -1.89541998 1.1117 -1.9049 0 P 0 ;0
L 1.1117 -1.9049 1.1245 -1.91456998 0 P 0 ;0
L 1.1245 -1.91456998 1.13638996 -1.92521004 0 P 0 ;0
L 1.13638996 -1.92521004 1.14733996 -1.93678996 0 P 0 ;0
L 1.14733996 -1.93678996 1.15408002 -1.94525 0 P 0 ;0
L 1.15408002 -1.94525 1.16001004 -1.95416998 0 P 0 ;0
L 1.16001004 -1.95416998 1.16516004 -1.96355 0 P 0 ;0
L 1.16516004 -1.96355 1.1695 -1.97336998 0 P 0 ;0
L 1.1695 -1.97336998 1.17066004 -1.97631004 0 P 0 ;0
L 1.17066004 -1.97631004 1.16015 -1.97631004 0 P 0 ;0
L 0.87563002 -1.90131004 0.8801 -1.90131004 0 P 0 ;0
L 0.87541004 -1.90031004 0.88493996 -1.90031004 0 P 0 ;0
L 0.8752 -1.89931004 0.88976998 -1.89931004 0 P 0 ;0
L 0.87498996 -1.89831004 0.8946 -1.89831004 0 P 0 ;0
L 0.89423002 -2.08316004 0.94355 -2.08316004 0 P 0 ;0
L 0.89428996 -2.08216004 0.9436 -2.08216004 0 P 0 ;0
L 0.89435 -2.08116004 0.94365 -2.08116004 0 P 0 ;0
L 0.89441004 -2.08016004 0.9437 -2.08016004 0 P 0 ;0
L 0.89446004 -2.07916004 0.94375 -2.07916004 0 P 0 ;0
L 0.89451998 -2.07816004 0.94378996 -2.07816004 0 P 0 ;0
L 0.89458002 -2.07716004 0.94383996 -2.07716004 0 P 0 ;0
L 0.89463996 -2.07616004 0.94388996 -2.07616004 0 P 0 ;0
L 0.8947 -2.07516004 0.94393996 -2.07516004 0 P 0 ;0
L 0.89475 -2.07416004 0.94398002 -2.07416004 0 P 0 ;0
L 0.89481004 -2.07316004 0.94403002 -2.07316004 0 P 0 ;0
L 0.89486998 -2.07216004 0.94408002 -2.07216004 0 P 0 ;0
L 0.89493002 -2.07116004 0.94415 -2.07116004 0 P 0 ;0
L 0.89498996 -2.07016004 0.94426004 -2.07016004 0 P 0 ;0
L 0.89505 -2.06916004 0.94436998 -2.06916004 0 P 0 ;0
L 0.8951 -2.06816004 0.94448002 -2.06816004 0 P 0 ;0
L 0.89516004 -2.06716004 0.94458996 -2.06716004 0 P 0 ;0
L 0.89521998 -2.06616004 0.9447 -2.06616004 0 P 0 ;0
L 0.89526998 -2.06516004 0.94481004 -2.06516004 0 P 0 ;0
L 0.89531004 -2.06416004 0.94491998 -2.06416004 0 P 0 ;0
L 0.89535 -2.06316004 0.94503002 -2.06316004 0 P 0 ;0
L 0.8954 -2.06216004 0.94513996 -2.06216004 0 P 0 ;0
L 0.89543996 -2.06116004 0.94531998 -2.06116004 0 P 0 ;0
L 0.89548996 -2.06016004 0.94551004 -2.06016004 0 P 0 ;0
L 0.89553002 -2.05916004 0.9457 -2.05916004 0 P 0 ;0
L 0.89558002 -2.05816004 0.94588996 -2.05816004 0 P 0 ;0
L 0.89561998 -2.05716004 0.94608002 -2.05716004 0 P 0 ;0
L 0.89566998 -2.05616004 0.94626998 -2.05616004 0 P 0 ;0
L 0.89571004 -2.05516004 0.94646998 -2.05516004 0 P 0 ;0
L 0.89575 -2.05416004 0.94666004 -2.05416004 0 P 0 ;0
L 0.8958 -2.05316004 0.94685 -2.05316004 0 P 0 ;0
L 0.89583996 -2.05216004 0.94708002 -2.05216004 0 P 0 ;0
L 0.89588996 -2.05116004 0.94735 -2.05116004 0 P 0 ;0
L 0.89593996 -2.05016004 0.94761998 -2.05016004 0 P 0 ;0
L 0.89598002 -2.04916004 0.9479 -2.04916004 0 P 0 ;0
L 0.89601998 -2.04816004 0.94825 -2.04816004 0 P 0 ;0
L 0.89606998 -2.04716004 0.94858996 -2.04716004 0 P 0 ;0
L 0.89611004 -2.04616004 0.94893002 -2.04616004 0 P 0 ;0
L 0.89616004 -2.04516004 0.94935 -2.04516004 0 P 0 ;0
L 0.8962 -2.04416004 0.94976998 -2.04416004 0 P 0 ;0
L 0.89625 -2.04316004 0.9502 -2.04316004 0 P 0 ;0
L 0.89628002 -2.04216004 0.95068996 -2.04216004 0 P 0 ;0
L 0.89631004 -2.04116004 0.95118996 -2.04116004 0 P 0 ;0
L 0.89633996 -2.04016004 0.95168996 -2.04016004 0 P 0 ;0
L 0.89638002 -2.03916004 0.95228002 -2.03916004 0 P 0 ;0
L 0.89641004 -2.03816004 0.95291004 -2.03816004 0 P 0 ;0
L 0.89643996 -2.03716004 0.95363002 -2.03716004 0 P 0 ;0
L 0.89646998 -2.03616004 0.95445 -2.03616004 0 P 0 ;0
L 0.89651004 -2.03516004 0.95535 -2.03516004 0 P 0 ;0
L 0.89653996 -2.03416004 0.95636998 -2.03416004 0 P 0 ;0
L 0.89656998 -2.03316004 0.95756998 -2.03316004 0 P 0 ;0
L 0.8966 -2.03216004 0.95893996 -2.03216004 0 P 0 ;0
L 0.89663996 -2.03116004 0.96055 -2.03116004 0 P 0 ;0
L 0.89666998 -2.03016004 0.96278002 -2.03016004 0 P 0 ;0
L 0.8967 -2.02916004 0.96676004 -2.02916004 0 P 0 ;0
L 0.89673996 -2.02816004 1.03838996 -2.02816004 0 P 0 ;0
L 0.89676998 -2.02716004 1.03838002 -2.02716004 0 P 0 ;0
L 0.8968 -2.02616004 1.03833996 -2.02616004 0 P 0 ;0
L 0.89683996 -2.02516004 1.03828996 -2.02516004 0 P 0 ;0
L 0.89686998 -2.02416004 1.03823002 -2.02416004 0 P 0 ;0
L 0.8969 -2.02316004 1.03816004 -2.02316004 0 P 0 ;0
L 0.89693996 -2.02216004 1.0381 -2.02216004 0 P 0 ;0
L 0.89696998 -2.02116004 1.03803996 -2.02116004 0 P 0 ;0
L 0.897 -2.02016004 1.0379 -2.02016004 0 P 0 ;0
L 0.89703002 -2.01916004 1.03773996 -2.01916004 0 P 0 ;0
L 0.89706004 -2.01816004 1.03751998 -2.01816004 0 P 0 ;0
L 0.89708996 -2.01716004 1.03728002 -2.01716004 0 P 0 ;0
L 0.89711998 -2.01616004 1.03698996 -2.01616004 0 P 0 ;0
L 0.89713996 -2.01516004 1.03668002 -2.01516004 0 P 0 ;0
L 0.89716998 -2.01416004 1.03631004 -2.01416004 0 P 0 ;0
L 0.8972 -2.01316004 1.03591998 -2.01316004 0 P 0 ;0
L 0.89721998 -2.01216004 1.03548996 -2.01216004 0 P 0 ;0
L 0.89725 -2.01116004 1.03505 -2.01116004 0 P 0 ;0
L 0.89726998 -2.01016004 1.03458002 -2.01016004 0 P 0 ;0
L 0.8973 -2.00916004 1.03405 -2.00916004 0 P 0 ;0
L 0.89733002 -2.00816004 1.03351998 -2.00816004 0 P 0 ;0
L 0.89736004 -2.00716004 0.94676004 -2.00716004 0 P 0 ;0
L 0.89738002 -2.00616004 0.9461 -2.00616004 0 P 0 ;0
L 0.89741004 -2.00516004 0.94563996 -2.00516004 0 P 0 ;0
L 0.89743996 -2.00416004 0.94563996 -2.00416004 0 P 0 ;0
L 0.89746004 -2.00316004 0.94563996 -2.00316004 0 P 0 ;0
L 0.89748996 -2.00216004 0.94563996 -2.00216004 0 P 0 ;0
L 0.89751004 -2.00116004 0.94563996 -2.00116004 0 P 0 ;0
L 0.89753996 -2.00016004 0.94563996 -2.00016004 0 P 0 ;0
L 0.89756998 -1.99916004 0.94563996 -1.99916004 0 P 0 ;0
L 0.8976 -1.99816004 0.94563996 -1.99816004 0 P 0 ;0
L 0.89761998 -1.99716004 0.94563996 -1.99716004 0 P 0 ;0
L 0.89765 -1.99616004 0.94563996 -1.99616004 0 P 0 ;0
L 0.89768002 -1.99516004 0.94563996 -1.99516004 0 P 0 ;0
L 0.97546998 -1.98933996 0.97236998 -1.99006004 0 P 0 ;0
L 0.97236998 -1.99006004 0.96931998 -1.99103002 0 P 0 ;0
L 0.96931998 -1.99103002 0.96603002 -1.99233002 0 P 0 ;0
L 0.96603002 -1.99233002 0.96281004 -1.99383002 0 P 0 ;0
L 0.96281004 -1.99383002 0.95976004 -1.99546998 0 P 0 ;0
L 0.95976004 -1.99546998 0.95681004 -1.99728996 0 P 0 ;0
L 0.95681004 -1.99728996 0.95521004 -1.99841004 0 P 0 ;0
L 0.95521004 -1.99841004 0.95368996 -1.99963002 0 P 0 ;0
L 0.95368996 -1.99963002 0.95223996 -2.00095 0 P 0 ;0
L 0.95223996 -2.00095 0.94763996 -2.00546998 0 P 0 ;0
L 0.94763996 -2.00546998 0.94763996 -1.99243996 0 P 0 ;0
L 0.94763996 -1.99243996 0.89575 -1.99243996 0 P 0 ;0
L 0.89575 -1.99243996 0.89505 -2.01878002 0 P 0 ;0
L 0.89505 -2.01878002 0.89423996 -2.04316004 0 P 0 ;0
L 0.89423996 -2.04316004 0.89321998 -2.0661 0 P 0 ;0
L 0.89321998 -2.0661 0.89198996 -2.08728996 0 P 0 ;0
L 0.89198996 -2.08728996 0.89055 -2.1063 0 P 0 ;0
L 0.89055 -2.1063 0.88993996 -2.11358002 0 P 0 ;0
L 0.88993996 -2.11358002 0.88943002 -2.11988002 0 P 0 ;0
L 0.88943002 -2.11988002 0.88898996 -2.12533996 0 P 0 ;0
L 0.88898996 -2.12533996 0.88896004 -2.12613002 0 P 0 ;0
L 0.88896004 -2.12613002 0.88896998 -2.12621004 0 P 0 ;0
L 0.88896998 -2.12621004 0.88898002 -2.12625 0 P 0 ;0
L 0.88898002 -2.12625 0.88898996 -2.12628002 0 P 0 ;0
L 0.88898996 -2.12628002 0.88901998 -2.12636004 0 P 0 ;0
L 0.88901998 -2.12636004 0.88903996 -2.12638996 0 P 0 ;0
L 0.88903996 -2.12638996 0.88906998 -2.12641998 0 P 0 ;0
L 0.88906998 -2.12641998 0.88908996 -2.12645 0 P 0 ;0
L 0.88908996 -2.12645 0.88911998 -2.12646998 0 P 0 ;0
L 0.88911998 -2.12646998 0.88915 -2.1265 0 P 0 ;0
L 0.88915 -2.1265 0.88921004 -2.12653996 0 P 0 ;0
L 0.88921004 -2.12653996 0.88925 -2.12655 0 P 0 ;0
L 0.88925 -2.12655 0.88928002 -2.12656004 0 P 0 ;0
L 0.88928002 -2.12656004 0.88931998 -2.12658002 0 P 0 ;0
L 0.88931998 -2.12658002 0.8894 -2.12658002 0 P 0 ;0
L 0.8894 -2.12658002 0.89648002 -2.12686998 0 P 0 ;0
L 0.89648002 -2.12686998 0.90518996 -2.1271 0 P 0 ;0
L 0.90518996 -2.1271 0.9165 -2.12716004 0 P 0 ;0
L 0.9165 -2.12716004 0.94403996 -2.12716004 0 P 0 ;0
L 0.94403996 -2.12716004 0.94468996 -2.10135 0 P 0 ;0
L 0.94468996 -2.10135 0.9461 -2.07171998 0 P 0 ;0
L 0.9461 -2.07171998 0.94713002 -2.06233002 0 P 0 ;0
L 0.94713002 -2.06233002 0.9489 -2.05308002 0 P 0 ;0
L 0.9489 -2.05308002 0.94975 -2.04995 0 P 0 ;0
L 0.94975 -2.04995 0.9508 -2.04688996 0 P 0 ;0
L 0.9508 -2.04688996 0.95205 -2.0439 0 P 0 ;0
L 0.95205 -2.0439 0.95351004 -2.041 0 P 0 ;0
L 0.95351004 -2.041 0.9544 -2.03951004 0 P 0 ;0
L 0.9544 -2.03951004 0.95541998 -2.03811004 0 P 0 ;0
L 0.95541998 -2.03811004 0.95655 -2.03678996 0 P 0 ;0
L 0.95655 -2.03678996 0.95778996 -2.03556998 0 P 0 ;0
L 0.95778996 -2.03556998 0.95911998 -2.03446998 0 P 0 ;0
L 0.95911998 -2.03446998 0.96056998 -2.03346998 0 P 0 ;0
L 0.96056998 -2.03346998 0.96151004 -2.03291004 0 P 0 ;0
L 0.96151004 -2.03291004 0.96248996 -2.03243002 0 P 0 ;0
L 0.96248996 -2.03243002 0.96351004 -2.03201998 0 P 0 ;0
L 0.96351004 -2.03201998 0.96455 -2.03168996 0 P 0 ;0
L 0.96455 -2.03168996 0.96613002 -2.0313 0 P 0 ;0
L 0.96613002 -2.0313 0.96773002 -2.03101998 0 P 0 ;0
L 0.96773002 -2.03101998 0.96935 -2.03086004 0 P 0 ;0
L 0.96935 -2.03086004 0.97095 -2.03081004 0 P 0 ;0
L 0.97095 -2.03081004 0.97255 -2.03086998 0 P 0 ;0
L 0.97255 -2.03086998 0.97413002 -2.03105 0 P 0 ;0
L 0.97413002 -2.03105 0.97513002 -2.03123996 0 P 0 ;0
L 0.97513002 -2.03123996 0.9761 -2.03151004 0 P 0 ;0
L 0.9761 -2.03151004 0.97706004 -2.03186004 0 P 0 ;0
L 0.97706004 -2.03186004 0.97796998 -2.0323 0 P 0 ;0
L 0.97796998 -2.0323 0.97885 -2.0328 0 P 0 ;0
L 0.97885 -2.0328 0.97968002 -2.03336998 0 P 0 ;0
L 0.97968002 -2.03336998 0.98046998 -2.03398996 0 P 0 ;0
L 0.98046998 -2.03398996 0.98121998 -2.03468002 0 P 0 ;0
L 0.98121998 -2.03468002 0.98191004 -2.03541998 0 P 0 ;0
L 0.98191004 -2.03541998 0.98253996 -2.0362 0 P 0 ;0
L 0.98253996 -2.0362 0.9831 -2.03703002 0 P 0 ;0
L 0.9831 -2.03703002 0.9836 -2.03788996 0 P 0 ;0
L 0.9836 -2.03788996 0.98403996 -2.0388 0 P 0 ;0
L 0.98403996 -2.0388 0.9844 -2.03973996 0 P 0 ;0
L 0.9844 -2.03973996 0.98505 -2.04188996 0 P 0 ;0
L 0.98505 -2.04188996 0.98553002 -2.04408002 0 P 0 ;0
L 0.98553002 -2.04408002 0.98583002 -2.0463 0 P 0 ;0
L 0.98583002 -2.0463 0.98653002 -2.05705 0 P 0 ;0
L 0.98653002 -2.05705 0.9866 -2.06961004 0 P 0 ;0
L 0.9866 -2.06961004 0.98596004 -2.08908002 0 P 0 ;0
L 0.98596004 -2.08908002 0.98498002 -2.10858002 0 P 0 ;0
L 0.98498002 -2.10858002 0.98388002 -2.12146998 0 P 0 ;0
L 0.98388002 -2.12146998 0.98323002 -2.12716004 0 P 0 ;0
L 0.98323002 -2.12716004 1.03741004 -2.12716004 0 P 0 ;0
L 1.03741004 -2.12716004 1.03896004 -2.09103002 0 P 0 ;0
L 1.03896004 -2.09103002 1.03956004 -2.0759 0 P 0 ;0
L 1.03956004 -2.0759 1.04005 -2.06025 0 P 0 ;0
L 1.04005 -2.06025 1.04038996 -2.04626004 0 P 0 ;0
L 1.04038996 -2.04626004 1.04048002 -2.03698996 0 P 0 ;0
L 1.04048002 -2.03698996 1.04036998 -2.02651998 0 P 0 ;0
L 1.04036998 -2.02651998 1.04003996 -2.02096998 0 P 0 ;0
L 1.04003996 -2.02096998 1.03975 -2.01895 0 P 0 ;0
L 1.03975 -2.01895 1.0393 -2.01693996 0 P 0 ;0
L 1.0393 -2.01693996 1.03868996 -2.01483996 0 P 0 ;0
L 1.03868996 -2.01483996 1.03793996 -2.01278002 0 P 0 ;0
L 1.03793996 -2.01278002 1.03658996 -2.00968002 0 P 0 ;0
L 1.03658996 -2.00968002 1.03501004 -2.00668996 0 P 0 ;0
L 1.03501004 -2.00668996 1.0332 -2.0038 0 P 0 ;0
L 1.0332 -2.0038 1.03186998 -2.002 0 P 0 ;0
L 1.03186998 -2.002 1.0304 -2.0003 0 P 0 ;0
L 1.0304 -2.0003 1.0288 -1.99873002 0 P 0 ;0
L 1.0288 -1.99873002 1.02708002 -1.99728996 0 P 0 ;0
L 1.02708002 -1.99728996 1.02518002 -1.99593002 0 P 0 ;0
L 1.02518002 -1.99593002 1.02318002 -1.99471998 0 P 0 ;0
L 1.02318002 -1.99471998 1.0211 -1.99365 0 P 0 ;0
L 1.0211 -1.99365 1.01893002 -1.99273996 0 P 0 ;0
L 1.01893002 -1.99273996 1.01358996 -1.99098996 0 P 0 ;0
L 1.01358996 -1.99098996 1.0081 -1.98971004 0 P 0 ;0
L 1.0081 -1.98971004 1.00428996 -1.98908996 0 P 0 ;0
L 1.00428996 -1.98908996 1.00043996 -1.98868002 0 P 0 ;0
L 1.00043996 -1.98868002 0.99138002 -1.98826004 0 P 0 ;0
L 0.99138002 -1.98826004 0.98251998 -1.98846998 0 P 0 ;0
L 0.98251998 -1.98846998 0.97898996 -1.98878996 0 P 0 ;0
L 0.97898996 -1.98878996 0.97546998 -1.98933996 0 P 0 ;0
L 0.91651004 -2.12516004 0.94208996 -2.12516004 0 P 0 ;0
L 0.8911 -2.12416004 0.94211004 -2.12416004 0 P 0 ;0
L 0.89118002 -2.12316004 0.94213996 -2.12316004 0 P 0 ;0
L 0.89125 -2.12216004 0.94216004 -2.12216004 0 P 0 ;0
L 0.89133002 -2.12116004 0.94218996 -2.12116004 0 P 0 ;0
L 0.89141004 -2.12016004 0.94221004 -2.12016004 0 P 0 ;0
L 0.89148996 -2.11916004 0.94223996 -2.11916004 0 P 0 ;0
L 0.89156998 -2.11816004 0.94226998 -2.11816004 0 P 0 ;0
L 0.89166004 -2.11716004 0.94228996 -2.11716004 0 P 0 ;0
L 0.89173996 -2.11616004 0.94231004 -2.11616004 0 P 0 ;0
L 0.89181998 -2.11516004 0.94233996 -2.11516004 0 P 0 ;0
L 0.8919 -2.11416004 0.94236004 -2.11416004 0 P 0 ;0
L 0.89198002 -2.11316004 0.94238996 -2.11316004 0 P 0 ;0
L 0.89206998 -2.11216004 0.94241998 -2.11216004 0 P 0 ;0
L 0.89215 -2.11116004 0.94243996 -2.11116004 0 P 0 ;0
L 0.89223002 -2.11016004 0.94246998 -2.11016004 0 P 0 ;0
L 0.89231998 -2.10916004 0.94248996 -2.10916004 0 P 0 ;0
L 0.8924 -2.10816004 0.94251998 -2.10816004 0 P 0 ;0
L 0.89248002 -2.10716004 0.94255 -2.10716004 0 P 0 ;0
L 0.89256998 -2.10616004 0.94256998 -2.10616004 0 P 0 ;0
L 0.89263996 -2.10516004 0.94258996 -2.10516004 0 P 0 ;0
L 0.89271004 -2.10416004 0.94261998 -2.10416004 0 P 0 ;0
L 0.89278996 -2.10316004 0.94263996 -2.10316004 0 P 0 ;0
L 0.89286998 -2.10216004 0.94266998 -2.10216004 0 P 0 ;0
L 0.89293996 -2.10116004 0.9427 -2.10116004 0 P 0 ;0
L 0.89301998 -2.10016004 0.94275 -2.10016004 0 P 0 ;0
L 0.89308996 -2.09916004 0.94278996 -2.09916004 0 P 0 ;0
L 0.89316998 -2.09816004 0.94283996 -2.09816004 0 P 0 ;0
L 0.89325 -2.09716004 0.94288996 -2.09716004 0 P 0 ;0
L 0.89331998 -2.09616004 0.94293996 -2.09616004 0 P 0 ;0
L 0.8934 -2.09516004 0.94298002 -2.09516004 0 P 0 ;0
L 0.89346998 -2.09416004 0.94303002 -2.09416004 0 P 0 ;0
L 0.89355 -2.09316004 0.94308002 -2.09316004 0 P 0 ;0
L 0.89361998 -2.09216004 0.94313002 -2.09216004 0 P 0 ;0
L 0.8937 -2.09116004 0.94318002 -2.09116004 0 P 0 ;0
L 0.89378002 -2.09016004 0.94321998 -2.09016004 0 P 0 ;0
L 0.89385 -2.08916004 0.94326998 -2.08916004 0 P 0 ;0
L 0.89393002 -2.08816004 0.94331998 -2.08816004 0 P 0 ;0
L 0.894 -2.08716004 0.94336004 -2.08716004 0 P 0 ;0
L 0.89406004 -2.08616004 0.94341004 -2.08616004 0 P 0 ;0
L 0.89411998 -2.08516004 0.94346004 -2.08516004 0 P 0 ;0
L 0.89418002 -2.08416004 0.94351004 -2.08416004 0 P 0 ;0
L 0.91651004 -2.12516004 0.90521998 -2.1251 0 P 0 ;0
L 0.90521998 -2.1251 0.89655 -2.12486998 0 P 0 ;0
L 0.89655 -2.12486998 0.89106004 -2.12465 0 P 0 ;0
L 0.89106004 -2.12465 0.89141998 -2.12003996 0 P 0 ;0
L 0.89141998 -2.12003996 0.89193996 -2.11373996 0 P 0 ;0
L 0.89193996 -2.11373996 0.89253996 -2.10645 0 P 0 ;0
L 0.89253996 -2.10645 0.89398002 -2.08741998 0 P 0 ;0
L 0.89398002 -2.08741998 0.89521998 -2.06621998 0 P 0 ;0
L 0.89521998 -2.06621998 0.89521998 -2.06618996 0 P 0 ;0
L 0.89521998 -2.06618996 0.89623996 -2.04323002 0 P 0 ;0
L 0.89623996 -2.04323002 0.89703996 -2.01883002 0 P 0 ;0
L 0.89703996 -2.01883002 0.8977 -1.99443996 0 P 0 ;0
L 0.8977 -1.99443996 0.94563996 -1.99443996 0 P 0 ;0
L 0.94563996 -1.99443996 0.94563996 -2.00546998 0 P 0 ;0
L 0.94563996 -2.00546998 0.94686004 -2.00731004 0 P 0 ;0
L 0.94686004 -2.00731004 0.94903002 -2.00688996 0 P 0 ;0
L 0.94903002 -2.00688996 0.95361998 -2.00241004 0 P 0 ;0
L 0.95361998 -2.00241004 0.95498996 -2.00115 0 P 0 ;0
L 0.95498996 -2.00115 0.95641998 -2.00001004 0 P 0 ;0
L 0.95641998 -2.00001004 0.9579 -1.99896004 0 P 0 ;0
L 0.9579 -1.99896004 0.96076004 -1.9972 0 P 0 ;0
L 0.96076004 -1.9972 0.9637 -1.99561998 0 P 0 ;0
L 0.9637 -1.99561998 0.96683002 -1.99416998 0 P 0 ;0
L 0.96683002 -1.99416998 0.96998996 -1.99291998 0 P 0 ;0
L 0.96998996 -1.99291998 0.9729 -1.99198996 0 P 0 ;0
L 0.9729 -1.99198996 0.97586004 -1.9913 0 P 0 ;0
L 0.97586004 -1.9913 0.97923002 -1.99076998 0 P 0 ;0
L 0.97923002 -1.99076998 0.98263002 -1.99046998 0 P 0 ;0
L 0.98263002 -1.99046998 0.99136004 -1.99026004 0 P 0 ;0
L 0.99136004 -1.99026004 1.00028996 -1.99066998 0 P 0 ;0
L 1.00028996 -1.99066998 1.00403002 -1.99108002 0 P 0 ;0
L 1.00403002 -1.99108002 1.00771004 -1.99166998 0 P 0 ;0
L 1.00771004 -1.99166998 1.01305 -1.99291998 0 P 0 ;0
L 1.01305 -1.99291998 1.01823002 -1.99461998 0 P 0 ;0
L 1.01823002 -1.99461998 1.02026004 -1.99546998 0 P 0 ;0
L 1.02026004 -1.99546998 1.02221004 -1.99646998 0 P 0 ;0
L 1.02221004 -1.99646998 1.02408002 -1.9976 0 P 0 ;0
L 1.02408002 -1.9976 1.02585 -1.99886998 0 P 0 ;0
L 1.02585 -1.99886998 1.02746004 -2.00021004 0 P 0 ;0
L 1.02746004 -2.00021004 1.02893996 -2.00166998 0 P 0 ;0
L 1.02893996 -2.00166998 1.03031004 -2.00325 0 P 0 ;0
L 1.03031004 -2.00325 1.03155 -2.00493002 0 P 0 ;0
L 1.03155 -2.00493002 1.03326998 -2.00768002 0 P 0 ;0
L 1.03326998 -2.00768002 1.03478002 -2.01055 0 P 0 ;0
L 1.03478002 -2.01055 1.03608002 -2.01351998 0 P 0 ;0
L 1.03608002 -2.01351998 1.03678996 -2.01546998 0 P 0 ;0
L 1.03678996 -2.01546998 1.03736004 -2.01743002 0 P 0 ;0
L 1.03736004 -2.01743002 1.03778002 -2.0193 0 P 0 ;0
L 1.03778002 -2.0193 1.03805 -2.02116998 0 P 0 ;0
L 1.03805 -2.02116998 1.03836998 -2.02658996 0 P 0 ;0
L 1.03836998 -2.02658996 1.03848002 -2.03698996 0 P 0 ;0
L 1.03848002 -2.03698996 1.03838996 -2.04623002 0 P 0 ;0
L 1.03838996 -2.04623002 1.03805 -2.06018996 0 P 0 ;0
L 1.03805 -2.06018996 1.03756004 -2.07583002 0 P 0 ;0
L 1.03756004 -2.07583002 1.03696998 -2.09095 0 P 0 ;0
L 1.03696998 -2.09095 1.03548996 -2.12516004 0 P 0 ;0
L 1.03548996 -2.12516004 0.98546998 -2.12516004 0 P 0 ;0
L 0.98546998 -2.12516004 0.98586998 -2.12166004 0 P 0 ;0
L 0.98586998 -2.12166004 0.98696998 -2.10871998 0 P 0 ;0
L 0.98696998 -2.10871998 0.98796004 -2.08916004 0 P 0 ;0
L 0.98796004 -2.08916004 0.9886 -2.06963002 0 P 0 ;0
L 0.9886 -2.06963002 0.98853002 -2.05698002 0 P 0 ;0
L 0.98853002 -2.05698002 0.98781998 -2.0461 0 P 0 ;0
L 0.98781998 -2.0461 0.9875 -2.04373002 0 P 0 ;0
L 0.9875 -2.04373002 0.98748002 -2.04365 0 P 0 ;0
L 0.98748002 -2.04365 0.98698996 -2.04138996 0 P 0 ;0
L 0.98698996 -2.04138996 0.9863 -2.03908002 0 P 0 ;0
L 0.9863 -2.03908002 0.98588002 -2.038 0 P 0 ;0
L 0.98588002 -2.038 0.98538002 -2.03696004 0 P 0 ;0
L 0.98538002 -2.03696004 0.9848 -2.03596004 0 P 0 ;0
L 0.9848 -2.03596004 0.98413996 -2.03501004 0 P 0 ;0
L 0.98413996 -2.03501004 0.98341998 -2.03411004 0 P 0 ;0
L 0.98341998 -2.03411004 0.98336998 -2.03405 0 P 0 ;0
L 0.98336998 -2.03405 0.98263002 -2.03326004 0 P 0 ;0
L 0.98263002 -2.03326004 0.98176998 -2.03246998 0 P 0 ;0
L 0.98176998 -2.03246998 0.98086998 -2.03175 0 P 0 ;0
L 0.98086998 -2.03175 0.97991004 -2.0311 0 P 0 ;0
L 0.97991004 -2.0311 0.9789 -2.03051998 0 P 0 ;0
L 0.9789 -2.03051998 0.97783002 -2.03001998 0 P 0 ;0
L 0.97783002 -2.03001998 0.97673002 -2.02961004 0 P 0 ;0
L 0.97673002 -2.02961004 0.97663996 -2.02958002 0 P 0 ;0
L 0.97663996 -2.02958002 0.97558996 -2.02928996 0 P 0 ;0
L 0.97558996 -2.02928996 0.97443002 -2.02906998 0 P 0 ;0
L 0.97443002 -2.02906998 0.9727 -2.02888002 0 P 0 ;0
L 0.9727 -2.02888002 0.97261998 -2.02886998 0 P 0 ;0
L 0.97261998 -2.02886998 0.97096004 -2.02881004 0 P 0 ;0
L 0.97096004 -2.02881004 0.96921004 -2.02886004 0 P 0 ;0
L 0.96921004 -2.02886004 0.96745 -2.02903996 0 P 0 ;0
L 0.96745 -2.02903996 0.96571004 -2.02933996 0 P 0 ;0
L 0.96571004 -2.02933996 0.964 -2.02976004 0 P 0 ;0
L 0.964 -2.02976004 0.96283002 -2.03013996 0 P 0 ;0
L 0.96283002 -2.03013996 0.96168002 -2.0306 0 P 0 ;0
L 0.96168002 -2.0306 0.96056998 -2.03115 0 P 0 ;0
L 0.96056998 -2.03115 0.95948996 -2.03178002 0 P 0 ;0
L 0.95948996 -2.03178002 0.95791004 -2.03286998 0 P 0 ;0
L 0.95791004 -2.03286998 0.95645 -2.03408996 0 P 0 ;0
L 0.95645 -2.03408996 0.95508996 -2.03541998 0 P 0 ;0
L 0.95508996 -2.03541998 0.95383996 -2.03686998 0 P 0 ;0
L 0.95383996 -2.03686998 0.9538 -2.03693002 0 P 0 ;0
L 0.9538 -2.03693002 0.95273002 -2.03841004 0 P 0 ;0
L 0.95273002 -2.03841004 0.95175 -2.04003996 0 P 0 ;0
L 0.95175 -2.04003996 0.95023002 -2.04306004 0 P 0 ;0
L 0.95023002 -2.04306004 0.94896004 -2.04611004 0 P 0 ;0
L 0.94896004 -2.04611004 0.94893002 -2.04616998 0 P 0 ;0
L 0.94893002 -2.04616998 0.94783002 -2.04936004 0 P 0 ;0
L 0.94783002 -2.04936004 0.94695 -2.05263002 0 P 0 ;0
L 0.94695 -2.05263002 0.94515 -2.06203002 0 P 0 ;0
L 0.94515 -2.06203002 0.9441 -2.07156004 0 P 0 ;0
L 0.9441 -2.07156004 0.9427 -2.10128002 0 P 0 ;0
L 0.9427 -2.10128002 0.94208996 -2.12516004 0 P 0 ;0
L 0.94208996 -2.12516004 0.91651004 -2.12516004 0 P 0 ;0
L 0.93143002 -2.21261998 1.00578996 -2.21261998 0 P 0 ;0
L 0.94051004 -2.21161998 1.00803002 -2.21161998 0 P 0 ;0
L 0.94941998 -2.21061998 1.01026004 -2.21061998 0 P 0 ;0
L 0.9555 -2.20961998 1.0125 -2.20961998 0 P 0 ;0
L 0.96158002 -2.20861998 1.01473996 -2.20861998 0 P 0 ;0
L 0.96766004 -2.20761998 1.01696998 -2.20761998 0 P 0 ;0
L 0.97373002 -2.20661998 1.01921004 -2.20661998 0 P 0 ;0
L 0.97981004 -2.20561998 1.02145 -2.20561998 0 P 0 ;0
L 0.98498996 -2.20461998 1.02368996 -2.20461998 0 P 0 ;0
L 0.98973996 -2.20361998 1.02591998 -2.20361998 0 P 0 ;0
L 0.99448996 -2.20261998 1.02816004 -2.20261998 0 P 0 ;0
L 0.99923996 -2.20161998 1.0304 -2.20161998 0 P 0 ;0
L 1.00398996 -2.20061998 1.03243996 -2.20061998 0 P 0 ;0
L 1.00875 -2.19961998 1.0344 -2.19961998 0 P 0 ;0
L 1.01348996 -2.19861998 1.03636998 -2.19861998 0 P 0 ;0
L 1.0178 -2.19761998 1.03833996 -2.19761998 0 P 0 ;0
L 1.02168996 -2.19661998 1.04031004 -2.19661998 0 P 0 ;0
L 1.02558002 -2.19561998 1.04228002 -2.19561998 0 P 0 ;0
L 1.02946998 -2.19461998 1.04415 -2.19461998 0 P 0 ;0
L 1.03336004 -2.19361998 1.04596998 -2.19361998 0 P 0 ;0
L 1.03725 -2.19261998 1.04778996 -2.19261998 0 P 0 ;0
L 1.04113996 -2.19161998 1.0496 -2.19161998 0 P 0 ;0
L 1.14356998 -1.98926998 1.13261004 -1.99086004 0 P 0 ;0
L 1.13261004 -1.99086004 1.12165 -1.9934 0 P 0 ;0
L 1.12165 -1.9934 1.11125 -1.99673002 0 P 0 ;0
L 1.11125 -1.99673002 1.10658002 -1.99858996 0 P 0 ;0
L 1.10658002 -1.99858996 1.10198996 -2.00071004 0 P 0 ;0
L 1.10198996 -2.00071004 1.09653002 -2.00358996 0 P 0 ;0
L 1.09653002 -2.00358996 1.09436998 -2.00488996 0 P 0 ;0
L 1.09436998 -2.00488996 1.09226004 -2.00631004 0 P 0 ;0
L 1.09226004 -2.00631004 1.09028002 -2.00781004 0 P 0 ;0
L 1.09028002 -2.00781004 1.08836998 -2.00941998 0 P 0 ;0
L 1.08836998 -2.00941998 1.08405 -2.0135 0 P 0 ;0
L 1.08405 -2.0135 1.08096998 -2.01678996 0 P 0 ;0
L 1.08096998 -2.01678996 1.07808002 -2.02026998 0 P 0 ;0
L 1.07808002 -2.02026998 1.0754 -2.02393002 0 P 0 ;0
L 1.0754 -2.02393002 1.07313996 -2.02748002 0 P 0 ;0
L 1.07313996 -2.02748002 1.07116004 -2.03118996 0 P 0 ;0
L 1.07116004 -2.03118996 1.06943996 -2.03505 0 P 0 ;0
L 1.06943996 -2.03505 1.06795 -2.03918996 0 P 0 ;0
L 1.06795 -2.03918996 1.06673996 -2.04343996 0 P 0 ;0
L 1.06673996 -2.04343996 1.06583002 -2.04778002 0 P 0 ;0
L 1.06583002 -2.04778002 1.06476998 -2.05538996 0 P 0 ;0
L 1.06476998 -2.05538996 1.06421004 -2.06306004 0 P 0 ;0
L 1.06421004 -2.06306004 1.06415 -2.07076004 0 P 0 ;0
L 1.06415 -2.07076004 1.06456998 -2.0785 0 P 0 ;0
L 1.06456998 -2.0785 1.06508996 -2.08276004 0 P 0 ;0
L 1.06508996 -2.08276004 1.06591004 -2.08696004 0 P 0 ;0
L 1.06591004 -2.08696004 1.06703002 -2.09108002 0 P 0 ;0
L 1.06703002 -2.09108002 1.06833002 -2.09473002 0 P 0 ;0
L 1.06833002 -2.09473002 1.06991998 -2.09823996 0 P 0 ;0
L 1.06991998 -2.09823996 1.0718 -2.10161998 0 P 0 ;0
L 1.0718 -2.10161998 1.07398002 -2.10491998 0 P 0 ;0
L 1.07398002 -2.10491998 1.07641998 -2.10803002 0 P 0 ;0
L 1.07641998 -2.10803002 1.07908996 -2.11095 0 P 0 ;0
L 1.07908996 -2.11095 1.08175 -2.11345 0 P 0 ;0
L 1.08175 -2.11345 1.08458996 -2.11573996 0 P 0 ;0
L 1.08458996 -2.11573996 1.08758996 -2.1178 0 P 0 ;0
L 1.08758996 -2.1178 1.09073002 -2.11963996 0 P 0 ;0
L 1.09073002 -2.11963996 1.094 -2.12123996 0 P 0 ;0
L 1.094 -2.12123996 1.0986 -2.12306998 0 P 0 ;0
L 1.0986 -2.12306998 1.10331004 -2.12456004 0 P 0 ;0
L 1.10331004 -2.12456004 1.10811004 -2.12568996 0 P 0 ;0
L 1.10811004 -2.12568996 1.11298002 -2.12646998 0 P 0 ;0
L 1.11298002 -2.12646998 1.1182 -2.12693002 0 P 0 ;0
L 1.1182 -2.12693002 1.12343996 -2.12703002 0 P 0 ;0
L 1.12343996 -2.12703002 1.12866998 -2.12676004 0 P 0 ;0
L 1.12866998 -2.12676004 1.13388002 -2.12613002 0 P 0 ;0
L 1.13388002 -2.12613002 1.14086004 -2.12473996 0 P 0 ;0
L 1.14086004 -2.12473996 1.1477 -2.12273996 0 P 0 ;0
L 1.1477 -2.12273996 1.15433996 -2.12015 0 P 0 ;0
L 1.15433996 -2.12015 1.1545 -2.12008996 0 P 0 ;0
L 1.1545 -2.12008996 1.15466004 -2.12003996 0 P 0 ;0
L 1.15466004 -2.12003996 1.15483002 -2.12001004 0 P 0 ;0
L 1.15483002 -2.12001004 1.15498996 -2.11998996 0 P 0 ;0
L 1.15498996 -2.11998996 1.15533002 -2.11998996 0 P 0 ;0
L 1.15533002 -2.11998996 1.15538996 -2.12 0 P 0 ;0
L 1.15538996 -2.12 1.15545 -2.12001998 0 P 0 ;0
L 1.15545 -2.12001998 1.15551004 -2.12003002 0 P 0 ;0
L 1.15551004 -2.12003002 1.15556004 -2.12006004 0 P 0 ;0
L 1.15556004 -2.12006004 1.15561004 -2.12008002 0 P 0 ;0
L 1.15561004 -2.12008002 1.15566004 -2.12011004 0 P 0 ;0
L 1.15566004 -2.12011004 1.15571004 -2.12015 0 P 0 ;0
L 1.15571004 -2.12015 1.15575 -2.12018996 0 P 0 ;0
L 1.15575 -2.12018996 1.15578996 -2.12023996 0 P 0 ;0
L 1.15578996 -2.12023996 1.15583002 -2.12028002 0 P 0 ;0
L 1.15583002 -2.12028002 1.15586004 -2.12033996 0 P 0 ;0
L 1.15586004 -2.12033996 1.15588002 -2.12038996 0 P 0 ;0
L 1.15588002 -2.12038996 1.15591004 -2.12043996 0 P 0 ;0
L 1.15591004 -2.12043996 1.15601998 -2.12076004 0 P 0 ;0
L 1.15601998 -2.12076004 1.1561 -2.12108002 0 P 0 ;0
L 1.1561 -2.12108002 1.15616004 -2.12141998 0 P 0 ;0
L 1.15616004 -2.12141998 1.15618002 -2.12175 0 P 0 ;0
L 1.15618002 -2.12175 1.15623996 -2.12505 0 P 0 ;0
L 1.15623996 -2.12505 1.15616004 -2.12688002 0 P 0 ;0
L 1.15616004 -2.12688002 1.15593002 -2.12871004 0 P 0 ;0
L 1.15593002 -2.12871004 1.15553996 -2.13051998 0 P 0 ;0
L 1.15553996 -2.13051998 1.15516004 -2.1318 0 P 0 ;0
L 1.15516004 -2.1318 1.1547 -2.13305 0 P 0 ;0
L 1.1547 -2.13305 1.15415 -2.13426004 0 P 0 ;0
L 1.15415 -2.13426004 1.15351004 -2.13545 0 P 0 ;0
L 1.15351004 -2.13545 1.15278996 -2.1366 0 P 0 ;0
L 1.15278996 -2.1366 1.15198002 -2.13768996 0 P 0 ;0
L 1.15198002 -2.13768996 1.15111004 -2.13873002 0 P 0 ;0
L 1.15111004 -2.13873002 1.15016004 -2.13971004 0 P 0 ;0
L 1.15016004 -2.13971004 1.14876004 -2.14096004 0 P 0 ;0
L 1.14876004 -2.14096004 1.14726004 -2.1421 0 P 0 ;0
L 1.14726004 -2.1421 1.14566998 -2.14311004 0 P 0 ;0
L 1.14566998 -2.14311004 1.144 -2.144 0 P 0 ;0
L 1.144 -2.144 1.14226004 -2.14476004 0 P 0 ;0
L 1.14226004 -2.14476004 1.14046004 -2.14536998 0 P 0 ;0
L 1.14046004 -2.14536998 1.13863002 -2.14583002 0 P 0 ;0
L 1.13863002 -2.14583002 1.13676004 -2.14613996 0 P 0 ;0
L 1.13676004 -2.14613996 1.13041998 -2.14663996 0 P 0 ;0
L 1.13041998 -2.14663996 1.12403996 -2.1466 0 P 0 ;0
L 1.12403996 -2.1466 1.11621998 -2.14593996 0 P 0 ;0
L 1.11621998 -2.14593996 1.10843996 -2.14471004 0 P 0 ;0
L 1.10843996 -2.14471004 1.09946998 -2.14276998 0 P 0 ;0
L 1.09946998 -2.14276998 1.0905 -2.14041004 0 P 0 ;0
L 1.0905 -2.14041004 1.07963996 -2.13728996 0 P 0 ;0
L 1.07963996 -2.13728996 1.07936004 -2.1401 0 P 0 ;0
L 1.07936004 -2.1401 1.07931004 -2.14103996 0 P 0 ;0
L 1.07931004 -2.14103996 1.07931998 -2.14198002 0 P 0 ;0
L 1.07931998 -2.14198002 1.07956998 -2.14735 0 P 0 ;0
L 1.07956998 -2.14735 1.07993996 -2.15375 0 P 0 ;0
L 1.07993996 -2.15375 1.08045 -2.16081998 0 P 0 ;0
L 1.08045 -2.16081998 1.08181004 -2.17873002 0 P 0 ;0
L 1.08181004 -2.17873002 1.08996004 -2.18061004 0 P 0 ;0
L 1.08996004 -2.18061004 1.09951004 -2.18246004 0 P 0 ;0
L 1.09951004 -2.18246004 1.11243996 -2.18416998 0 P 0 ;0
L 1.11243996 -2.18416998 1.1254 -2.18543002 0 P 0 ;0
L 1.1254 -2.18543002 1.13508002 -2.18583002 0 P 0 ;0
L 1.13508002 -2.18583002 1.14765 -2.18528996 0 P 0 ;0
L 1.14765 -2.18528996 1.15368002 -2.18461004 0 P 0 ;0
L 1.15368002 -2.18461004 1.15971004 -2.18363996 0 P 0 ;0
L 1.15971004 -2.18363996 1.16521004 -2.18248002 0 P 0 ;0
L 1.16521004 -2.18248002 1.17063996 -2.18103002 0 P 0 ;0
L 1.17063996 -2.18103002 1.17528996 -2.17946998 0 P 0 ;0
L 1.17528996 -2.17946998 1.17978002 -2.17753996 0 P 0 ;0
L 1.17978002 -2.17753996 1.18216998 -2.1763 0 P 0 ;0
L 1.18216998 -2.1763 1.18446004 -2.17488996 0 P 0 ;0
L 1.18446004 -2.17488996 1.18663996 -2.17331004 0 P 0 ;0
L 1.18663996 -2.17331004 1.18871004 -2.17156004 0 P 0 ;0
L 1.18871004 -2.17156004 1.19161004 -2.16871998 0 P 0 ;0
L 1.19161004 -2.16871998 1.19431004 -2.16568996 0 P 0 ;0
L 1.19431004 -2.16568996 1.19678996 -2.16246998 0 P 0 ;0
L 1.19678996 -2.16246998 1.19908996 -2.15901998 0 P 0 ;0
L 1.19908996 -2.15901998 1.20113996 -2.15543996 0 P 0 ;0
L 1.20113996 -2.15543996 1.20295 -2.15171004 0 P 0 ;0
L 1.20295 -2.15171004 1.20435 -2.14815 0 P 0 ;0
L 1.20435 -2.14815 1.20543996 -2.14448996 0 P 0 ;0
L 1.20543996 -2.14448996 1.20621004 -2.14073996 0 P 0 ;0
L 1.20621004 -2.14073996 1.20651998 -2.13855 0 P 0 ;0
L 1.20651998 -2.13855 1.20671998 -2.13633996 0 P 0 ;0
L 1.20671998 -2.13633996 1.20761998 -2.12321004 0 P 0 ;0
L 1.20761998 -2.12321004 1.20858002 -2.10753996 0 P 0 ;0
L 1.20858002 -2.10753996 1.20951004 -2.09021998 0 P 0 ;0
L 1.20951004 -2.09021998 1.21048002 -2.07166004 0 P 0 ;0
L 1.21048002 -2.07166004 1.21156004 -2.05228002 0 P 0 ;0
L 1.21156004 -2.05228002 1.21258002 -2.03478996 0 P 0 ;0
L 1.21258002 -2.03478996 1.21333002 -2.02286004 0 P 0 ;0
L 1.21333002 -2.02286004 1.21393996 -2.01373996 0 P 0 ;0
L 1.21393996 -2.01373996 1.21443996 -2.00568996 0 P 0 ;0
L 1.21443996 -2.00568996 1.21485 -1.99883996 0 P 0 ;0
L 1.21485 -1.99883996 1.2149 -1.99721004 0 P 0 ;0
L 1.2149 -1.99721004 1.21488996 -1.99703996 0 P 0 ;0
L 1.21488996 -1.99703996 1.21486998 -1.99686004 0 P 0 ;0
L 1.21486998 -1.99686004 1.21483996 -1.99668996 0 P 0 ;0
L 1.21483996 -1.99668996 1.21478996 -1.99653002 0 P 0 ;0
L 1.21478996 -1.99653002 1.21473002 -1.99636998 0 P 0 ;0
L 1.21473002 -1.99636998 1.21466004 -1.99621004 0 P 0 ;0
L 1.21466004 -1.99621004 1.21458002 -1.99606004 0 P 0 ;0
L 1.21458002 -1.99606004 1.21448002 -1.99591004 0 P 0 ;0
L 1.21448002 -1.99591004 1.21433002 -1.99571998 0 P 0 ;0
L 1.21433002 -1.99571998 1.21416998 -1.99553996 0 P 0 ;0
L 1.21416998 -1.99553996 1.21398996 -1.99538002 0 P 0 ;0
L 1.21398996 -1.99538002 1.21378996 -1.99523996 0 P 0 ;0
L 1.21378996 -1.99523996 1.21358002 -1.99511004 0 P 0 ;0
L 1.21358002 -1.99511004 1.21336004 -1.995 0 P 0 ;0
L 1.21336004 -1.995 1.21261004 -1.99468996 0 P 0 ;0
L 1.21261004 -1.99468996 1.21183996 -1.99443996 0 P 0 ;0
L 1.21183996 -1.99443996 1.21105 -1.99423002 0 P 0 ;0
L 1.21105 -1.99423002 1.20593996 -1.99318002 0 P 0 ;0
L 1.20593996 -1.99318002 1.18996998 -1.99065 0 P 0 ;0
L 1.18996998 -1.99065 1.17318996 -1.98908002 0 P 0 ;0
L 1.17318996 -1.98908002 1.15718996 -1.98858002 0 P 0 ;0
L 1.15718996 -1.98858002 1.1504 -1.98876004 0 P 0 ;0
L 1.1504 -1.98876004 1.14356998 -1.98926998 0 P 0 ;0
L 1.04503996 -2.19061998 1.05141998 -2.19061998 0 P 0 ;0
L 1.04893002 -2.18961998 1.05323002 -2.18961998 0 P 0 ;0
L 1.05263002 -2.18861998 1.05503996 -2.18861998 0 P 0 ;0
L 1.05628996 -2.18761998 1.05676004 -2.18761998 0 P 0 ;0
L 1.09645 -2.17983002 1.16738002 -2.17983002 0 P 0 ;0
L 1.09126004 -2.17883002 1.17091004 -2.17883002 0 P 0 ;0
L 1.0868 -2.17783002 1.17386998 -2.17783002 0 P 0 ;0
L 1.08368002 -2.17683002 1.17636004 -2.17683002 0 P 0 ;0
L 1.0836 -2.17583002 1.1787 -2.17583002 0 P 0 ;0
L 1.08351998 -2.17483002 1.18066998 -2.17483002 0 P 0 ;0
L 1.08345 -2.17383002 1.18236998 -2.17383002 0 P 0 ;0
L 1.08336998 -2.17283002 1.1839 -2.17283002 0 P 0 ;0
L 1.08328996 -2.17183002 1.18526998 -2.17183002 0 P 0 ;0
L 1.08321998 -2.17083002 1.18646998 -2.17083002 0 P 0 ;0
L 1.08313996 -2.16983002 1.18761998 -2.16983002 0 P 0 ;0
L 1.08306998 -2.16883002 1.18863996 -2.16883002 0 P 0 ;0
L 1.08298996 -2.16783002 1.18966004 -2.16783002 0 P 0 ;0
L 1.08291998 -2.16683002 1.19061004 -2.16683002 0 P 0 ;0
L 1.08283996 -2.16583002 1.1915 -2.16583002 0 P 0 ;0
L 1.08276004 -2.16483002 1.19238996 -2.16483002 0 P 0 ;0
L 1.08268996 -2.16383002 1.19321004 -2.16383002 0 P 0 ;0
L 1.08261004 -2.16283002 1.19398002 -2.16283002 0 P 0 ;0
L 1.08253002 -2.16183002 1.19476004 -2.16183002 0 P 0 ;0
L 1.08246004 -2.16083002 1.19548002 -2.16083002 0 P 0 ;0
L 1.08238002 -2.15983002 1.19613996 -2.15983002 0 P 0 ;0
L 1.08231004 -2.15883002 1.19681004 -2.15883002 0 P 0 ;0
L 1.08223996 -2.15783002 1.19746004 -2.15783002 0 P 0 ;0
L 1.13506998 -2.18383002 1.12553002 -2.18343996 0 P 0 ;0
L 1.12553002 -2.18343996 1.11266004 -2.18218002 0 P 0 ;0
L 1.11266004 -2.18218002 1.09983002 -2.18048002 0 P 0 ;0
L 1.09983002 -2.18048002 1.09036998 -2.17866004 0 P 0 ;0
L 1.09036998 -2.17866004 1.0837 -2.17711004 0 P 0 ;0
L 1.0837 -2.17711004 1.08245 -2.16066998 0 P 0 ;0
L 1.08245 -2.16066998 1.08193996 -2.15361998 0 P 0 ;0
L 1.08193996 -2.15361998 1.08156998 -2.14726004 0 P 0 ;0
L 1.08156998 -2.14726004 1.08131998 -2.14191004 0 P 0 ;0
L 1.08131998 -2.14191004 1.08131004 -2.14108996 0 P 0 ;0
L 1.08131004 -2.14108996 1.08136004 -2.14026004 0 P 0 ;0
L 1.08136004 -2.14026004 1.0814 -2.13986998 0 P 0 ;0
L 1.0814 -2.13986998 1.08996004 -2.14233002 0 P 0 ;0
L 1.08996004 -2.14233002 1.08996998 -2.14233996 0 P 0 ;0
L 1.08996998 -2.14233996 1.08998996 -2.14233996 0 P 0 ;0
L 1.08998996 -2.14233996 1.099 -2.14471998 0 P 0 ;0
L 1.099 -2.14471998 1.10806998 -2.14668002 0 P 0 ;0
L 1.10806998 -2.14668002 1.11598002 -2.14791998 0 P 0 ;0
L 1.11598002 -2.14791998 1.12395 -2.1486 0 P 0 ;0
L 1.12395 -2.1486 1.13048996 -2.14863996 0 P 0 ;0
L 1.13048996 -2.14863996 1.137 -2.14811998 0 P 0 ;0
L 1.137 -2.14811998 1.13903002 -2.14778996 0 P 0 ;0
L 1.13903002 -2.14778996 1.14103002 -2.14728996 0 P 0 ;0
L 1.14103002 -2.14728996 1.14298002 -2.14661998 0 P 0 ;0
L 1.14298002 -2.14661998 1.14486998 -2.14581004 0 P 0 ;0
L 1.14486998 -2.14581004 1.14668002 -2.14483996 0 P 0 ;0
L 1.14668002 -2.14483996 1.1484 -2.14373996 0 P 0 ;0
L 1.1484 -2.14373996 1.15003002 -2.1425 0 P 0 ;0
L 1.15003002 -2.1425 1.15155 -2.14115 0 P 0 ;0
L 1.15155 -2.14115 1.1526 -2.14006998 0 P 0 ;0
L 1.1526 -2.14006998 1.15263996 -2.14001998 0 P 0 ;0
L 1.15263996 -2.14001998 1.15356004 -2.13893002 0 P 0 ;0
L 1.15356004 -2.13893002 1.15443996 -2.13771998 0 P 0 ;0
L 1.15443996 -2.13771998 1.15523002 -2.13646004 0 P 0 ;0
L 1.15523002 -2.13646004 1.15593996 -2.13515 0 P 0 ;0
L 1.15593996 -2.13515 1.15655 -2.13381004 0 P 0 ;0
L 1.15655 -2.13381004 1.15706004 -2.13243002 0 P 0 ;0
L 1.15706004 -2.13243002 1.15748002 -2.13101004 0 P 0 ;0
L 1.15748002 -2.13101004 1.1579 -2.12905 0 P 0 ;0
L 1.1579 -2.12905 1.15816004 -2.12706004 0 P 0 ;0
L 1.15816004 -2.12706004 1.15825 -2.12506998 0 P 0 ;0
L 1.15825 -2.12506998 1.15818002 -2.12165 0 P 0 ;0
L 1.15818002 -2.12165 1.15813996 -2.12118002 0 P 0 ;0
L 1.15813996 -2.12118002 1.15813002 -2.1211 0 P 0 ;0
L 1.15813002 -2.1211 1.15806004 -2.12068002 0 P 0 ;0
L 1.15806004 -2.12068002 1.15793996 -2.12018996 0 P 0 ;0
L 1.15793996 -2.12018996 1.15778002 -2.11973002 0 P 0 ;0
L 1.15778002 -2.11973002 1.1577 -2.11953002 0 P 0 ;0
L 1.1577 -2.11953002 1.15758996 -2.11933002 0 P 0 ;0
L 1.15758996 -2.11933002 1.15746998 -2.11913996 0 P 0 ;0
L 1.15746998 -2.11913996 1.15733002 -2.11895 0 P 0 ;0
L 1.15733002 -2.11895 1.15716998 -2.11878002 0 P 0 ;0
L 1.15716998 -2.11878002 1.157 -2.11863002 0 P 0 ;0
L 1.157 -2.11863002 1.15681998 -2.11848996 0 P 0 ;0
L 1.15681998 -2.11848996 1.15663002 -2.11836004 0 P 0 ;0
L 1.15663002 -2.11836004 1.15641998 -2.11825 0 P 0 ;0
L 1.15641998 -2.11825 1.15621004 -2.11816004 0 P 0 ;0
L 1.15621004 -2.11816004 1.15598996 -2.11808996 0 P 0 ;0
L 1.15598996 -2.11808996 1.15576998 -2.11803996 0 P 0 ;0
L 1.15576998 -2.11803996 1.15553002 -2.118 0 P 0 ;0
L 1.15553002 -2.118 1.15518002 -2.11798002 0 P 0 ;0
L 1.15518002 -2.11798002 1.15483996 -2.11798996 0 P 0 ;0
L 1.15483996 -2.11798996 1.15451004 -2.11803002 0 P 0 ;0
L 1.15451004 -2.11803002 1.15418002 -2.1181 0 P 0 ;0
L 1.15418002 -2.1181 1.15386004 -2.1182 0 P 0 ;0
L 1.15386004 -2.1182 1.15361004 -2.11828996 0 P 0 ;0
L 1.15361004 -2.11828996 1.14705 -2.12083996 0 P 0 ;0
L 1.14705 -2.12083996 1.14038996 -2.12278996 0 P 0 ;0
L 1.14038996 -2.12278996 1.13356004 -2.12416004 0 P 0 ;0
L 1.13356004 -2.12416004 1.1285 -2.12476998 0 P 0 ;0
L 1.1285 -2.12476998 1.12341004 -2.12501998 0 P 0 ;0
L 1.12341004 -2.12501998 1.11831004 -2.12493002 0 P 0 ;0
L 1.11831004 -2.12493002 1.11323002 -2.12448996 0 P 0 ;0
L 1.11323002 -2.12448996 1.10848996 -2.12373002 0 P 0 ;0
L 1.10848996 -2.12373002 1.10383996 -2.12263002 0 P 0 ;0
L 1.10383996 -2.12263002 1.09926998 -2.12118996 0 P 0 ;0
L 1.09926998 -2.12118996 1.09481004 -2.11941004 0 P 0 ;0
L 1.09481004 -2.11941004 1.09168002 -2.11788002 0 P 0 ;0
L 1.09168002 -2.11788002 1.08866004 -2.11611998 0 P 0 ;0
L 1.08866004 -2.11611998 1.08578002 -2.11413002 0 P 0 ;0
L 1.08578002 -2.11413002 1.08306998 -2.11193996 0 P 0 ;0
L 1.08306998 -2.11193996 1.08051998 -2.10955 0 P 0 ;0
L 1.08051998 -2.10955 1.07793996 -2.10673002 0 P 0 ;0
L 1.07793996 -2.10673002 1.07561004 -2.10373996 0 P 0 ;0
L 1.07561004 -2.10373996 1.07351004 -2.10058002 0 P 0 ;0
L 1.07351004 -2.10058002 1.07171004 -2.09733996 0 P 0 ;0
L 1.07171004 -2.09733996 1.07018002 -2.09396998 0 P 0 ;0
L 1.07018002 -2.09396998 1.06893996 -2.09048002 0 P 0 ;0
L 1.06893996 -2.09048002 1.06786004 -2.0865 0 P 0 ;0
L 1.06786004 -2.0865 1.06706004 -2.08243996 0 P 0 ;0
L 1.06706004 -2.08243996 1.06656004 -2.07833002 0 P 0 ;0
L 1.06656004 -2.07833002 1.06615 -2.07071004 0 P 0 ;0
L 1.06615 -2.07071004 1.06621004 -2.06313996 0 P 0 ;0
L 1.06621004 -2.06313996 1.06675 -2.0556 0 P 0 ;0
L 1.06675 -2.0556 1.0678 -2.04813002 0 P 0 ;0
L 1.0678 -2.04813002 1.06868996 -2.04391998 0 P 0 ;0
L 1.06868996 -2.04391998 1.06985 -2.03981004 0 P 0 ;0
L 1.06985 -2.03981004 1.0713 -2.03578996 0 P 0 ;0
L 1.0713 -2.03578996 1.07296004 -2.03206998 0 P 0 ;0
L 1.07296004 -2.03206998 1.07486998 -2.02848996 0 P 0 ;0
L 1.07486998 -2.02848996 1.07705 -2.02506004 0 P 0 ;0
L 1.07705 -2.02506004 1.07966004 -2.0215 0 P 0 ;0
L 1.07966004 -2.0215 1.08246998 -2.01811004 0 P 0 ;0
L 1.08246998 -2.01811004 1.08546998 -2.01491004 0 P 0 ;0
L 1.08546998 -2.01491004 1.0897 -2.01091004 0 P 0 ;0
L 1.0897 -2.01091004 1.09153002 -2.00936998 0 P 0 ;0
L 1.09153002 -2.00936998 1.09341998 -2.00793996 0 P 0 ;0
L 1.09341998 -2.00793996 1.09545 -2.00658002 0 P 0 ;0
L 1.09545 -2.00658002 1.09751004 -2.00533996 0 P 0 ;0
L 1.09751004 -2.00533996 1.10288002 -2.0025 0 P 0 ;0
L 1.10288002 -2.0025 1.10736998 -2.00043002 0 P 0 ;0
L 1.10736998 -2.00043002 1.11193002 -1.99861004 0 P 0 ;0
L 1.11193002 -1.99861004 1.12218002 -1.99533002 0 P 0 ;0
L 1.12218002 -1.99533002 1.13298002 -1.99281998 0 P 0 ;0
L 1.13298002 -1.99281998 1.14378996 -1.99126004 0 P 0 ;0
L 1.14378996 -1.99126004 1.1505 -1.99075 0 P 0 ;0
L 1.1505 -1.99075 1.15718002 -1.99058996 0 P 0 ;0
L 1.15718002 -1.99058996 1.17306998 -1.99108002 0 P 0 ;0
L 1.17306998 -1.99108002 1.18971998 -1.99263002 0 P 0 ;0
L 1.18971998 -1.99263002 1.20558002 -1.99515 0 P 0 ;0
L 1.20558002 -1.99515 1.21058996 -1.99618002 0 P 0 ;0
L 1.21058996 -1.99618002 1.21126998 -1.99636004 0 P 0 ;0
L 1.21126998 -1.99636004 1.21191998 -1.99656998 0 P 0 ;0
L 1.21191998 -1.99656998 1.21253002 -1.99681998 0 P 0 ;0
L 1.21253002 -1.99681998 1.21261004 -1.99686004 0 P 0 ;0
L 1.21261004 -1.99686004 1.21266004 -1.99688996 0 P 0 ;0
L 1.21266004 -1.99688996 1.21271998 -1.99693002 0 P 0 ;0
L 1.21271998 -1.99693002 1.21281998 -1.99703002 0 P 0 ;0
L 1.21281998 -1.99703002 1.21286004 -1.99708996 0 P 0 ;0
L 1.21286004 -1.99708996 1.21288002 -1.99711004 0 P 0 ;0
L 1.21288002 -1.99711004 1.21288002 -1.99711998 0 P 0 ;0
L 1.21288002 -1.99711998 1.21288996 -1.99715 0 P 0 ;0
L 1.21288996 -1.99715 1.2129 -1.99716998 0 P 0 ;0
L 1.2129 -1.99716998 1.2129 -1.99721998 0 P 0 ;0
L 1.2129 -1.99721998 1.21285 -1.99875 0 P 0 ;0
L 1.21285 -1.99875 1.21243996 -2.00556998 0 P 0 ;0
L 1.21243996 -2.00556998 1.21193996 -2.01361004 0 P 0 ;0
L 1.21193996 -2.01361004 1.21133996 -2.02273002 0 P 0 ;0
L 1.21133996 -2.02273002 1.21133996 -2.02273996 0 P 0 ;0
L 1.21133996 -2.02273996 1.21058996 -2.03468002 0 P 0 ;0
L 1.21058996 -2.03468002 1.20956004 -2.05216998 0 P 0 ;0
L 1.20956004 -2.05216998 1.20848996 -2.07156004 0 P 0 ;0
L 1.20848996 -2.07156004 1.20848996 -2.07156998 0 P 0 ;0
L 1.20848996 -2.07156998 1.20751004 -2.09011004 0 P 0 ;0
L 1.20751004 -2.09011004 1.20658996 -2.10743996 0 P 0 ;0
L 1.20658996 -2.10743996 1.20561998 -2.12308996 0 P 0 ;0
L 1.20561998 -2.12308996 1.20473002 -2.13618996 0 P 0 ;0
L 1.20473002 -2.13618996 1.20453002 -2.13831998 0 P 0 ;0
L 1.20453002 -2.13831998 1.20423996 -2.14041004 0 P 0 ;0
L 1.20423996 -2.14041004 1.2035 -2.144 0 P 0 ;0
L 1.2035 -2.144 1.20246004 -2.1475 0 P 0 ;0
L 1.20246004 -2.1475 1.20111998 -2.1509 0 P 0 ;0
L 1.20111998 -2.1509 1.19936998 -2.1545 0 P 0 ;0
L 1.19936998 -2.1545 1.19738002 -2.15796998 0 P 0 ;0
L 1.19738002 -2.15796998 1.19516004 -2.1613 0 P 0 ;0
L 1.19516004 -2.1613 1.19276998 -2.16441004 0 P 0 ;0
L 1.19276998 -2.16441004 1.19016004 -2.16733996 0 P 0 ;0
L 1.19016004 -2.16733996 1.18736004 -2.17008002 0 P 0 ;0
L 1.18736004 -2.17008002 1.1854 -2.17173996 0 P 0 ;0
L 1.1854 -2.17173996 1.18335 -2.17323002 0 P 0 ;0
L 1.18335 -2.17323002 1.18118002 -2.17456004 0 P 0 ;0
L 1.18118002 -2.17456004 1.17893002 -2.17573002 0 P 0 ;0
L 1.17893002 -2.17573002 1.17456998 -2.1776 0 P 0 ;0
L 1.17456998 -2.1776 1.17006998 -2.17911998 0 P 0 ;0
L 1.17006998 -2.17911998 1.16473996 -2.18053002 0 P 0 ;0
L 1.16473996 -2.18053002 1.15935 -2.18166998 0 P 0 ;0
L 1.15935 -2.18166998 1.15341998 -2.18263002 0 P 0 ;0
L 1.15341998 -2.18263002 1.1475 -2.18328996 0 P 0 ;0
L 1.1475 -2.18328996 1.13506998 -2.18383002 0 P 0 ;0
L 0.90491998 -2.21461998 1.00131004 -2.21461998 0 P 0 ;0
L 0.92235 -2.21361998 1.00355 -2.21361998 0 P 0 ;0
L 0.76925 -1.8965 0.85586998 -1.8965 0 P 0 ;0
L 0.76958996 -1.8955 0.85556004 -1.8955 0 P 0 ;0
L 0.76995 -1.8945 0.85521004 -1.8945 0 P 0 ;0
L 0.77031004 -1.8935 0.85486004 -1.8935 0 P 0 ;0
L 0.77071004 -1.8925 0.85443996 -1.8925 0 P 0 ;0
L 0.77115 -1.8915 0.85401004 -1.8915 0 P 0 ;0
L 0.7716 -1.8905 0.85355 -1.8905 0 P 0 ;0
L 0.77206004 -1.8895 0.85303002 -1.8895 0 P 0 ;0
L 0.7726 -1.8885 0.85251004 -1.8885 0 P 0 ;0
L 0.77313996 -1.8875 0.85198996 -1.8875 0 P 0 ;0
L 0.77368996 -1.8865 0.85138002 -1.8865 0 P 0 ;0
L 0.77433002 -1.8855 0.85073996 -1.8855 0 P 0 ;0
L 0.77496004 -1.8845 0.85011004 -1.8845 0 P 0 ;0
L 0.77561998 -1.8835 0.84943002 -1.8835 0 P 0 ;0
L 0.77636004 -1.8825 0.84866998 -1.8825 0 P 0 ;0
L 0.77711004 -1.8815 0.84791004 -1.8815 0 P 0 ;0
L 0.7779 -1.8805 0.84713002 -1.8805 0 P 0 ;0
L 0.77876998 -1.8795 0.84623002 -1.8795 0 P 0 ;0
L 0.77963996 -1.8785 0.84533002 -1.8785 0 P 0 ;0
L 0.7806 -1.8775 0.8444 -1.8775 0 P 0 ;0
L 0.78161004 -1.8765 0.84335 -1.8765 0 P 0 ;0
L 0.78265 -1.8755 0.84228996 -1.8755 0 P 0 ;0
L 0.78381998 -1.8745 0.84108996 -1.8745 0 P 0 ;0
L 0.78498996 -1.8735 0.83986998 -1.8735 0 P 0 ;0
L 0.78635 -1.8725 0.83848002 -1.8725 0 P 0 ;0
L 0.78773002 -1.8715 0.83706004 -1.8715 0 P 0 ;0
L 0.78933002 -1.8705 0.83541998 -1.8705 0 P 0 ;0
L 0.791 -1.8695 0.83366004 -1.8695 0 P 0 ;0
L 0.793 -1.8685 0.83171998 -1.8685 0 P 0 ;0
L 0.79525 -1.8675 0.82941998 -1.8675 0 P 0 ;0
L 0.79791998 -1.8665 0.82671004 -1.8665 0 P 0 ;0
L 0.80143996 -1.8655 0.82328996 -1.8655 0 P 0 ;0
L 0.80705 -1.8645 0.81776004 -1.8645 0 P 0 ;0
L 0.74543002 -1.89661998 0.75033002 -1.89661998 0 P 0 ;0
L 0.74751004 -1.89561998 0.75058996 -1.89561998 0 P 0 ;0
L 0.74958996 -1.89461998 0.75086004 -1.89461998 0 P 0 ;0
L 0.76733996 -1.9125 0.85751998 -1.9125 0 P 0 ;0
L 0.76728996 -1.9115 0.85756004 -1.9115 0 P 0 ;0
L 0.76723996 -1.9105 0.85758996 -1.9105 0 P 0 ;0
L 0.76721998 -1.9095 0.85763002 -1.9095 0 P 0 ;0
L 0.76725 -1.9085 0.85761004 -1.9085 0 P 0 ;0
L 0.76728002 -1.9075 0.85756998 -1.9075 0 P 0 ;0
L 0.76731004 -1.9065 0.85753002 -1.9065 0 P 0 ;0
L 0.76741998 -1.9055 0.85748996 -1.9055 0 P 0 ;0
L 0.76753996 -1.9045 0.85738002 -1.9045 0 P 0 ;0
L 0.76766004 -1.9035 0.85726004 -1.9035 0 P 0 ;0
L 0.76781998 -1.9025 0.85713996 -1.9025 0 P 0 ;0
L 0.76801998 -1.9015 0.85701004 -1.9015 0 P 0 ;0
L 0.76821004 -1.9005 0.85683002 -1.9005 0 P 0 ;0
L 0.76841998 -1.8995 0.85661998 -1.8995 0 P 0 ;0
L 0.7687 -1.8985 0.85641004 -1.8985 0 P 0 ;0
L 0.76896998 -1.8975 0.85613996 -1.8975 0 P 0 ;0
L 0.76751004 -2.08325 0.8416 -2.08325 0 P 0 ;0
L 0.76761998 -2.08225 0.84161998 -2.08225 0 P 0 ;0
L 0.76773996 -2.08125 0.84166998 -2.08125 0 P 0 ;0
L 0.76786004 -2.08025 0.84171998 -2.08025 0 P 0 ;0
L 0.76796998 -2.07925 0.84176998 -2.07925 0 P 0 ;0
L 0.76808002 -2.07825 0.84181004 -2.07825 0 P 0 ;0
L 0.76818002 -2.07725 0.84186004 -2.07725 0 P 0 ;0
L 0.76828996 -2.07625 0.8419 -2.07625 0 P 0 ;0
L 0.76838996 -2.07525 0.84195 -2.07525 0 P 0 ;0
L 0.76848996 -2.07425 0.842 -2.07425 0 P 0 ;0
L 0.7686 -2.07325 0.84205 -2.07325 0 P 0 ;0
L 0.7687 -2.07225 0.84208996 -2.07225 0 P 0 ;0
L 0.7688 -2.07125 0.84213996 -2.07125 0 P 0 ;0
L 0.7689 -2.07025 0.84218002 -2.07025 0 P 0 ;0
L 0.76901004 -2.06925 0.84223002 -2.06925 0 P 0 ;0
L 0.76911004 -2.06825 0.84228002 -2.06825 0 P 0 ;0
L 0.76921004 -2.06725 0.84233002 -2.06725 0 P 0 ;0
L 0.76931998 -2.06625 0.84236998 -2.06625 0 P 0 ;0
L 0.76941998 -2.06525 0.84241998 -2.06525 0 P 0 ;0
L 0.76948996 -2.06425 0.84246004 -2.06425 0 P 0 ;0
L 0.76956004 -2.06325 0.84251004 -2.06325 0 P 0 ;0
L 0.76963002 -2.06225 0.84256004 -2.06225 0 P 0 ;0
L 0.7697 -2.06125 0.8426 -2.06125 0 P 0 ;0
L 0.76976998 -2.06025 0.84265 -2.06025 0 P 0 ;0
L 0.76983996 -2.05925 0.8427 -2.05925 0 P 0 ;0
L 0.76991004 -2.05825 0.84273996 -2.05825 0 P 0 ;0
L 0.76996998 -2.05725 0.84278996 -2.05725 0 P 0 ;0
L 0.77001004 -2.05625 0.84283996 -2.05625 0 P 0 ;0
L 0.77003996 -2.05525 0.84288002 -2.05525 0 P 0 ;0
L 0.77008002 -2.05425 0.84295 -2.05425 0 P 0 ;0
L 0.77011998 -2.05325 0.84303996 -2.05325 0 P 0 ;0
L 0.77016004 -2.05225 0.84311998 -2.05225 0 P 0 ;0
L 0.77018996 -2.05125 0.84321004 -2.05125 0 P 0 ;0
L 0.77023002 -2.05025 0.8433 -2.05025 0 P 0 ;0
L 0.77026998 -2.04925 0.84338002 -2.04925 0 P 0 ;0
L 0.77031004 -2.04825 0.84346998 -2.04825 0 P 0 ;0
L 0.77033996 -2.04725 0.84356004 -2.04725 0 P 0 ;0
L 0.77038002 -2.04625 0.84363996 -2.04625 0 P 0 ;0
L 0.77041004 -2.04525 0.84373002 -2.04525 0 P 0 ;0
L 0.77043996 -2.04425 0.84381004 -2.04425 0 P 0 ;0
L 0.77046004 -2.04325 0.8439 -2.04325 0 P 0 ;0
L 0.77048002 -2.04225 0.84398996 -2.04225 0 P 0 ;0
L 0.77051004 -2.04125 0.84406998 -2.04125 0 P 0 ;0
L 0.77053002 -2.04025 0.84416004 -2.04025 0 P 0 ;0
L 0.77055 -2.03925 0.84425 -2.03925 0 P 0 ;0
L 0.77058002 -2.03825 0.84433002 -2.03825 0 P 0 ;0
L 0.7706 -2.03725 0.84441998 -2.03725 0 P 0 ;0
L 0.77061998 -2.03625 0.84451004 -2.03625 0 P 0 ;0
L 0.77065 -2.03525 0.84458996 -2.03525 0 P 0 ;0
L 0.77066998 -2.03425 0.84468002 -2.03425 0 P 0 ;0
L 0.7707 -2.03325 0.84476998 -2.03325 0 P 0 ;0
L 0.77071998 -2.03225 0.84485 -2.03225 0 P 0 ;0
L 0.77073002 -2.03125 0.84493996 -2.03125 0 P 0 ;0
L 0.77073996 -2.03025 0.84503002 -2.03025 0 P 0 ;0
L 0.79986004 -1.8638 0.79643996 -1.86486998 0 P 0 ;0
L 0.79643996 -1.86486998 0.79311998 -1.86621004 0 P 0 ;0
L 0.79311998 -1.86621004 0.78991004 -1.86781004 0 P 0 ;0
L 0.78991004 -1.86781004 0.78683996 -1.86966998 0 P 0 ;0
L 0.78683996 -1.86966998 0.78391998 -1.87178002 0 P 0 ;0
L 0.78391998 -1.87178002 0.78111998 -1.87416998 0 P 0 ;0
L 0.78111998 -1.87416998 0.7785 -1.87676004 0 P 0 ;0
L 0.7785 -1.87676004 0.77608002 -1.87953996 0 P 0 ;0
L 0.77608002 -1.87953996 0.77386998 -1.8825 0 P 0 ;0
L 0.77386998 -1.8825 0.77188002 -1.88561998 0 P 0 ;0
L 0.77188002 -1.88561998 0.77013996 -1.88886004 0 P 0 ;0
L 0.77013996 -1.88886004 0.76863996 -1.89221004 0 P 0 ;0
L 0.76863996 -1.89221004 0.7674 -1.89566998 0 P 0 ;0
L 0.7674 -1.89566998 0.76643002 -1.89921004 0 P 0 ;0
L 0.76643002 -1.89921004 0.76571004 -1.90283996 0 P 0 ;0
L 0.76571004 -1.90283996 0.76531004 -1.90636004 0 P 0 ;0
L 0.76531004 -1.90636004 0.7652 -1.90991004 0 P 0 ;0
L 0.7652 -1.90991004 0.76538996 -1.91345 0 P 0 ;0
L 0.76538996 -1.91345 0.76586998 -1.91696998 0 P 0 ;0
L 0.76586998 -1.91696998 0.76663996 -1.92046004 0 P 0 ;0
L 0.76663996 -1.92046004 0.76803002 -1.92493996 0 P 0 ;0
L 0.76803002 -1.92493996 0.76978002 -1.9293 0 P 0 ;0
L 0.76978002 -1.9293 0.77106998 -1.93193996 0 P 0 ;0
L 0.77106998 -1.93193996 0.77253002 -1.93448002 0 P 0 ;0
L 0.77253002 -1.93448002 0.77416004 -1.93693996 0 P 0 ;0
L 0.77416004 -1.93693996 0.77593002 -1.93923002 0 P 0 ;0
L 0.77593002 -1.93923002 0.77783996 -1.94141004 0 P 0 ;0
L 0.77783996 -1.94141004 0.77988996 -1.94345 0 P 0 ;0
L 0.77988996 -1.94345 0.78216004 -1.94545 0 P 0 ;0
L 0.78216004 -1.94545 0.78453996 -1.9473 0 P 0 ;0
L 0.78453996 -1.9473 0.78703002 -1.94901998 0 P 0 ;0
L 0.78703002 -1.94901998 0.79016998 -1.95088002 0 P 0 ;0
L 0.79016998 -1.95088002 0.79343996 -1.95248996 0 P 0 ;0
L 0.79343996 -1.95248996 0.79683002 -1.95383996 0 P 0 ;0
L 0.79683002 -1.95383996 0.80031998 -1.95491998 0 P 0 ;0
L 0.80031998 -1.95491998 0.80391004 -1.95573996 0 P 0 ;0
L 0.80391004 -1.95573996 0.80751998 -1.95626004 0 P 0 ;0
L 0.80751998 -1.95626004 0.81116004 -1.9565 0 P 0 ;0
L 0.81116004 -1.9565 0.81481004 -1.95646004 0 P 0 ;0
L 0.81481004 -1.95646004 0.81843996 -1.95613002 0 P 0 ;0
L 0.81843996 -1.95613002 0.82205 -1.95551004 0 P 0 ;0
L 0.82205 -1.95551004 0.82561998 -1.95461004 0 P 0 ;0
L 0.82561998 -1.95461004 0.82911004 -1.95345 0 P 0 ;0
L 0.82911004 -1.95345 0.83248996 -1.95201004 0 P 0 ;0
L 0.83248996 -1.95201004 0.83576004 -1.95031998 0 P 0 ;0
L 0.83576004 -1.95031998 0.83891998 -1.94836004 0 P 0 ;0
L 0.83891998 -1.94836004 0.84191998 -1.94616998 0 P 0 ;0
L 0.84191998 -1.94616998 0.84475 -1.94375 0 P 0 ;0
L 0.84475 -1.94375 0.84738996 -1.94113996 0 P 0 ;0
L 0.84738996 -1.94113996 0.84983002 -1.93833996 0 P 0 ;0
L 0.84983002 -1.93833996 0.85206998 -1.93533996 0 P 0 ;0
L 0.85206998 -1.93533996 0.8536 -1.93291998 0 P 0 ;0
L 0.8536 -1.93291998 0.85496004 -1.93041004 0 P 0 ;0
L 0.85496004 -1.93041004 0.85613996 -1.9278 0 P 0 ;0
L 0.85613996 -1.9278 0.85711998 -1.92511004 0 P 0 ;0
L 0.85711998 -1.92511004 0.85823002 -1.92123002 0 P 0 ;0
L 0.85823002 -1.92123002 0.85901998 -1.91726998 0 P 0 ;0
L 0.85901998 -1.91726998 0.85948996 -1.91323996 0 P 0 ;0
L 0.85948996 -1.91323996 0.85963996 -1.90918002 0 P 0 ;0
L 0.85963996 -1.90918002 0.85946998 -1.90513002 0 P 0 ;0
L 0.85946998 -1.90513002 0.85898002 -1.9011 0 P 0 ;0
L 0.85898002 -1.9011 0.85841998 -1.89826004 0 P 0 ;0
L 0.85841998 -1.89826004 0.85766004 -1.89546004 0 P 0 ;0
L 0.85766004 -1.89546004 0.85671004 -1.89273002 0 P 0 ;0
L 0.85671004 -1.89273002 0.85556998 -1.89006004 0 P 0 ;0
L 0.85556998 -1.89006004 0.85361998 -1.88631004 0 P 0 ;0
L 0.85361998 -1.88631004 0.85136004 -1.88273996 0 P 0 ;0
L 0.85136004 -1.88273996 0.84881004 -1.87938002 0 P 0 ;0
L 0.84881004 -1.87938002 0.84596998 -1.87623002 0 P 0 ;0
L 0.84596998 -1.87623002 0.84355 -1.87393996 0 P 0 ;0
L 0.84355 -1.87393996 0.84096998 -1.87181998 0 P 0 ;0
L 0.84096998 -1.87181998 0.83826004 -1.86988996 0 P 0 ;0
L 0.83826004 -1.86988996 0.83541004 -1.86815 0 P 0 ;0
L 0.83541004 -1.86815 0.83243996 -1.86661004 0 P 0 ;0
L 0.83243996 -1.86661004 0.82938996 -1.86531004 0 P 0 ;0
L 0.82938996 -1.86531004 0.82625 -1.86423002 0 P 0 ;0
L 0.82625 -1.86423002 0.82303996 -1.86336004 0 P 0 ;0
L 0.82303996 -1.86336004 0.81978002 -1.86273002 0 P 0 ;0
L 0.81978002 -1.86273002 0.81646998 -1.86233002 0 P 0 ;0
L 0.81646998 -1.86233002 0.81228996 -1.86215 0 P 0 ;0
L 0.81228996 -1.86215 0.80811004 -1.86233996 0 P 0 ;0
L 0.80811004 -1.86233996 0.80396004 -1.86288996 0 P 0 ;0
L 0.80396004 -1.86288996 0.79986004 -1.8638 0 P 0 ;0
L 0.80308996 -1.9535 0.82186004 -1.9535 0 P 0 ;0
L 0.79926004 -1.9525 0.82563996 -1.9525 0 P 0 ;0
L 0.79636004 -1.9515 0.82856998 -1.9515 0 P 0 ;0
L 0.79393002 -1.9505 0.83093996 -1.9505 0 P 0 ;0
L 0.7919 -1.9495 0.83298996 -1.9495 0 P 0 ;0
L 0.79008002 -1.9485 0.8349 -1.9485 0 P 0 ;0
L 0.78838996 -1.9475 0.83651004 -1.9475 0 P 0 ;0
L 0.7869 -1.9465 0.83806998 -1.9465 0 P 0 ;0
L 0.78548002 -1.9455 0.83943996 -1.9455 0 P 0 ;0
L 0.7842 -1.9445 0.84078996 -1.9445 0 P 0 ;0
L 0.78298002 -1.9435 0.84196998 -1.9435 0 P 0 ;0
L 0.78183996 -1.9425 0.84313996 -1.9425 0 P 0 ;0
L 0.78076998 -1.9415 0.84418996 -1.9415 0 P 0 ;0
L 0.77976004 -1.9405 0.8452 -1.9405 0 P 0 ;0
L 0.77883002 -1.9395 0.84616998 -1.9395 0 P 0 ;0
L 0.77793996 -1.9385 0.84703996 -1.9385 0 P 0 ;0
L 0.77711998 -1.9375 0.84791004 -1.9375 0 P 0 ;0
L 0.77635 -1.9365 0.84871004 -1.9365 0 P 0 ;0
L 0.77561004 -1.9355 0.84945 -1.9355 0 P 0 ;0
L 0.77493996 -1.9345 0.8502 -1.9345 0 P 0 ;0
L 0.77428002 -1.9335 0.85086998 -1.9335 0 P 0 ;0
L 0.7737 -1.9325 0.8515 -1.9325 0 P 0 ;0
L 0.77311998 -1.9315 0.8521 -1.9315 0 P 0 ;0
L 0.77258996 -1.9305 0.85263996 -1.9305 0 P 0 ;0
L 0.7721 -1.9295 0.85318002 -1.9295 0 P 0 ;0
L 0.77161004 -1.9285 0.85363002 -1.9285 0 P 0 ;0
L 0.77121004 -1.9275 0.85408002 -1.9275 0 P 0 ;0
L 0.77081004 -1.9265 0.85448002 -1.9265 0 P 0 ;0
L 0.77041004 -1.9255 0.85485 -1.9255 0 P 0 ;0
L 0.77001004 -1.9245 0.85521998 -1.9245 0 P 0 ;0
L 0.76968002 -1.9235 0.8555 -1.9235 0 P 0 ;0
L 0.76936998 -1.9225 0.85578996 -1.9225 0 P 0 ;0
L 0.76906004 -1.9215 0.85606998 -1.9215 0 P 0 ;0
L 0.76875 -1.9205 0.85633002 -1.9205 0 P 0 ;0
L 0.76848002 -1.9195 0.85653002 -1.9195 0 P 0 ;0
L 0.76826004 -1.9185 0.85673002 -1.9185 0 P 0 ;0
L 0.76803002 -1.9175 0.85693002 -1.9175 0 P 0 ;0
L 0.76783002 -1.9165 0.85708996 -1.9165 0 P 0 ;0
L 0.76768996 -1.9155 0.85721004 -1.9155 0 P 0 ;0
L 0.76755 -1.9145 0.85733002 -1.9145 0 P 0 ;0
L 0.76741998 -1.9135 0.85745 -1.9135 0 P 0 ;0
L 0.81121004 -1.9545 0.80773002 -1.95426998 0 P 0 ;0
L 0.80773002 -1.95426998 0.80426998 -1.95376998 0 P 0 ;0
L 0.80426998 -1.95376998 0.80083996 -1.95298996 0 P 0 ;0
L 0.80083996 -1.95298996 0.7975 -1.95195 0 P 0 ;0
L 0.7975 -1.95195 0.79426004 -1.95066004 0 P 0 ;0
L 0.79426004 -1.95066004 0.79111998 -1.94911998 0 P 0 ;0
L 0.79111998 -1.94911998 0.78811004 -1.94733002 0 P 0 ;0
L 0.78811004 -1.94733002 0.78573002 -1.94568996 0 P 0 ;0
L 0.78573002 -1.94568996 0.78343996 -1.9439 0 P 0 ;0
L 0.78343996 -1.9439 0.78126004 -1.94198996 0 P 0 ;0
L 0.78126004 -1.94198996 0.7793 -1.94003996 0 P 0 ;0
L 0.7793 -1.94003996 0.77746998 -1.93796004 0 P 0 ;0
L 0.77746998 -1.93796004 0.77578996 -1.93576998 0 P 0 ;0
L 0.77578996 -1.93576998 0.77423002 -1.93343002 0 P 0 ;0
L 0.77423002 -1.93343002 0.77283996 -1.931 0 P 0 ;0
L 0.77283996 -1.931 0.77161004 -1.92848996 0 P 0 ;0
L 0.77161004 -1.92848996 0.76991998 -1.92426998 0 P 0 ;0
L 0.76991998 -1.92426998 0.76858002 -1.91993996 0 P 0 ;0
L 0.76858002 -1.91993996 0.76783996 -1.91661998 0 P 0 ;0
L 0.76783996 -1.91661998 0.76738002 -1.91326998 0 P 0 ;0
L 0.76738002 -1.91326998 0.76721004 -1.90988996 0 P 0 ;0
L 0.76721004 -1.90988996 0.76731004 -1.90651004 0 P 0 ;0
L 0.76731004 -1.90651004 0.7677 -1.90315 0 P 0 ;0
L 0.7677 -1.90315 0.76838002 -1.89966998 0 P 0 ;0
L 0.76838002 -1.89966998 0.76931004 -1.89626998 0 P 0 ;0
L 0.76931004 -1.89626998 0.7705 -1.89296004 0 P 0 ;0
L 0.7705 -1.89296004 0.77193996 -1.88973996 0 P 0 ;0
L 0.77193996 -1.88973996 0.7736 -1.88663996 0 P 0 ;0
L 0.7736 -1.88663996 0.77551004 -1.88363996 0 P 0 ;0
L 0.77551004 -1.88363996 0.77763002 -1.8808 0 P 0 ;0
L 0.77763002 -1.8808 0.77996004 -1.87813002 0 P 0 ;0
L 0.77996004 -1.87813002 0.78246998 -1.87565 0 P 0 ;0
L 0.78246998 -1.87565 0.78516004 -1.87336004 0 P 0 ;0
L 0.78516004 -1.87336004 0.78795 -1.87133996 0 P 0 ;0
L 0.78795 -1.87133996 0.79088002 -1.86956004 0 P 0 ;0
L 0.79088002 -1.86956004 0.79393996 -1.86803002 0 P 0 ;0
L 0.79393996 -1.86803002 0.79711004 -1.86675 0 P 0 ;0
L 0.79711004 -1.86675 0.80038002 -1.86573002 0 P 0 ;0
L 0.80038002 -1.86573002 0.80431004 -1.86486004 0 P 0 ;0
L 0.80431004 -1.86486004 0.80828996 -1.86433996 0 P 0 ;0
L 0.80828996 -1.86433996 0.8123 -1.86416004 0 P 0 ;0
L 0.8123 -1.86416004 0.81631004 -1.86431998 0 P 0 ;0
L 0.81631004 -1.86431998 0.81946998 -1.86471004 0 P 0 ;0
L 0.81946998 -1.86471004 0.82258996 -1.86531004 0 P 0 ;0
L 0.82258996 -1.86531004 0.82566004 -1.86613996 0 P 0 ;0
L 0.82566004 -1.86613996 0.82866998 -1.86718002 0 P 0 ;0
L 0.82866998 -1.86718002 0.83158996 -1.86843002 0 P 0 ;0
L 0.83158996 -1.86843002 0.83443002 -1.86988996 0 P 0 ;0
L 0.83443002 -1.86988996 0.83716004 -1.87156004 0 P 0 ;0
L 0.83716004 -1.87156004 0.83976004 -1.87341004 0 P 0 ;0
L 0.83976004 -1.87341004 0.84223002 -1.87543996 0 P 0 ;0
L 0.84223002 -1.87543996 0.84453996 -1.87763002 0 P 0 ;0
L 0.84453996 -1.87763002 0.84726998 -1.88065 0 P 0 ;0
L 0.84726998 -1.88065 0.84971998 -1.88388002 0 P 0 ;0
L 0.84971998 -1.88388002 0.85188996 -1.88731004 0 P 0 ;0
L 0.85188996 -1.88731004 0.85376004 -1.89091004 0 P 0 ;0
L 0.85376004 -1.89091004 0.85483996 -1.89345 0 P 0 ;0
L 0.85483996 -1.89345 0.85575 -1.89605 0 P 0 ;0
L 0.85575 -1.89605 0.85646998 -1.89871004 0 P 0 ;0
L 0.85646998 -1.89871004 0.857 -1.90141004 0 P 0 ;0
L 0.857 -1.90141004 0.85748002 -1.9053 0 P 0 ;0
L 0.85748002 -1.9053 0.85763996 -1.90918996 0 P 0 ;0
L 0.85763996 -1.90918996 0.8575 -1.91308002 0 P 0 ;0
L 0.8575 -1.91308002 0.85703996 -1.91696004 0 P 0 ;0
L 0.85703996 -1.91696004 0.85628002 -1.92076004 0 P 0 ;0
L 0.85628002 -1.92076004 0.85521998 -1.92448996 0 P 0 ;0
L 0.85521998 -1.92448996 0.85428002 -1.92705 0 P 0 ;0
L 0.85428002 -1.92705 0.85316998 -1.92951998 0 P 0 ;0
L 0.85316998 -1.92951998 0.85188002 -1.93191004 0 P 0 ;0
L 0.85188002 -1.93191004 0.85041998 -1.9342 0 P 0 ;0
L 0.85041998 -1.9342 0.84826998 -1.93708002 0 P 0 ;0
L 0.84826998 -1.93708002 0.84593002 -1.93976998 0 P 0 ;0
L 0.84593002 -1.93976998 0.8434 -1.94228002 0 P 0 ;0
L 0.8434 -1.94228002 0.84068002 -1.9446 0 P 0 ;0
L 0.84068002 -1.9446 0.8378 -1.9467 0 P 0 ;0
L 0.8378 -1.9467 0.83476998 -1.94858002 0 P 0 ;0
L 0.83476998 -1.94858002 0.83163996 -1.9502 0 P 0 ;0
L 0.83163996 -1.9502 0.8284 -1.95158002 0 P 0 ;0
L 0.8284 -1.95158002 0.82506004 -1.95268996 0 P 0 ;0
L 0.82506004 -1.95268996 0.82163996 -1.95356004 0 P 0 ;0
L 0.82163996 -1.95356004 0.81818002 -1.95413996 0 P 0 ;0
L 0.81818002 -1.95413996 0.8147 -1.95446004 0 P 0 ;0
L 0.8147 -1.95446004 0.81121004 -1.9545 0 P 0 ;0
L 0.77075 -2.02925 0.84511004 -2.02925 0 P 0 ;0
L 0.77076004 -2.02825 0.8452 -2.02825 0 P 0 ;0
L 0.77076998 -2.02725 0.84528996 -2.02725 0 P 0 ;0
L 0.77078002 -2.02625 0.84536998 -2.02625 0 P 0 ;0
L 0.77078996 -2.02525 0.84548996 -2.02525 0 P 0 ;0
L 0.7708 -2.02425 0.84561998 -2.02425 0 P 0 ;0
L 0.77081004 -2.02325 0.84575 -2.02325 0 P 0 ;0
L 0.77081998 -2.02225 0.84588002 -2.02225 0 P 0 ;0
L 0.77083002 -2.02125 0.84601004 -2.02125 0 P 0 ;0
L 0.77083996 -2.02025 0.84613996 -2.02025 0 P 0 ;0
L 0.77085 -2.01925 0.84626004 -2.01925 0 P 0 ;0
L 0.77085 -2.01825 0.84638996 -2.01825 0 P 0 ;0
L 0.77085 -2.01725 0.84651998 -2.01725 0 P 0 ;0
L 0.77086004 -2.01625 0.84663996 -2.01625 0 P 0 ;0
L 0.77086004 -2.01525 0.84676998 -2.01525 0 P 0 ;0
L 0.77086004 -2.01425 0.8469 -2.01425 0 P 0 ;0
L 0.77086004 -2.01325 0.84703002 -2.01325 0 P 0 ;0
L 0.77086004 -2.01225 0.84716004 -2.01225 0 P 0 ;0
L 0.77086004 -2.01125 0.84728996 -2.01125 0 P 0 ;0
L 0.77086004 -2.01025 0.84741004 -2.01025 0 P 0 ;0
L 0.77086998 -2.00925 0.84753996 -2.00925 0 P 0 ;0
L 0.77086998 -2.00825 0.84766998 -2.00825 0 P 0 ;0
L 0.77086998 -2.00725 0.84778996 -2.00725 0 P 0 ;0
L 0.77086998 -2.00625 0.84791998 -2.00625 0 P 0 ;0
L 0.77086998 -2.00525 0.84805 -2.00525 0 P 0 ;0
L 0.77086998 -2.00425 0.84818002 -2.00425 0 P 0 ;0
L 0.77088002 -2.00325 0.84831004 -2.00325 0 P 0 ;0
L 0.77088002 -2.00225 0.84843996 -2.00225 0 P 0 ;0
L 0.77088002 -2.00125 0.84856004 -2.00125 0 P 0 ;0
L 0.77088002 -2.00025 0.84868996 -2.00025 0 P 0 ;0
L 0.77088002 -1.99925 0.84881998 -1.99925 0 P 0 ;0
L 0.77088002 -1.99825 0.84896004 -1.99825 0 P 0 ;0
L 0.77088002 -1.99725 0.84911004 -1.99725 0 P 0 ;0
L 0.77088996 -1.99625 0.84926998 -1.99625 0 P 0 ;0
L 0.77088996 -1.99525 0.84941998 -1.99525 0 P 0 ;0
L 0.77088996 -1.99425 0.84956998 -1.99425 0 P 0 ;0
L 0.77088996 -1.99325 0.84971998 -1.99325 0 P 0 ;0
L 0.77088996 -1.99225 0.84986998 -1.99225 0 P 0 ;0
L 0.77088996 -1.99125 0.85003002 -1.99125 0 P 0 ;0
L 0.7709 -1.99025 0.85018002 -1.99025 0 P 0 ;0
L 0.7709 -1.98925 0.85033002 -1.98925 0 P 0 ;0
L 0.76885 -2.01878002 0.76871998 -2.03201998 0 P 0 ;0
L 0.76871998 -2.03201998 0.7684 -2.04553996 0 P 0 ;0
L 0.7684 -2.04553996 0.76796004 -2.05751004 0 P 0 ;0
L 0.76796004 -2.05751004 0.76741004 -2.06523002 0 P 0 ;0
L 0.76741004 -2.06523002 0.76596004 -2.07933996 0 P 0 ;0
L 0.76596004 -2.07933996 0.7636 -2.09918002 0 P 0 ;0
L 0.7636 -2.09918002 0.76116004 -2.119 0 P 0 ;0
L 0.76116004 -2.119 0.76011998 -2.12526004 0 P 0 ;0
L 0.76011998 -2.12526004 0.75948996 -2.12825 0 P 0 ;0
L 0.75948996 -2.12825 0.84418002 -2.12825 0 P 0 ;0
L 0.84418002 -2.12825 0.84361998 -2.10788002 0 P 0 ;0
L 0.84361998 -2.10788002 0.8436 -2.08276004 0 P 0 ;0
L 0.8436 -2.08276004 0.8449 -2.05491998 0 P 0 ;0
L 0.8449 -2.05491998 0.84736004 -2.02641004 0 P 0 ;0
L 0.84736004 -2.02641004 0.85083996 -1.99923002 0 P 0 ;0
L 0.85083996 -1.99923002 0.85268996 -1.987 0 P 0 ;0
L 0.85268996 -1.987 0.7689 -1.987 0 P 0 ;0
L 0.7689 -1.987 0.76885 -2.01878002 0 P 0 ;0
L 0.76195 -2.12625 0.84211998 -2.12625 0 P 0 ;0
L 0.76213996 -2.12525 0.8421 -2.12525 0 P 0 ;0
L 0.76231004 -2.12425 0.84206998 -2.12425 0 P 0 ;0
L 0.76248002 -2.12325 0.84203996 -2.12325 0 P 0 ;0
L 0.76263996 -2.12225 0.84201004 -2.12225 0 P 0 ;0
L 0.76281004 -2.12125 0.84198996 -2.12125 0 P 0 ;0
L 0.76296998 -2.12025 0.84196004 -2.12025 0 P 0 ;0
L 0.76313996 -2.11925 0.84193002 -2.11925 0 P 0 ;0
L 0.76326998 -2.11825 0.8419 -2.11825 0 P 0 ;0
L 0.76338996 -2.11725 0.84188002 -2.11725 0 P 0 ;0
L 0.76351004 -2.11625 0.84185 -2.11625 0 P 0 ;0
L 0.76363996 -2.11525 0.84181998 -2.11525 0 P 0 ;0
L 0.76376004 -2.11425 0.84178996 -2.11425 0 P 0 ;0
L 0.76388002 -2.11325 0.84176998 -2.11325 0 P 0 ;0
L 0.76401004 -2.11225 0.84173996 -2.11225 0 P 0 ;0
L 0.76413002 -2.11125 0.84171004 -2.11125 0 P 0 ;0
L 0.76425 -2.11025 0.84168002 -2.11025 0 P 0 ;0
L 0.76438002 -2.10925 0.84166004 -2.10925 0 P 0 ;0
L 0.7645 -2.10825 0.84163002 -2.10825 0 P 0 ;0
L 0.76461998 -2.10725 0.84161998 -2.10725 0 P 0 ;0
L 0.76475 -2.10625 0.84161998 -2.10625 0 P 0 ;0
L 0.76486998 -2.10525 0.84161998 -2.10525 0 P 0 ;0
L 0.76498996 -2.10425 0.84161998 -2.10425 0 P 0 ;0
L 0.76511998 -2.10325 0.84161998 -2.10325 0 P 0 ;0
L 0.76523996 -2.10225 0.84161998 -2.10225 0 P 0 ;0
L 0.76536004 -2.10125 0.84161998 -2.10125 0 P 0 ;0
L 0.76548996 -2.10025 0.84161998 -2.10025 0 P 0 ;0
L 0.76561004 -2.09925 0.84161998 -2.09925 0 P 0 ;0
L 0.76573002 -2.09825 0.84161004 -2.09825 0 P 0 ;0
L 0.76583996 -2.09725 0.84161004 -2.09725 0 P 0 ;0
L 0.76596998 -2.09625 0.84161004 -2.09625 0 P 0 ;0
L 0.76608996 -2.09525 0.84161004 -2.09525 0 P 0 ;0
L 0.7662 -2.09425 0.84161004 -2.09425 0 P 0 ;0
L 0.76631998 -2.09325 0.84161004 -2.09325 0 P 0 ;0
L 0.76643996 -2.09225 0.84161004 -2.09225 0 P 0 ;0
L 0.76656004 -2.09125 0.84161004 -2.09125 0 P 0 ;0
L 0.76668002 -2.09025 0.84161004 -2.09025 0 P 0 ;0
L 0.76678996 -2.08925 0.84161004 -2.08925 0 P 0 ;0
L 0.76691998 -2.08825 0.84161004 -2.08825 0 P 0 ;0
L 0.76703002 -2.08725 0.84161004 -2.08725 0 P 0 ;0
L 0.76715 -2.08625 0.8416 -2.08625 0 P 0 ;0
L 0.76726998 -2.08525 0.8416 -2.08525 0 P 0 ;0
L 0.76738996 -2.08425 0.8416 -2.08425 0 P 0 ;0
L 0.76195 -2.12625 0.76208002 -2.12561998 0 P 0 ;0
L 0.76208002 -2.12561998 0.76313996 -2.11928996 0 P 0 ;0
L 0.76313996 -2.11928996 0.76558996 -2.09941998 0 P 0 ;0
L 0.76558996 -2.09941998 0.76558996 -2.09941004 0 P 0 ;0
L 0.76558996 -2.09941004 0.76793996 -2.07956004 0 P 0 ;0
L 0.76793996 -2.07956004 0.7694 -2.0654 0 P 0 ;0
L 0.7694 -2.0654 0.76941004 -2.06536004 0 P 0 ;0
L 0.76941004 -2.06536004 0.76996004 -2.05761998 0 P 0 ;0
L 0.76996004 -2.05761998 0.76996004 -2.05758996 0 P 0 ;0
L 0.76996004 -2.05758996 0.7704 -2.0456 0 P 0 ;0
L 0.7704 -2.0456 0.77071998 -2.03206004 0 P 0 ;0
L 0.77071998 -2.03206004 0.77085 -2.01878002 0 P 0 ;0
L 0.77085 -2.01878002 0.7709 -1.989 0 P 0 ;0
L 0.7709 -1.989 0.85036004 -1.989 0 P 0 ;0
L 0.85036004 -1.989 0.84886004 -1.99895 0 P 0 ;0
L 0.84886004 -1.99895 0.84538002 -2.02618996 0 P 0 ;0
L 0.84538002 -2.02618996 0.8429 -2.05478996 0 P 0 ;0
L 0.8429 -2.05478996 0.8416 -2.08271004 0 P 0 ;0
L 0.8416 -2.08271004 0.84161998 -2.10791004 0 P 0 ;0
L 0.84161998 -2.10791004 0.84211998 -2.12625 0 P 0 ;0
L 0.84211998 -2.12625 0.76195 -2.12625 0 P 0 ;0
L 0.71628996 -1.91261998 0.74938002 -1.91261998 0 P 0 ;0
L 0.71783002 -1.91161998 0.74933002 -1.91161998 0 P 0 ;0
L 0.71953002 -1.91061998 0.74931004 -1.91061998 0 P 0 ;0
L 0.72133002 -1.90961998 0.74928996 -1.90961998 0 P 0 ;0
L 0.72313996 -1.90861998 0.74926998 -1.90861998 0 P 0 ;0
L 0.72493996 -1.90761998 0.74928996 -1.90761998 0 P 0 ;0
L 0.72673996 -1.90661998 0.74931998 -1.90661998 0 P 0 ;0
L 0.72855 -1.90561998 0.74935 -1.90561998 0 P 0 ;0
L 0.73035 -1.90461998 0.74938996 -1.90461998 0 P 0 ;0
L 0.73215 -1.90361998 0.74946998 -1.90361998 0 P 0 ;0
L 0.73396004 -1.90261998 0.74953996 -1.90261998 0 P 0 ;0
L 0.73576004 -1.90161998 0.74961998 -1.90161998 0 P 0 ;0
L 0.73756998 -1.90061998 0.74973996 -1.90061998 0 P 0 ;0
L 0.73943002 -1.89961998 0.74986004 -1.89961998 0 P 0 ;0
L 0.74141998 -1.89861998 0.74998996 -1.89861998 0 P 0 ;0
L 0.74341004 -1.89761998 0.75015 -1.89761998 0 P 0 ;0
L 0.59843002 -2.08361998 0.6754 -2.08361998 0 P 0 ;0
L 0.59846004 -2.08261998 0.67538996 -2.08261998 0 P 0 ;0
L 0.59848002 -2.08161998 0.67538002 -2.08161998 0 P 0 ;0
L 0.59851004 -2.08061998 0.67538002 -2.08061998 0 P 0 ;0
L 0.59853002 -2.07961998 0.67546004 -2.07961998 0 P 0 ;0
L 0.59856004 -2.07861998 0.67553996 -2.07861998 0 P 0 ;0
L 0.59861998 -2.07761998 0.67561004 -2.07761998 0 P 0 ;0
L 0.5987 -2.07661998 0.67568996 -2.07661998 0 P 0 ;0
L 0.59878002 -2.07561998 0.67576004 -2.07561998 0 P 0 ;0
L 0.59885 -2.07461998 0.67583996 -2.07461998 0 P 0 ;0
L 0.59893002 -2.07361998 0.67591998 -2.07361998 0 P 0 ;0
L 0.59901004 -2.07261998 0.67598996 -2.07261998 0 P 0 ;0
L 0.59908002 -2.07161998 0.67606998 -2.07161998 0 P 0 ;0
L 0.59916004 -2.07061998 0.67613996 -2.07061998 0 P 0 ;0
L 0.59923002 -2.06961998 0.67621004 -2.06961998 0 P 0 ;0
L 0.59936004 -2.06861998 0.6763 -2.06861998 0 P 0 ;0
L 0.59948996 -2.06761998 0.67645 -2.06761998 0 P 0 ;0
L 0.59963002 -2.06661998 0.6766 -2.06661998 0 P 0 ;0
L 0.59976998 -2.06561998 0.67676004 -2.06561998 0 P 0 ;0
L 0.5999 -2.06461998 0.67691998 -2.06461998 0 P 0 ;0
L 0.60003002 -2.06361998 0.67706998 -2.06361998 0 P 0 ;0
L 0.60016998 -2.06261998 0.6773 -2.06261998 0 P 0 ;0
L 0.60031004 -2.06161998 0.67753002 -2.06161998 0 P 0 ;0
L 0.60051004 -2.06061998 0.67776004 -2.06061998 0 P 0 ;0
L 0.60071004 -2.05961998 0.67798996 -2.05961998 0 P 0 ;0
L 0.60091998 -2.05861998 0.67823002 -2.05861998 0 P 0 ;0
L 0.60111998 -2.05761998 0.67853002 -2.05761998 0 P 0 ;0
L 0.60133002 -2.05661998 0.67883996 -2.05661998 0 P 0 ;0
L 0.60153996 -2.05561998 0.67913996 -2.05561998 0 P 0 ;0
L 0.60173996 -2.05461998 0.67945 -2.05461998 0 P 0 ;0
L 0.60195 -2.05361998 0.67975 -2.05361998 0 P 0 ;0
L 0.60223002 -2.05261998 0.68006004 -2.05261998 0 P 0 ;0
L 0.60251004 -2.05161998 0.68036004 -2.05161998 0 P 0 ;0
L 0.60278996 -2.05061998 0.68066998 -2.05061998 0 P 0 ;0
L 0.60306004 -2.04961998 0.68096998 -2.04961998 0 P 0 ;0
L 0.60333996 -2.04861998 0.68135 -2.04861998 0 P 0 ;0
L 0.60361998 -2.04761998 0.68173002 -2.04761998 0 P 0 ;0
L 0.6039 -2.04661998 0.68211004 -2.04661998 0 P 0 ;0
L 0.60418002 -2.04561998 0.68248996 -2.04561998 0 P 0 ;0
L 0.60453002 -2.04461998 0.68288002 -2.04461998 0 P 0 ;0
L 0.60488002 -2.04361998 0.68326004 -2.04361998 0 P 0 ;0
L 0.60523002 -2.04261998 0.68363996 -2.04261998 0 P 0 ;0
L 0.60556998 -2.04161998 0.68401998 -2.04161998 0 P 0 ;0
L 0.60591998 -2.04061998 0.6844 -2.04061998 0 P 0 ;0
L 0.60626998 -2.03961998 0.68486004 -2.03961998 0 P 0 ;0
L 0.60661998 -2.03861998 0.68531998 -2.03861998 0 P 0 ;0
L 0.60698996 -2.03761998 0.68578002 -2.03761998 0 P 0 ;0
L 0.60743002 -2.03661998 0.68623996 -2.03661998 0 P 0 ;0
L 0.60786004 -2.03561998 0.6867 -2.03561998 0 P 0 ;0
L 0.60828996 -2.03461998 0.68716004 -2.03461998 0 P 0 ;0
L 0.60873002 -2.03361998 0.68761998 -2.03361998 0 P 0 ;0
L 0.60916004 -2.03261998 0.68808996 -2.03261998 0 P 0 ;0
L 0.60958996 -2.03161998 0.68856998 -2.03161998 0 P 0 ;0
L 0.61003002 -2.03061998 0.68911004 -2.03061998 0 P 0 ;0
L 0.61046004 -2.02961998 0.68965 -2.02961998 0 P 0 ;0
L 0.61088996 -2.02861998 0.69018996 -2.02861998 0 P 0 ;0
L 0.61133002 -2.02761998 0.69073002 -2.02761998 0 P 0 ;0
L 0.61176004 -2.02661998 0.69126998 -2.02661998 0 P 0 ;0
L 0.6122 -2.02561998 0.69181004 -2.02561998 0 P 0 ;0
L 0.61263002 -2.02461998 0.69235 -2.02461998 0 P 0 ;0
L 0.61306004 -2.02361998 0.69288002 -2.02361998 0 P 0 ;0
L 0.61348996 -2.02261998 0.69346998 -2.02261998 0 P 0 ;0
L 0.61393002 -2.02161998 0.69408996 -2.02161998 0 P 0 ;0
L 0.61436004 -2.02061998 0.6947 -2.02061998 0 P 0 ;0
L 0.61478996 -2.01961998 0.69531998 -2.01961998 0 P 0 ;0
L 0.61531004 -2.01861998 0.69593996 -2.01861998 0 P 0 ;0
L 0.61583996 -2.01761998 0.69656004 -2.01761998 0 P 0 ;0
L 0.61636004 -2.01661998 0.69718002 -2.01661998 0 P 0 ;0
L 0.61688002 -2.01561998 0.69778996 -2.01561998 0 P 0 ;0
L 0.6174 -2.01461998 0.69841998 -2.01461998 0 P 0 ;0
L 0.61791998 -2.01361998 0.69911998 -2.01361998 0 P 0 ;0
L 0.61843996 -2.01261998 0.69981998 -2.01261998 0 P 0 ;0
L 0.61896004 -2.01161998 0.70051998 -2.01161998 0 P 0 ;0
L 0.61948002 -2.01061998 0.70123002 -2.01061998 0 P 0 ;0
L 0.62 -2.00961998 0.70193002 -2.00961998 0 P 0 ;0
L 0.62051998 -2.00861998 0.70263002 -2.00861998 0 P 0 ;0
L 0.62103996 -2.00761998 0.70333002 -2.00761998 0 P 0 ;0
L 0.62163996 -2.00661998 0.70403996 -2.00661998 0 P 0 ;0
L 0.62225 -2.00561998 0.70483002 -2.00561998 0 P 0 ;0
L 0.62285 -2.00461998 0.70565 -2.00461998 0 P 0 ;0
L 0.62346004 -2.00361998 0.70646004 -2.00361998 0 P 0 ;0
L 0.62406004 -2.00261998 0.70726998 -2.00261998 0 P 0 ;0
L 0.62466004 -2.00161998 0.70808996 -2.00161998 0 P 0 ;0
L 0.62526998 -2.00061998 0.7089 -2.00061998 0 P 0 ;0
L 0.62586998 -1.99961998 0.70971004 -1.99961998 0 P 0 ;0
L 0.62648002 -1.99861998 0.71053002 -1.99861998 0 P 0 ;0
L 0.62708002 -1.99761998 0.71133996 -1.99761998 0 P 0 ;0
L 0.62768996 -1.99661998 0.71216004 -1.99661998 0 P 0 ;0
L 0.62831998 -1.99561998 0.71296998 -1.99561998 0 P 0 ;0
L 0.62901004 -1.99461998 0.71378996 -1.99461998 0 P 0 ;0
L 0.62971004 -1.99361998 0.71466004 -1.99361998 0 P 0 ;0
L 0.6304 -1.99261998 0.71561004 -1.99261998 0 P 0 ;0
L 0.6311 -1.99161998 0.71656998 -1.99161998 0 P 0 ;0
L 0.63178996 -1.99061998 0.71753002 -1.99061998 0 P 0 ;0
L 0.63248996 -1.98961998 0.71848996 -1.98961998 0 P 0 ;0
L 0.63318002 -1.98861998 0.71945 -1.98861998 0 P 0 ;0
L 0.63388002 -1.98761998 0.72041004 -1.98761998 0 P 0 ;0
L 0.63456998 -1.98661998 0.72136998 -1.98661998 0 P 0 ;0
L 0.63526998 -1.98561998 0.72233002 -1.98561998 0 P 0 ;0
L 0.63598002 -1.98461998 0.72328996 -1.98461998 0 P 0 ;0
L 0.63678996 -1.98361998 0.72425 -1.98361998 0 P 0 ;0
L 0.6376 -1.98261998 0.72521004 -1.98261998 0 P 0 ;0
L 0.63841004 -1.98161998 0.72628002 -1.98161998 0 P 0 ;0
L 0.63921998 -1.98061998 0.72738996 -1.98061998 0 P 0 ;0
L 0.64003002 -1.97961998 0.7285 -1.97961998 0 P 0 ;0
L 0.64083996 -1.97861998 0.72961004 -1.97861998 0 P 0 ;0
L 0.64165 -1.97761998 0.73071004 -1.97761998 0 P 0 ;0
L 0.64246004 -1.97661998 0.73181998 -1.97661998 0 P 0 ;0
L 0.64326998 -1.97561998 0.73293002 -1.97561998 0 P 0 ;0
L 0.64406998 -1.97461998 0.73403996 -1.97461998 0 P 0 ;0
L 0.64488002 -1.97361998 0.73515 -1.97361998 0 P 0 ;0
L 0.64568996 -1.97261998 0.73625 -1.97261998 0 P 0 ;0
L 0.6465 -1.97161998 0.73736004 -1.97161998 0 P 0 ;0
L 0.64731004 -1.97061998 0.73848002 -1.97061998 0 P 0 ;0
L 0.64811998 -1.96961998 0.73973002 -1.96961998 0 P 0 ;0
L 0.64893002 -1.96861998 0.74098996 -1.96861998 0 P 0 ;0
L 0.64981004 -1.96761998 0.74225 -1.96761998 0 P 0 ;0
L 0.65076004 -1.96661998 0.74351004 -1.96661998 0 P 0 ;0
L 0.65171004 -1.96561998 0.74476998 -1.96561998 0 P 0 ;0
L 0.65266998 -1.96461998 0.74603002 -1.96461998 0 P 0 ;0
L 0.65361998 -1.96361998 0.74728996 -1.96361998 0 P 0 ;0
L 0.65458002 -1.96261998 0.74855 -1.96261998 0 P 0 ;0
L 0.65553002 -1.96161998 0.74981004 -1.96161998 0 P 0 ;0
L 0.65648996 -1.96061998 0.75106004 -1.96061998 0 P 0 ;0
L 0.65743996 -1.95961998 0.75233996 -1.95961998 0 P 0 ;0
L 0.6584 -1.95861998 0.7537 -1.95861998 0 P 0 ;0
L 0.65935 -1.95761998 0.75506004 -1.95761998 0 P 0 ;0
L 0.66031004 -1.95661998 0.75641998 -1.95661998 0 P 0 ;0
L 0.66126004 -1.95561998 0.75778996 -1.95561998 0 P 0 ;0
L 0.66221004 -1.95461998 0.75916004 -1.95461998 0 P 0 ;0
L 0.66316998 -1.95361998 0.76053996 -1.95361998 0 P 0 ;0
L 0.66411998 -1.95261998 0.76193996 -1.95261998 0 P 0 ;0
L 0.66523002 -1.95161998 0.76333996 -1.95161998 0 P 0 ;0
L 0.66636004 -1.95061998 0.76406998 -1.95061998 0 P 0 ;0
L 0.66746998 -1.94961998 0.76355 -1.94961998 0 P 0 ;0
L 0.6686 -1.94861998 0.76291998 -1.94861998 0 P 0 ;0
L 0.66971004 -1.94761998 0.76226998 -1.94761998 0 P 0 ;0
L 0.67083996 -1.94661998 0.76161998 -1.94661998 0 P 0 ;0
L 0.67196004 -1.94561998 0.76096998 -1.94561998 0 P 0 ;0
L 0.67306998 -1.94461998 0.76033002 -1.94461998 0 P 0 ;0
L 0.6742 -1.94361998 0.75968996 -1.94361998 0 P 0 ;0
L 0.67531004 -1.94261998 0.75905 -1.94261998 0 P 0 ;0
L 0.67643996 -1.94161998 0.75846004 -1.94161998 0 P 0 ;0
L 0.67755 -1.94061998 0.75788996 -1.94061998 0 P 0 ;0
L 0.67868002 -1.93961998 0.75731998 -1.93961998 0 P 0 ;0
L 0.67978996 -1.93861998 0.75676998 -1.93861998 0 P 0 ;0
L 0.68091998 -1.93761998 0.75626998 -1.93761998 0 P 0 ;0
L 0.68221004 -1.93661998 0.75576998 -1.93661998 0 P 0 ;0
L 0.68353002 -1.93561998 0.75528002 -1.93561998 0 P 0 ;0
L 0.68483996 -1.93461998 0.75483996 -1.93461998 0 P 0 ;0
L 0.68616004 -1.93361998 0.75441004 -1.93361998 0 P 0 ;0
L 0.68746998 -1.93261998 0.75398002 -1.93261998 0 P 0 ;0
L 0.68878002 -1.93161998 0.7536 -1.93161998 0 P 0 ;0
L 0.6901 -1.93061998 0.75323996 -1.93061998 0 P 0 ;0
L 0.69141004 -1.92961998 0.75286998 -1.92961998 0 P 0 ;0
L 0.69271998 -1.92861998 0.75253996 -1.92861998 0 P 0 ;0
L 0.69403002 -1.92761998 0.75223002 -1.92761998 0 P 0 ;0
L 0.69535 -1.92661998 0.75193002 -1.92661998 0 P 0 ;0
L 0.69666004 -1.92561998 0.75163002 -1.92561998 0 P 0 ;0
L 0.69796998 -1.92461998 0.75138002 -1.92461998 0 P 0 ;0
L 0.69936998 -1.92361998 0.75113996 -1.92361998 0 P 0 ;0
L 0.70091004 -1.92261998 0.75088996 -1.92261998 0 P 0 ;0
L 0.70243996 -1.92161998 0.75066004 -1.92161998 0 P 0 ;0
L 0.70398002 -1.92061998 0.75046004 -1.92061998 0 P 0 ;0
L 0.70551998 -1.91961998 0.75026004 -1.91961998 0 P 0 ;0
L 0.70706004 -1.91861998 0.75006998 -1.91861998 0 P 0 ;0
L 0.7086 -1.91761998 0.7499 -1.91761998 0 P 0 ;0
L 0.71013996 -1.91661998 0.74976998 -1.91661998 0 P 0 ;0
L 0.71166998 -1.91561998 0.74961998 -1.91561998 0 P 0 ;0
L 0.71321004 -1.91461998 0.74951998 -1.91461998 0 P 0 ;0
L 0.71475 -1.91361998 0.74945 -1.91361998 0 P 0 ;0
L 0.61556998 -2.15661998 0.70655 -2.15661998 0 P 0 ;0
L 0.61503002 -2.15561998 0.7056 -2.15561998 0 P 0 ;0
L 0.61448996 -2.15461998 0.70465 -2.15461998 0 P 0 ;0
L 0.61395 -2.15361998 0.7037 -2.15361998 0 P 0 ;0
L 0.61341004 -2.15261998 0.70273996 -2.15261998 0 P 0 ;0
L 0.61286998 -2.15161998 0.70178996 -2.15161998 0 P 0 ;0
L 0.61233002 -2.15061998 0.70095 -2.15061998 0 P 0 ;0
L 0.61188002 -2.14961998 0.70015 -2.14961998 0 P 0 ;0
L 0.61143002 -2.14861998 0.69935 -2.14861998 0 P 0 ;0
L 0.61098002 -2.14761998 0.69855 -2.14761998 0 P 0 ;0
L 0.61053002 -2.14661998 0.69775 -2.14661998 0 P 0 ;0
L 0.61008002 -2.14561998 0.69695 -2.14561998 0 P 0 ;0
L 0.60963002 -2.14461998 0.69615 -2.14461998 0 P 0 ;0
L 0.60918002 -2.14361998 0.69535 -2.14361998 0 P 0 ;0
L 0.60873002 -2.14261998 0.69455 -2.14261998 0 P 0 ;0
L 0.60831004 -2.14161998 0.69381998 -2.14161998 0 P 0 ;0
L 0.60793996 -2.14061998 0.69315 -2.14061998 0 P 0 ;0
L 0.60756998 -2.13961998 0.69248002 -2.13961998 0 P 0 ;0
L 0.60721004 -2.13861998 0.69181004 -2.13861998 0 P 0 ;0
L 0.60683996 -2.13761998 0.69115 -2.13761998 0 P 0 ;0
L 0.60646998 -2.13661998 0.69048002 -2.13661998 0 P 0 ;0
L 0.60611004 -2.13561998 0.68981004 -2.13561998 0 P 0 ;0
L 0.60573996 -2.13461998 0.68918002 -2.13461998 0 P 0 ;0
L 0.60538002 -2.13361998 0.68863002 -2.13361998 0 P 0 ;0
L 0.60503996 -2.13261998 0.68808002 -2.13261998 0 P 0 ;0
L 0.60476004 -2.13161998 0.68753002 -2.13161998 0 P 0 ;0
L 0.60446998 -2.13061998 0.68698002 -2.13061998 0 P 0 ;0
L 0.60418002 -2.12961998 0.68643002 -2.12961998 0 P 0 ;0
L 0.6039 -2.12861998 0.68588002 -2.12861998 0 P 0 ;0
L 0.60361004 -2.12761998 0.68533002 -2.12761998 0 P 0 ;0
L 0.60331998 -2.12661998 0.68486004 -2.12661998 0 P 0 ;0
L 0.60303002 -2.12561998 0.68441998 -2.12561998 0 P 0 ;0
L 0.60275 -2.12461998 0.68396998 -2.12461998 0 P 0 ;0
L 0.60246004 -2.12361998 0.68353002 -2.12361998 0 P 0 ;0
L 0.60218002 -2.12261998 0.68308996 -2.12261998 0 P 0 ;0
L 0.60188996 -2.12161998 0.68263996 -2.12161998 0 P 0 ;0
L 0.60166998 -2.12061998 0.6822 -2.12061998 0 P 0 ;0
L 0.60145 -2.11961998 0.68176004 -2.11961998 0 P 0 ;0
L 0.60123002 -2.11861998 0.68138996 -2.11861998 0 P 0 ;0
L 0.60101004 -2.11761998 0.68105 -2.11761998 0 P 0 ;0
L 0.60078002 -2.11661998 0.68071004 -2.11661998 0 P 0 ;0
L 0.6006 -2.11561998 0.68036004 -2.11561998 0 P 0 ;0
L 0.60043002 -2.11461998 0.68001998 -2.11461998 0 P 0 ;0
L 0.60025 -2.11361998 0.67968002 -2.11361998 0 P 0 ;0
L 0.60008002 -2.11261998 0.67933002 -2.11261998 0 P 0 ;0
L 0.59991004 -2.11161998 0.67898996 -2.11161998 0 P 0 ;0
L 0.59976004 -2.11061998 0.6787 -2.11061998 0 P 0 ;0
L 0.59963996 -2.10961998 0.67845 -2.10961998 0 P 0 ;0
L 0.59951004 -2.10861998 0.6782 -2.10861998 0 P 0 ;0
L 0.59938002 -2.10761998 0.67795 -2.10761998 0 P 0 ;0
L 0.59925 -2.10661998 0.6777 -2.10661998 0 P 0 ;0
L 0.59913002 -2.10561998 0.67746004 -2.10561998 0 P 0 ;0
L 0.59905 -2.10461998 0.67721004 -2.10461998 0 P 0 ;0
L 0.59896998 -2.10361998 0.67696004 -2.10361998 0 P 0 ;0
L 0.59888002 -2.10261998 0.67671004 -2.10261998 0 P 0 ;0
L 0.5988 -2.10161998 0.67653996 -2.10161998 0 P 0 ;0
L 0.59871998 -2.10061998 0.67638002 -2.10061998 0 P 0 ;0
L 0.59866998 -2.09961998 0.67621004 -2.09961998 0 P 0 ;0
L 0.59863996 -2.09861998 0.67605 -2.09861998 0 P 0 ;0
L 0.59861004 -2.09761998 0.67588996 -2.09761998 0 P 0 ;0
L 0.59858996 -2.09661998 0.6758 -2.09661998 0 P 0 ;0
L 0.59856004 -2.09561998 0.67571004 -2.09561998 0 P 0 ;0
L 0.59853002 -2.09461998 0.67563002 -2.09461998 0 P 0 ;0
L 0.5985 -2.09361998 0.67553996 -2.09361998 0 P 0 ;0
L 0.59846998 -2.09261998 0.67546004 -2.09261998 0 P 0 ;0
L 0.59843996 -2.09161998 0.67546004 -2.09161998 0 P 0 ;0
L 0.59841998 -2.09061998 0.67545 -2.09061998 0 P 0 ;0
L 0.59838002 -2.08961998 0.67543996 -2.08961998 0 P 0 ;0
L 0.59836004 -2.08861998 0.67543002 -2.08861998 0 P 0 ;0
L 0.59833002 -2.08761998 0.67543002 -2.08761998 0 P 0 ;0
L 0.59835 -2.08661998 0.67541998 -2.08661998 0 P 0 ;0
L 0.59836998 -2.08561998 0.67541004 -2.08561998 0 P 0 ;0
L 0.5984 -2.08461998 0.67541004 -2.08461998 0 P 0 ;0
L 0.80005 -2.25161998 0.85543996 -2.25161998 0 P 0 ;0
L 0.78651998 -2.25061998 0.86596004 -2.25061998 0 P 0 ;0
L 0.77878996 -2.24961998 0.87636004 -2.24961998 0 P 0 ;0
L 0.77106004 -2.24861998 0.88285 -2.24861998 0 P 0 ;0
L 0.76398996 -2.24761998 0.88933996 -2.24761998 0 P 0 ;0
L 0.75891998 -2.24661998 0.89583996 -2.24661998 0 P 0 ;0
L 0.73781004 -1.8982 0.71738996 -1.90951998 0 P 0 ;0
L 0.71738996 -1.90951998 0.69766998 -1.92233996 0 P 0 ;0
L 0.69766998 -1.92233996 0.67971004 -1.93601998 0 P 0 ;0
L 0.67971004 -1.93601998 0.66278996 -1.95113002 0 P 0 ;0
L 0.66278996 -1.95113002 0.64786998 -1.96675 0 P 0 ;0
L 0.64786998 -1.96675 0.63423996 -1.98358996 0 P 0 ;0
L 0.63423996 -1.98358996 0.62643996 -1.99483002 0 P 0 ;0
L 0.62643996 -1.99483002 0.61933996 -2.00655 0 P 0 ;0
L 0.61933996 -2.00655 0.61298996 -2.01873996 0 P 0 ;0
L 0.61298996 -2.01873996 0.60503002 -2.03713002 0 P 0 ;0
L 0.60503002 -2.03713002 0.60225 -2.04506004 0 P 0 ;0
L 0.60225 -2.04506004 0.59998996 -2.05323002 0 P 0 ;0
L 0.59998996 -2.05323002 0.59833996 -2.0612 0 P 0 ;0
L 0.59833996 -2.0612 0.59725 -2.06928996 0 P 0 ;0
L 0.59725 -2.06928996 0.59656998 -2.07833996 0 P 0 ;0
L 0.59656998 -2.07833996 0.59633002 -2.0875 0 P 0 ;0
L 0.59633002 -2.0875 0.59668996 -2.10036998 0 P 0 ;0
L 0.59668996 -2.10036998 0.59715 -2.10596004 0 P 0 ;0
L 0.59715 -2.10596004 0.59786004 -2.11151004 0 P 0 ;0
L 0.59786004 -2.11151004 0.59878996 -2.11686998 0 P 0 ;0
L 0.59878996 -2.11686998 0.59996998 -2.1222 0 P 0 ;0
L 0.59996998 -2.1222 0.60326998 -2.13368996 0 P 0 ;0
L 0.60326998 -2.13368996 0.60656998 -2.1427 0 P 0 ;0
L 0.60656998 -2.1427 0.6105 -2.15143996 0 P 0 ;0
L 0.6105 -2.15143996 0.61505 -2.15988002 0 P 0 ;0
L 0.61505 -2.15988002 0.62023996 -2.16803996 0 P 0 ;0
L 0.62023996 -2.16803996 0.62828996 -2.17873002 0 P 0 ;0
L 0.62828996 -2.17873002 0.63718996 -2.18871004 0 P 0 ;0
L 0.63718996 -2.18871004 0.64693002 -2.19795 0 P 0 ;0
L 0.64693002 -2.19795 0.6582 -2.20701998 0 P 0 ;0
L 0.6582 -2.20701998 0.67011004 -2.21518996 0 P 0 ;0
L 0.67011004 -2.21518996 0.68261004 -2.22243002 0 P 0 ;0
L 0.68261004 -2.22243002 0.69673996 -2.22936004 0 P 0 ;0
L 0.69673996 -2.22936004 0.71123002 -2.23543996 0 P 0 ;0
L 0.71123002 -2.23543996 0.72611998 -2.24066998 0 P 0 ;0
L 0.72611998 -2.24066998 0.74536004 -2.24598996 0 P 0 ;0
L 0.74536004 -2.24598996 0.76493002 -2.24985 0 P 0 ;0
L 0.76493002 -2.24985 0.78671998 -2.25266998 0 P 0 ;0
L 0.78671998 -2.25266998 0.80863002 -2.25425 0 P 0 ;0
L 0.80863002 -2.25425 0.83146004 -2.25463002 0 P 0 ;0
L 0.83146004 -2.25463002 0.85418002 -2.25375 0 P 0 ;0
L 0.85418002 -2.25375 0.87641004 -2.25163996 0 P 0 ;0
L 0.87641004 -2.25163996 0.89853002 -2.24823002 0 P 0 ;0
L 0.89853002 -2.24823002 0.93045 -2.24101998 0 P 0 ;0
L 0.93045 -2.24101998 0.96466004 -2.23063002 0 P 0 ;0
L 0.96466004 -2.23063002 0.99911004 -2.2178 0 P 0 ;0
L 0.99911004 -2.2178 1.03183002 -2.20318002 0 P 0 ;0
L 1.03183002 -2.20318002 1.04391998 -2.19703002 0 P 0 ;0
L 1.04391998 -2.19703002 1.05581004 -2.19048996 0 P 0 ;0
L 1.05581004 -2.19048996 1.06676004 -2.18411998 0 P 0 ;0
L 1.06676004 -2.18411998 1.06681004 -2.18408996 0 P 0 ;0
L 1.06681004 -2.18408996 1.06685 -2.18405 0 P 0 ;0
L 1.06685 -2.18405 1.0669 -2.18401004 0 P 0 ;0
L 1.0669 -2.18401004 1.06693996 -2.18396998 0 P 0 ;0
L 1.06693996 -2.18396998 1.06696998 -2.18391998 0 P 0 ;0
L 1.06696998 -2.18391998 1.06701004 -2.18386998 0 P 0 ;0
L 1.06701004 -2.18386998 1.06703002 -2.18381998 0 P 0 ;0
L 1.06703002 -2.18381998 1.06706004 -2.18376004 0 P 0 ;0
L 1.06706004 -2.18376004 1.06706998 -2.18371004 0 P 0 ;0
L 1.06706998 -2.18371004 1.06708996 -2.18365 0 P 0 ;0
L 1.06708996 -2.18365 1.06708996 -2.18358996 0 P 0 ;0
L 1.06708996 -2.18358996 1.0671 -2.18353002 0 P 0 ;0
L 1.0671 -2.18353002 1.0671 -2.18346998 0 P 0 ;0
L 1.0671 -2.18346998 1.06708996 -2.18341004 0 P 0 ;0
L 1.06708996 -2.18341004 1.06706998 -2.18336004 0 P 0 ;0
L 1.06706998 -2.18336004 1.06706004 -2.1833 0 P 0 ;0
L 1.06706004 -2.1833 1.06703002 -2.18323996 0 P 0 ;0
L 1.06703002 -2.18323996 1.06701004 -2.18318996 0 P 0 ;0
L 1.06701004 -2.18318996 1.06696998 -2.18313996 0 P 0 ;0
L 1.06696998 -2.18313996 1.06693996 -2.18308996 0 P 0 ;0
L 1.06693996 -2.18308996 1.06688002 -2.18303002 0 P 0 ;0
L 1.06688002 -2.18303002 1.06678996 -2.18296998 0 P 0 ;0
L 1.06678996 -2.18296998 1.06673002 -2.18295 0 P 0 ;0
L 1.06673002 -2.18295 1.0667 -2.18295 0 P 0 ;0
L 1.0667 -2.18295 1.06666004 -2.18293996 0 P 0 ;0
L 1.06666004 -2.18293996 1.0666 -2.18293996 0 P 0 ;0
L 1.0666 -2.18293996 1.06656998 -2.18295 0 P 0 ;0
L 1.06656998 -2.18295 1.06653002 -2.18295 0 P 0 ;0
L 1.06653002 -2.18295 1.06153002 -2.1842 0 P 0 ;0
L 1.06153002 -2.1842 1.05583996 -2.18566998 0 P 0 ;0
L 1.05583996 -2.18566998 1.04916998 -2.1875 0 P 0 ;0
L 1.04916998 -2.1875 1.0153 -2.1962 0 P 0 ;0
L 1.0153 -2.1962 0.9814 -2.20333996 0 P 0 ;0
L 0.9814 -2.20333996 0.94881998 -2.2087 0 P 0 ;0
L 0.94881998 -2.2087 0.9189 -2.21198996 0 P 0 ;0
L 0.9189 -2.21198996 0.90113996 -2.21278996 0 P 0 ;0
L 0.90113996 -2.21278996 0.87738002 -2.21265 0 P 0 ;0
L 0.87738002 -2.21265 0.854 -2.21183002 0 P 0 ;0
L 0.854 -2.21183002 0.83788996 -2.21033996 0 P 0 ;0
L 0.83788996 -2.21033996 0.8174 -2.20693002 0 P 0 ;0
L 0.8174 -2.20693002 0.79708996 -2.2023 0 P 0 ;0
L 0.79708996 -2.2023 0.7769 -2.19641004 0 P 0 ;0
L 0.7769 -2.19641004 0.76433002 -2.19183996 0 P 0 ;0
L 0.76433002 -2.19183996 0.75208996 -2.18638002 0 P 0 ;0
L 0.75208996 -2.18638002 0.74026998 -2.18006998 0 P 0 ;0
L 0.74026998 -2.18006998 0.72886998 -2.17291004 0 P 0 ;0
L 0.72886998 -2.17291004 0.71961998 -2.16603002 0 P 0 ;0
L 0.71961998 -2.16603002 0.71098996 -2.15838996 0 P 0 ;0
L 0.71098996 -2.15838996 0.70303002 -2.15003002 0 P 0 ;0
L 0.70303002 -2.15003002 0.6958 -2.14098996 0 P 0 ;0
L 0.6958 -2.14098996 0.69106998 -2.1339 0 P 0 ;0
L 0.69106998 -2.1339 0.68696004 -2.12643002 0 P 0 ;0
L 0.68696004 -2.12643002 0.68351004 -2.11863002 0 P 0 ;0
L 0.68351004 -2.11863002 0.68073996 -2.11056004 0 P 0 ;0
L 0.68073996 -2.11056004 0.67866004 -2.10218996 0 P 0 ;0
L 0.67866004 -2.10218996 0.67788002 -2.09741998 0 P 0 ;0
L 0.67788002 -2.09741998 0.67746004 -2.0926 0 P 0 ;0
L 0.67746004 -2.0926 0.67738002 -2.08076004 0 P 0 ;0
L 0.67738002 -2.08076004 0.67828002 -2.06891004 0 P 0 ;0
L 0.67828002 -2.06891004 0.67903002 -2.06403996 0 P 0 ;0
L 0.67903002 -2.06403996 0.68013002 -2.05923996 0 P 0 ;0
L 0.68013002 -2.05923996 0.68288002 -2.05021998 0 P 0 ;0
L 0.68288002 -2.05021998 0.68623996 -2.04141004 0 P 0 ;0
L 0.68623996 -2.04141004 0.69018002 -2.03286004 0 P 0 ;0
L 0.69018002 -2.03286004 0.69486004 -2.02418002 0 P 0 ;0
L 0.69486004 -2.02418002 0.70003996 -2.0158 0 P 0 ;0
L 0.70003996 -2.0158 0.70573002 -2.00768996 0 P 0 ;0
L 0.70573002 -2.00768996 0.7158 -1.99531998 0 P 0 ;0
L 0.7158 -1.99531998 0.72681004 -1.98385 0 P 0 ;0
L 0.72681004 -1.98385 0.73971004 -1.9722 0 P 0 ;0
L 0.73971004 -1.9722 0.7533 -1.9614 0 P 0 ;0
L 0.7533 -1.9614 0.75753996 -1.95828002 0 P 0 ;0
L 0.75753996 -1.95828002 0.76138002 -1.95548002 0 P 0 ;0
L 0.76138002 -1.95548002 0.76463002 -1.95316004 0 P 0 ;0
L 0.76463002 -1.95316004 0.76516004 -1.95281004 0 P 0 ;0
L 0.76516004 -1.95281004 0.7657 -1.95248996 0 P 0 ;0
L 0.7657 -1.95248996 0.76578002 -1.95243996 0 P 0 ;0
L 0.76578002 -1.95243996 0.76586004 -1.95238002 0 P 0 ;0
L 0.76586004 -1.95238002 0.76593002 -1.95231998 0 P 0 ;0
L 0.76593002 -1.95231998 0.766 -1.95223996 0 P 0 ;0
L 0.766 -1.95223996 0.76606004 -1.95216998 0 P 0 ;0
L 0.76606004 -1.95216998 0.76616004 -1.95201004 0 P 0 ;0
L 0.76616004 -1.95201004 0.7662 -1.95191998 0 P 0 ;0
L 0.7662 -1.95191998 0.76626004 -1.95173996 0 P 0 ;0
L 0.76626004 -1.95173996 0.76628002 -1.95163996 0 P 0 ;0
L 0.76628002 -1.95163996 0.7663 -1.95143002 0 P 0 ;0
L 0.7663 -1.95143002 0.7663 -1.95121004 0 P 0 ;0
L 0.7663 -1.95121004 0.76628996 -1.951 0 P 0 ;0
L 0.76628996 -1.951 0.76625 -1.95078996 0 P 0 ;0
L 0.76625 -1.95078996 0.7662 -1.95058002 0 P 0 ;0
L 0.7662 -1.95058002 0.76613002 -1.95036998 0 P 0 ;0
L 0.76613002 -1.95036998 0.76583002 -1.94966998 0 P 0 ;0
L 0.76583002 -1.94966998 0.76548996 -1.94896998 0 P 0 ;0
L 0.76548996 -1.94896998 0.76508996 -1.9483 0 P 0 ;0
L 0.76508996 -1.9483 0.76253002 -1.94436004 0 P 0 ;0
L 0.76253002 -1.94436004 0.76056998 -1.94126998 0 P 0 ;0
L 0.76056998 -1.94126998 0.75871998 -1.93806004 0 P 0 ;0
L 0.75871998 -1.93806004 0.75716998 -1.93496998 0 P 0 ;0
L 0.75716998 -1.93496998 0.7558 -1.93178002 0 P 0 ;0
L 0.7558 -1.93178002 0.7546 -1.92853996 0 P 0 ;0
L 0.7546 -1.92853996 0.75358996 -1.92521004 0 P 0 ;0
L 0.75358996 -1.92521004 0.7527 -1.92161998 0 P 0 ;0
L 0.7527 -1.92161998 0.75196998 -1.91796004 0 P 0 ;0
L 0.75196998 -1.91796004 0.75155 -1.91496004 0 P 0 ;0
L 0.75155 -1.91496004 0.75133002 -1.91193002 0 P 0 ;0
L 0.75133002 -1.91193002 0.75126998 -1.9085 0 P 0 ;0
L 0.75126998 -1.9085 0.75136004 -1.90506004 0 P 0 ;0
L 0.75136004 -1.90506004 0.75161004 -1.90181998 0 P 0 ;0
L 0.75161004 -1.90181998 0.752 -1.8986 0 P 0 ;0
L 0.752 -1.8986 0.75228996 -1.89701998 0 P 0 ;0
L 0.75228996 -1.89701998 0.75268996 -1.89546998 0 P 0 ;0
L 0.75268996 -1.89546998 0.7532 -1.89395 0 P 0 ;0
L 0.7532 -1.89395 0.75358996 -1.89281998 0 P 0 ;0
L 0.75358996 -1.89281998 0.75373002 -1.89231998 0 P 0 ;0
L 0.75373002 -1.89231998 0.75383996 -1.8918 0 P 0 ;0
L 0.75383996 -1.8918 0.75391998 -1.89138996 0 P 0 ;0
L 0.75391998 -1.89138996 0.75396998 -1.89098996 0 P 0 ;0
L 0.75396998 -1.89098996 0.75396998 -1.89086004 0 P 0 ;0
L 0.75396998 -1.89086004 0.75393996 -1.89076998 0 P 0 ;0
L 0.75393996 -1.89076998 0.7539 -1.89071004 0 P 0 ;0
L 0.7539 -1.89071004 0.75386004 -1.89066998 0 P 0 ;0
L 0.75386004 -1.89066998 0.75381004 -1.89063002 0 P 0 ;0
L 0.75381004 -1.89063002 0.75378996 -1.89061004 0 P 0 ;0
L 0.75378996 -1.89061004 0.75373002 -1.89058996 0 P 0 ;0
L 0.75373002 -1.89058996 0.75368002 -1.89056998 0 P 0 ;0
L 0.75368002 -1.89056998 0.75356004 -1.89056998 0 P 0 ;0
L 0.75356004 -1.89056998 0.75346998 -1.8906 0 P 0 ;0
L 0.75346998 -1.8906 0.74898002 -1.8927 0 P 0 ;0
L 0.74898002 -1.8927 0.74383002 -1.89518002 0 P 0 ;0
L 0.74383002 -1.89518002 0.73781004 -1.8982 0 P 0 ;0
L 0.69776998 -2.22761998 0.96701004 -2.22761998 0 P 0 ;0
L 0.6957 -2.22661998 0.96968996 -2.22661998 0 P 0 ;0
L 0.69366998 -2.22561998 0.97238002 -2.22561998 0 P 0 ;0
L 0.69163002 -2.22461998 0.97506004 -2.22461998 0 P 0 ;0
L 0.68958996 -2.22361998 0.97775 -2.22361998 0 P 0 ;0
L 0.68756004 -2.22261998 0.98043002 -2.22261998 0 P 0 ;0
L 0.68551998 -2.22161998 0.98311004 -2.22161998 0 P 0 ;0
L 0.68348996 -2.22061998 0.9858 -2.22061998 0 P 0 ;0
L 0.68176998 -2.21961998 0.98848002 -2.21961998 0 P 0 ;0
L 0.68003996 -2.21861998 0.99116998 -2.21861998 0 P 0 ;0
L 0.67831004 -2.21761998 0.99385 -2.21761998 0 P 0 ;0
L 0.67658002 -2.21661998 0.99653996 -2.21661998 0 P 0 ;0
L 0.67485 -2.21561998 0.99908002 -2.21561998 0 P 0 ;0
L 0.67311998 -2.21461998 0.87665 -2.21461998 0 P 0 ;0
L 0.6714 -2.21361998 0.85166004 -2.21361998 0 P 0 ;0
L 0.6699 -2.21261998 0.84083002 -2.21261998 0 P 0 ;0
L 0.66845 -2.21161998 0.8334 -2.21161998 0 P 0 ;0
L 0.66698996 -2.21061998 0.8274 -2.21061998 0 P 0 ;0
L 0.66553002 -2.20961998 0.82138996 -2.20961998 0 P 0 ;0
L 0.66406998 -2.20861998 0.81583002 -2.20861998 0 P 0 ;0
L 0.66261998 -2.20761998 0.81143996 -2.20761998 0 P 0 ;0
L 0.66116004 -2.20661998 0.80706004 -2.20661998 0 P 0 ;0
L 0.6597 -2.20561998 0.80266998 -2.20561998 0 P 0 ;0
L 0.65841004 -2.20461998 0.79828996 -2.20461998 0 P 0 ;0
L 0.65716998 -2.20361998 0.79448996 -2.20361998 0 P 0 ;0
L 0.65593002 -2.20261998 0.79106004 -2.20261998 0 P 0 ;0
L 0.65468996 -2.20161998 0.78763996 -2.20161998 0 P 0 ;0
L 0.83143002 -2.25261998 0.80871998 -2.25225 0 P 0 ;0
L 0.80871998 -2.25225 0.78691998 -2.25066998 0 P 0 ;0
L 0.78691998 -2.25066998 0.76525 -2.24786998 0 P 0 ;0
L 0.76525 -2.24786998 0.74581998 -2.24403996 0 P 0 ;0
L 0.74581998 -2.24403996 0.72671004 -2.23876004 0 P 0 ;0
L 0.72671004 -2.23876004 0.71196004 -2.23356998 0 P 0 ;0
L 0.71196004 -2.23356998 0.69756998 -2.22753996 0 P 0 ;0
L 0.69756998 -2.22753996 0.68355 -2.22066004 0 P 0 ;0
L 0.68355 -2.22066004 0.67118002 -2.2135 0 P 0 ;0
L 0.67118002 -2.2135 0.65938996 -2.20541004 0 P 0 ;0
L 0.65938996 -2.20541004 0.64825 -2.19643996 0 P 0 ;0
L 0.64825 -2.19643996 0.63861998 -2.18731998 0 P 0 ;0
L 0.63861998 -2.18731998 0.62983002 -2.17746998 0 P 0 ;0
L 0.62983002 -2.17746998 0.62188996 -2.1669 0 P 0 ;0
L 0.62188996 -2.1669 0.61678002 -2.15886998 0 P 0 ;0
L 0.61678002 -2.15886998 0.6123 -2.15056004 0 P 0 ;0
L 0.6123 -2.15056004 0.60841998 -2.14193996 0 P 0 ;0
L 0.60841998 -2.14193996 0.60516998 -2.13306998 0 P 0 ;0
L 0.60516998 -2.13306998 0.60191004 -2.12171004 0 P 0 ;0
L 0.60191004 -2.12171004 0.60075 -2.11648002 0 P 0 ;0
L 0.60075 -2.11648002 0.59983996 -2.11121004 0 P 0 ;0
L 0.59983996 -2.11121004 0.59913996 -2.10576004 0 P 0 ;0
L 0.59913996 -2.10576004 0.59868996 -2.10026004 0 P 0 ;0
L 0.59868996 -2.10026004 0.59833002 -2.0875 0 P 0 ;0
L 0.59833002 -2.0875 0.59856998 -2.07843996 0 P 0 ;0
L 0.59856998 -2.07843996 0.59923996 -2.0695 0 P 0 ;0
L 0.59923996 -2.0695 0.60031998 -2.06153996 0 P 0 ;0
L 0.60031998 -2.06153996 0.60193002 -2.05368996 0 P 0 ;0
L 0.60193002 -2.05368996 0.60416004 -2.04566004 0 P 0 ;0
L 0.60416004 -2.04566004 0.60688996 -2.03786004 0 P 0 ;0
L 0.60688996 -2.03786004 0.6148 -2.01961004 0 P 0 ;0
L 0.6148 -2.01961004 0.62108996 -2.00753002 0 P 0 ;0
L 0.62108996 -2.00753002 0.62811998 -1.99591998 0 P 0 ;0
L 0.62811998 -1.99591998 0.63583996 -1.98478996 0 P 0 ;0
L 0.63583996 -1.98478996 0.64936998 -1.96808002 0 P 0 ;0
L 0.64936998 -1.96808002 0.66418002 -1.95256998 0 P 0 ;0
L 0.66418002 -1.95256998 0.68098002 -1.93756004 0 P 0 ;0
L 0.68098002 -1.93756004 0.69881998 -1.92398002 0 P 0 ;0
L 0.69881998 -1.92398002 0.71841998 -1.91123996 0 P 0 ;0
L 0.71841998 -1.91123996 0.73875 -1.89996998 0 P 0 ;0
L 0.73875 -1.89996998 0.74471004 -1.89696998 0 P 0 ;0
L 0.74471004 -1.89696998 0.74983002 -1.89451004 0 P 0 ;0
L 0.74983002 -1.89451004 0.7511 -1.89391004 0 P 0 ;0
L 0.7511 -1.89391004 0.75076998 -1.89488996 0 P 0 ;0
L 0.75076998 -1.89488996 0.75033996 -1.89658996 0 P 0 ;0
L 0.75033996 -1.89658996 0.75003002 -1.8983 0 P 0 ;0
L 0.75003002 -1.8983 0.74961998 -1.90161998 0 P 0 ;0
L 0.74961998 -1.90161998 0.74936004 -1.90496004 0 P 0 ;0
L 0.74936004 -1.90496004 0.74926998 -1.9085 0 P 0 ;0
L 0.74926998 -1.9085 0.74933002 -1.91201998 0 P 0 ;0
L 0.74933002 -1.91201998 0.74956004 -1.91516998 0 P 0 ;0
L 0.74956004 -1.91516998 0.75 -1.91828996 0 P 0 ;0
L 0.75 -1.91828996 0.75075 -1.92205 0 P 0 ;0
L 0.75075 -1.92205 0.75166004 -1.92573996 0 P 0 ;0
L 0.75166004 -1.92573996 0.7527 -1.92916998 0 P 0 ;0
L 0.7527 -1.92916998 0.75393996 -1.93253002 0 P 0 ;0
L 0.75393996 -1.93253002 0.75536004 -1.93581998 0 P 0 ;0
L 0.75536004 -1.93581998 0.75696004 -1.939 0 P 0 ;0
L 0.75696004 -1.939 0.75885 -1.94231004 0 P 0 ;0
L 0.75885 -1.94231004 0.76083996 -1.94543996 0 P 0 ;0
L 0.76083996 -1.94543996 0.76338996 -1.94933996 0 P 0 ;0
L 0.76338996 -1.94933996 0.76371998 -1.94991998 0 P 0 ;0
L 0.76371998 -1.94991998 0.76401004 -1.9505 0 P 0 ;0
L 0.76401004 -1.9505 0.76423996 -1.95103002 0 P 0 ;0
L 0.76423996 -1.95103002 0.76408996 -1.95111004 0 P 0 ;0
L 0.76408996 -1.95111004 0.76348996 -1.95151004 0 P 0 ;0
L 0.76348996 -1.95151004 0.76021004 -1.95386004 0 P 0 ;0
L 0.76021004 -1.95386004 0.7602 -1.95386998 0 P 0 ;0
L 0.7602 -1.95386998 0.75636998 -1.95666004 0 P 0 ;0
L 0.75636998 -1.95666004 0.75636004 -1.95666998 0 P 0 ;0
L 0.75636004 -1.95666998 0.75635 -1.95666998 0 P 0 ;0
L 0.75635 -1.95666998 0.75208996 -1.95981004 0 P 0 ;0
L 0.75208996 -1.95981004 0.73841004 -1.97066998 0 P 0 ;0
L 0.73841004 -1.97066998 0.72541004 -1.98241004 0 P 0 ;0
L 0.72541004 -1.98241004 0.7143 -1.994 0 P 0 ;0
L 0.7143 -1.994 0.71425 -1.99406004 0 P 0 ;0
L 0.71425 -1.99406004 0.70413996 -2.00648002 0 P 0 ;0
L 0.70413996 -2.00648002 0.69836998 -2.01468996 0 P 0 ;0
L 0.69836998 -2.01468996 0.69313002 -2.02318002 0 P 0 ;0
L 0.69313002 -2.02318002 0.68838996 -2.03196004 0 P 0 ;0
L 0.68838996 -2.03196004 0.68438996 -2.04063996 0 P 0 ;0
L 0.68438996 -2.04063996 0.68098996 -2.04958002 0 P 0 ;0
L 0.68098996 -2.04958002 0.6782 -2.05873002 0 P 0 ;0
L 0.6782 -2.05873002 0.67706004 -2.06366004 0 P 0 ;0
L 0.67706004 -2.06366004 0.67628996 -2.06866998 0 P 0 ;0
L 0.67628996 -2.06866998 0.67538002 -2.08068996 0 P 0 ;0
L 0.67538002 -2.08068996 0.67546004 -2.09268996 0 P 0 ;0
L 0.67546004 -2.09268996 0.67588996 -2.09766998 0 P 0 ;0
L 0.67588996 -2.09766998 0.6767 -2.10258996 0 P 0 ;0
L 0.6767 -2.10258996 0.67881998 -2.11111998 0 P 0 ;0
L 0.67881998 -2.11111998 0.68163996 -2.11936004 0 P 0 ;0
L 0.68163996 -2.11936004 0.68516004 -2.12731998 0 P 0 ;0
L 0.68516004 -2.12731998 0.68935 -2.13493996 0 P 0 ;0
L 0.68935 -2.13493996 0.69418002 -2.14216998 0 P 0 ;0
L 0.69418002 -2.14216998 0.70153002 -2.15135 0 P 0 ;0
L 0.70153002 -2.15135 0.7096 -2.15983002 0 P 0 ;0
L 0.7096 -2.15983002 0.71836004 -2.16758996 0 P 0 ;0
L 0.71836004 -2.16758996 0.71843002 -2.16763996 0 P 0 ;0
L 0.71843002 -2.16763996 0.72773996 -2.17456004 0 P 0 ;0
L 0.72773996 -2.17456004 0.73926998 -2.1818 0 P 0 ;0
L 0.73926998 -2.1818 0.75121004 -2.18818002 0 P 0 ;0
L 0.75121004 -2.18818002 0.75128002 -2.18821004 0 P 0 ;0
L 0.75128002 -2.18821004 0.76358002 -2.19368996 0 P 0 ;0
L 0.76358002 -2.19368996 0.77628002 -2.19831004 0 P 0 ;0
L 0.77628002 -2.19831004 0.79658996 -2.20423996 0 P 0 ;0
L 0.79658996 -2.20423996 0.81701004 -2.20888996 0 P 0 ;0
L 0.81701004 -2.20888996 0.83763996 -2.21233002 0 P 0 ;0
L 0.83763996 -2.21233002 0.85388002 -2.21383002 0 P 0 ;0
L 0.85388002 -2.21383002 0.87733996 -2.21465 0 P 0 ;0
L 0.87733996 -2.21465 0.90118002 -2.21478996 0 P 0 ;0
L 0.90118002 -2.21478996 0.91906004 -2.21398996 0 P 0 ;0
L 0.91906004 -2.21398996 0.94908996 -2.21068002 0 P 0 ;0
L 0.94908996 -2.21068002 0.98176998 -2.2053 0 P 0 ;0
L 0.98176998 -2.2053 1.01575 -2.19815 0 P 0 ;0
L 1.01575 -2.19815 1.04968002 -2.18943002 0 P 0 ;0
L 1.04968002 -2.18943002 1.05633996 -2.18761004 0 P 0 ;0
L 1.05633996 -2.18761004 1.05713996 -2.1874 0 P 0 ;0
L 1.05713996 -2.1874 1.05483002 -2.18875 0 P 0 ;0
L 1.05483002 -2.18875 1.04298996 -2.19526004 0 P 0 ;0
L 1.04298996 -2.19526004 1.03096998 -2.20136998 0 P 0 ;0
L 1.03096998 -2.20136998 0.99835 -2.21595 0 P 0 ;0
L 0.99835 -2.21595 0.96401998 -2.22873996 0 P 0 ;0
L 0.96401998 -2.22873996 0.92993996 -2.23908002 0 P 0 ;0
L 0.92993996 -2.23908002 0.89816004 -2.24626004 0 P 0 ;0
L 0.89816004 -2.24626004 0.87616004 -2.24965 0 P 0 ;0
L 0.87616004 -2.24965 0.85405 -2.25176004 0 P 0 ;0
L 0.85405 -2.25176004 0.83143002 -2.25261998 0 P 0 ;0
L 0.65345 -2.20061998 0.78421004 -2.20061998 0 P 0 ;0
L 0.65221004 -2.19961998 0.78078002 -2.19961998 0 P 0 ;0
L 0.65096004 -2.19861998 0.77735 -2.19861998 0 P 0 ;0
L 0.64971998 -2.19761998 0.77438996 -2.19761998 0 P 0 ;0
L 0.64848002 -2.19661998 0.77163996 -2.19661998 0 P 0 ;0
L 0.64738996 -2.19561998 0.76888996 -2.19561998 0 P 0 ;0
L 0.64633996 -2.19461998 0.76613996 -2.19461998 0 P 0 ;0
L 0.64528002 -2.19361998 0.76343002 -2.19361998 0 P 0 ;0
L 0.64421998 -2.19261998 0.76118996 -2.19261998 0 P 0 ;0
L 0.64316998 -2.19161998 0.75893996 -2.19161998 0 P 0 ;0
L 0.64211004 -2.19061998 0.7567 -2.19061998 0 P 0 ;0
L 0.64106004 -2.18961998 0.75446004 -2.18961998 0 P 0 ;0
L 0.64 -2.18861998 0.75221004 -2.18861998 0 P 0 ;0
L 0.63895 -2.18761998 0.75018002 -2.18761998 0 P 0 ;0
L 0.63801004 -2.18661998 0.74831004 -2.18661998 0 P 0 ;0
L 0.63711004 -2.18561998 0.74643002 -2.18561998 0 P 0 ;0
L 0.63621998 -2.18461998 0.74456004 -2.18461998 0 P 0 ;0
L 0.63533002 -2.18361998 0.74268002 -2.18361998 0 P 0 ;0
L 0.63443996 -2.18261998 0.74081004 -2.18261998 0 P 0 ;0
L 0.63353996 -2.18161998 0.73898996 -2.18161998 0 P 0 ;0
L 0.63265 -2.18061998 0.73738996 -2.18061998 0 P 0 ;0
L 0.63176004 -2.17961998 0.7358 -2.17961998 0 P 0 ;0
L 0.63086998 -2.17861998 0.73421004 -2.17861998 0 P 0 ;0
L 0.62996998 -2.17761998 0.73261998 -2.17761998 0 P 0 ;0
L 0.6292 -2.17661998 0.73103002 -2.17661998 0 P 0 ;0
L 0.62845 -2.17561998 0.72943996 -2.17561998 0 P 0 ;0
L 0.6277 -2.17461998 0.72783996 -2.17461998 0 P 0 ;0
L 0.62693996 -2.17361998 0.72648002 -2.17361998 0 P 0 ;0
L 0.62618996 -2.17261998 0.72513996 -2.17261998 0 P 0 ;0
L 0.62543996 -2.17161998 0.72378996 -2.17161998 0 P 0 ;0
L 0.62468996 -2.17061998 0.72245 -2.17061998 0 P 0 ;0
L 0.62393996 -2.16961998 0.7211 -2.16961998 0 P 0 ;0
L 0.62318002 -2.16861998 0.71976004 -2.16861998 0 P 0 ;0
L 0.62243996 -2.16761998 0.71841004 -2.16761998 0 P 0 ;0
L 0.62171004 -2.16661998 0.71726998 -2.16661998 0 P 0 ;0
L 0.62108002 -2.16561998 0.71613996 -2.16561998 0 P 0 ;0
L 0.62043996 -2.16461998 0.71501004 -2.16461998 0 P 0 ;0
L 0.61981004 -2.16361998 0.71388002 -2.16361998 0 P 0 ;0
L 0.61916998 -2.16261998 0.71276004 -2.16261998 0 P 0 ;0
L 0.61853002 -2.16161998 0.71163002 -2.16161998 0 P 0 ;0
L 0.6179 -2.16061998 0.7105 -2.16061998 0 P 0 ;0
L 0.61726004 -2.15961998 0.7094 -2.15961998 0 P 0 ;0
L 0.61665 -2.15861998 0.70845 -2.15861998 0 P 0 ;0
L 0.61611004 -2.15761998 0.7075 -2.15761998 0 P 0 ;0
L 0.75383996 -2.24561998 0.901 -2.24561998 0 P 0 ;0
L 0.74876998 -2.24461998 0.90541998 -2.24461998 0 P 0 ;0
L 0.74431004 -2.24361998 0.90985 -2.24361998 0 P 0 ;0
L 0.7407 -2.24261998 0.91426998 -2.24261998 0 P 0 ;0
L 0.73708002 -2.24161998 0.9187 -2.24161998 0 P 0 ;0
L 0.73346998 -2.24061998 0.92311998 -2.24061998 0 P 0 ;0
L 0.72986004 -2.23961998 0.92753996 -2.23961998 0 P 0 ;0
L 0.72633996 -2.23861998 0.93145 -2.23861998 0 P 0 ;0
L 0.72348996 -2.23761998 0.93473996 -2.23761998 0 P 0 ;0
L 0.72063996 -2.23661998 0.93803996 -2.23661998 0 P 0 ;0
L 0.7178 -2.23561998 0.94133002 -2.23561998 0 P 0 ;0
L 0.71495 -2.23461998 0.94461998 -2.23461998 0 P 0 ;0
L 0.7121 -2.23361998 0.94791998 -2.23361998 0 P 0 ;0
L 0.70968996 -2.23261998 0.95121004 -2.23261998 0 P 0 ;0
L 0.70731004 -2.23161998 0.95451004 -2.23161998 0 P 0 ;0
L 0.70491998 -2.23061998 0.9578 -2.23061998 0 P 0 ;0
L 0.70253996 -2.22961998 0.9611 -2.22961998 0 P 0 ;0
L 0.70015 -2.22861998 0.96431998 -2.22861998 0 P 0 ;0
L 0.0349 -2.3038 0.0349 -1.0038 4 P 0 ;0
L 0.0349 -1.0038 4.5349 -1.0038 4 P 0 ;0
L 4.5349 -1.0038 4.5349 -2.3038 4 P 0 ;0
L 4.5349 -2.3038 0.0349 -2.3038 4 P 0 ;0
L 0.0349 -1.6038 4.5349 -1.6038 4 P 0 ;0
L 0.0349 -1.8038 4.5349 -1.8038 4 P 0 ;0
L 2.4349 -2.1038 4.0349 -2.1038 4 P 0 ;0
L 2.4349 -2.3038 2.4349 -1.8038 4 P 0 ;0
L 3.2349 -2.1038 3.2349 -1.8038 4 P 0 ;0
L 4.0349 -2.3038 4.0349 -1.8038 4 P 0 ;0
L 0.0723999 -1.6844687 0.07906663 -1.69030079 3 P 0 ;0,3=6,5=0.000000
L 0.07906663 -1.69030079 0.08656654 -1.6938 3 P 0 ;0,3=6,5=0.000000
L 0.08656654 -1.6938 0.09323337 -1.6938 3 P 0 ;0,3=6,5=0.000000
L 0.09323337 -1.6938 0.0999001 -1.69030079 3 P 0 ;0,3=6,5=0.000000
L 0.0999001 -1.69030079 0.10490059 -1.6844687 3 P 0 ;0,3=6,5=0.000000
L 0.10490059 -1.6844687 0.1074 -1.67629951 3 P 0 ;0,3=6,5=0.000000
L 0.1074 -1.67629951 0.10573376 -1.66813455 3 P 0 ;0,3=6,5=0.000000
L 0.10573376 -1.66813455 0.10156644 -1.66113396 3 P 0 ;0,3=6,5=0.000000
L 0.10156644 -1.66113396 0.09406654 -1.65646614 3 P 0 ;0,3=6,5=0.000000
L 0.09406654 -1.65646614 0.08406713 -1.65413327 3 P 0 ;0,3=6,5=0.000000
L 0.08406713 -1.65413327 0.07823346 -1.64946762 3 P 0 ;0,3=6,5=0.000000
L 0.07823346 -1.64946762 0.07573248 -1.64130059 3 P 0 ;0,3=6,5=0.000000
L 0.07573248 -1.64130059 0.0774003 -1.63313356 3 P 0 ;0,3=6,5=0.000000
L 0.0774003 -1.63313356 0.08156614 -1.62730148 3 P 0 ;0,3=6,5=0.000000
L 0.08156614 -1.62730148 0.0873997 -1.6238 3 P 0 ;0,3=6,5=0.000000
L 0.0873997 -1.6238 0.09323337 -1.6238 3 P 0 ;0,3=6,5=0.000000
L 0.09323337 -1.6238 0.09906693 -1.62613287 3 P 0 ;0,3=6,5=0.000000
L 0.09906693 -1.62613287 0.10406742 -1.63196713 3 P 0 ;0,3=6,5=0.000000
L 0.1383999 -1.6938 0.1383999 -1.6238 3 P 0 ;0,3=6,5=0.000000
L 0.1734 -1.6238 0.1734 -1.6938 3 P 0 ;0,3=6,5=0.000000
L 0.1734 -1.65880108 0.1383999 -1.65880108 3 P 0 ;0,3=6,5=0.000000
L 0.23856683 -1.6938 0.20523307 -1.6938 3 P 0 ;0,3=6,5=0.000000
L 0.20523307 -1.6938 0.20523307 -1.6238 3 P 0 ;0,3=6,5=0.000000
L 0.20523307 -1.6238 0.23856683 -1.6238 3 P 0 ;0,3=6,5=0.000000
L 0.22523337 -1.65763258 0.20523307 -1.65763258 3 P 0 ;0,3=6,5=0.000000
L 0.30456683 -1.6938 0.27123307 -1.6938 3 P 0 ;0,3=6,5=0.000000
L 0.27123307 -1.6938 0.27123307 -1.6238 3 P 0 ;0,3=6,5=0.000000
L 0.27123307 -1.6238 0.30456683 -1.6238 3 P 0 ;0,3=6,5=0.000000
L 0.29123337 -1.65763258 0.27123307 -1.65763258 3 P 0 ;0,3=6,5=0.000000
L 0.35389921 -1.6238 0.35389921 -1.6938 3 P 0 ;0,3=6,5=0.000000
L 0.33473356 -1.6238 0.37306634 -1.6238 3 P 0 ;0,3=6,5=0.000000
L 0.09489921 -1.7188 0.09489921 -1.7888 3 P 0 ;0,3=7,5=0.000000
L 0.07573356 -1.7188 0.11406634 -1.7188 3 P 0 ;0,3=7,5=0.000000
L 0.1508998 -1.7188 0.17089862 -1.7188 3 P 0 ;0,3=7,5=0.000000
L 0.16089921 -1.7188 0.16089921 -1.7888 3 P 0 ;0,3=7,5=0.000000
L 0.1508998 -1.7888 0.17089862 -1.7888 3 P 0 ;0,3=7,5=0.000000
L 0.22689921 -1.7188 0.22689921 -1.7888 3 P 0 ;0,3=7,5=0.000000
L 0.20773356 -1.7188 0.24606634 -1.7188 3 P 0 ;0,3=7,5=0.000000
L 0.27623307 -1.7188 0.27623307 -1.7888 3 P 0 ;0,3=7,5=0.000000
L 0.27623307 -1.7888 0.30956683 -1.7888 3 P 0 ;0,3=7,5=0.000000
L 0.37556683 -1.7888 0.34223307 -1.7888 3 P 0 ;0,3=7,5=0.000000
L 0.34223307 -1.7888 0.34223307 -1.7188 3 P 0 ;0,3=7,5=0.000000
L 0.34223307 -1.7188 0.37556683 -1.7188 3 P 0 ;0,3=7,5=0.000000
L 0.36223337 -1.75263258 0.34223307 -1.75263258 3 P 0 ;0,3=7,5=0.000000
L 2.5438999 -1.96813563 2.5519 -1.97480089 3 P 0 ;0,3=8,5=0.000000
L 2.5519 -1.97480089 2.5608999 -1.9788 3 P 0 ;0,3=8,5=0.000000
L 2.5608999 -1.9788 2.5689 -1.9788 3 P 0 ;0,3=8,5=0.000000
L 2.5689 -1.9788 2.5769001 -1.97480089 3 P 0 ;0,3=8,5=0.000000
L 2.5769001 -1.97480089 2.58290069 -1.96813563 3 P 0 ;0,3=8,5=0.000000
L 2.58290069 -1.96813563 2.5859 -1.95879941 3 P 0 ;0,3=8,5=0.000000
L 2.5859 -1.95879941 2.58390049 -1.94946811 3 P 0 ;0,3=8,5=0.000000
L 2.58390049 -1.94946811 2.5788997 -1.94146732 3 P 0 ;0,3=8,5=0.000000
L 2.5788997 -1.94146732 2.5698998 -1.93613278 3 P 0 ;0,3=8,5=0.000000
L 2.5698998 -1.93613278 2.55790049 -1.93346663 3 P 0 ;0,3=8,5=0.000000
L 2.55790049 -1.93346663 2.5509002 -1.92813445 3 P 0 ;0,3=8,5=0.000000
L 2.5509002 -1.92813445 2.54789902 -1.91880069 3 P 0 ;0,3=8,5=0.000000
L 2.54789902 -1.91880069 2.54990039 -1.90946683 3 P 0 ;0,3=8,5=0.000000
L 2.54990039 -1.90946683 2.55489931 -1.90280167 3 P 0 ;0,3=8,5=0.000000
L 2.55489931 -1.90280167 2.5618997 -1.8988 3 P 0 ;0,3=8,5=0.000000
L 2.5618997 -1.8988 2.5689 -1.8988 3 P 0 ;0,3=8,5=0.000000
L 2.5689 -1.8988 2.57590039 -1.90146614 3 P 0 ;0,3=8,5=0.000000
L 2.57590039 -1.90146614 2.58190089 -1.90813386 3 P 0 ;0,3=8,5=0.000000
L 2.6648998 -1.90546772 2.65889931 -1.90146614 3 P 0 ;0,3=8,5=0.000000
L 2.65889931 -1.90146614 2.65190079 -1.8988 3 P 0 ;0,3=8,5=0.000000
L 2.65190079 -1.8988 2.64390069 -1.8988 3 P 0 ;0,3=8,5=0.000000
L 2.64390069 -1.8988 2.63489892 -1.90280167 3 P 0 ;0,3=8,5=0.000000
L 2.63489892 -1.90280167 2.62790039 -1.90946683 3 P 0 ;0,3=8,5=0.000000
L 2.62790039 -1.90946683 2.62289961 -1.91746762 3 P 0 ;0,3=8,5=0.000000
L 2.62289961 -1.91746762 2.61889862 -1.93080049 3 P 0 ;0,3=8,5=0.000000
L 2.61889862 -1.93080049 2.61789892 -1.94280039 3 P 0 ;0,3=8,5=0.000000
L 2.61789892 -1.94280039 2.6199003 -1.9548003 3 P 0 ;0,3=8,5=0.000000
L 2.6199003 -1.9548003 2.62289961 -1.96280098 3 P 0 ;0,3=8,5=0.000000
L 2.62289961 -1.96280098 2.6289002 -1.97080177 3 P 0 ;0,3=8,5=0.000000
L 2.6289002 -1.97080177 2.63590049 -1.97613396 3 P 0 ;0,3=8,5=0.000000
L 2.63590049 -1.97613396 2.64289902 -1.9788 3 P 0 ;0,3=8,5=0.000000
L 2.64289902 -1.9788 2.64989941 -1.9788 3 P 0 ;0,3=8,5=0.000000
L 2.64989941 -1.9788 2.6568997 -1.97613396 3 P 0 ;0,3=8,5=0.000000
L 2.6568997 -1.97613396 2.6629003 -1.97213484 3 P 0 ;0,3=8,5=0.000000
L 2.6629003 -1.97213484 2.66790098 -1.96680266 3 P 0 ;0,3=8,5=0.000000
L 2.69589892 -1.9788 2.72089902 -1.8988 3 P 0 ;0,3=8,5=0.000000
L 2.72089902 -1.8988 2.74590098 -1.9788 3 P 0 ;0,3=8,5=0.000000
L 2.73689931 -1.95080118 2.70489882 -1.95080118 3 P 0 ;0,3=8,5=0.000000
L 2.77889961 -1.8988 2.77889961 -1.9788 3 P 0 ;0,3=8,5=0.000000
L 2.77889961 -1.9788 2.8189003 -1.9788 3 P 0 ;0,3=8,5=0.000000
L 2.8969003 -1.9788 2.85689961 -1.9788 3 P 0 ;0,3=8,5=0.000000
L 2.85689961 -1.9788 2.85689961 -1.8988 3 P 0 ;0,3=8,5=0.000000
L 2.85689961 -1.8988 2.8969003 -1.8988 3 P 0 ;0,3=8,5=0.000000
L 2.8809 -1.93746575 2.85689961 -1.93746575 3 P 0 ;0,3=8,5=0.000000
L 3.03289902 -1.9788 3.03289902 -1.8988 3 P 0 ;0,3=8,5=0.000000
L 3.03289902 -1.8988 3.0208998 -1.91479911 3 P 0 ;0,3=8,5=0.000000
L 3.0208998 -1.9788 3.04489833 -1.9788 3 P 0 ;0,3=8,5=0.000000
L 3.11089902 -1.98146604 3.10889951 -1.98013297 3 P 0 ;0,3=8,5=0.000000
L 3.10889951 -1.98013297 3.10889951 -1.97746703 3 P 0 ;0,3=8,5=0.000000
L 3.10889951 -1.97746703 3.11089902 -1.97613396 3 P 0 ;0,3=8,5=0.000000
L 3.11089902 -1.97613396 3.11290039 -1.97746703 3 P 0 ;0,3=8,5=0.000000
L 3.11290039 -1.97746703 3.11290039 -1.98013297 3 P 0 ;0,3=8,5=0.000000
L 3.11290039 -1.98013297 3.11089902 -1.98146604 3 P 0 ;0,3=8,5=0.000000
L 3.11089902 -1.945469 3.10889951 -1.94413346 3 P 0 ;0,3=8,5=0.000000
L 3.10889951 -1.94413346 3.10889951 -1.94146732 3 P 0 ;0,3=8,5=0.000000
L 3.10889951 -1.94146732 3.11089902 -1.94013435 3 P 0 ;0,3=8,5=0.000000
L 3.11089902 -1.94013435 3.11290039 -1.94146732 3 P 0 ;0,3=8,5=0.000000
L 3.11290039 -1.94146732 3.11290039 -1.94413346 3 P 0 ;0,3=8,5=0.000000
L 3.11290039 -1.94413346 3.11089902 -1.945469 3 P 0 ;0,3=8,5=0.000000
L 3.18889902 -1.9788 3.18889902 -1.8988 3 P 0 ;0,3=8,5=0.000000
L 3.18889902 -1.8988 3.1768998 -1.91479911 3 P 0 ;0,3=8,5=0.000000
L 3.1768998 -1.9788 3.20089833 -1.9788 3 P 0 ;0,3=8,5=0.000000
L 2.5138999 -2.23313563 2.5219 -2.23980089 3 P 0 ;0,3=6,5=0.000000
L 2.5219 -2.23980089 2.5308999 -2.2438 3 P 0 ;0,3=6,5=0.000000
L 2.5308999 -2.2438 2.5389 -2.2438 3 P 0 ;0,3=6,5=0.000000
L 2.5389 -2.2438 2.5469001 -2.23980089 3 P 0 ;0,3=6,5=0.000000
L 2.5469001 -2.23980089 2.55290069 -2.23313563 3 P 0 ;0,3=6,5=0.000000
L 2.55290069 -2.23313563 2.5559 -2.22379941 3 P 0 ;0,3=6,5=0.000000
L 2.5559 -2.22379941 2.55390049 -2.21446811 3 P 0 ;0,3=6,5=0.000000
L 2.55390049 -2.21446811 2.5488997 -2.20646732 3 P 0 ;0,3=6,5=0.000000
L 2.5488997 -2.20646732 2.5398998 -2.20113278 3 P 0 ;0,3=6,5=0.000000
L 2.5398998 -2.20113278 2.52790049 -2.19846663 3 P 0 ;0,3=6,5=0.000000
L 2.52790049 -2.19846663 2.5209002 -2.19313445 3 P 0 ;0,3=6,5=0.000000
L 2.5209002 -2.19313445 2.51789902 -2.18380069 3 P 0 ;0,3=6,5=0.000000
L 2.51789902 -2.18380069 2.51990039 -2.17446683 3 P 0 ;0,3=6,5=0.000000
L 2.51990039 -2.17446683 2.52489931 -2.16780167 3 P 0 ;0,3=6,5=0.000000
L 2.52489931 -2.16780167 2.5318997 -2.1638 3 P 0 ;0,3=6,5=0.000000
L 2.5318997 -2.1638 2.5389 -2.1638 3 P 0 ;0,3=6,5=0.000000
L 2.5389 -2.1638 2.54590039 -2.16646614 3 P 0 ;0,3=6,5=0.000000
L 2.54590039 -2.16646614 2.55190089 -2.17313386 3 P 0 ;0,3=6,5=0.000000
L 2.5918999 -2.2438 2.5918999 -2.1638 3 P 0 ;0,3=6,5=0.000000
L 2.6339 -2.1638 2.6339 -2.2438 3 P 0 ;0,3=6,5=0.000000
L 2.6339 -2.20380128 2.5918999 -2.20380128 3 P 0 ;0,3=6,5=0.000000
L 2.7109003 -2.2438 2.67089961 -2.2438 3 P 0 ;0,3=6,5=0.000000
L 2.67089961 -2.2438 2.67089961 -2.1638 3 P 0 ;0,3=6,5=0.000000
L 2.67089961 -2.1638 2.7109003 -2.1638 3 P 0 ;0,3=6,5=0.000000
L 2.6949 -2.20246575 2.67089961 -2.20246575 3 P 0 ;0,3=6,5=0.000000
L 2.7889003 -2.2438 2.74889961 -2.2438 3 P 0 ;0,3=6,5=0.000000
L 2.74889961 -2.2438 2.74889961 -2.1638 3 P 0 ;0,3=6,5=0.000000
L 2.74889961 -2.1638 2.7889003 -2.1638 3 P 0 ;0,3=6,5=0.000000
L 2.7729 -2.20246575 2.74889961 -2.20246575 3 P 0 ;0,3=6,5=0.000000
L 2.84689902 -2.1638 2.84689902 -2.2438 3 P 0 ;0,3=6,5=0.000000
L 2.8239003 -2.1638 2.86989961 -2.1638 3 P 0 ;0,3=6,5=0.000000
L 3.29489961 -1.9238 3.29489961 -2.0038 3 P 0 ;0,3=9,5=0.000000
L 3.29489961 -2.0038 3.3349003 -2.0038 3 P 0 ;0,3=9,5=0.000000
L 3.36789892 -2.0038 3.39289902 -1.9238 3 P 0 ;0,3=9,5=0.000000
L 3.39289902 -1.9238 3.41790098 -2.0038 3 P 0 ;0,3=9,5=0.000000
L 3.40889931 -1.97580118 3.37689882 -1.97580118 3 P 0 ;0,3=9,5=0.000000
L 3.47089902 -2.0038 3.47089902 -1.96780039 3 P 0 ;0,3=9,5=0.000000
L 3.47089902 -1.96780039 3.45089961 -1.9238 3 P 0 ;0,3=9,5=0.000000
L 3.4909003 -1.9238 3.47089902 -1.96780039 3 P 0 ;0,3=9,5=0.000000
L 3.5689003 -2.0038 3.52889961 -2.0038 3 P 0 ;0,3=9,5=0.000000
L 3.52889961 -2.0038 3.52889961 -1.9238 3 P 0 ;0,3=9,5=0.000000
L 3.52889961 -1.9238 3.5689003 -1.9238 3 P 0 ;0,3=9,5=0.000000
L 3.5529 -1.96246575 3.52889961 -1.96246575 3 P 0 ;0,3=9,5=0.000000
L 3.60689961 -2.0038 3.60689961 -1.9238 3 P 0 ;0,3=9,5=0.000000
L 3.60689961 -1.9238 3.6318998 -1.9238 3 P 0 ;0,3=9,5=0.000000
L 3.6318998 -1.9238 3.6398999 -1.92780167 3 P 0 ;0,3=9,5=0.000000
L 3.6398999 -1.92780167 3.64490069 -1.93313386 3 P 0 ;0,3=9,5=0.000000
L 3.64490069 -1.93313386 3.6469003 -1.94380069 3 P 0 ;0,3=9,5=0.000000
L 3.6469003 -1.94380069 3.64490069 -1.95446752 3 P 0 ;0,3=9,5=0.000000
L 3.64490069 -1.95446752 3.6389001 -1.96113278 3 P 0 ;0,3=9,5=0.000000
L 3.6389001 -1.96113278 3.6318998 -1.96513435 3 P 0 ;0,3=9,5=0.000000
L 3.6318998 -1.96513435 3.60689961 -1.96513435 3 P 0 ;0,3=9,5=0.000000
L 3.6318998 -1.96513435 3.6469003 -2.0038 3 P 0 ;0,3=9,5=0.000000
L 3.33989902 -2.2538 3.33189892 -2.25246703 3 P 0 ;0,3=10,5=0.000000
L 3.33189892 -2.25246703 3.32490039 -2.24713484 3 P 0 ;0,3=10,5=0.000000
L 3.32490039 -2.24713484 3.3188999 -2.23913406 3 P 0 ;0,3=10,5=0.000000
L 3.3188999 -2.23913406 3.31489892 -2.2298003 3 P 0 ;0,3=10,5=0.000000
L 3.31489892 -2.2298003 3.31289931 -2.21913346 3 P 0 ;0,3=10,5=0.000000
L 3.31289931 -2.21913346 3.31289931 -2.20846663 3 P 0 ;0,3=10,5=0.000000
L 3.31289931 -2.20846663 3.31489892 -2.1977998 3 P 0 ;0,3=10,5=0.000000
L 3.31489892 -2.1977998 3.3188999 -2.18846604 3 P 0 ;0,3=10,5=0.000000
L 3.3188999 -2.18846604 3.32490039 -2.18046772 3 P 0 ;0,3=10,5=0.000000
L 3.32490039 -2.18046772 3.33189892 -2.17513307 3 P 0 ;0,3=10,5=0.000000
L 3.33189892 -2.17513307 3.33989902 -2.1738 3 P 0 ;0,3=10,5=0.000000
L 3.33989902 -2.1738 3.34789911 -2.17513307 3 P 0 ;0,3=10,5=0.000000
L 3.34789911 -2.17513307 3.35489951 -2.18046772 3 P 0 ;0,3=10,5=0.000000
L 3.35489951 -2.18046772 3.3609 -2.18846604 3 P 0 ;0,3=10,5=0.000000
L 3.3609 -2.18846604 3.36490098 -2.1977998 3 P 0 ;0,3=10,5=0.000000
L 3.36490098 -2.1977998 3.36690059 -2.20846663 3 P 0 ;0,3=10,5=0.000000
L 3.36690059 -2.20846663 3.36690059 -2.21913346 3 P 0 ;0,3=10,5=0.000000
L 3.36690059 -2.21913346 3.36490098 -2.2298003 3 P 0 ;0,3=10,5=0.000000
L 3.36490098 -2.2298003 3.3609 -2.23913406 3 P 0 ;0,3=10,5=0.000000
L 3.3609 -2.23913406 3.35489951 -2.24713484 3 P 0 ;0,3=10,5=0.000000
L 3.35489951 -2.24713484 3.34789911 -2.25246703 3 P 0 ;0,3=10,5=0.000000
L 3.34789911 -2.25246703 3.33989902 -2.2538 3 P 0 ;0,3=10,5=0.000000
L 3.39889941 -2.2538 3.39889941 -2.1738 3 P 0 ;0,3=10,5=0.000000
L 3.39889941 -2.1738 3.43690049 -2.1738 3 P 0 ;0,3=10,5=0.000000
L 3.4228998 -2.21246575 3.39889941 -2.21246575 3 P 0 ;0,3=10,5=0.000000
L 0.16489872 -1.0538 0.16489872 -1.1538 3 P 0 ;0,3=7,5=0.000000
L 0.13423376 -1.0538 0.19556614 -1.0538 3 P 0 ;0,3=7,5=0.000000
L 0.2588997 -1.0538 0.29089774 -1.0538 3 P 0 ;0,3=7,5=0.000000
L 0.27489872 -1.0538 0.27489872 -1.1538 3 P 0 ;0,3=7,5=0.000000
L 0.2588997 -1.1538 0.29089774 -1.1538 3 P 0 ;0,3=7,5=0.000000
L 0.38489872 -1.0538 0.38489872 -1.1538 3 P 0 ;0,3=7,5=0.000000
L 0.35423376 -1.0538 0.41556614 -1.0538 3 P 0 ;0,3=7,5=0.000000
L 0.46823287 -1.0538 0.46823287 -1.1538 3 P 0 ;0,3=7,5=0.000000
L 0.46823287 -1.1538 0.52156703 -1.1538 3 P 0 ;0,3=7,5=0.000000
L 0.63156703 -1.1538 0.57823287 -1.1538 3 P 0 ;0,3=7,5=0.000000
L 0.57823287 -1.1538 0.57823287 -1.0538 3 P 0 ;0,3=7,5=0.000000
L 0.57823287 -1.0538 0.63156703 -1.0538 3 P 0 ;0,3=7,5=0.000000
L 0.61023337 -1.10213219 0.57823287 -1.10213219 3 P 0 ;0,3=7,5=0.000000
L 4.18989892 -1.9538 4.21489902 -1.8738 3 P 0 ;0,3=11,5=0.000000
L 4.21489902 -1.8738 4.23990098 -1.9538 3 P 0 ;0,3=11,5=0.000000
L 4.23089931 -1.92580118 4.19889882 -1.92580118 3 P 0 ;0,3=11,5=0.000000
L 4.27289961 -1.9538 4.27289961 -1.8738 3 P 0 ;0,3=11,5=0.000000
L 4.27289961 -1.8738 4.2978998 -1.8738 3 P 0 ;0,3=11,5=0.000000
L 4.2978998 -1.8738 4.3058999 -1.87780167 3 P 0 ;0,3=11,5=0.000000
L 4.3058999 -1.87780167 4.31090069 -1.88313386 3 P 0 ;0,3=11,5=0.000000
L 4.31090069 -1.88313386 4.3129003 -1.89380069 3 P 0 ;0,3=11,5=0.000000
L 4.3129003 -1.89380069 4.31090069 -1.90446752 3 P 0 ;0,3=11,5=0.000000
L 4.31090069 -1.90446752 4.3049001 -1.91113278 3 P 0 ;0,3=11,5=0.000000
L 4.3049001 -1.91113278 4.2978998 -1.91513435 3 P 0 ;0,3=11,5=0.000000
L 4.2978998 -1.91513435 4.27289961 -1.91513435 3 P 0 ;0,3=11,5=0.000000
L 4.2978998 -1.91513435 4.3129003 -1.9538 3 P 0 ;0,3=11,5=0.000000
L 4.37089902 -1.8738 4.37089902 -1.9538 3 P 0 ;0,3=11,5=0.000000
L 4.3479003 -1.8738 4.39389961 -1.8738 3 P 0 ;0,3=11,5=0.000000
L 3.61989892 -2.2538 3.61989892 -2.1638 3 P 0 ;0,3=12,5=0.000000
L 3.61989892 -2.1638 3.6058997 -2.18179892 3 P 0 ;0,3=12,5=0.000000
L 3.6058997 -2.2538 3.63389803 -2.2538 3 P 0 ;0,3=12,5=0.000000
L 3.68773268 -2.17879961 3.69473337 -2.16980148 3 P 0 ;0,3=12,5=0.000000
L 3.69473337 -2.16980148 3.70290039 -2.1652997 3 P 0 ;0,3=12,5=0.000000
L 3.70290039 -2.1652997 3.71223386 -2.1638 3 P 0 ;0,3=12,5=0.000000
L 3.71223386 -2.1638 3.7239002 -2.16679941 3 P 0 ;0,3=12,5=0.000000
L 3.7239002 -2.16679941 3.73206722 -2.17430059 3 P 0 ;0,3=12,5=0.000000
L 3.73206722 -2.17430059 3.7344001 -2.18329862 3 P 0 ;0,3=12,5=0.000000
L 3.7344001 -2.18329862 3.73323366 -2.19230217 3 P 0 ;0,3=12,5=0.000000
L 3.73323366 -2.19230217 3.72856585 -2.19980059 3 P 0 ;0,3=12,5=0.000000
L 3.72856585 -2.19980059 3.70523317 -2.2148001 3 P 0 ;0,3=12,5=0.000000
L 3.70523317 -2.2148001 3.69473337 -2.22530069 3 P 0 ;0,3=12,5=0.000000
L 3.69473337 -2.22530069 3.68773268 -2.24030295 3 P 0 ;0,3=12,5=0.000000
L 3.68773268 -2.24030295 3.6853998 -2.2538 3 P 0 ;0,3=12,5=0.000000
L 3.6853998 -2.2538 3.7344001 -2.2538 3 P 0 ;0,3=12,5=0.000000
L 0.5058997 -1.6638 0.53389803 -1.6638 3 P 0 ;0,3=13,5=0.000000
L 0.51989892 -1.6638 0.51989892 -1.7538 3 P 0 ;0,3=13,5=0.000000
L 0.5058997 -1.7538 0.53389803 -1.7538 3 P 0 ;0,3=13,5=0.000000
L 0.58306703 -1.7538 0.58306703 -1.6638 3 P 0 ;0,3=13,5=0.000000
L 0.58306703 -1.6638 0.63673287 -1.7538 3 P 0 ;0,3=13,5=0.000000
L 0.63673287 -1.7538 0.63673287 -1.6638 3 P 0 ;0,3=13,5=0.000000
L 0.69989892 -1.6638 0.69989892 -1.7538 3 P 0 ;0,3=13,5=0.000000
L 0.67306703 -1.6638 0.72673287 -1.6638 3 P 0 ;0,3=13,5=0.000000
L 0.81323366 -1.7538 0.76656624 -1.7538 3 P 0 ;0,3=13,5=0.000000
L 0.76656624 -1.7538 0.76656624 -1.6638 3 P 0 ;0,3=13,5=0.000000
L 0.76656624 -1.6638 0.81323366 -1.6638 3 P 0 ;0,3=13,5=0.000000
L 0.79456673 -1.70729902 0.76656624 -1.70729902 3 P 0 ;0,3=13,5=0.000000
L 0.85656624 -1.7538 0.85656624 -1.6638 3 P 0 ;0,3=13,5=0.000000
L 0.85656624 -1.6638 0.88573307 -1.6638 3 P 0 ;0,3=13,5=0.000000
L 0.88573307 -1.6638 0.89506654 -1.66830187 3 P 0 ;0,3=13,5=0.000000
L 0.89506654 -1.66830187 0.90090079 -1.67430059 3 P 0 ;0,3=13,5=0.000000
L 0.90090079 -1.67430059 0.90323366 -1.68630069 3 P 0 ;0,3=13,5=0.000000
L 0.90323366 -1.68630069 0.90090079 -1.69830089 3 P 0 ;0,3=13,5=0.000000
L 0.90090079 -1.69830089 0.8939002 -1.70579931 3 P 0 ;0,3=13,5=0.000000
L 0.8939002 -1.70579931 0.88573307 -1.71030108 3 P 0 ;0,3=13,5=0.000000
L 0.88573307 -1.71030108 0.85656624 -1.71030108 3 P 0 ;0,3=13,5=0.000000
L 0.88573307 -1.71030108 0.90323366 -1.7538 3 P 0 ;0,3=13,5=0.000000
L 0.94306703 -1.7538 0.94306703 -1.6638 3 P 0 ;0,3=13,5=0.000000
L 0.94306703 -1.6638 0.99673287 -1.7538 3 P 0 ;0,3=13,5=0.000000
L 0.99673287 -1.7538 0.99673287 -1.6638 3 P 0 ;0,3=13,5=0.000000
L 1.03073209 -1.7538 1.05989892 -1.6638 3 P 0 ;0,3=13,5=0.000000
L 1.05989892 -1.6638 1.08906782 -1.7538 3 P 0 ;0,3=13,5=0.000000
L 1.07856585 -1.72230128 1.04123189 -1.72230128 3 P 0 ;0,3=13,5=0.000000
L 1.12656624 -1.6638 1.12656624 -1.7538 3 P 0 ;0,3=13,5=0.000000
L 1.12656624 -1.7538 1.17323366 -1.7538 3 P 0 ;0,3=13,5=0.000000
L 1.30656624 -1.6638 1.30656624 -1.7538 3 P 0 ;0,3=13,5=0.000000
L 1.30656624 -1.7538 1.35323366 -1.7538 3 P 0 ;0,3=13,5=0.000000
L 1.39073209 -1.7538 1.41989892 -1.6638 3 P 0 ;0,3=13,5=0.000000
L 1.41989892 -1.6638 1.44906782 -1.7538 3 P 0 ;0,3=13,5=0.000000
L 1.43856585 -1.72230128 1.40123189 -1.72230128 3 P 0 ;0,3=13,5=0.000000
L 1.50989892 -1.7538 1.50989892 -1.71330049 3 P 0 ;0,3=13,5=0.000000
L 1.50989892 -1.71330049 1.48656624 -1.6638 3 P 0 ;0,3=13,5=0.000000
L 1.53323366 -1.6638 1.50989892 -1.71330049 3 P 0 ;0,3=13,5=0.000000
L 1.62323366 -1.7538 1.57656624 -1.7538 3 P 0 ;0,3=13,5=0.000000
L 1.57656624 -1.7538 1.57656624 -1.6638 3 P 0 ;0,3=13,5=0.000000
L 1.57656624 -1.6638 1.62323366 -1.6638 3 P 0 ;0,3=13,5=0.000000
L 1.60456673 -1.70729902 1.57656624 -1.70729902 3 P 0 ;0,3=13,5=0.000000
L 1.66656624 -1.7538 1.66656624 -1.6638 3 P 0 ;0,3=13,5=0.000000
L 1.66656624 -1.6638 1.69573307 -1.6638 3 P 0 ;0,3=13,5=0.000000
L 1.69573307 -1.6638 1.70506654 -1.66830187 3 P 0 ;0,3=13,5=0.000000
L 1.70506654 -1.66830187 1.71090079 -1.67430059 3 P 0 ;0,3=13,5=0.000000
L 1.71090079 -1.67430059 1.71323366 -1.68630069 3 P 0 ;0,3=13,5=0.000000
L 1.71323366 -1.68630069 1.71090079 -1.69830089 3 P 0 ;0,3=13,5=0.000000
L 1.71090079 -1.69830089 1.7039002 -1.70579931 3 P 0 ;0,3=13,5=0.000000
L 1.7039002 -1.70579931 1.69573307 -1.71030108 3 P 0 ;0,3=13,5=0.000000
L 1.69573307 -1.71030108 1.66656624 -1.71030108 3 P 0 ;0,3=13,5=0.000000
L 1.69573307 -1.71030108 1.71323366 -1.7538 3 P 0 ;0,3=13,5=0.000000
L 1.84423346 -1.73580118 1.85123189 -1.74630167 3 P 0 ;0,3=13,5=0.000000
L 1.85123189 -1.74630167 1.86056545 -1.75230039 3 P 0 ;0,3=13,5=0.000000
L 1.86056545 -1.75230039 1.87106742 -1.7538 3 P 0 ;0,3=13,5=0.000000
L 1.87106742 -1.7538 1.88040089 -1.75230039 3 P 0 ;0,3=13,5=0.000000
L 1.88040089 -1.75230039 1.88973435 -1.74480197 3 P 0 ;0,3=13,5=0.000000
L 1.88973435 -1.74480197 1.89556644 -1.73580118 3 P 0 ;0,3=13,5=0.000000
L 1.89556644 -1.73580118 1.89673287 -1.7268003 3 P 0 ;0,3=13,5=0.000000
L 1.89673287 -1.7268003 1.8944001 -1.71630256 3 P 0 ;0,3=13,5=0.000000
L 1.8944001 -1.71630256 1.88623297 -1.70880138 3 P 0 ;0,3=13,5=0.000000
L 1.88623297 -1.70880138 1.87806594 -1.70579931 3 P 0 ;0,3=13,5=0.000000
L 1.87806594 -1.70579931 1.86756604 -1.70579931 3 P 0 ;0,3=13,5=0.000000
L 1.87806594 -1.70579931 1.88506654 -1.7013003 3 P 0 ;0,3=13,5=0.000000
L 1.88506654 -1.7013003 1.89090079 -1.69380187 3 P 0 ;0,3=13,5=0.000000
L 1.89090079 -1.69380187 1.89323366 -1.68480108 3 P 0 ;0,3=13,5=0.000000
L 1.89323366 -1.68480108 1.89090079 -1.6758002 3 P 0 ;0,3=13,5=0.000000
L 1.89090079 -1.6758002 1.88506654 -1.66830187 3 P 0 ;0,3=13,5=0.000000
L 1.88506654 -1.66830187 1.87456673 -1.6638 3 P 0 ;0,3=13,5=0.000000
L 1.87456673 -1.6638 1.86406683 -1.6652997 3 P 0 ;0,3=13,5=0.000000
L 1.86406683 -1.6652997 1.85356693 -1.67130118 3 P 0 ;0,3=13,5=0.000000
L 3.79423346 -1.98580118 3.80123189 -1.99630167 3 P 0 ;0,3=14,5=0.000000
L 3.80123189 -1.99630167 3.81056545 -2.00230039 3 P 0 ;0,3=14,5=0.000000
L 3.81056545 -2.00230039 3.82106742 -2.0038 3 P 0 ;0,3=14,5=0.000000
L 3.82106742 -2.0038 3.83040089 -2.00230039 3 P 0 ;0,3=14,5=0.000000
L 3.83040089 -2.00230039 3.83973435 -1.99480197 3 P 0 ;0,3=14,5=0.000000
L 3.83973435 -1.99480197 3.84556644 -1.98580118 3 P 0 ;0,3=14,5=0.000000
L 3.84556644 -1.98580118 3.84673287 -1.9768003 3 P 0 ;0,3=14,5=0.000000
L 3.84673287 -1.9768003 3.8444001 -1.96630256 3 P 0 ;0,3=14,5=0.000000
L 3.8444001 -1.96630256 3.83623297 -1.95880138 3 P 0 ;0,3=14,5=0.000000
L 3.83623297 -1.95880138 3.82806594 -1.95579931 3 P 0 ;0,3=14,5=0.000000
L 3.82806594 -1.95579931 3.81756604 -1.95579931 3 P 0 ;0,3=14,5=0.000000
L 3.82806594 -1.95579931 3.83506654 -1.9513003 3 P 0 ;0,3=14,5=0.000000
L 3.83506654 -1.9513003 3.84090079 -1.94380187 3 P 0 ;0,3=14,5=0.000000
L 3.84090079 -1.94380187 3.84323366 -1.93480108 3 P 0 ;0,3=14,5=0.000000
L 3.84323366 -1.93480108 3.84090079 -1.9258002 3 P 0 ;0,3=14,5=0.000000
L 3.84090079 -1.9258002 3.83506654 -1.91830187 3 P 0 ;0,3=14,5=0.000000
L 3.83506654 -1.91830187 3.82456673 -1.9138 3 P 0 ;0,3=14,5=0.000000
L 3.82456673 -1.9138 3.81406683 -1.9152997 3 P 0 ;0,3=14,5=0.000000
L 3.81406683 -1.9152997 3.80356693 -1.92130118 3 P 0 ;0,3=14,5=0.000000
L 3.04423346 -2.23580118 3.05123189 -2.24630167 3 P 0 ;0,3=14,5=0.000000
L 3.05123189 -2.24630167 3.06056545 -2.25230039 3 P 0 ;0,3=14,5=0.000000
L 3.06056545 -2.25230039 3.07106742 -2.2538 3 P 0 ;0,3=14,5=0.000000
L 3.07106742 -2.2538 3.08040089 -2.25230039 3 P 0 ;0,3=14,5=0.000000
L 3.08040089 -2.25230039 3.08973435 -2.24480197 3 P 0 ;0,3=14,5=0.000000
L 3.08973435 -2.24480197 3.09556644 -2.23580118 3 P 0 ;0,3=14,5=0.000000
L 3.09556644 -2.23580118 3.09673287 -2.2268003 3 P 0 ;0,3=14,5=0.000000
L 3.09673287 -2.2268003 3.0944001 -2.21630256 3 P 0 ;0,3=14,5=0.000000
L 3.0944001 -2.21630256 3.08623297 -2.20880138 3 P 0 ;0,3=14,5=0.000000
L 3.08623297 -2.20880138 3.07806594 -2.20579931 3 P 0 ;0,3=14,5=0.000000
L 3.07806594 -2.20579931 3.06756604 -2.20579931 3 P 0 ;0,3=14,5=0.000000
L 3.07806594 -2.20579931 3.08506654 -2.2013003 3 P 0 ;0,3=14,5=0.000000
L 3.08506654 -2.2013003 3.09090079 -2.19380187 3 P 0 ;0,3=14,5=0.000000
L 3.09090079 -2.19380187 3.09323366 -2.18480108 3 P 0 ;0,3=14,5=0.000000
L 3.09323366 -2.18480108 3.09090079 -2.1758002 3 P 0 ;0,3=14,5=0.000000
L 3.09090079 -2.1758002 3.08506654 -2.16830187 3 P 0 ;0,3=14,5=0.000000
L 3.08506654 -2.16830187 3.07456673 -2.1638 3 P 0 ;0,3=14,5=0.000000
L 3.07456673 -2.1638 3.06406683 -2.1652997 3 P 0 ;0,3=14,5=0.000000
L 3.06406683 -2.1652997 3.05356693 -2.17130118 3 P 0 ;0,3=14,5=0.000000
L 0.59099833 -1.36499882 0.5990003 -1.35750039 3 P 0 ;0,3=15,5=0.000000
L 0.5990003 -1.35750039 0.60499902 -1.34500315 3 P 0 ;0,3=15,5=0.000000
L 0.60499902 -1.34500315 0.60900187 -1.32749764 3 P 0 ;0,3=15,5=0.000000
L 0.60900187 -1.32749764 0.60499902 -1.31250089 3 P 0 ;0,3=15,5=0.000000
L 0.60499902 -1.31250089 0.59700079 -1.30250305 3 P 0 ;0,3=15,5=0.000000
L 0.59700079 -1.30250305 0.5830001 -1.295 3 P 0 ;0,3=15,5=0.000000
L 0.5830001 -1.295 0.52900059 -1.295 3 P 0 ;0,3=15,5=0.000000
L 0.52900059 -1.295 0.52900059 -1.445 3 P 0 ;0,3=15,5=0.000000
L 0.52900059 -1.445 0.59500118 -1.445 3 P 0 ;0,3=15,5=0.000000
L 0.59500118 -1.445 0.60900187 -1.43500217 3 P 0 ;0,3=15,5=0.000000
L 0.60900187 -1.43500217 0.6170001 -1.42000079 3 P 0 ;0,3=15,5=0.000000
L 0.6170001 -1.42000079 0.62099931 -1.4025 3 P 0 ;0,3=15,5=0.000000
L 0.62099931 -1.4025 0.6170001 -1.38500374 3 P 0 ;0,3=15,5=0.000000
L 0.6170001 -1.38500374 0.60499902 -1.37000236 3 P 0 ;0,3=15,5=0.000000
L 0.60499902 -1.37000236 0.59099833 -1.36499882 3 P 0 ;0,3=15,5=0.000000
L 0.59099833 -1.36499882 0.52900059 -1.36499882 3 P 0 ;0,3=15,5=0.000000
L 0.77100138 -1.445 0.77100138 -1.34500315 3 P 0 ;0,3=15,5=0.000000
L 0.77100138 -1.36249941 0.76299951 -1.35250148 3 P 0 ;0,3=15,5=0.000000
L 0.76299951 -1.35250148 0.75099833 -1.34750256 3 P 0 ;0,3=15,5=0.000000
L 0.75099833 -1.34750256 0.73700138 -1.34500315 3 P 0 ;0,3=15,5=0.000000
L 0.73700138 -1.34500315 0.72300069 -1.35000207 3 P 0 ;0,3=15,5=0.000000
L 0.72300069 -1.35000207 0.71099961 -1.3599999 3 P 0 ;0,3=15,5=0.000000
L 0.71099961 -1.3599999 0.70299764 -1.37500128 3 P 0 ;0,3=15,5=0.000000
L 0.70299764 -1.37500128 0.69899852 -1.39500157 3 P 0 ;0,3=15,5=0.000000
L 0.69899852 -1.39500157 0.70299764 -1.41500187 3 P 0 ;0,3=15,5=0.000000
L 0.70299764 -1.41500187 0.71099961 -1.43000325 3 P 0 ;0,3=15,5=0.000000
L 0.71099961 -1.43000325 0.72300069 -1.44000108 3 P 0 ;0,3=15,5=0.000000
L 0.72300069 -1.44000108 0.73700138 -1.445 3 P 0 ;0,3=15,5=0.000000
L 0.73700138 -1.445 0.75099833 -1.44250059 3 P 0 ;0,3=15,5=0.000000
L 0.75099833 -1.44250059 0.76299951 -1.43500217 3 P 0 ;0,3=15,5=0.000000
L 0.76299951 -1.43500217 0.77100138 -1.42500433 3 P 0 ;0,3=15,5=0.000000
L 0.86700039 -1.445 0.86700039 -1.34500315 3 P 0 ;0,3=15,5=0.000000
L 0.86700039 -1.36499882 0.87699833 -1.35500098 3 P 0 ;0,3=15,5=0.000000
L 0.87699833 -1.35500098 0.8869998 -1.34750256 3 P 0 ;0,3=15,5=0.000000
L 0.8869998 -1.34750256 0.90100049 -1.34500315 3 P 0 ;0,3=15,5=0.000000
L 0.90100049 -1.34500315 0.91099833 -1.34750256 3 P 0 ;0,3=15,5=0.000000
L 0.91099833 -1.34750256 0.92299951 -1.35500098 3 P 0 ;0,3=15,5=0.000000
L 1.02700039 -1.445 1.02700039 -1.34500315 3 P 0 ;0,3=15,5=0.000000
L 1.02700039 -1.36499882 1.03699833 -1.35500098 3 P 0 ;0,3=15,5=0.000000
L 1.03699833 -1.35500098 1.0469998 -1.34750256 3 P 0 ;0,3=15,5=0.000000
L 1.0469998 -1.34750256 1.06100049 -1.34500315 3 P 0 ;0,3=15,5=0.000000
L 1.06100049 -1.34500315 1.07099833 -1.34750256 3 P 0 ;0,3=15,5=0.000000
L 1.07099833 -1.34750256 1.08299951 -1.35500098 3 P 0 ;0,3=15,5=0.000000
L 1.18500089 -1.37750069 1.24900187 -1.37750069 3 P 0 ;0,3=15,5=0.000000
L 1.24900187 -1.37750069 1.24299951 -1.3599999 3 P 0 ;0,3=15,5=0.000000
L 1.24299951 -1.3599999 1.23300157 -1.35000207 3 P 0 ;0,3=15,5=0.000000
L 1.23300157 -1.35000207 1.21900089 -1.34500315 3 P 0 ;0,3=15,5=0.000000
L 1.21900089 -1.34500315 1.2050003 -1.34750256 3 P 0 ;0,3=15,5=0.000000
L 1.2050003 -1.34750256 1.19299911 -1.35500098 3 P 0 ;0,3=15,5=0.000000
L 1.19299911 -1.35500098 1.18500089 -1.37250177 3 P 0 ;0,3=15,5=0.000000
L 1.18500089 -1.37250177 1.18099803 -1.38750315 3 P 0 ;0,3=15,5=0.000000
L 1.18099803 -1.38750315 1.18099803 -1.4025 3 P 0 ;0,3=15,5=0.000000
L 1.18099803 -1.4025 1.18500089 -1.41750138 3 P 0 ;0,3=15,5=0.000000
L 1.18500089 -1.41750138 1.19499872 -1.43250276 3 P 0 ;0,3=15,5=0.000000
L 1.19499872 -1.43250276 1.2069998 -1.44250059 3 P 0 ;0,3=15,5=0.000000
L 1.2069998 -1.44250059 1.22100049 -1.445 3 P 0 ;0,3=15,5=0.000000
L 1.22100049 -1.445 1.23500118 -1.44000108 3 P 0 ;0,3=15,5=0.000000
L 1.23500118 -1.44000108 1.24900187 -1.42500433 3 P 0 ;0,3=15,5=0.000000
L 1.37499813 -1.445 1.37499813 -1.295 3 P 0 ;0,3=15,5=0.000000
L 1.50500089 -1.37750069 1.56900187 -1.37750069 3 P 0 ;0,3=15,5=0.000000
L 1.56900187 -1.37750069 1.56299951 -1.3599999 3 P 0 ;0,3=15,5=0.000000
L 1.56299951 -1.3599999 1.55300157 -1.35000207 3 P 0 ;0,3=15,5=0.000000
L 1.55300157 -1.35000207 1.53900089 -1.34500315 3 P 0 ;0,3=15,5=0.000000
L 1.53900089 -1.34500315 1.5250003 -1.34750256 3 P 0 ;0,3=15,5=0.000000
L 1.5250003 -1.34750256 1.51299911 -1.35500098 3 P 0 ;0,3=15,5=0.000000
L 1.51299911 -1.35500098 1.50500089 -1.37250177 3 P 0 ;0,3=15,5=0.000000
L 1.50500089 -1.37250177 1.50099803 -1.38750315 3 P 0 ;0,3=15,5=0.000000
L 1.50099803 -1.38750315 1.50099803 -1.4025 3 P 0 ;0,3=15,5=0.000000
L 1.50099803 -1.4025 1.50500089 -1.41750138 3 P 0 ;0,3=15,5=0.000000
L 1.50500089 -1.41750138 1.51499872 -1.43250276 3 P 0 ;0,3=15,5=0.000000
L 1.51499872 -1.43250276 1.5269998 -1.44250059 3 P 0 ;0,3=15,5=0.000000
L 1.5269998 -1.44250059 1.54100049 -1.445 3 P 0 ;0,3=15,5=0.000000
L 1.54100049 -1.445 1.55500118 -1.44000108 3 P 0 ;0,3=15,5=0.000000
L 1.55500118 -1.44000108 1.56900187 -1.42500433 3 P 0 ;0,3=15,5=0.000000
L 1.6529998 -1.48999951 1.66500089 -1.49499843 3 P 0 ;0,3=15,5=0.000000
L 1.66500089 -1.49499843 1.68100108 -1.48999951 3 P 0 ;0,3=15,5=0.000000
L 1.68100108 -1.48999951 1.69099902 -1.48000167 3 P 0 ;0,3=15,5=0.000000
L 1.69099902 -1.48000167 1.69900089 -1.4674997 3 P 0 ;0,3=15,5=0.000000
L 1.69900089 -1.4674997 1.71099833 -1.42750374 3 P 0 ;0,3=15,5=0.000000
L 1.71099833 -1.42750374 1.7370001 -1.34500315 3 P 0 ;0,3=15,5=0.000000
L 1.67299911 -1.34500315 1.71099833 -1.42750374 3 P 0 ;0,3=15,5=0.000000
L 1.82500089 -1.37750069 1.88900187 -1.37750069 3 P 0 ;0,3=15,5=0.000000
L 1.88900187 -1.37750069 1.88299951 -1.3599999 3 P 0 ;0,3=15,5=0.000000
L 1.88299951 -1.3599999 1.87300157 -1.35000207 3 P 0 ;0,3=15,5=0.000000
L 1.87300157 -1.35000207 1.85900089 -1.34500315 3 P 0 ;0,3=15,5=0.000000
L 1.85900089 -1.34500315 1.8450003 -1.34750256 3 P 0 ;0,3=15,5=0.000000
L 1.8450003 -1.34750256 1.83299911 -1.35500098 3 P 0 ;0,3=15,5=0.000000
L 1.83299911 -1.35500098 1.82500089 -1.37250177 3 P 0 ;0,3=15,5=0.000000
L 1.82500089 -1.37250177 1.82099803 -1.38750315 3 P 0 ;0,3=15,5=0.000000
L 1.82099803 -1.38750315 1.82099803 -1.4025 3 P 0 ;0,3=15,5=0.000000
L 1.82099803 -1.4025 1.82500089 -1.41750138 3 P 0 ;0,3=15,5=0.000000
L 1.82500089 -1.41750138 1.83499872 -1.43250276 3 P 0 ;0,3=15,5=0.000000
L 1.83499872 -1.43250276 1.8469998 -1.44250059 3 P 0 ;0,3=15,5=0.000000
L 1.8469998 -1.44250059 1.86100049 -1.445 3 P 0 ;0,3=15,5=0.000000
L 1.86100049 -1.445 1.87500118 -1.44000108 3 P 0 ;0,3=15,5=0.000000
L 1.87500118 -1.44000108 1.88900187 -1.42500433 3 P 0 ;0,3=15,5=0.000000
L 2.18699921 -1.37000236 2.22700167 -1.37000236 3 P 0 ;0,3=15,5=0.000000
L 2.22700167 -1.37000236 2.22700167 -1.41500187 3 P 0 ;0,3=15,5=0.000000
L 2.22700167 -1.41500187 2.21500059 -1.43000325 3 P 0 ;0,3=15,5=0.000000
L 2.21500059 -1.43000325 2.2009999 -1.44000108 3 P 0 ;0,3=15,5=0.000000
L 2.2009999 -1.44000108 2.18100049 -1.445 3 P 0 ;0,3=15,5=0.000000
L 2.18100049 -1.445 2.16100108 -1.44000108 3 P 0 ;0,3=15,5=0.000000
L 2.16100108 -1.44000108 2.14700039 -1.43000325 3 P 0 ;0,3=15,5=0.000000
L 2.14700039 -1.43000325 2.13499931 -1.41500187 3 P 0 ;0,3=15,5=0.000000
L 2.13499931 -1.41500187 2.12699734 -1.39750108 3 P 0 ;0,3=15,5=0.000000
L 2.12699734 -1.39750108 2.12299823 -1.37750069 3 P 0 ;0,3=15,5=0.000000
L 2.12299823 -1.37750069 2.12299823 -1.3599999 3 P 0 ;0,3=15,5=0.000000
L 2.12299823 -1.3599999 2.12699734 -1.34500315 3 P 0 ;0,3=15,5=0.000000
L 2.12699734 -1.34500315 2.13499931 -1.32749764 3 P 0 ;0,3=15,5=0.000000
L 2.13499931 -1.32749764 2.14700039 -1.31250089 3 P 0 ;0,3=15,5=0.000000
L 2.14700039 -1.31250089 2.15899783 -1.30250305 3 P 0 ;0,3=15,5=0.000000
L 2.15899783 -1.30250305 2.17499813 -1.295 3 P 0 ;0,3=15,5=0.000000
L 2.17499813 -1.295 2.18899882 -1.295 3 P 0 ;0,3=15,5=0.000000
L 2.18899882 -1.295 2.20499902 -1.29999902 3 P 0 ;0,3=15,5=0.000000
L 2.20499902 -1.29999902 2.2170001 -1.31000138 3 P 0 ;0,3=15,5=0.000000
L 2.29699892 -1.31999931 2.309 -1.30500246 3 P 0 ;0,3=15,5=0.000000
L 2.309 -1.30500246 2.32300069 -1.29749951 3 P 0 ;0,3=15,5=0.000000
L 2.32300069 -1.29749951 2.33900089 -1.295 3 P 0 ;0,3=15,5=0.000000
L 2.33900089 -1.295 2.3590003 -1.29999902 3 P 0 ;0,3=15,5=0.000000
L 2.3590003 -1.29999902 2.37300098 -1.31250089 3 P 0 ;0,3=15,5=0.000000
L 2.37300098 -1.31250089 2.3770001 -1.32749764 3 P 0 ;0,3=15,5=0.000000
L 2.3770001 -1.32749764 2.37500059 -1.34250364 3 P 0 ;0,3=15,5=0.000000
L 2.37500059 -1.34250364 2.36699862 -1.35500098 3 P 0 ;0,3=15,5=0.000000
L 2.36699862 -1.35500098 2.3269998 -1.3800002 3 P 0 ;0,3=15,5=0.000000
L 2.3269998 -1.3800002 2.309 -1.39750108 3 P 0 ;0,3=15,5=0.000000
L 2.309 -1.39750108 2.29699892 -1.42250482 3 P 0 ;0,3=15,5=0.000000
L 2.29699892 -1.42250482 2.2929998 -1.445 3 P 0 ;0,3=15,5=0.000000
L 2.2929998 -1.445 2.3770001 -1.445 3 P 0 ;0,3=15,5=0.000000
L 2.6129998 -1.42500433 2.629 -1.43750167 3 P 0 ;0,3=15,5=0.000000
L 2.629 -1.43750167 2.6469998 -1.445 3 P 0 ;0,3=15,5=0.000000
L 2.6469998 -1.445 2.6630001 -1.445 3 P 0 ;0,3=15,5=0.000000
L 2.6630001 -1.445 2.6790003 -1.43750167 3 P 0 ;0,3=15,5=0.000000
L 2.6790003 -1.43750167 2.69100138 -1.42500433 3 P 0 ;0,3=15,5=0.000000
L 2.69100138 -1.42500433 2.6970001 -1.40749892 3 P 0 ;0,3=15,5=0.000000
L 2.6970001 -1.40749892 2.69300098 -1.39000266 3 P 0 ;0,3=15,5=0.000000
L 2.69300098 -1.39000266 2.68299951 -1.37500128 3 P 0 ;0,3=15,5=0.000000
L 2.68299951 -1.37500128 2.66499961 -1.36499882 3 P 0 ;0,3=15,5=0.000000
L 2.66499961 -1.36499882 2.64100108 -1.3599999 3 P 0 ;0,3=15,5=0.000000
L 2.64100108 -1.3599999 2.62700039 -1.35000207 3 P 0 ;0,3=15,5=0.000000
L 2.62700039 -1.35000207 2.62099803 -1.33250118 3 P 0 ;0,3=15,5=0.000000
L 2.62099803 -1.33250118 2.62500089 -1.31500039 3 P 0 ;0,3=15,5=0.000000
L 2.62500089 -1.31500039 2.63499872 -1.30250305 3 P 0 ;0,3=15,5=0.000000
L 2.63499872 -1.30250305 2.64899941 -1.295 3 P 0 ;0,3=15,5=0.000000
L 2.64899941 -1.295 2.6630001 -1.295 3 P 0 ;0,3=15,5=0.000000
L 2.6630001 -1.295 2.67700079 -1.29999902 3 P 0 ;0,3=15,5=0.000000
L 2.67700079 -1.29999902 2.68900187 -1.31250089 3 P 0 ;0,3=15,5=0.000000
L 2.7729998 -1.445 2.8570001 -1.295 3 P 0 ;0,3=15,5=0.000000
L 2.7729998 -1.295 2.8570001 -1.445 3 P 0 ;0,3=15,5=0.000000
L 2.92299823 -1.445 2.92299823 -1.295 3 P 0 ;0,3=15,5=0.000000
L 2.92299823 -1.295 2.97499813 -1.42000079 3 P 0 ;0,3=15,5=0.000000
L 2.97499813 -1.42000079 3.02700167 -1.295 3 P 0 ;0,3=15,5=0.000000
L 3.02700167 -1.295 3.02700167 -1.445 3 P 0 ;0,3=15,5=0.000000
L 3.09699892 -1.31999931 3.109 -1.30500246 3 P 0 ;0,3=15,5=0.000000
L 3.109 -1.30500246 3.12300069 -1.29749951 3 P 0 ;0,3=15,5=0.000000
L 3.12300069 -1.29749951 3.13900089 -1.295 3 P 0 ;0,3=15,5=0.000000
L 3.13900089 -1.295 3.1590003 -1.29999902 3 P 0 ;0,3=15,5=0.000000
L 3.1590003 -1.29999902 3.17300098 -1.31250089 3 P 0 ;0,3=15,5=0.000000
L 3.17300098 -1.31250089 3.1770001 -1.32749764 3 P 0 ;0,3=15,5=0.000000
L 3.1770001 -1.32749764 3.17500059 -1.34250364 3 P 0 ;0,3=15,5=0.000000
L 3.17500059 -1.34250364 3.16699862 -1.35500098 3 P 0 ;0,3=15,5=0.000000
L 3.16699862 -1.35500098 3.1269998 -1.3800002 3 P 0 ;0,3=15,5=0.000000
L 3.1269998 -1.3800002 3.109 -1.39750108 3 P 0 ;0,3=15,5=0.000000
L 3.109 -1.39750108 3.09699892 -1.42250482 3 P 0 ;0,3=15,5=0.000000
L 3.09699892 -1.42250482 3.0929998 -1.445 3 P 0 ;0,3=15,5=0.000000
L 3.0929998 -1.445 3.1770001 -1.445 3 P 0 ;0,3=15,5=0.000000
L 3.269 -1.39500157 3.3209999 -1.39500157 3 P 0 ;0,3=15,5=0.000000
L 3.41499931 -1.445 3.41499931 -1.295 3 P 0 ;0,3=15,5=0.000000
L 3.41499931 -1.295 3.46499961 -1.295 3 P 0 ;0,3=15,5=0.000000
L 3.46499961 -1.295 3.4809999 -1.30250305 3 P 0 ;0,3=15,5=0.000000
L 3.4809999 -1.30250305 3.49100138 -1.31250089 3 P 0 ;0,3=15,5=0.000000
L 3.49100138 -1.31250089 3.49500059 -1.33250118 3 P 0 ;0,3=15,5=0.000000
L 3.49500059 -1.33250118 3.49100138 -1.35250148 3 P 0 ;0,3=15,5=0.000000
L 3.49100138 -1.35250148 3.4790003 -1.36499882 3 P 0 ;0,3=15,5=0.000000
L 3.4790003 -1.36499882 3.46499961 -1.37250177 3 P 0 ;0,3=15,5=0.000000
L 3.46499961 -1.37250177 3.41499931 -1.37250177 3 P 0 ;0,3=15,5=0.000000
L 3.46499961 -1.37250177 3.49500059 -1.445 3 P 0 ;0,3=15,5=0.000000
L 3.61499813 -1.34500315 3.61499813 -1.445 3 P 0 ;0,3=15,5=0.000000
L 3.61499813 -1.30500246 3.61099902 -1.30250305 3 P 0 ;0,3=15,5=0.000000
L 3.61099902 -1.30250305 3.61099902 -1.29749951 3 P 0 ;0,3=15,5=0.000000
L 3.61099902 -1.29749951 3.61499813 -1.295 3 P 0 ;0,3=15,5=0.000000
L 3.61499813 -1.295 3.61900089 -1.29749951 3 P 0 ;0,3=15,5=0.000000
L 3.61900089 -1.29749951 3.61900089 -1.30250305 3 P 0 ;0,3=15,5=0.000000
L 3.61900089 -1.30250305 3.61499813 -1.30500246 3 P 0 ;0,3=15,5=0.000000
L 3.74500089 -1.42750374 3.75499872 -1.43750167 3 P 0 ;0,3=15,5=0.000000
L 3.75499872 -1.43750167 3.76899941 -1.445 3 P 0 ;0,3=15,5=0.000000
L 3.76899941 -1.445 3.78100049 -1.445 3 P 0 ;0,3=15,5=0.000000
L 3.78100049 -1.445 3.79300157 -1.44000108 3 P 0 ;0,3=15,5=0.000000
L 3.79300157 -1.44000108 3.8009999 -1.43250276 3 P 0 ;0,3=15,5=0.000000
L 3.8009999 -1.43250276 3.80499902 -1.42250482 3 P 0 ;0,3=15,5=0.000000
L 3.80499902 -1.42250482 3.80299951 -1.40749892 3 P 0 ;0,3=15,5=0.000000
L 3.80299951 -1.40749892 3.79500118 -1.40000049 3 P 0 ;0,3=15,5=0.000000
L 3.79500118 -1.40000049 3.75899783 -1.38500374 3 P 0 ;0,3=15,5=0.000000
L 3.75899783 -1.38500374 3.75099961 -1.36749833 3 P 0 ;0,3=15,5=0.000000
L 3.75099961 -1.36749833 3.75499872 -1.35500098 3 P 0 ;0,3=15,5=0.000000
L 3.75499872 -1.35500098 3.76300069 -1.34750256 3 P 0 ;0,3=15,5=0.000000
L 3.76300069 -1.34750256 3.77499813 -1.34500315 3 P 0 ;0,3=15,5=0.000000
L 3.77499813 -1.34500315 3.78699921 -1.34750256 3 P 0 ;0,3=15,5=0.000000
L 3.78699921 -1.34750256 3.7990003 -1.35500098 3 P 0 ;0,3=15,5=0.000000
L 3.90500089 -1.37750069 3.96900187 -1.37750069 3 P 0 ;0,3=15,5=0.000000
L 3.96900187 -1.37750069 3.96299951 -1.3599999 3 P 0 ;0,3=15,5=0.000000
L 3.96299951 -1.3599999 3.95300157 -1.35000207 3 P 0 ;0,3=15,5=0.000000
L 3.95300157 -1.35000207 3.93900089 -1.34500315 3 P 0 ;0,3=15,5=0.000000
L 3.93900089 -1.34500315 3.9250003 -1.34750256 3 P 0 ;0,3=15,5=0.000000
L 3.9250003 -1.34750256 3.91299911 -1.35500098 3 P 0 ;0,3=15,5=0.000000
L 3.91299911 -1.35500098 3.90500089 -1.37250177 3 P 0 ;0,3=15,5=0.000000
L 3.90500089 -1.37250177 3.90099803 -1.38750315 3 P 0 ;0,3=15,5=0.000000
L 3.90099803 -1.38750315 3.90099803 -1.4025 3 P 0 ;0,3=15,5=0.000000
L 3.90099803 -1.4025 3.90500089 -1.41750138 3 P 0 ;0,3=15,5=0.000000
L 3.90500089 -1.41750138 3.91499872 -1.43250276 3 P 0 ;0,3=15,5=0.000000
L 3.91499872 -1.43250276 3.9269998 -1.44250059 3 P 0 ;0,3=15,5=0.000000
L 3.9269998 -1.44250059 3.94100049 -1.445 3 P 0 ;0,3=15,5=0.000000
L 3.94100049 -1.445 3.95500118 -1.44000108 3 P 0 ;0,3=15,5=0.000000
L 3.95500118 -1.44000108 3.96900187 -1.42500433 3 P 0 ;0,3=15,5=0.000000
L 4.06700039 -1.445 4.06700039 -1.34500315 3 P 0 ;0,3=15,5=0.000000
L 4.06700039 -1.36499882 4.07699833 -1.35500098 3 P 0 ;0,3=15,5=0.000000
L 4.07699833 -1.35500098 4.0869998 -1.34750256 3 P 0 ;0,3=15,5=0.000000
L 4.0869998 -1.34750256 4.10100049 -1.34500315 3 P 0 ;0,3=15,5=0.000000
L 4.10100049 -1.34500315 4.11099833 -1.34750256 3 P 0 ;0,3=15,5=0.000000
L 4.11099833 -1.34750256 4.12299951 -1.35500098 3 P 0 ;0,3=15,5=0.000000
L 4.16964783 -2.2038 4.21839813 -2.0478 3 P 0 ;0,3=16,5=0.000000
L 4.21839813 -2.0478 4.26715207 -2.2038 3 P 0 ;0,3=16,5=0.000000
L 4.24959862 -2.14920217 4.18719774 -2.14920217 3 P 0 ;0,3=16,5=0.000000
L 4.37939813 -2.2038 4.37939813 -2.0478 3 P 0 ;0,3=16,5=0.000000
L 4.37939813 -2.0478 4.35599961 -2.07899813 3 P 0 ;0,3=16,5=0.000000
L 4.35599961 -2.2038 4.40279675 -2.2038 3 P 0 ;0,3=16,5=0.000000
L 2.0009002 -0.9538 2.0009002 -0.8038 3 P 0 ;0,3=17,5=0.000000
L 2.0009002 -0.8038 2.04089902 -0.8038 3 P 0 ;0,3=17,5=0.000000
L 2.04089902 -0.8038 2.05689921 -0.81130305 3 P 0 ;0,3=17,5=0.000000
L 2.05689921 -0.81130305 2.0689003 -0.82130089 3 P 0 ;0,3=17,5=0.000000
L 2.0689003 -0.82130089 2.07890187 -0.83629764 3 P 0 ;0,3=17,5=0.000000
L 2.07890187 -0.83629764 2.0869001 -0.85380315 3 P 0 ;0,3=17,5=0.000000
L 2.0869001 -0.85380315 2.0888997 -0.87880236 3 P 0 ;0,3=17,5=0.000000
L 2.0888997 -0.87880236 2.0869001 -0.90380157 3 P 0 ;0,3=17,5=0.000000
L 2.0869001 -0.90380157 2.07890187 -0.92130246 3 P 0 ;0,3=17,5=0.000000
L 2.07890187 -0.92130246 2.0689003 -0.93630374 3 P 0 ;0,3=17,5=0.000000
L 2.0689003 -0.93630374 2.05689921 -0.94630167 3 P 0 ;0,3=17,5=0.000000
L 2.05689921 -0.94630167 2.04089902 -0.9538 3 P 0 ;0,3=17,5=0.000000
L 2.04089902 -0.9538 2.0009002 -0.9538 3 P 0 ;0,3=17,5=0.000000
L 2.15489783 -0.9538 2.20489813 -0.8038 3 P 0 ;0,3=17,5=0.000000
L 2.20489813 -0.8038 2.25490207 -0.9538 3 P 0 ;0,3=17,5=0.000000
L 2.23689862 -0.90130207 2.17289764 -0.90130207 3 P 0 ;0,3=17,5=0.000000
L 2.36489813 -0.8038 2.36489813 -0.9538 3 P 0 ;0,3=17,5=0.000000
L 2.31890059 -0.8038 2.41089931 -0.8038 3 P 0 ;0,3=17,5=0.000000
L 2.56490059 -0.9538 2.48489931 -0.9538 3 P 0 ;0,3=17,5=0.000000
L 2.48489931 -0.9538 2.48489931 -0.8038 3 P 0 ;0,3=17,5=0.000000
L 2.48489931 -0.8038 2.56490059 -0.8038 3 P 0 ;0,3=17,5=0.000000
L 2.5329001 -0.87629833 2.48489931 -0.87629833 3 P 0 ;0,3=17,5=0.000000
L 2.84489813 -0.9538 2.82889783 -0.95130059 3 P 0 ;0,3=17,5=0.000000
L 2.82889783 -0.95130059 2.81490089 -0.94130276 3 P 0 ;0,3=17,5=0.000000
L 2.81490089 -0.94130276 2.8028998 -0.92630138 3 P 0 ;0,3=17,5=0.000000
L 2.8028998 -0.92630138 2.79489783 -0.90880049 3 P 0 ;0,3=17,5=0.000000
L 2.79489783 -0.90880049 2.79089862 -0.8888002 3 P 0 ;0,3=17,5=0.000000
L 2.79089862 -0.8888002 2.79089862 -0.8687999 3 P 0 ;0,3=17,5=0.000000
L 2.79089862 -0.8687999 2.79489783 -0.84879961 3 P 0 ;0,3=17,5=0.000000
L 2.79489783 -0.84879961 2.8028998 -0.83129872 3 P 0 ;0,3=17,5=0.000000
L 2.8028998 -0.83129872 2.81490089 -0.81630197 3 P 0 ;0,3=17,5=0.000000
L 2.81490089 -0.81630197 2.82889783 -0.80629951 3 P 0 ;0,3=17,5=0.000000
L 2.82889783 -0.80629951 2.84489813 -0.8038 3 P 0 ;0,3=17,5=0.000000
L 2.84489813 -0.8038 2.86089833 -0.80629951 3 P 0 ;0,3=17,5=0.000000
L 2.86089833 -0.80629951 2.87489902 -0.81630197 3 P 0 ;0,3=17,5=0.000000
L 2.87489902 -0.81630197 2.8869001 -0.83129872 3 P 0 ;0,3=17,5=0.000000
L 2.8869001 -0.83129872 2.89490207 -0.84879961 3 P 0 ;0,3=17,5=0.000000
L 2.89490207 -0.84879961 2.89890128 -0.8687999 3 P 0 ;0,3=17,5=0.000000
L 2.89890128 -0.8687999 2.89890128 -0.8888002 3 P 0 ;0,3=17,5=0.000000
L 2.89890128 -0.8888002 2.89490207 -0.90880049 3 P 0 ;0,3=17,5=0.000000
L 2.89490207 -0.90880049 2.8869001 -0.92630138 3 P 0 ;0,3=17,5=0.000000
L 2.8869001 -0.92630138 2.87489902 -0.94130276 3 P 0 ;0,3=17,5=0.000000
L 2.87489902 -0.94130276 2.86089833 -0.95130059 3 P 0 ;0,3=17,5=0.000000
L 2.86089833 -0.95130059 2.84489813 -0.9538 3 P 0 ;0,3=17,5=0.000000
L 3.0488997 -0.81630197 3.03689862 -0.80879902 3 P 0 ;0,3=17,5=0.000000
L 3.03689862 -0.80879902 3.02290157 -0.8038 3 P 0 ;0,3=17,5=0.000000
L 3.02290157 -0.8038 3.00690138 -0.8038 3 P 0 ;0,3=17,5=0.000000
L 3.00690138 -0.8038 2.98889783 -0.81130305 3 P 0 ;0,3=17,5=0.000000
L 2.98889783 -0.81130305 2.97490089 -0.82380039 3 P 0 ;0,3=17,5=0.000000
L 2.97490089 -0.82380039 2.96489931 -0.83880177 3 P 0 ;0,3=17,5=0.000000
L 2.96489931 -0.83880177 2.95689734 -0.86380098 3 P 0 ;0,3=17,5=0.000000
L 2.95689734 -0.86380098 2.95489783 -0.88630069 3 P 0 ;0,3=17,5=0.000000
L 2.95489783 -0.88630069 2.95890059 -0.90880049 3 P 0 ;0,3=17,5=0.000000
L 2.95890059 -0.90880049 2.96489931 -0.92380187 3 P 0 ;0,3=17,5=0.000000
L 2.96489931 -0.92380187 2.97690039 -0.93880325 3 P 0 ;0,3=17,5=0.000000
L 2.97690039 -0.93880325 2.99090108 -0.94880108 3 P 0 ;0,3=17,5=0.000000
L 2.99090108 -0.94880108 3.00489813 -0.9538 3 P 0 ;0,3=17,5=0.000000
L 3.00489813 -0.9538 3.01889882 -0.9538 3 P 0 ;0,3=17,5=0.000000
L 3.01889882 -0.9538 3.03289951 -0.94880108 3 P 0 ;0,3=17,5=0.000000
L 3.03289951 -0.94880108 3.04490059 -0.94130276 3 P 0 ;0,3=17,5=0.000000
L 3.04490059 -0.94130276 3.05490207 -0.93130482 3 P 0 ;0,3=17,5=0.000000
L 3.16489813 -0.8038 3.16489813 -0.9538 3 P 0 ;0,3=17,5=0.000000
L 3.11890059 -0.8038 3.21089931 -0.8038 3 P 0 ;0,3=17,5=0.000000
L 3.28889852 -0.95879892 3.36090138 -0.8038 3 P 0 ;0,3=17,5=0.000000
L 3.44689892 -0.82879931 3.4589 -0.81380246 3 P 0 ;0,3=17,5=0.000000
L 3.4589 -0.81380246 3.47290069 -0.80629951 3 P 0 ;0,3=17,5=0.000000
L 3.47290069 -0.80629951 3.48890089 -0.8038 3 P 0 ;0,3=17,5=0.000000
L 3.48890089 -0.8038 3.5089003 -0.80879902 3 P 0 ;0,3=17,5=0.000000
L 3.5089003 -0.80879902 3.52290098 -0.82130089 3 P 0 ;0,3=17,5=0.000000
L 3.52290098 -0.82130089 3.5269001 -0.83629764 3 P 0 ;0,3=17,5=0.000000
L 3.5269001 -0.83629764 3.52490059 -0.85130364 3 P 0 ;0,3=17,5=0.000000
L 3.52490059 -0.85130364 3.51689862 -0.86380098 3 P 0 ;0,3=17,5=0.000000
L 3.51689862 -0.86380098 3.4768998 -0.8888002 3 P 0 ;0,3=17,5=0.000000
L 3.4768998 -0.8888002 3.4589 -0.90630108 3 P 0 ;0,3=17,5=0.000000
L 3.4589 -0.90630108 3.44689892 -0.93130482 3 P 0 ;0,3=17,5=0.000000
L 3.44689892 -0.93130482 3.4428998 -0.9538 3 P 0 ;0,3=17,5=0.000000
L 3.4428998 -0.9538 3.5269001 -0.9538 3 P 0 ;0,3=17,5=0.000000
L 3.64089902 -0.9538 3.64489813 -0.92130246 3 P 0 ;0,3=17,5=0.000000
L 3.64489813 -0.92130246 3.65090049 -0.89380374 3 P 0 ;0,3=17,5=0.000000
L 3.65090049 -0.89380374 3.65889882 -0.8687999 3 P 0 ;0,3=17,5=0.000000
L 3.65889882 -0.8687999 3.6689003 -0.84130118 3 P 0 ;0,3=17,5=0.000000
L 3.6689003 -0.84130118 3.68490059 -0.8038 3 P 0 ;0,3=17,5=0.000000
L 3.68490059 -0.8038 3.60489931 -0.8038 3 P 0 ;0,3=17,5=0.000000
L 3.76889852 -0.95879892 3.84090138 -0.8038 3 P 0 ;0,3=17,5=0.000000
L 3.92689892 -0.82879931 3.9389 -0.81380246 3 P 0 ;0,3=17,5=0.000000
L 3.9389 -0.81380246 3.95290069 -0.80629951 3 P 0 ;0,3=17,5=0.000000
L 3.95290069 -0.80629951 3.96890089 -0.8038 3 P 0 ;0,3=17,5=0.000000
L 3.96890089 -0.8038 3.9889003 -0.80879902 3 P 0 ;0,3=17,5=0.000000
L 3.9889003 -0.80879902 4.00290098 -0.82130089 3 P 0 ;0,3=17,5=0.000000
L 4.00290098 -0.82130089 4.0069001 -0.83629764 3 P 0 ;0,3=17,5=0.000000
L 4.0069001 -0.83629764 4.00490059 -0.85130364 3 P 0 ;0,3=17,5=0.000000
L 4.00490059 -0.85130364 3.99689862 -0.86380098 3 P 0 ;0,3=17,5=0.000000
L 3.99689862 -0.86380098 3.9568998 -0.8888002 3 P 0 ;0,3=17,5=0.000000
L 3.9568998 -0.8888002 3.9389 -0.90630108 3 P 0 ;0,3=17,5=0.000000
L 3.9389 -0.90630108 3.92689892 -0.93130482 3 P 0 ;0,3=17,5=0.000000
L 3.92689892 -0.93130482 3.9228998 -0.9538 3 P 0 ;0,3=17,5=0.000000
L 3.9228998 -0.9538 4.0069001 -0.9538 3 P 0 ;0,3=17,5=0.000000
L 4.12489813 -0.8038 4.10889783 -0.80879902 3 P 0 ;0,3=17,5=0.000000
L 4.10889783 -0.80879902 4.09690039 -0.82130089 3 P 0 ;0,3=17,5=0.000000
L 4.09690039 -0.82130089 4.08889852 -0.83629764 3 P 0 ;0,3=17,5=0.000000
L 4.08889852 -0.83629764 4.0828998 -0.85630256 3 P 0 ;0,3=17,5=0.000000
L 4.0828998 -0.85630256 4.0809002 -0.87880236 3 P 0 ;0,3=17,5=0.000000
L 4.0809002 -0.87880236 4.0828998 -0.90130207 3 P 0 ;0,3=17,5=0.000000
L 4.0828998 -0.90130207 4.08889852 -0.92130246 3 P 0 ;0,3=17,5=0.000000
L 4.08889852 -0.92130246 4.09690039 -0.93630374 3 P 0 ;0,3=17,5=0.000000
L 4.09690039 -0.93630374 4.10889783 -0.94880108 3 P 0 ;0,3=17,5=0.000000
L 4.10889783 -0.94880108 4.12489813 -0.9538 3 P 0 ;0,3=17,5=0.000000
L 4.12489813 -0.9538 4.14089833 -0.94880108 3 P 0 ;0,3=17,5=0.000000
L 4.14089833 -0.94880108 4.15289951 -0.93630374 3 P 0 ;0,3=17,5=0.000000
L 4.15289951 -0.93630374 4.16090138 -0.92130246 3 P 0 ;0,3=17,5=0.000000
L 4.16090138 -0.92130246 4.1669001 -0.90130207 3 P 0 ;0,3=17,5=0.000000
L 4.1669001 -0.90130207 4.1688997 -0.87880236 3 P 0 ;0,3=17,5=0.000000
L 4.1688997 -0.87880236 4.1669001 -0.85630256 3 P 0 ;0,3=17,5=0.000000
L 4.1669001 -0.85630256 4.16090138 -0.83629764 3 P 0 ;0,3=17,5=0.000000
L 4.16090138 -0.83629764 4.15289951 -0.82130089 3 P 0 ;0,3=17,5=0.000000
L 4.15289951 -0.82130089 4.14089833 -0.80879902 3 P 0 ;0,3=17,5=0.000000
L 4.14089833 -0.80879902 4.12489813 -0.8038 3 P 0 ;0,3=17,5=0.000000
L 4.28489813 -0.9538 4.28489813 -0.8038 3 P 0 ;0,3=17,5=0.000000
L 4.28489813 -0.8038 4.26089961 -0.83379823 3 P 0 ;0,3=17,5=0.000000
L 4.26089961 -0.9538 4.30889665 -0.9538 3 P 0 ;0,3=17,5=0.000000
L 4.44089902 -0.9538 4.44489813 -0.92130246 3 P 0 ;0,3=17,5=0.000000
L 4.44489813 -0.92130246 4.45090049 -0.89380374 3 P 0 ;0,3=17,5=0.000000
L 4.45090049 -0.89380374 4.45889882 -0.8687999 3 P 0 ;0,3=17,5=0.000000
L 4.45889882 -0.8687999 4.4689003 -0.84130118 3 P 0 ;0,3=17,5=0.000000
L 4.4689003 -0.84130118 4.48490059 -0.8038 3 P 0 ;0,3=17,5=0.000000
L 4.48490059 -0.8038 4.40489931 -0.8038 3 P 0 ;0,3=17,5=0.000000
L 0.1075 0.8575 0.1075 0.8575 9 P 0 ;1
L 0.1075 4.8075 0.1075 4.8075 9 P 0 ;1
L 0.1575 0.1575 0.1575 0.1575 9 P 0 ;1
L 0.1575 0.2075 0.1575 0.2075 9 P 0 ;1
L 0.1575 0.2575 0.1575 0.2575 9 P 0 ;1
L 0.1575 1.0575 0.1575 1.0575 9 P 0 ;1
L 0.1575 1.1075 0.1575 1.1075 9 P 0 ;1
L 0.1575 1.1575 0.1575 1.1575 9 P 0 ;1
L 0.1575 1.2075 0.1575 1.2075 9 P 0 ;1
L 0.1575 5.5575 0.1575 5.5575 9 P 0 ;1
L 0.1575 5.6075 0.1575 5.6075 9 P 0 ;1
L 0.1575 5.6575 0.1575 5.6575 9 P 0 ;1
L 0.2075 0.1575 0.2075 0.1575 9 P 0 ;1
L 0.2075 0.2075 0.2075 0.2075 9 P 0 ;1
L 0.2075 0.2575 0.2075 0.2575 9 P 0 ;1
L 0.2075 1.0575 0.2075 1.0575 9 P 0 ;1
L 0.2075 1.1075 0.2075 1.1075 9 P 0 ;1
L 0.2075 1.1575 0.2075 1.1575 9 P 0 ;1
L 0.2075 1.2075 0.2075 1.2075 9 P 0 ;1
L 0.2075 5.5575 0.2075 5.5575 9 P 0 ;1
L 0.2075 5.6075 0.2075 5.6075 9 P 0 ;1
L 0.2075 5.6575 0.2075 5.6575 9 P 0 ;1
L 0.2575 0.1575 0.2575 0.1575 9 P 0 ;1
L 0.2575 0.2075 0.2575 0.2075 9 P 0 ;1
L 0.2575 0.2575 0.2575 0.2575 9 P 0 ;1
L 0.2575 1.0575 0.2575 1.0575 9 P 0 ;1
L 0.2575 1.1075 0.2575 1.1075 9 P 0 ;1
L 0.2575 1.1575 0.2575 1.1575 9 P 0 ;1
L 0.2575 1.2075 0.2575 1.2075 9 P 0 ;1
L 0.2575 5.5575 0.2575 5.5575 9 P 0 ;1
L 0.2575 5.6075 0.2575 5.6075 9 P 0 ;1
L 0.2575 5.6575 0.2575 5.6575 9 P 0 ;1
L 0.3075 0.1575 0.3075 0.1575 9 P 0 ;1
L 0.3075 0.2075 0.3075 0.2075 9 P 0 ;1
L 0.3075 0.2575 0.3075 0.2575 9 P 0 ;1
L 0.3075 0.3075 0.3075 0.3075 9 P 0 ;1
L 0.3075 1.0575 0.3075 1.0575 9 P 0 ;1
L 0.3075 1.1075 0.3075 1.1075 9 P 0 ;1
L 0.3075 1.1575 0.3075 1.1575 9 P 0 ;1
L 0.3075 1.2075 0.3075 1.2075 9 P 0 ;1
L 0.3075 5.5075 0.3075 5.5075 9 P 0 ;1
L 0.3075 5.5575 0.3075 5.5575 9 P 0 ;1
L 0.3075 5.6075 0.3075 5.6075 9 P 0 ;1
L 0.3075 5.6575 0.3075 5.6575 9 P 0 ;1
L 0.3075 5.7075 0.3075 5.7075 9 P 0 ;1
L 0.3575 0.1575 0.3575 0.1575 9 P 0 ;1
L 0.3575 0.2075 0.3575 0.2075 9 P 0 ;1
L 0.3575 0.2575 0.3575 0.2575 9 P 0 ;1
L 0.3575 0.3075 0.3575 0.3075 9 P 0 ;1
L 0.3575 0.3575 0.3575 0.3575 9 P 0 ;1
L 0.3575 0.4575 0.3575 0.4575 9 P 0 ;1
L 0.3575 0.5075 0.3575 0.5075 9 P 0 ;1
L 0.3575 0.8575 0.3575 0.8575 9 P 0 ;1
L 0.3575 0.9075 0.3575 0.9075 9 P 0 ;1
L 0.3575 0.9575 0.3575 0.9575 9 P 0 ;1
L 0.3575 1.0075 0.3575 1.0075 9 P 0 ;1
L 0.3575 1.0575 0.3575 1.0575 9 P 0 ;1
L 0.3575 1.1075 0.3575 1.1075 9 P 0 ;1
L 0.3575 1.1575 0.3575 1.1575 9 P 0 ;1
L 0.3575 1.2075 0.3575 1.2075 9 P 0 ;1
L 0.3575 1.2575 0.3575 1.2575 9 P 0 ;1
L 0.3575 4.7075 0.3575 4.7075 9 P 0 ;1
L 0.3575 4.7575 0.3575 4.7575 9 P 0 ;1
L 0.3575 4.8075 0.3575 4.8075 9 P 0 ;1
L 0.3575 4.8575 0.3575 4.8575 9 P 0 ;1
L 0.3575 4.9075 0.3575 4.9075 9 P 0 ;1
L 0.3575 4.9575 0.3575 4.9575 9 P 0 ;1
L 0.3575 5.3075 0.3575 5.3075 9 P 0 ;1
L 0.3575 5.4575 0.3575 5.4575 9 P 0 ;1
L 0.3575 5.5075 0.3575 5.5075 9 P 0 ;1
L 0.3575 5.5575 0.3575 5.5575 9 P 0 ;1
L 0.3575 5.6075 0.3575 5.6075 9 P 0 ;1
L 0.3575 5.6575 0.3575 5.6575 9 P 0 ;1
L 0.3575 5.7075 0.3575 5.7075 9 P 0 ;1
L 0.3575 5.7575 0.3575 5.7575 9 P 0 ;1
L 0.3575 5.8075 0.3575 5.8075 9 P 0 ;1
L 0.3575 5.8575 0.3575 5.8575 9 P 0 ;1
L 0.3575 5.9075 0.3575 5.9075 9 P 0 ;1
L 0.4075 0.1575 0.4075 0.1575 9 P 0 ;1
L 0.4075 0.2075 0.4075 0.2075 9 P 0 ;1
L 0.4075 0.2575 0.4075 0.2575 9 P 0 ;1
L 0.4075 0.3075 0.4075 0.3075 9 P 0 ;1
L 0.4075 0.3575 0.4075 0.3575 9 P 0 ;1
L 0.4075 0.4075 0.4075 0.4075 9 P 0 ;1
L 0.4075 0.4575 0.4075 0.4575 9 P 0 ;1
L 0.4075 0.5075 0.4075 0.5075 9 P 0 ;1
L 0.4075 0.5575 0.4075 0.5575 9 P 0 ;1
L 0.4075 0.6075 0.4075 0.6075 9 P 0 ;1
L 0.4075 0.7575 0.4075 0.7575 9 P 0 ;1
L 0.4075 0.8075 0.4075 0.8075 9 P 0 ;1
L 0.4075 0.8575 0.4075 0.8575 9 P 0 ;1
L 0.4075 0.9075 0.4075 0.9075 9 P 0 ;1
L 0.4075 0.9575 0.4075 0.9575 9 P 0 ;1
L 0.4075 1.0075 0.4075 1.0075 9 P 0 ;1
L 0.4075 1.0575 0.4075 1.0575 9 P 0 ;1
L 0.4075 1.1075 0.4075 1.1075 9 P 0 ;1
L 0.4075 1.1575 0.4075 1.1575 9 P 0 ;1
L 0.4075 1.2075 0.4075 1.2075 9 P 0 ;1
L 0.4075 1.2575 0.4075 1.2575 9 P 0 ;1
L 0.4075 4.7075 0.4075 4.7075 9 P 0 ;1
L 0.4075 4.7575 0.4075 4.7575 9 P 0 ;1
L 0.4075 4.8075 0.4075 4.8075 9 P 0 ;1
L 0.4075 4.8575 0.4075 4.8575 9 P 0 ;1
L 0.4075 4.9075 0.4075 4.9075 9 P 0 ;1
L 0.4075 4.9575 0.4075 4.9575 9 P 0 ;1
L 0.4075 5.0075 0.4075 5.0075 9 P 0 ;1
L 0.4075 5.0575 0.4075 5.0575 9 P 0 ;1
L 0.4075 5.2075 0.4075 5.2075 9 P 0 ;1
L 0.4075 5.2575 0.4075 5.2575 9 P 0 ;1
L 0.4075 5.3075 0.4075 5.3075 9 P 0 ;1
L 0.4075 5.3575 0.4075 5.3575 9 P 0 ;1
L 0.4075 5.4075 0.4075 5.4075 9 P 0 ;1
L 0.4075 5.4575 0.4075 5.4575 9 P 0 ;1
L 0.4075 5.5075 0.4075 5.5075 9 P 0 ;1
L 0.4075 5.5575 0.4075 5.5575 9 P 0 ;1
L 0.4075 5.6075 0.4075 5.6075 9 P 0 ;1
L 0.4075 5.6575 0.4075 5.6575 9 P 0 ;1
L 0.4075 5.7075 0.4075 5.7075 9 P 0 ;1
L 0.4075 5.7575 0.4075 5.7575 9 P 0 ;1
L 0.4075 5.8075 0.4075 5.8075 9 P 0 ;1
L 0.4075 5.8575 0.4075 5.8575 9 P 0 ;1
L 0.4575 0.1575 0.4575 0.1575 9 P 0 ;1
L 0.4575 0.2075 0.4575 0.2075 9 P 0 ;1
L 0.4575 0.2575 0.4575 0.2575 9 P 0 ;1
L 0.4575 0.3075 0.4575 0.3075 9 P 0 ;1
L 0.4575 0.3575 0.4575 0.3575 9 P 0 ;1
L 0.4575 0.4075 0.4575 0.4075 9 P 0 ;1
L 0.4575 0.4575 0.4575 0.4575 9 P 0 ;1
L 0.4575 0.5075 0.4575 0.5075 9 P 0 ;1
L 0.4575 0.5575 0.4575 0.5575 9 P 0 ;1
L 0.4575 0.6075 0.4575 0.6075 9 P 0 ;1
L 0.4575 0.6575 0.4575 0.6575 9 P 0 ;1
L 0.4575 0.7075 0.4575 0.7075 9 P 0 ;1
L 0.4575 0.7575 0.4575 0.7575 9 P 0 ;1
L 0.4575 0.8075 0.4575 0.8075 9 P 0 ;1
L 0.4575 0.8575 0.4575 0.8575 9 P 0 ;1
L 0.4575 0.9075 0.4575 0.9075 9 P 0 ;1
L 0.4575 0.9575 0.4575 0.9575 9 P 0 ;1
L 0.4575 1.0075 0.4575 1.0075 9 P 0 ;1
L 0.4575 1.0575 0.4575 1.0575 9 P 0 ;1
L 0.4575 1.1075 0.4575 1.1075 9 P 0 ;1
L 0.4575 1.1575 0.4575 1.1575 9 P 0 ;1
L 0.4575 1.2075 0.4575 1.2075 9 P 0 ;1
L 0.4575 1.2575 0.4575 1.2575 9 P 0 ;1
L 0.4575 1.3075 0.4575 1.3075 9 P 0 ;1
L 0.4575 1.3575 0.4575 1.3575 9 P 0 ;1
L 0.4575 1.4075 0.4575 1.4075 9 P 0 ;1
L 0.4575 1.4575 0.4575 1.4575 9 P 0 ;1
L 0.4575 1.5075 0.4575 1.5075 9 P 0 ;1
L 0.4575 1.5575 0.4575 1.5575 9 P 0 ;1
L 0.4575 1.6075 0.4575 1.6075 9 P 0 ;1
L 0.4575 1.6575 0.4575 1.6575 9 P 0 ;1
L 0.4575 1.7075 0.4575 1.7075 9 P 0 ;1
L 0.4575 1.7575 0.4575 1.7575 9 P 0 ;1
L 0.4575 1.8075 0.4575 1.8075 9 P 0 ;1
L 0.4575 1.8575 0.4575 1.8575 9 P 0 ;1
L 0.4575 1.9075 0.4575 1.9075 9 P 0 ;1
L 0.4575 1.9575 0.4575 1.9575 9 P 0 ;1
L 0.4575 2.0075 0.4575 2.0075 9 P 0 ;1
L 0.4575 2.0575 0.4575 2.0575 9 P 0 ;1
L 0.4575 2.1075 0.4575 2.1075 9 P 0 ;1
L 0.4575 2.1575 0.4575 2.1575 9 P 0 ;1
L 0.4575 2.2075 0.4575 2.2075 9 P 0 ;1
L 0.4575 2.2575 0.4575 2.2575 9 P 0 ;1
L 0.4575 2.3075 0.4575 2.3075 9 P 0 ;1
L 0.4575 2.3575 0.4575 2.3575 9 P 0 ;1
L 0.4575 2.4075 0.4575 2.4075 9 P 0 ;1
L 0.4575 2.4575 0.4575 2.4575 9 P 0 ;1
L 0.4575 2.5075 0.4575 2.5075 9 P 0 ;1
L 0.4575 2.5575 0.4575 2.5575 9 P 0 ;1
L 0.4575 2.6075 0.4575 2.6075 9 P 0 ;1
L 0.4575 2.6575 0.4575 2.6575 9 P 0 ;1
L 0.4575 2.7075 0.4575 2.7075 9 P 0 ;1
L 0.4575 2.7575 0.4575 2.7575 9 P 0 ;1
L 0.4575 2.8075 0.4575 2.8075 9 P 0 ;1
L 0.4575 2.8575 0.4575 2.8575 9 P 0 ;1
L 0.4575 2.9075 0.4575 2.9075 9 P 0 ;1
L 0.4575 2.9575 0.4575 2.9575 9 P 0 ;1
L 0.4575 3.0075 0.4575 3.0075 9 P 0 ;1
L 0.4575 3.0575 0.4575 3.0575 9 P 0 ;1
L 0.4575 3.1075 0.4575 3.1075 9 P 0 ;1
L 0.4575 3.1575 0.4575 3.1575 9 P 0 ;1
L 0.4575 3.2075 0.4575 3.2075 9 P 0 ;1
L 0.4575 3.2575 0.4575 3.2575 9 P 0 ;1
L 0.4575 3.3075 0.4575 3.3075 9 P 0 ;1
L 0.4575 3.3575 0.4575 3.3575 9 P 0 ;1
L 0.4575 3.4075 0.4575 3.4075 9 P 0 ;1
L 0.4575 3.4575 0.4575 3.4575 9 P 0 ;1
L 0.4575 3.5075 0.4575 3.5075 9 P 0 ;1
L 0.4575 3.5575 0.4575 3.5575 9 P 0 ;1
L 0.4575 3.6075 0.4575 3.6075 9 P 0 ;1
L 0.4575 3.6575 0.4575 3.6575 9 P 0 ;1
L 0.4575 3.7075 0.4575 3.7075 9 P 0 ;1
L 0.4575 3.7575 0.4575 3.7575 9 P 0 ;1
L 0.4575 3.8075 0.4575 3.8075 9 P 0 ;1
L 0.4575 3.8575 0.4575 3.8575 9 P 0 ;1
L 0.4575 3.9075 0.4575 3.9075 9 P 0 ;1
L 0.4575 3.9575 0.4575 3.9575 9 P 0 ;1
L 0.4575 4.0075 0.4575 4.0075 9 P 0 ;1
L 0.4575 4.0575 0.4575 4.0575 9 P 0 ;1
L 0.4575 4.1075 0.4575 4.1075 9 P 0 ;1
L 0.4575 4.1575 0.4575 4.1575 9 P 0 ;1
L 0.4575 4.2075 0.4575 4.2075 9 P 0 ;1
L 0.4575 4.2575 0.4575 4.2575 9 P 0 ;1
L 0.4575 4.3075 0.4575 4.3075 9 P 0 ;1
L 0.4575 4.3575 0.4575 4.3575 9 P 0 ;1
L 0.4575 4.4075 0.4575 4.4075 9 P 0 ;1
L 0.4575 4.4575 0.4575 4.4575 9 P 0 ;1
L 0.4575 4.5075 0.4575 4.5075 9 P 0 ;1
L 0.4575 4.5575 0.4575 4.5575 9 P 0 ;1
L 0.4575 4.6075 0.4575 4.6075 9 P 0 ;1
L 0.4575 4.6575 0.4575 4.6575 9 P 0 ;1
L 0.4575 4.7075 0.4575 4.7075 9 P 0 ;1
L 0.4575 4.7575 0.4575 4.7575 9 P 0 ;1
L 0.4575 4.8075 0.4575 4.8075 9 P 0 ;1
L 0.4575 4.8575 0.4575 4.8575 9 P 0 ;1
L 0.4575 4.9075 0.4575 4.9075 9 P 0 ;1
L 0.4575 4.9575 0.4575 4.9575 9 P 0 ;1
L 0.4575 5.0075 0.4575 5.0075 9 P 0 ;1
L 0.4575 5.0575 0.4575 5.0575 9 P 0 ;1
L 0.4575 5.1075 0.4575 5.1075 9 P 0 ;1
L 0.4575 5.1575 0.4575 5.1575 9 P 0 ;1
L 0.4575 5.2075 0.4575 5.2075 9 P 0 ;1
L 0.4575 5.2575 0.4575 5.2575 9 P 0 ;1
L 0.4575 5.3075 0.4575 5.3075 9 P 0 ;1
L 0.4575 5.3575 0.4575 5.3575 9 P 0 ;1
L 0.4575 5.4075 0.4575 5.4075 9 P 0 ;1
L 0.4575 5.4575 0.4575 5.4575 9 P 0 ;1
L 0.4575 5.5075 0.4575 5.5075 9 P 0 ;1
L 0.4575 5.5575 0.4575 5.5575 9 P 0 ;1
L 0.4575 5.6075 0.4575 5.6075 9 P 0 ;1
L 0.4575 5.6575 0.4575 5.6575 9 P 0 ;1
L 0.4575 5.7075 0.4575 5.7075 9 P 0 ;1
L 0.4575 5.7575 0.4575 5.7575 9 P 0 ;1
L 0.4575 5.8075 0.4575 5.8075 9 P 0 ;1
L 0.5075 0.1575 0.5075 0.1575 9 P 0 ;1
L 0.5075 0.2075 0.5075 0.2075 9 P 0 ;1
L 0.5075 0.2575 0.5075 0.2575 9 P 0 ;1
L 0.5075 0.3075 0.5075 0.3075 9 P 0 ;1
L 0.5075 0.3575 0.5075 0.3575 9 P 0 ;1
L 0.5075 0.4075 0.5075 0.4075 9 P 0 ;1
L 0.5075 0.4575 0.5075 0.4575 9 P 0 ;1
L 0.5075 0.5075 0.5075 0.5075 9 P 0 ;1
L 0.5075 0.5575 0.5075 0.5575 9 P 0 ;1
L 0.5075 0.6075 0.5075 0.6075 9 P 0 ;1
L 0.5075 0.6575 0.5075 0.6575 9 P 0 ;1
L 0.5075 0.7075 0.5075 0.7075 9 P 0 ;1
L 0.5075 0.7575 0.5075 0.7575 9 P 0 ;1
L 0.5075 0.8075 0.5075 0.8075 9 P 0 ;1
L 0.5075 0.8575 0.5075 0.8575 9 P 0 ;1
L 0.5075 0.9075 0.5075 0.9075 9 P 0 ;1
L 0.5075 0.9575 0.5075 0.9575 9 P 0 ;1
L 0.5075 1.0075 0.5075 1.0075 9 P 0 ;1
L 0.5075 1.0575 0.5075 1.0575 9 P 0 ;1
L 0.5075 1.1075 0.5075 1.1075 9 P 0 ;1
L 0.5075 1.1575 0.5075 1.1575 9 P 0 ;1
L 0.5075 1.2075 0.5075 1.2075 9 P 0 ;1
L 0.5075 1.2575 0.5075 1.2575 9 P 0 ;1
L 0.5075 1.3075 0.5075 1.3075 9 P 0 ;1
L 0.5075 1.3575 0.5075 1.3575 9 P 0 ;1
L 0.5075 1.4075 0.5075 1.4075 9 P 0 ;1
L 0.5075 1.4575 0.5075 1.4575 9 P 0 ;1
L 0.5075 1.5075 0.5075 1.5075 9 P 0 ;1
L 0.5075 1.5575 0.5075 1.5575 9 P 0 ;1
L 0.5075 1.6075 0.5075 1.6075 9 P 0 ;1
L 0.5075 1.6575 0.5075 1.6575 9 P 0 ;1
L 0.5075 1.7075 0.5075 1.7075 9 P 0 ;1
L 0.5075 1.7575 0.5075 1.7575 9 P 0 ;1
L 0.5075 1.8075 0.5075 1.8075 9 P 0 ;1
L 0.5075 1.8575 0.5075 1.8575 9 P 0 ;1
L 0.5075 1.9075 0.5075 1.9075 9 P 0 ;1
L 0.5075 1.9575 0.5075 1.9575 9 P 0 ;1
L 0.5075 2.0075 0.5075 2.0075 9 P 0 ;1
L 0.5075 2.0575 0.5075 2.0575 9 P 0 ;1
L 0.5075 2.1075 0.5075 2.1075 9 P 0 ;1
L 0.5075 2.1575 0.5075 2.1575 9 P 0 ;1
L 0.5075 2.2075 0.5075 2.2075 9 P 0 ;1
L 0.5075 2.2575 0.5075 2.2575 9 P 0 ;1
L 0.5075 2.3075 0.5075 2.3075 9 P 0 ;1
L 0.5075 2.3575 0.5075 2.3575 9 P 0 ;1
L 0.5075 2.4075 0.5075 2.4075 9 P 0 ;1
L 0.5075 2.4575 0.5075 2.4575 9 P 0 ;1
L 0.5075 2.5075 0.5075 2.5075 9 P 0 ;1
L 0.5075 2.5575 0.5075 2.5575 9 P 0 ;1
L 0.5075 2.6075 0.5075 2.6075 9 P 0 ;1
L 0.5075 2.6575 0.5075 2.6575 9 P 0 ;1
L 0.5075 2.7075 0.5075 2.7075 9 P 0 ;1
L 0.5075 2.7575 0.5075 2.7575 9 P 0 ;1
L 0.5075 2.8075 0.5075 2.8075 9 P 0 ;1
L 0.5075 2.8575 0.5075 2.8575 9 P 0 ;1
L 0.5075 2.9075 0.5075 2.9075 9 P 0 ;1
L 0.5075 2.9575 0.5075 2.9575 9 P 0 ;1
L 0.5075 3.0075 0.5075 3.0075 9 P 0 ;1
L 0.5075 3.0575 0.5075 3.0575 9 P 0 ;1
L 0.5075 3.1075 0.5075 3.1075 9 P 0 ;1
L 0.5075 3.1575 0.5075 3.1575 9 P 0 ;1
L 0.5075 3.2075 0.5075 3.2075 9 P 0 ;1
L 0.5075 3.2575 0.5075 3.2575 9 P 0 ;1
L 0.5075 3.3075 0.5075 3.3075 9 P 0 ;1
L 0.5075 3.3575 0.5075 3.3575 9 P 0 ;1
L 0.5075 3.4075 0.5075 3.4075 9 P 0 ;1
L 0.5075 3.4575 0.5075 3.4575 9 P 0 ;1
L 0.5075 3.5075 0.5075 3.5075 9 P 0 ;1
L 0.5075 3.5575 0.5075 3.5575 9 P 0 ;1
L 0.5075 3.6075 0.5075 3.6075 9 P 0 ;1
L 0.5075 3.6575 0.5075 3.6575 9 P 0 ;1
L 0.5075 3.7075 0.5075 3.7075 9 P 0 ;1
L 0.5075 3.7575 0.5075 3.7575 9 P 0 ;1
L 0.5075 3.8075 0.5075 3.8075 9 P 0 ;1
L 0.5075 3.8575 0.5075 3.8575 9 P 0 ;1
L 0.5075 3.9075 0.5075 3.9075 9 P 0 ;1
L 0.5075 3.9575 0.5075 3.9575 9 P 0 ;1
L 0.5075 4.0075 0.5075 4.0075 9 P 0 ;1
L 0.5075 4.0575 0.5075 4.0575 9 P 0 ;1
L 0.5075 4.1075 0.5075 4.1075 9 P 0 ;1
L 0.5075 4.1575 0.5075 4.1575 9 P 0 ;1
L 0.5075 4.2075 0.5075 4.2075 9 P 0 ;1
L 0.5075 4.2575 0.5075 4.2575 9 P 0 ;1
L 0.5075 4.3075 0.5075 4.3075 9 P 0 ;1
L 0.5075 4.3575 0.5075 4.3575 9 P 0 ;1
L 0.5075 4.4075 0.5075 4.4075 9 P 0 ;1
L 0.5075 4.4575 0.5075 4.4575 9 P 0 ;1
L 0.5075 4.5075 0.5075 4.5075 9 P 0 ;1
L 0.5075 4.5575 0.5075 4.5575 9 P 0 ;1
L 0.5075 4.6075 0.5075 4.6075 9 P 0 ;1
L 0.5075 4.6575 0.5075 4.6575 9 P 0 ;1
L 0.5075 4.7075 0.5075 4.7075 9 P 0 ;1
L 0.5075 4.7575 0.5075 4.7575 9 P 0 ;1
L 0.5075 4.8075 0.5075 4.8075 9 P 0 ;1
L 0.5075 4.8575 0.5075 4.8575 9 P 0 ;1
L 0.5075 4.9075 0.5075 4.9075 9 P 0 ;1
L 0.5075 4.9575 0.5075 4.9575 9 P 0 ;1
L 0.5075 5.0075 0.5075 5.0075 9 P 0 ;1
L 0.5075 5.0575 0.5075 5.0575 9 P 0 ;1
L 0.5075 5.1075 0.5075 5.1075 9 P 0 ;1
L 0.5075 5.1575 0.5075 5.1575 9 P 0 ;1
L 0.5075 5.2075 0.5075 5.2075 9 P 0 ;1
L 0.5075 5.2575 0.5075 5.2575 9 P 0 ;1
L 0.5075 5.3075 0.5075 5.3075 9 P 0 ;1
L 0.5075 5.3575 0.5075 5.3575 9 P 0 ;1
L 0.5075 5.4075 0.5075 5.4075 9 P 0 ;1
L 0.5075 5.4575 0.5075 5.4575 9 P 0 ;1
L 0.5075 5.5075 0.5075 5.5075 9 P 0 ;1
L 0.5075 5.5575 0.5075 5.5575 9 P 0 ;1
L 0.5075 5.6575 0.5075 5.6575 9 P 0 ;1
L 0.5075 5.7075 0.5075 5.7075 9 P 0 ;1
L 0.5075 5.7575 0.5075 5.7575 9 P 0 ;1
L 0.5075 5.8075 0.5075 5.8075 9 P 0 ;1
L 0.5575 0.1575 0.5575 0.1575 9 P 0 ;1
L 0.5575 0.4075 0.5575 0.4075 9 P 0 ;1
L 0.5575 0.4575 0.5575 0.4575 9 P 0 ;1
L 0.5575 0.5075 0.5575 0.5075 9 P 0 ;1
L 0.5575 0.5575 0.5575 0.5575 9 P 0 ;1
L 0.5575 0.6075 0.5575 0.6075 9 P 0 ;1
L 0.5575 0.6575 0.5575 0.6575 9 P 0 ;1
L 0.5575 0.7075 0.5575 0.7075 9 P 0 ;1
L 0.5575 0.7575 0.5575 0.7575 9 P 0 ;1
L 0.5575 0.8075 0.5575 0.8075 9 P 0 ;1
L 0.5575 0.8575 0.5575 0.8575 9 P 0 ;1
L 0.5575 0.9075 0.5575 0.9075 9 P 0 ;1
L 0.5575 0.9575 0.5575 0.9575 9 P 0 ;1
L 0.5575 1.0075 0.5575 1.0075 9 P 0 ;1
L 0.5575 1.0575 0.5575 1.0575 9 P 0 ;1
L 0.5575 1.1075 0.5575 1.1075 9 P 0 ;1
L 0.5575 1.1575 0.5575 1.1575 9 P 0 ;1
L 0.5575 1.2075 0.5575 1.2075 9 P 0 ;1
L 0.5575 1.2575 0.5575 1.2575 9 P 0 ;1
L 0.5575 1.3075 0.5575 1.3075 9 P 0 ;1
L 0.5575 1.3575 0.5575 1.3575 9 P 0 ;1
L 0.5575 1.4075 0.5575 1.4075 9 P 0 ;1
L 0.5575 1.4575 0.5575 1.4575 9 P 0 ;1
L 0.5575 1.5075 0.5575 1.5075 9 P 0 ;1
L 0.5575 1.5575 0.5575 1.5575 9 P 0 ;1
L 0.5575 1.6075 0.5575 1.6075 9 P 0 ;1
L 0.5575 1.6575 0.5575 1.6575 9 P 0 ;1
L 0.5575 1.7075 0.5575 1.7075 9 P 0 ;1
L 0.5575 1.7575 0.5575 1.7575 9 P 0 ;1
L 0.5575 1.8075 0.5575 1.8075 9 P 0 ;1
L 0.5575 1.8575 0.5575 1.8575 9 P 0 ;1
L 0.5575 1.9075 0.5575 1.9075 9 P 0 ;1
L 0.5575 1.9575 0.5575 1.9575 9 P 0 ;1
L 0.5575 2.0075 0.5575 2.0075 9 P 0 ;1
L 0.5575 2.0575 0.5575 2.0575 9 P 0 ;1
L 0.5575 2.1075 0.5575 2.1075 9 P 0 ;1
L 0.5575 2.1575 0.5575 2.1575 9 P 0 ;1
L 0.5575 2.2075 0.5575 2.2075 9 P 0 ;1
L 0.5575 2.2575 0.5575 2.2575 9 P 0 ;1
L 0.5575 2.3075 0.5575 2.3075 9 P 0 ;1
L 0.5575 2.3575 0.5575 2.3575 9 P 0 ;1
L 0.5575 2.4075 0.5575 2.4075 9 P 0 ;1
L 0.5575 2.4575 0.5575 2.4575 9 P 0 ;1
L 0.5575 2.5075 0.5575 2.5075 9 P 0 ;1
L 0.5575 2.5575 0.5575 2.5575 9 P 0 ;1
L 0.5575 2.6075 0.5575 2.6075 9 P 0 ;1
L 0.5575 2.6575 0.5575 2.6575 9 P 0 ;1
L 0.5575 2.7075 0.5575 2.7075 9 P 0 ;1
L 0.5575 2.7575 0.5575 2.7575 9 P 0 ;1
L 0.5575 2.8075 0.5575 2.8075 9 P 0 ;1
L 0.5575 2.8575 0.5575 2.8575 9 P 0 ;1
L 0.5575 2.9075 0.5575 2.9075 9 P 0 ;1
L 0.5575 2.9575 0.5575 2.9575 9 P 0 ;1
L 0.5575 3.0075 0.5575 3.0075 9 P 0 ;1
L 0.5575 3.0575 0.5575 3.0575 9 P 0 ;1
L 0.5575 3.1075 0.5575 3.1075 9 P 0 ;1
L 0.5575 3.1575 0.5575 3.1575 9 P 0 ;1
L 0.5575 3.2075 0.5575 3.2075 9 P 0 ;1
L 0.5575 3.2575 0.5575 3.2575 9 P 0 ;1
L 0.5575 3.3075 0.5575 3.3075 9 P 0 ;1
L 0.5575 3.3575 0.5575 3.3575 9 P 0 ;1
L 0.5575 3.4075 0.5575 3.4075 9 P 0 ;1
L 0.5575 3.4575 0.5575 3.4575 9 P 0 ;1
L 0.5575 3.5075 0.5575 3.5075 9 P 0 ;1
L 0.5575 3.5575 0.5575 3.5575 9 P 0 ;1
L 0.5575 3.6075 0.5575 3.6075 9 P 0 ;1
L 0.5575 3.6575 0.5575 3.6575 9 P 0 ;1
L 0.5575 3.7075 0.5575 3.7075 9 P 0 ;1
L 0.5575 3.7575 0.5575 3.7575 9 P 0 ;1
L 0.5575 3.8075 0.5575 3.8075 9 P 0 ;1
L 0.5575 3.8575 0.5575 3.8575 9 P 0 ;1
L 0.5575 3.9075 0.5575 3.9075 9 P 0 ;1
L 0.5575 3.9575 0.5575 3.9575 9 P 0 ;1
L 0.5575 4.0075 0.5575 4.0075 9 P 0 ;1
L 0.5575 4.0575 0.5575 4.0575 9 P 0 ;1
L 0.5575 4.1075 0.5575 4.1075 9 P 0 ;1
L 0.5575 4.1575 0.5575 4.1575 9 P 0 ;1
L 0.5575 4.2075 0.5575 4.2075 9 P 0 ;1
L 0.5575 4.2575 0.5575 4.2575 9 P 0 ;1
L 0.5575 4.3075 0.5575 4.3075 9 P 0 ;1
L 0.5575 4.3575 0.5575 4.3575 9 P 0 ;1
L 0.5575 4.4075 0.5575 4.4075 9 P 0 ;1
L 0.5575 4.4575 0.5575 4.4575 9 P 0 ;1
L 0.5575 4.5075 0.5575 4.5075 9 P 0 ;1
L 0.5575 4.5575 0.5575 4.5575 9 P 0 ;1
L 0.5575 4.6075 0.5575 4.6075 9 P 0 ;1
L 0.5575 4.6575 0.5575 4.6575 9 P 0 ;1
L 0.5575 4.7075 0.5575 4.7075 9 P 0 ;1
L 0.5575 4.7575 0.5575 4.7575 9 P 0 ;1
L 0.5575 4.8075 0.5575 4.8075 9 P 0 ;1
L 0.5575 4.8575 0.5575 4.8575 9 P 0 ;1
L 0.5575 4.9075 0.5575 4.9075 9 P 0 ;1
L 0.5575 4.9575 0.5575 4.9575 9 P 0 ;1
L 0.5575 5.0075 0.5575 5.0075 9 P 0 ;1
L 0.5575 5.0575 0.5575 5.0575 9 P 0 ;1
L 0.5575 5.1075 0.5575 5.1075 9 P 0 ;1
L 0.5575 5.1575 0.5575 5.1575 9 P 0 ;1
L 0.5575 5.2075 0.5575 5.2075 9 P 0 ;1
L 0.5575 5.2575 0.5575 5.2575 9 P 0 ;1
L 0.5575 5.3075 0.5575 5.3075 9 P 0 ;1
L 0.5575 5.3575 0.5575 5.3575 9 P 0 ;1
L 0.5575 5.4075 0.5575 5.4075 9 P 0 ;1
L 0.5575 5.4575 0.5575 5.4575 9 P 0 ;1
L 0.5575 5.5075 0.5575 5.5075 9 P 0 ;1
L 0.5575 5.7075 0.5575 5.7075 9 P 0 ;1
L 0.5575 5.7575 0.5575 5.7575 9 P 0 ;1
L 0.5575 5.8075 0.5575 5.8075 9 P 0 ;1
L 0.5575 5.8575 0.5575 5.8575 9 P 0 ;1
L 0.6075 0.1575 0.6075 0.1575 9 P 0 ;1
L 0.6075 0.4575 0.6075 0.4575 9 P 0 ;1
L 0.6075 0.5075 0.6075 0.5075 9 P 0 ;1
L 0.6075 0.5575 0.6075 0.5575 9 P 0 ;1
L 0.6075 0.6075 0.6075 0.6075 9 P 0 ;1
L 0.6075 0.6575 0.6075 0.6575 9 P 0 ;1
L 0.6075 0.7075 0.6075 0.7075 9 P 0 ;1
L 0.6075 0.7575 0.6075 0.7575 9 P 0 ;1
L 0.6075 0.8075 0.6075 0.8075 9 P 0 ;1
L 0.6075 0.8575 0.6075 0.8575 9 P 0 ;1
L 0.6075 0.9075 0.6075 0.9075 9 P 0 ;1
L 0.6075 0.9575 0.6075 0.9575 9 P 0 ;1
L 0.6075 1.0075 0.6075 1.0075 9 P 0 ;1
L 0.6075 1.0575 0.6075 1.0575 9 P 0 ;1
L 0.6075 1.1075 0.6075 1.1075 9 P 0 ;1
L 0.6075 1.1575 0.6075 1.1575 9 P 0 ;1
L 0.6075 1.2075 0.6075 1.2075 9 P 0 ;1
L 0.6075 1.2575 0.6075 1.2575 9 P 0 ;1
L 0.6075 1.3075 0.6075 1.3075 9 P 0 ;1
L 0.6075 1.3575 0.6075 1.3575 9 P 0 ;1
L 0.6075 1.4075 0.6075 1.4075 9 P 0 ;1
L 0.6075 1.4575 0.6075 1.4575 9 P 0 ;1
L 0.6075 1.5075 0.6075 1.5075 9 P 0 ;1
L 0.6075 1.5575 0.6075 1.5575 9 P 0 ;1
L 0.6075 1.7575 0.6075 1.7575 9 P 0 ;1
L 0.6075 2.1075 0.6075 2.1075 9 P 0 ;1
L 0.6075 2.1575 0.6075 2.1575 9 P 0 ;1
L 0.6075 2.2075 0.6075 2.2075 9 P 0 ;1
L 0.6075 2.2575 0.6075 2.2575 9 P 0 ;1
L 0.6075 2.3075 0.6075 2.3075 9 P 0 ;1
L 0.6075 2.3575 0.6075 2.3575 9 P 0 ;1
L 0.6075 2.4075 0.6075 2.4075 9 P 0 ;1
L 0.6075 2.4575 0.6075 2.4575 9 P 0 ;1
L 0.6075 2.5075 0.6075 2.5075 9 P 0 ;1
L 0.6075 2.5575 0.6075 2.5575 9 P 0 ;1
L 0.6075 2.6075 0.6075 2.6075 9 P 0 ;1
L 0.6075 2.6575 0.6075 2.6575 9 P 0 ;1
L 0.6075 2.7075 0.6075 2.7075 9 P 0 ;1
L 0.6075 2.7575 0.6075 2.7575 9 P 0 ;1
L 0.6075 2.8075 0.6075 2.8075 9 P 0 ;1
L 0.6075 2.8575 0.6075 2.8575 9 P 0 ;1
L 0.6075 2.9075 0.6075 2.9075 9 P 0 ;1
L 0.6075 2.9575 0.6075 2.9575 9 P 0 ;1
L 0.6075 3.0075 0.6075 3.0075 9 P 0 ;1
L 0.6075 3.0575 0.6075 3.0575 9 P 0 ;1
L 0.6075 3.1075 0.6075 3.1075 9 P 0 ;1
L 0.6075 3.1575 0.6075 3.1575 9 P 0 ;1
L 0.6075 3.2075 0.6075 3.2075 9 P 0 ;1
L 0.6075 3.2575 0.6075 3.2575 9 P 0 ;1
L 0.6075 3.3075 0.6075 3.3075 9 P 0 ;1
L 0.6075 3.3575 0.6075 3.3575 9 P 0 ;1
L 0.6075 3.4075 0.6075 3.4075 9 P 0 ;1
L 0.6075 3.4575 0.6075 3.4575 9 P 0 ;1
L 0.6075 3.5075 0.6075 3.5075 9 P 0 ;1
L 0.6075 3.5575 0.6075 3.5575 9 P 0 ;1
L 0.6075 3.6075 0.6075 3.6075 9 P 0 ;1
L 0.6075 3.6575 0.6075 3.6575 9 P 0 ;1
L 0.6075 3.7075 0.6075 3.7075 9 P 0 ;1
L 0.6075 3.7575 0.6075 3.7575 9 P 0 ;1
L 0.6075 3.8075 0.6075 3.8075 9 P 0 ;1
L 0.6075 3.8575 0.6075 3.8575 9 P 0 ;1
L 0.6075 3.9075 0.6075 3.9075 9 P 0 ;1
L 0.6075 3.9575 0.6075 3.9575 9 P 0 ;1
L 0.6075 4.0075 0.6075 4.0075 9 P 0 ;1
L 0.6075 4.0575 0.6075 4.0575 9 P 0 ;1
L 0.6075 4.1075 0.6075 4.1075 9 P 0 ;1
L 0.6075 4.1575 0.6075 4.1575 9 P 0 ;1
L 0.6075 4.2075 0.6075 4.2075 9 P 0 ;1
L 0.6075 4.2575 0.6075 4.2575 9 P 0 ;1
L 0.6075 4.3075 0.6075 4.3075 9 P 0 ;1
L 0.6075 4.3575 0.6075 4.3575 9 P 0 ;1
L 0.6075 4.4075 0.6075 4.4075 9 P 0 ;1
L 0.6075 4.4575 0.6075 4.4575 9 P 0 ;1
L 0.6075 4.5075 0.6075 4.5075 9 P 0 ;1
L 0.6075 4.5575 0.6075 4.5575 9 P 0 ;1
L 0.6075 4.6075 0.6075 4.6075 9 P 0 ;1
L 0.6075 4.6575 0.6075 4.6575 9 P 0 ;1
L 0.6075 4.7075 0.6075 4.7075 9 P 0 ;1
L 0.6075 4.7575 0.6075 4.7575 9 P 0 ;1
L 0.6075 4.8075 0.6075 4.8075 9 P 0 ;1
L 0.6075 4.8575 0.6075 4.8575 9 P 0 ;1
L 0.6075 4.9075 0.6075 4.9075 9 P 0 ;1
L 0.6075 4.9575 0.6075 4.9575 9 P 0 ;1
L 0.6075 5.0075 0.6075 5.0075 9 P 0 ;1
L 0.6075 5.0575 0.6075 5.0575 9 P 0 ;1
L 0.6075 5.1075 0.6075 5.1075 9 P 0 ;1
L 0.6075 5.1575 0.6075 5.1575 9 P 0 ;1
L 0.6075 5.2075 0.6075 5.2075 9 P 0 ;1
L 0.6075 5.2575 0.6075 5.2575 9 P 0 ;1
L 0.6075 5.3075 0.6075 5.3075 9 P 0 ;1
L 0.6075 5.3575 0.6075 5.3575 9 P 0 ;1
L 0.6075 5.4075 0.6075 5.4075 9 P 0 ;1
L 0.6075 5.4575 0.6075 5.4575 9 P 0 ;1
L 0.6075 5.5075 0.6075 5.5075 9 P 0 ;1
L 0.6075 5.7075 0.6075 5.7075 9 P 0 ;1
L 0.6075 5.7575 0.6075 5.7575 9 P 0 ;1
L 0.6075 5.8075 0.6075 5.8075 9 P 0 ;1
L 0.6075 5.8575 0.6075 5.8575 9 P 0 ;1
L 0.6075 5.9075 0.6075 5.9075 9 P 0 ;1
L 0.6575 0.4575 0.6575 0.4575 9 P 0 ;1
L 0.6575 0.5075 0.6575 0.5075 9 P 0 ;1
L 0.6575 0.5575 0.6575 0.5575 9 P 0 ;1
L 0.6575 0.6075 0.6575 0.6075 9 P 0 ;1
L 0.6575 0.6575 0.6575 0.6575 9 P 0 ;1
L 0.6575 0.7075 0.6575 0.7075 9 P 0 ;1
L 0.6575 0.7575 0.6575 0.7575 9 P 0 ;1
L 0.6575 0.8075 0.6575 0.8075 9 P 0 ;1
L 0.6575 0.8575 0.6575 0.8575 9 P 0 ;1
L 0.6575 0.9075 0.6575 0.9075 9 P 0 ;1
L 0.6575 0.9575 0.6575 0.9575 9 P 0 ;1
L 0.6575 1.0075 0.6575 1.0075 9 P 0 ;1
L 0.6575 1.0575 0.6575 1.0575 9 P 0 ;1
L 0.6575 1.1075 0.6575 1.1075 9 P 0 ;1
L 0.6575 1.1575 0.6575 1.1575 9 P 0 ;1
L 0.6575 1.2075 0.6575 1.2075 9 P 0 ;1
L 0.6575 1.2575 0.6575 1.2575 9 P 0 ;1
L 0.6575 1.3075 0.6575 1.3075 9 P 0 ;1
L 0.6575 1.3575 0.6575 1.3575 9 P 0 ;1
L 0.6575 1.4075 0.6575 1.4075 9 P 0 ;1
L 0.6575 1.4575 0.6575 1.4575 9 P 0 ;1
L 0.6575 1.5075 0.6575 1.5075 9 P 0 ;1
L 0.6575 1.5575 0.6575 1.5575 9 P 0 ;1
L 0.6575 1.7575 0.6575 1.7575 9 P 0 ;1
L 0.6575 2.1575 0.6575 2.1575 9 P 0 ;1
L 0.6575 2.2075 0.6575 2.2075 9 P 0 ;1
L 0.6575 2.2575 0.6575 2.2575 9 P 0 ;1
L 0.6575 2.3075 0.6575 2.3075 9 P 0 ;1
L 0.6575 2.3575 0.6575 2.3575 9 P 0 ;1
L 0.6575 2.4075 0.6575 2.4075 9 P 0 ;1
L 0.6575 2.4575 0.6575 2.4575 9 P 0 ;1
L 0.6575 2.5075 0.6575 2.5075 9 P 0 ;1
L 0.6575 2.5575 0.6575 2.5575 9 P 0 ;1
L 0.6575 2.6075 0.6575 2.6075 9 P 0 ;1
L 0.6575 2.6575 0.6575 2.6575 9 P 0 ;1
L 0.6575 2.7075 0.6575 2.7075 9 P 0 ;1
L 0.6575 2.7575 0.6575 2.7575 9 P 0 ;1
L 0.6575 2.8075 0.6575 2.8075 9 P 0 ;1
L 0.6575 2.8575 0.6575 2.8575 9 P 0 ;1
L 0.6575 2.9075 0.6575 2.9075 9 P 0 ;1
L 0.6575 2.9575 0.6575 2.9575 9 P 0 ;1
L 0.6575 3.0075 0.6575 3.0075 9 P 0 ;1
L 0.6575 3.0575 0.6575 3.0575 9 P 0 ;1
L 0.6575 3.1075 0.6575 3.1075 9 P 0 ;1
L 0.6575 3.1575 0.6575 3.1575 9 P 0 ;1
L 0.6575 3.2075 0.6575 3.2075 9 P 0 ;1
L 0.6575 3.2575 0.6575 3.2575 9 P 0 ;1
L 0.6575 3.3075 0.6575 3.3075 9 P 0 ;1
L 0.6575 3.3575 0.6575 3.3575 9 P 0 ;1
L 0.6575 3.4075 0.6575 3.4075 9 P 0 ;1
L 0.6575 3.4575 0.6575 3.4575 9 P 0 ;1
L 0.6575 3.5075 0.6575 3.5075 9 P 0 ;1
L 0.6575 3.5575 0.6575 3.5575 9 P 0 ;1
L 0.6575 3.6075 0.6575 3.6075 9 P 0 ;1
L 0.6575 3.6575 0.6575 3.6575 9 P 0 ;1
L 0.6575 3.7075 0.6575 3.7075 9 P 0 ;1
L 0.6575 3.7575 0.6575 3.7575 9 P 0 ;1
L 0.6575 3.8075 0.6575 3.8075 9 P 0 ;1
L 0.6575 3.8575 0.6575 3.8575 9 P 0 ;1
L 0.6575 3.9075 0.6575 3.9075 9 P 0 ;1
L 0.6575 3.9575 0.6575 3.9575 9 P 0 ;1
L 0.6575 4.0075 0.6575 4.0075 9 P 0 ;1
L 0.6575 4.0575 0.6575 4.0575 9 P 0 ;1
L 0.6575 4.1075 0.6575 4.1075 9 P 0 ;1
L 0.6575 4.1575 0.6575 4.1575 9 P 0 ;1
L 0.6575 4.2075 0.6575 4.2075 9 P 0 ;1
L 0.6575 4.2575 0.6575 4.2575 9 P 0 ;1
L 0.6575 4.3075 0.6575 4.3075 9 P 0 ;1
L 0.6575 4.3575 0.6575 4.3575 9 P 0 ;1
L 0.6575 4.4075 0.6575 4.4075 9 P 0 ;1
L 0.6575 4.4575 0.6575 4.4575 9 P 0 ;1
L 0.6575 4.5075 0.6575 4.5075 9 P 0 ;1
L 0.6575 4.5575 0.6575 4.5575 9 P 0 ;1
L 0.6575 4.6075 0.6575 4.6075 9 P 0 ;1
L 0.6575 4.6575 0.6575 4.6575 9 P 0 ;1
L 0.6575 4.7075 0.6575 4.7075 9 P 0 ;1
L 0.6575 4.7575 0.6575 4.7575 9 P 0 ;1
L 0.6575 4.8075 0.6575 4.8075 9 P 0 ;1
L 0.6575 4.8575 0.6575 4.8575 9 P 0 ;1
L 0.6575 4.9075 0.6575 4.9075 9 P 0 ;1
L 0.6575 5.0075 0.6575 5.0075 9 P 0 ;1
L 0.6575 5.0575 0.6575 5.0575 9 P 0 ;1
L 0.6575 5.1075 0.6575 5.1075 9 P 0 ;1
L 0.6575 5.5075 0.6575 5.5075 9 P 0 ;1
L 0.6575 5.5575 0.6575 5.5575 9 P 0 ;1
L 0.6575 5.6075 0.6575 5.6075 9 P 0 ;1
L 0.6575 5.6575 0.6575 5.6575 9 P 0 ;1
L 0.6575 5.7075 0.6575 5.7075 9 P 0 ;1
L 0.7075 0.1575 0.7075 0.1575 9 P 0 ;1
L 0.7075 0.4575 0.7075 0.4575 9 P 0 ;1
L 0.7075 0.5075 0.7075 0.5075 9 P 0 ;1
L 0.7075 0.5575 0.7075 0.5575 9 P 0 ;1
L 0.7075 0.6075 0.7075 0.6075 9 P 0 ;1
L 0.7075 0.6575 0.7075 0.6575 9 P 0 ;1
L 0.7075 0.7075 0.7075 0.7075 9 P 0 ;1
L 0.7075 0.7575 0.7075 0.7575 9 P 0 ;1
L 0.7075 0.8075 0.7075 0.8075 9 P 0 ;1
L 0.7075 0.8575 0.7075 0.8575 9 P 0 ;1
L 0.7075 0.9075 0.7075 0.9075 9 P 0 ;1
L 0.7075 0.9575 0.7075 0.9575 9 P 0 ;1
L 0.7075 1.0075 0.7075 1.0075 9 P 0 ;1
L 0.7075 1.0575 0.7075 1.0575 9 P 0 ;1
L 0.7075 1.1075 0.7075 1.1075 9 P 0 ;1
L 0.7075 1.1575 0.7075 1.1575 9 P 0 ;1
L 0.7075 1.2075 0.7075 1.2075 9 P 0 ;1
L 0.7075 1.2575 0.7075 1.2575 9 P 0 ;1
L 0.7075 1.3075 0.7075 1.3075 9 P 0 ;1
L 0.7075 1.3575 0.7075 1.3575 9 P 0 ;1
L 0.7075 1.4075 0.7075 1.4075 9 P 0 ;1
L 0.7075 1.4575 0.7075 1.4575 9 P 0 ;1
L 0.7075 1.5075 0.7075 1.5075 9 P 0 ;1
L 0.7075 1.5575 0.7075 1.5575 9 P 0 ;1
L 0.7075 1.7575 0.7075 1.7575 9 P 0 ;1
L 0.7075 2.1575 0.7075 2.1575 9 P 0 ;1
L 0.7075 2.2075 0.7075 2.2075 9 P 0 ;1
L 0.7075 2.2575 0.7075 2.2575 9 P 0 ;1
L 0.7075 2.3075 0.7075 2.3075 9 P 0 ;1
L 0.7075 2.3575 0.7075 2.3575 9 P 0 ;1
L 0.7075 2.4075 0.7075 2.4075 9 P 0 ;1
L 0.7075 2.4575 0.7075 2.4575 9 P 0 ;1
L 0.7075 2.5075 0.7075 2.5075 9 P 0 ;1
L 0.7075 2.5575 0.7075 2.5575 9 P 0 ;1
L 0.7075 2.6075 0.7075 2.6075 9 P 0 ;1
L 0.7075 2.6575 0.7075 2.6575 9 P 0 ;1
L 0.7075 2.7075 0.7075 2.7075 9 P 0 ;1
L 0.7075 2.7575 0.7075 2.7575 9 P 0 ;1
L 0.7075 2.8075 0.7075 2.8075 9 P 0 ;1
L 0.7075 2.8575 0.7075 2.8575 9 P 0 ;1
L 0.7075 2.9075 0.7075 2.9075 9 P 0 ;1
L 0.7075 2.9575 0.7075 2.9575 9 P 0 ;1
L 0.7075 3.0075 0.7075 3.0075 9 P 0 ;1
L 0.7075 3.0575 0.7075 3.0575 9 P 0 ;1
L 0.7075 3.1075 0.7075 3.1075 9 P 0 ;1
L 0.7075 3.1575 0.7075 3.1575 9 P 0 ;1
L 0.7075 3.2075 0.7075 3.2075 9 P 0 ;1
L 0.7075 3.2575 0.7075 3.2575 9 P 0 ;1
L 0.7075 3.3075 0.7075 3.3075 9 P 0 ;1
L 0.7075 3.3575 0.7075 3.3575 9 P 0 ;1
L 0.7075 3.4075 0.7075 3.4075 9 P 0 ;1
L 0.7075 3.4575 0.7075 3.4575 9 P 0 ;1
L 0.7075 3.5075 0.7075 3.5075 9 P 0 ;1
L 0.7075 3.5575 0.7075 3.5575 9 P 0 ;1
L 0.7075 3.6075 0.7075 3.6075 9 P 0 ;1
L 0.7075 3.6575 0.7075 3.6575 9 P 0 ;1
L 0.7075 3.7075 0.7075 3.7075 9 P 0 ;1
L 0.7075 3.7575 0.7075 3.7575 9 P 0 ;1
L 0.7075 3.8075 0.7075 3.8075 9 P 0 ;1
L 0.7075 3.8575 0.7075 3.8575 9 P 0 ;1
L 0.7075 3.9075 0.7075 3.9075 9 P 0 ;1
L 0.7075 3.9575 0.7075 3.9575 9 P 0 ;1
L 0.7075 4.0075 0.7075 4.0075 9 P 0 ;1
L 0.7075 4.0575 0.7075 4.0575 9 P 0 ;1
L 0.7075 4.1075 0.7075 4.1075 9 P 0 ;1
L 0.7075 4.1575 0.7075 4.1575 9 P 0 ;1
L 0.7075 4.2075 0.7075 4.2075 9 P 0 ;1
L 0.7075 4.2575 0.7075 4.2575 9 P 0 ;1
L 0.7075 4.3075 0.7075 4.3075 9 P 0 ;1
L 0.7075 4.3575 0.7075 4.3575 9 P 0 ;1
L 0.7075 4.4075 0.7075 4.4075 9 P 0 ;1
L 0.7075 4.4575 0.7075 4.4575 9 P 0 ;1
L 0.7075 4.5075 0.7075 4.5075 9 P 0 ;1
L 0.7075 4.5575 0.7075 4.5575 9 P 0 ;1
L 0.7075 4.6075 0.7075 4.6075 9 P 0 ;1
L 0.7075 4.6575 0.7075 4.6575 9 P 0 ;1
L 0.7075 4.7075 0.7075 4.7075 9 P 0 ;1
L 0.7075 4.7575 0.7075 4.7575 9 P 0 ;1
L 0.7075 4.8075 0.7075 4.8075 9 P 0 ;1
L 0.7075 4.8575 0.7075 4.8575 9 P 0 ;1
L 0.7075 5.0575 0.7075 5.0575 9 P 0 ;1
L 0.7575 0.1575 0.7575 0.1575 9 P 0 ;1
L 0.7575 0.4075 0.7575 0.4075 9 P 0 ;1
L 0.7575 0.4575 0.7575 0.4575 9 P 0 ;1
L 0.7575 0.5075 0.7575 0.5075 9 P 0 ;1
L 0.7575 0.5575 0.7575 0.5575 9 P 0 ;1
L 0.7575 0.6075 0.7575 0.6075 9 P 0 ;1
L 0.7575 0.6575 0.7575 0.6575 9 P 0 ;1
L 0.7575 0.7075 0.7575 0.7075 9 P 0 ;1
L 0.7575 0.7575 0.7575 0.7575 9 P 0 ;1
L 0.7575 0.8075 0.7575 0.8075 9 P 0 ;1
L 0.7575 0.8575 0.7575 0.8575 9 P 0 ;1
L 0.7575 0.9075 0.7575 0.9075 9 P 0 ;1
L 0.7575 0.9575 0.7575 0.9575 9 P 0 ;1
L 0.7575 1.0075 0.7575 1.0075 9 P 0 ;1
L 0.7575 1.0575 0.7575 1.0575 9 P 0 ;1
L 0.7575 1.1075 0.7575 1.1075 9 P 0 ;1
L 0.7575 1.1575 0.7575 1.1575 9 P 0 ;1
L 0.7575 1.2075 0.7575 1.2075 9 P 0 ;1
L 0.7575 1.2575 0.7575 1.2575 9 P 0 ;1
L 0.7575 1.3075 0.7575 1.3075 9 P 0 ;1
L 0.7575 1.3575 0.7575 1.3575 9 P 0 ;1
L 0.7575 1.4075 0.7575 1.4075 9 P 0 ;1
L 0.7575 1.4575 0.7575 1.4575 9 P 0 ;1
L 0.7575 1.6075 0.7575 1.6075 9 P 0 ;1
L 0.7575 1.6575 0.7575 1.6575 9 P 0 ;1
L 0.7575 1.7075 0.7575 1.7075 9 P 0 ;1
L 0.7575 1.7575 0.7575 1.7575 9 P 0 ;1
L 0.7575 1.8075 0.7575 1.8075 9 P 0 ;1
L 0.7575 1.9575 0.7575 1.9575 9 P 0 ;1
L 0.7575 2.0075 0.7575 2.0075 9 P 0 ;1
L 0.7575 2.0575 0.7575 2.0575 9 P 0 ;1
L 0.7575 2.1075 0.7575 2.1075 9 P 0 ;1
L 0.7575 2.1575 0.7575 2.1575 9 P 0 ;1
L 0.7575 2.2075 0.7575 2.2075 9 P 0 ;1
L 0.7575 2.2575 0.7575 2.2575 9 P 0 ;1
L 0.7575 2.3075 0.7575 2.3075 9 P 0 ;1
L 0.7575 2.3575 0.7575 2.3575 9 P 0 ;1
L 0.7575 2.4075 0.7575 2.4075 9 P 0 ;1
L 0.7575 2.4575 0.7575 2.4575 9 P 0 ;1
L 0.7575 2.5075 0.7575 2.5075 9 P 0 ;1
L 0.7575 2.5575 0.7575 2.5575 9 P 0 ;1
L 0.7575 2.6075 0.7575 2.6075 9 P 0 ;1
L 0.7575 2.6575 0.7575 2.6575 9 P 0 ;1
L 0.7575 2.7075 0.7575 2.7075 9 P 0 ;1
L 0.7575 2.7575 0.7575 2.7575 9 P 0 ;1
L 0.7575 2.8075 0.7575 2.8075 9 P 0 ;1
L 0.7575 2.8575 0.7575 2.8575 9 P 0 ;1
L 0.7575 2.9075 0.7575 2.9075 9 P 0 ;1
L 0.7575 2.9575 0.7575 2.9575 9 P 0 ;1
L 0.7575 3.0075 0.7575 3.0075 9 P 0 ;1
L 0.7575 3.0575 0.7575 3.0575 9 P 0 ;1
L 0.7575 3.1075 0.7575 3.1075 9 P 0 ;1
L 0.7575 3.1575 0.7575 3.1575 9 P 0 ;1
L 0.7575 3.2075 0.7575 3.2075 9 P 0 ;1
L 0.7575 3.2575 0.7575 3.2575 9 P 0 ;1
L 0.7575 3.3075 0.7575 3.3075 9 P 0 ;1
L 0.7575 3.3575 0.7575 3.3575 9 P 0 ;1
L 0.7575 3.4075 0.7575 3.4075 9 P 0 ;1
L 0.7575 3.4575 0.7575 3.4575 9 P 0 ;1
L 0.7575 3.5075 0.7575 3.5075 9 P 0 ;1
L 0.7575 3.5575 0.7575 3.5575 9 P 0 ;1
L 0.7575 3.6075 0.7575 3.6075 9 P 0 ;1
L 0.7575 3.6575 0.7575 3.6575 9 P 0 ;1
L 0.7575 3.7075 0.7575 3.7075 9 P 0 ;1
L 0.7575 3.7575 0.7575 3.7575 9 P 0 ;1
L 0.7575 3.8075 0.7575 3.8075 9 P 0 ;1
L 0.7575 3.8575 0.7575 3.8575 9 P 0 ;1
L 0.7575 3.9075 0.7575 3.9075 9 P 0 ;1
L 0.7575 3.9575 0.7575 3.9575 9 P 0 ;1
L 0.7575 4.0075 0.7575 4.0075 9 P 0 ;1
L 0.7575 4.0575 0.7575 4.0575 9 P 0 ;1
L 0.7575 4.1075 0.7575 4.1075 9 P 0 ;1
L 0.7575 4.1575 0.7575 4.1575 9 P 0 ;1
L 0.7575 4.2575 0.7575 4.2575 9 P 0 ;1
L 0.7575 4.3075 0.7575 4.3075 9 P 0 ;1
L 0.7575 4.3575 0.7575 4.3575 9 P 0 ;1
L 0.7575 4.4075 0.7575 4.4075 9 P 0 ;1
L 0.7575 4.4575 0.7575 4.4575 9 P 0 ;1
L 0.7575 4.5075 0.7575 4.5075 9 P 0 ;1
L 0.7575 4.5575 0.7575 4.5575 9 P 0 ;1
L 0.7575 4.6075 0.7575 4.6075 9 P 0 ;1
L 0.7575 4.6575 0.7575 4.6575 9 P 0 ;1
L 0.7575 4.7075 0.7575 4.7075 9 P 0 ;1
L 0.7575 4.7575 0.7575 4.7575 9 P 0 ;1
L 0.7575 4.8075 0.7575 4.8075 9 P 0 ;1
L 0.7575 4.8575 0.7575 4.8575 9 P 0 ;1
L 0.7575 5.0575 0.7575 5.0575 9 P 0 ;1
L 0.8075 0.1575 0.8075 0.1575 9 P 0 ;1
L 0.8075 0.2075 0.8075 0.2075 9 P 0 ;1
L 0.8075 0.2575 0.8075 0.2575 9 P 0 ;1
L 0.8075 0.3075 0.8075 0.3075 9 P 0 ;1
L 0.8075 0.3575 0.8075 0.3575 9 P 0 ;1
L 0.8075 0.4075 0.8075 0.4075 9 P 0 ;1
L 0.8075 0.4575 0.8075 0.4575 9 P 0 ;1
L 0.8075 0.5075 0.8075 0.5075 9 P 0 ;1
L 0.8075 0.5575 0.8075 0.5575 9 P 0 ;1
L 0.8075 0.6075 0.8075 0.6075 9 P 0 ;1
L 0.8075 0.6575 0.8075 0.6575 9 P 0 ;1
L 0.8075 0.7075 0.8075 0.7075 9 P 0 ;1
L 0.8075 0.7575 0.8075 0.7575 9 P 0 ;1
L 0.8075 0.8075 0.8075 0.8075 9 P 0 ;1
L 0.8075 0.8575 0.8075 0.8575 9 P 0 ;1
L 0.8075 0.9075 0.8075 0.9075 9 P 0 ;1
L 0.8075 0.9575 0.8075 0.9575 9 P 0 ;1
L 0.8075 1.0075 0.8075 1.0075 9 P 0 ;1
L 0.8075 1.0575 0.8075 1.0575 9 P 0 ;1
L 0.8075 1.1075 0.8075 1.1075 9 P 0 ;1
L 0.8075 1.1575 0.8075 1.1575 9 P 0 ;1
L 0.8075 1.2075 0.8075 1.2075 9 P 0 ;1
L 0.8075 1.2575 0.8075 1.2575 9 P 0 ;1
L 0.8075 1.3075 0.8075 1.3075 9 P 0 ;1
L 0.8075 1.3575 0.8075 1.3575 9 P 0 ;1
L 0.8075 1.7075 0.8075 1.7075 9 P 0 ;1
L 0.8075 1.7575 0.8075 1.7575 9 P 0 ;1
L 0.8075 1.8075 0.8075 1.8075 9 P 0 ;1
L 0.8075 1.8575 0.8075 1.8575 9 P 0 ;1
L 0.8075 1.9075 0.8075 1.9075 9 P 0 ;1
L 0.8075 1.9575 0.8075 1.9575 9 P 0 ;1
L 0.8075 2.0075 0.8075 2.0075 9 P 0 ;1
L 0.8075 2.0575 0.8075 2.0575 9 P 0 ;1
L 0.8075 2.1075 0.8075 2.1075 9 P 0 ;1
L 0.8075 2.1575 0.8075 2.1575 9 P 0 ;1
L 0.8075 2.2075 0.8075 2.2075 9 P 0 ;1
L 0.8075 2.2575 0.8075 2.2575 9 P 0 ;1
L 0.8075 2.3075 0.8075 2.3075 9 P 0 ;1
L 0.8075 2.3575 0.8075 2.3575 9 P 0 ;1
L 0.8075 2.4075 0.8075 2.4075 9 P 0 ;1
L 0.8075 2.4575 0.8075 2.4575 9 P 0 ;1
L 0.8075 2.5075 0.8075 2.5075 9 P 0 ;1
L 0.8075 2.5575 0.8075 2.5575 9 P 0 ;1
L 0.8075 2.6075 0.8075 2.6075 9 P 0 ;1
L 0.8075 2.6575 0.8075 2.6575 9 P 0 ;1
L 0.8075 2.7075 0.8075 2.7075 9 P 0 ;1
L 0.8075 2.7575 0.8075 2.7575 9 P 0 ;1
L 0.8075 2.8075 0.8075 2.8075 9 P 0 ;1
L 0.8075 2.8575 0.8075 2.8575 9 P 0 ;1
L 0.8075 2.9075 0.8075 2.9075 9 P 0 ;1
L 0.8075 2.9575 0.8075 2.9575 9 P 0 ;1
L 0.8075 3.0075 0.8075 3.0075 9 P 0 ;1
L 0.8075 3.0575 0.8075 3.0575 9 P 0 ;1
L 0.8075 3.1075 0.8075 3.1075 9 P 0 ;1
L 0.8075 3.1575 0.8075 3.1575 9 P 0 ;1
L 0.8075 3.2075 0.8075 3.2075 9 P 0 ;1
L 0.8075 3.2575 0.8075 3.2575 9 P 0 ;1
L 0.8075 3.3075 0.8075 3.3075 9 P 0 ;1
L 0.8075 3.3575 0.8075 3.3575 9 P 0 ;1
L 0.8075 3.4075 0.8075 3.4075 9 P 0 ;1
L 0.8075 3.4575 0.8075 3.4575 9 P 0 ;1
L 0.8075 3.5075 0.8075 3.5075 9 P 0 ;1
L 0.8075 3.5575 0.8075 3.5575 9 P 0 ;1
L 0.8075 3.6075 0.8075 3.6075 9 P 0 ;1
L 0.8075 3.6575 0.8075 3.6575 9 P 0 ;1
L 0.8075 3.7075 0.8075 3.7075 9 P 0 ;1
L 0.8075 3.7575 0.8075 3.7575 9 P 0 ;1
L 0.8075 3.8075 0.8075 3.8075 9 P 0 ;1
L 0.8075 3.8575 0.8075 3.8575 9 P 0 ;1
L 0.8075 3.9075 0.8075 3.9075 9 P 0 ;1
L 0.8075 3.9575 0.8075 3.9575 9 P 0 ;1
L 0.8075 4.0075 0.8075 4.0075 9 P 0 ;1
L 0.8075 4.0575 0.8075 4.0575 9 P 0 ;1
L 0.8075 4.3575 0.8075 4.3575 9 P 0 ;1
L 0.8075 4.4075 0.8075 4.4075 9 P 0 ;1
L 0.8075 4.4575 0.8075 4.4575 9 P 0 ;1
L 0.8075 4.5075 0.8075 4.5075 9 P 0 ;1
L 0.8075 4.5575 0.8075 4.5575 9 P 0 ;1
L 0.8075 4.6075 0.8075 4.6075 9 P 0 ;1
L 0.8075 4.6575 0.8075 4.6575 9 P 0 ;1
L 0.8075 4.7075 0.8075 4.7075 9 P 0 ;1
L 0.8075 4.7575 0.8075 4.7575 9 P 0 ;1
L 0.8075 4.8075 0.8075 4.8075 9 P 0 ;1
L 0.8075 4.8575 0.8075 4.8575 9 P 0 ;1
L 0.8075 4.9075 0.8075 4.9075 9 P 0 ;1
L 0.8075 5.0075 0.8075 5.0075 9 P 0 ;1
L 0.8075 5.0575 0.8075 5.0575 9 P 0 ;1
L 0.8075 5.2575 0.8075 5.2575 9 P 0 ;1
L 0.8575 0.1575 0.8575 0.1575 9 P 0 ;1
L 0.8575 0.2075 0.8575 0.2075 9 P 0 ;1
L 0.8575 0.2575 0.8575 0.2575 9 P 0 ;1
L 0.8575 0.3075 0.8575 0.3075 9 P 0 ;1
L 0.8575 0.3575 0.8575 0.3575 9 P 0 ;1
L 0.8575 0.4075 0.8575 0.4075 9 P 0 ;1
L 0.8575 0.4575 0.8575 0.4575 9 P 0 ;1
L 0.8575 0.5075 0.8575 0.5075 9 P 0 ;1
L 0.8575 0.5575 0.8575 0.5575 9 P 0 ;1
L 0.8575 0.6075 0.8575 0.6075 9 P 0 ;1
L 0.8575 0.6575 0.8575 0.6575 9 P 0 ;1
L 0.8575 0.7075 0.8575 0.7075 9 P 0 ;1
L 0.8575 0.7575 0.8575 0.7575 9 P 0 ;1
L 0.8575 0.8075 0.8575 0.8075 9 P 0 ;1
L 0.8575 0.8575 0.8575 0.8575 9 P 0 ;1
L 0.8575 0.9075 0.8575 0.9075 9 P 0 ;1
L 0.8575 0.9575 0.8575 0.9575 9 P 0 ;1
L 0.8575 1.0075 0.8575 1.0075 9 P 0 ;1
L 0.8575 1.0575 0.8575 1.0575 9 P 0 ;1
L 0.8575 1.1075 0.8575 1.1075 9 P 0 ;1
L 0.8575 1.1575 0.8575 1.1575 9 P 0 ;1
L 0.8575 1.2075 0.8575 1.2075 9 P 0 ;1
L 0.8575 1.2575 0.8575 1.2575 9 P 0 ;1
L 0.8575 1.3075 0.8575 1.3075 9 P 0 ;1
L 0.8575 1.3575 0.8575 1.3575 9 P 0 ;1
L 0.8575 1.7075 0.8575 1.7075 9 P 0 ;1
L 0.8575 1.7575 0.8575 1.7575 9 P 0 ;1
L 0.8575 1.8075 0.8575 1.8075 9 P 0 ;1
L 0.8575 1.8575 0.8575 1.8575 9 P 0 ;1
L 0.8575 1.9075 0.8575 1.9075 9 P 0 ;1
L 0.8575 1.9575 0.8575 1.9575 9 P 0 ;1
L 0.8575 2.0075 0.8575 2.0075 9 P 0 ;1
L 0.8575 2.0575 0.8575 2.0575 9 P 0 ;1
L 0.8575 2.1075 0.8575 2.1075 9 P 0 ;1
L 0.8575 2.1575 0.8575 2.1575 9 P 0 ;1
L 0.8575 2.2075 0.8575 2.2075 9 P 0 ;1
L 0.8575 2.2575 0.8575 2.2575 9 P 0 ;1
L 0.8575 2.3075 0.8575 2.3075 9 P 0 ;1
L 0.8575 2.3575 0.8575 2.3575 9 P 0 ;1
L 0.8575 2.4075 0.8575 2.4075 9 P 0 ;1
L 0.8575 2.4575 0.8575 2.4575 9 P 0 ;1
L 0.8575 2.5075 0.8575 2.5075 9 P 0 ;1
L 0.8575 2.5575 0.8575 2.5575 9 P 0 ;1
L 0.8575 2.6075 0.8575 2.6075 9 P 0 ;1
L 0.8575 2.6575 0.8575 2.6575 9 P 0 ;1
L 0.8575 2.7075 0.8575 2.7075 9 P 0 ;1
L 0.8575 2.7575 0.8575 2.7575 9 P 0 ;1
L 0.8575 2.8075 0.8575 2.8075 9 P 0 ;1
L 0.8575 2.8575 0.8575 2.8575 9 P 0 ;1
L 0.8575 2.9075 0.8575 2.9075 9 P 0 ;1
L 0.8575 2.9575 0.8575 2.9575 9 P 0 ;1
L 0.8575 3.0075 0.8575 3.0075 9 P 0 ;1
L 0.8575 3.0575 0.8575 3.0575 9 P 0 ;1
L 0.8575 3.1075 0.8575 3.1075 9 P 0 ;1
L 0.8575 3.1575 0.8575 3.1575 9 P 0 ;1
L 0.8575 3.2075 0.8575 3.2075 9 P 0 ;1
L 0.8575 3.2575 0.8575 3.2575 9 P 0 ;1
L 0.8575 3.3075 0.8575 3.3075 9 P 0 ;1
L 0.8575 3.3575 0.8575 3.3575 9 P 0 ;1
L 0.8575 3.4075 0.8575 3.4075 9 P 0 ;1
L 0.8575 3.4575 0.8575 3.4575 9 P 0 ;1
L 0.8575 3.5075 0.8575 3.5075 9 P 0 ;1
L 0.8575 3.5575 0.8575 3.5575 9 P 0 ;1
L 0.8575 3.6075 0.8575 3.6075 9 P 0 ;1
L 0.8575 3.6575 0.8575 3.6575 9 P 0 ;1
L 0.8575 3.7075 0.8575 3.7075 9 P 0 ;1
L 0.8575 3.7575 0.8575 3.7575 9 P 0 ;1
L 0.8575 3.8075 0.8575 3.8075 9 P 0 ;1
L 0.8575 3.8575 0.8575 3.8575 9 P 0 ;1
L 0.8575 3.9075 0.8575 3.9075 9 P 0 ;1
L 0.8575 3.9575 0.8575 3.9575 9 P 0 ;1
L 0.8575 4.0075 0.8575 4.0075 9 P 0 ;1
L 0.8575 4.4075 0.8575 4.4075 9 P 0 ;1
L 0.8575 4.4575 0.8575 4.4575 9 P 0 ;1
L 0.8575 4.5075 0.8575 4.5075 9 P 0 ;1
L 0.8575 4.5575 0.8575 4.5575 9 P 0 ;1
L 0.8575 4.6075 0.8575 4.6075 9 P 0 ;1
L 0.8575 4.6575 0.8575 4.6575 9 P 0 ;1
L 0.8575 4.7075 0.8575 4.7075 9 P 0 ;1
L 0.8575 4.7575 0.8575 4.7575 9 P 0 ;1
L 0.8575 4.8075 0.8575 4.8075 9 P 0 ;1
L 0.8575 4.8575 0.8575 4.8575 9 P 0 ;1
L 0.8575 4.9075 0.8575 4.9075 9 P 0 ;1
L 0.8575 4.9575 0.8575 4.9575 9 P 0 ;1
L 0.8575 5.0075 0.8575 5.0075 9 P 0 ;1
L 0.8575 5.2575 0.8575 5.2575 9 P 0 ;1
L 0.8575 5.5575 0.8575 5.5575 9 P 0 ;1
L 0.8575 5.6575 0.8575 5.6575 9 P 0 ;1
L 0.8575 5.7075 0.8575 5.7075 9 P 0 ;1
L 0.9075 0.1575 0.9075 0.1575 9 P 0 ;1
L 0.9075 0.2075 0.9075 0.2075 9 P 0 ;1
L 0.9075 0.2575 0.9075 0.2575 9 P 0 ;1
L 0.9075 0.3075 0.9075 0.3075 9 P 0 ;1
L 0.9075 0.3575 0.9075 0.3575 9 P 0 ;1
L 0.9075 0.4075 0.9075 0.4075 9 P 0 ;1
L 0.9075 0.4575 0.9075 0.4575 9 P 0 ;1
L 0.9075 0.5075 0.9075 0.5075 9 P 0 ;1
L 0.9075 0.5575 0.9075 0.5575 9 P 0 ;1
L 0.9075 0.6075 0.9075 0.6075 9 P 0 ;1
L 0.9075 0.6575 0.9075 0.6575 9 P 0 ;1
L 0.9075 0.7075 0.9075 0.7075 9 P 0 ;1
L 0.9075 0.7575 0.9075 0.7575 9 P 0 ;1
L 0.9075 0.8075 0.9075 0.8075 9 P 0 ;1
L 0.9075 0.8575 0.9075 0.8575 9 P 0 ;1
L 0.9075 0.9075 0.9075 0.9075 9 P 0 ;1
L 0.9075 0.9575 0.9075 0.9575 9 P 0 ;1
L 0.9075 1.0075 0.9075 1.0075 9 P 0 ;1
L 0.9075 1.0575 0.9075 1.0575 9 P 0 ;1
L 0.9075 1.1075 0.9075 1.1075 9 P 0 ;1
L 0.9075 1.1575 0.9075 1.1575 9 P 0 ;1
L 0.9075 1.2075 0.9075 1.2075 9 P 0 ;1
L 0.9075 1.2575 0.9075 1.2575 9 P 0 ;1
L 0.9075 1.3075 0.9075 1.3075 9 P 0 ;1
L 0.9075 1.7575 0.9075 1.7575 9 P 0 ;1
L 0.9075 1.8075 0.9075 1.8075 9 P 0 ;1
L 0.9075 1.8575 0.9075 1.8575 9 P 0 ;1
L 0.9075 1.9075 0.9075 1.9075 9 P 0 ;1
L 0.9075 1.9575 0.9075 1.9575 9 P 0 ;1
L 0.9075 2.0075 0.9075 2.0075 9 P 0 ;1
L 0.9075 2.0575 0.9075 2.0575 9 P 0 ;1
L 0.9075 2.1075 0.9075 2.1075 9 P 0 ;1
L 0.9075 2.1575 0.9075 2.1575 9 P 0 ;1
L 0.9075 2.2075 0.9075 2.2075 9 P 0 ;1
L 0.9075 2.2575 0.9075 2.2575 9 P 0 ;1
L 0.9075 2.3075 0.9075 2.3075 9 P 0 ;1
L 0.9075 2.3575 0.9075 2.3575 9 P 0 ;1
L 0.9075 2.4075 0.9075 2.4075 9 P 0 ;1
L 0.9075 2.4575 0.9075 2.4575 9 P 0 ;1
L 0.9075 2.7075 0.9075 2.7075 9 P 0 ;1
L 0.9075 2.7575 0.9075 2.7575 9 P 0 ;1
L 0.9075 2.8075 0.9075 2.8075 9 P 0 ;1
L 0.9075 2.8575 0.9075 2.8575 9 P 0 ;1
L 0.9075 2.9075 0.9075 2.9075 9 P 0 ;1
L 0.9075 2.9575 0.9075 2.9575 9 P 0 ;1
L 0.9075 3.0075 0.9075 3.0075 9 P 0 ;1
L 0.9075 3.0575 0.9075 3.0575 9 P 0 ;1
L 0.9075 3.1075 0.9075 3.1075 9 P 0 ;1
L 0.9075 3.1575 0.9075 3.1575 9 P 0 ;1
L 0.9075 3.2075 0.9075 3.2075 9 P 0 ;1
L 0.9075 3.2575 0.9075 3.2575 9 P 0 ;1
L 0.9075 3.3075 0.9075 3.3075 9 P 0 ;1
L 0.9075 3.3575 0.9075 3.3575 9 P 0 ;1
L 0.9075 3.4075 0.9075 3.4075 9 P 0 ;1
L 0.9075 3.4575 0.9075 3.4575 9 P 0 ;1
L 0.9075 3.5075 0.9075 3.5075 9 P 0 ;1
L 0.9075 3.5575 0.9075 3.5575 9 P 0 ;1
L 0.9075 3.6075 0.9075 3.6075 9 P 0 ;1
L 0.9075 3.6575 0.9075 3.6575 9 P 0 ;1
L 0.9075 3.7075 0.9075 3.7075 9 P 0 ;1
L 0.9075 3.7575 0.9075 3.7575 9 P 0 ;1
L 0.9075 3.8075 0.9075 3.8075 9 P 0 ;1
L 0.9075 3.8575 0.9075 3.8575 9 P 0 ;1
L 0.9075 3.9075 0.9075 3.9075 9 P 0 ;1
L 0.9075 3.9575 0.9075 3.9575 9 P 0 ;1
L 0.9075 4.0075 0.9075 4.0075 9 P 0 ;1
L 0.9075 4.4075 0.9075 4.4075 9 P 0 ;1
L 0.9075 4.4575 0.9075 4.4575 9 P 0 ;1
L 0.9075 4.5075 0.9075 4.5075 9 P 0 ;1
L 0.9075 4.5575 0.9075 4.5575 9 P 0 ;1
L 0.9075 4.6075 0.9075 4.6075 9 P 0 ;1
L 0.9075 4.6575 0.9075 4.6575 9 P 0 ;1
L 0.9075 4.7075 0.9075 4.7075 9 P 0 ;1
L 0.9075 4.7575 0.9075 4.7575 9 P 0 ;1
L 0.9075 4.8075 0.9075 4.8075 9 P 0 ;1
L 0.9075 4.8575 0.9075 4.8575 9 P 0 ;1
L 0.9075 4.9075 0.9075 4.9075 9 P 0 ;1
L 0.9075 4.9575 0.9075 4.9575 9 P 0 ;1
L 0.9075 5.2575 0.9075 5.2575 9 P 0 ;1
L 0.9075 5.5575 0.9075 5.5575 9 P 0 ;1
L 0.9075 5.6075 0.9075 5.6075 9 P 0 ;1
L 0.9075 5.6575 0.9075 5.6575 9 P 0 ;1
L 0.9575 0.1575 0.9575 0.1575 9 P 0 ;1
L 0.9575 0.2075 0.9575 0.2075 9 P 0 ;1
L 0.9575 0.2575 0.9575 0.2575 9 P 0 ;1
L 0.9575 0.3075 0.9575 0.3075 9 P 0 ;1
L 0.9575 0.3575 0.9575 0.3575 9 P 0 ;1
L 0.9575 0.4075 0.9575 0.4075 9 P 0 ;1
L 0.9575 0.4575 0.9575 0.4575 9 P 0 ;1
L 0.9575 0.5075 0.9575 0.5075 9 P 0 ;1
L 0.9575 0.5575 0.9575 0.5575 9 P 0 ;1
L 0.9575 0.6075 0.9575 0.6075 9 P 0 ;1
L 0.9575 0.6575 0.9575 0.6575 9 P 0 ;1
L 0.9575 0.7075 0.9575 0.7075 9 P 0 ;1
L 0.9575 0.7575 0.9575 0.7575 9 P 0 ;1
L 0.9575 0.8075 0.9575 0.8075 9 P 0 ;1
L 0.9575 0.8575 0.9575 0.8575 9 P 0 ;1
L 0.9575 0.9075 0.9575 0.9075 9 P 0 ;1
L 0.9575 0.9575 0.9575 0.9575 9 P 0 ;1
L 0.9575 1.0075 0.9575 1.0075 9 P 0 ;1
L 0.9575 1.0575 0.9575 1.0575 9 P 0 ;1
L 0.9575 1.1075 0.9575 1.1075 9 P 0 ;1
L 0.9575 1.1575 0.9575 1.1575 9 P 0 ;1
L 0.9575 1.2075 0.9575 1.2075 9 P 0 ;1
L 0.9575 1.2575 0.9575 1.2575 9 P 0 ;1
L 0.9575 1.3075 0.9575 1.3075 9 P 0 ;1
L 0.9575 1.7575 0.9575 1.7575 9 P 0 ;1
L 0.9575 1.8075 0.9575 1.8075 9 P 0 ;1
L 0.9575 1.8575 0.9575 1.8575 9 P 0 ;1
L 0.9575 1.9075 0.9575 1.9075 9 P 0 ;1
L 0.9575 1.9575 0.9575 1.9575 9 P 0 ;1
L 0.9575 2.0075 0.9575 2.0075 9 P 0 ;1
L 0.9575 2.0575 0.9575 2.0575 9 P 0 ;1
L 0.9575 2.1075 0.9575 2.1075 9 P 0 ;1
L 0.9575 2.1575 0.9575 2.1575 9 P 0 ;1
L 0.9575 2.2075 0.9575 2.2075 9 P 0 ;1
L 0.9575 2.2575 0.9575 2.2575 9 P 0 ;1
L 0.9575 2.3075 0.9575 2.3075 9 P 0 ;1
L 0.9575 2.3575 0.9575 2.3575 9 P 0 ;1
L 0.9575 2.4075 0.9575 2.4075 9 P 0 ;1
L 0.9575 2.4575 0.9575 2.4575 9 P 0 ;1
L 0.9575 2.7575 0.9575 2.7575 9 P 0 ;1
L 0.9575 2.8075 0.9575 2.8075 9 P 0 ;1
L 0.9575 2.8575 0.9575 2.8575 9 P 0 ;1
L 0.9575 2.9075 0.9575 2.9075 9 P 0 ;1
L 0.9575 2.9575 0.9575 2.9575 9 P 0 ;1
L 0.9575 3.0075 0.9575 3.0075 9 P 0 ;1
L 0.9575 3.0575 0.9575 3.0575 9 P 0 ;1
L 0.9575 3.1075 0.9575 3.1075 9 P 0 ;1
L 0.9575 3.1575 0.9575 3.1575 9 P 0 ;1
L 0.9575 3.2075 0.9575 3.2075 9 P 0 ;1
L 0.9575 3.2575 0.9575 3.2575 9 P 0 ;1
L 0.9575 3.3075 0.9575 3.3075 9 P 0 ;1
L 0.9575 3.3575 0.9575 3.3575 9 P 0 ;1
L 0.9575 3.4075 0.9575 3.4075 9 P 0 ;1
L 0.9575 3.4575 0.9575 3.4575 9 P 0 ;1
L 0.9575 3.5075 0.9575 3.5075 9 P 0 ;1
L 0.9575 3.5575 0.9575 3.5575 9 P 0 ;1
L 0.9575 3.6075 0.9575 3.6075 9 P 0 ;1
L 0.9575 3.6575 0.9575 3.6575 9 P 0 ;1
L 0.9575 3.7075 0.9575 3.7075 9 P 0 ;1
L 0.9575 3.7575 0.9575 3.7575 9 P 0 ;1
L 0.9575 3.8075 0.9575 3.8075 9 P 0 ;1
L 0.9575 3.8575 0.9575 3.8575 9 P 0 ;1
L 0.9575 3.9075 0.9575 3.9075 9 P 0 ;1
L 0.9575 3.9575 0.9575 3.9575 9 P 0 ;1
L 0.9575 4.4575 0.9575 4.4575 9 P 0 ;1
L 0.9575 4.5075 0.9575 4.5075 9 P 0 ;1
L 0.9575 4.5575 0.9575 4.5575 9 P 0 ;1
L 0.9575 4.6075 0.9575 4.6075 9 P 0 ;1
L 0.9575 4.6575 0.9575 4.6575 9 P 0 ;1
L 0.9575 4.7075 0.9575 4.7075 9 P 0 ;1
L 0.9575 4.7575 0.9575 4.7575 9 P 0 ;1
L 0.9575 4.8075 0.9575 4.8075 9 P 0 ;1
L 0.9575 4.8575 0.9575 4.8575 9 P 0 ;1
L 0.9575 4.9075 0.9575 4.9075 9 P 0 ;1
L 0.9575 5.0075 0.9575 5.0075 9 P 0 ;1
L 0.9575 5.2075 0.9575 5.2075 9 P 0 ;1
L 0.9575 5.5575 0.9575 5.5575 9 P 0 ;1
L 0.9575 5.6075 0.9575 5.6075 9 P 0 ;1
L 0.9575 5.6575 0.9575 5.6575 9 P 0 ;1
L 1.0075 0.1575 1.0075 0.1575 9 P 0 ;1
L 1.0075 0.2075 1.0075 0.2075 9 P 0 ;1
L 1.0075 0.2575 1.0075 0.2575 9 P 0 ;1
L 1.0075 0.3075 1.0075 0.3075 9 P 0 ;1
L 1.0075 0.3575 1.0075 0.3575 9 P 0 ;1
L 1.0075 0.4075 1.0075 0.4075 9 P 0 ;1
L 1.0075 0.4575 1.0075 0.4575 9 P 0 ;1
L 1.0075 0.5075 1.0075 0.5075 9 P 0 ;1
L 1.0075 0.5575 1.0075 0.5575 9 P 0 ;1
L 1.0075 0.6075 1.0075 0.6075 9 P 0 ;1
L 1.0075 0.6575 1.0075 0.6575 9 P 0 ;1
L 1.0075 0.7075 1.0075 0.7075 9 P 0 ;1
L 1.0075 0.7575 1.0075 0.7575 9 P 0 ;1
L 1.0075 0.8075 1.0075 0.8075 9 P 0 ;1
L 1.0075 0.8575 1.0075 0.8575 9 P 0 ;1
L 1.0075 0.9075 1.0075 0.9075 9 P 0 ;1
L 1.0075 0.9575 1.0075 0.9575 9 P 0 ;1
L 1.0075 1.0075 1.0075 1.0075 9 P 0 ;1
L 1.0075 1.0575 1.0075 1.0575 9 P 0 ;1
L 1.0075 1.1075 1.0075 1.1075 9 P 0 ;1
L 1.0075 1.1575 1.0075 1.1575 9 P 0 ;1
L 1.0075 1.2075 1.0075 1.2075 9 P 0 ;1
L 1.0075 1.2575 1.0075 1.2575 9 P 0 ;1
L 1.0075 1.3075 1.0075 1.3075 9 P 0 ;1
L 1.0075 1.7575 1.0075 1.7575 9 P 0 ;1
L 1.0075 1.8075 1.0075 1.8075 9 P 0 ;1
L 1.0075 1.8575 1.0075 1.8575 9 P 0 ;1
L 1.0075 1.9075 1.0075 1.9075 9 P 0 ;1
L 1.0075 1.9575 1.0075 1.9575 9 P 0 ;1
L 1.0075 2.0075 1.0075 2.0075 9 P 0 ;1
L 1.0075 2.0575 1.0075 2.0575 9 P 0 ;1
L 1.0075 2.1075 1.0075 2.1075 9 P 0 ;1
L 1.0075 2.1575 1.0075 2.1575 9 P 0 ;1
L 1.0075 2.2075 1.0075 2.2075 9 P 0 ;1
L 1.0075 2.2575 1.0075 2.2575 9 P 0 ;1
L 1.0075 2.3075 1.0075 2.3075 9 P 0 ;1
L 1.0075 2.3575 1.0075 2.3575 9 P 0 ;1
L 1.0075 2.4075 1.0075 2.4075 9 P 0 ;1
L 1.0075 2.7575 1.0075 2.7575 9 P 0 ;1
L 1.0075 2.8075 1.0075 2.8075 9 P 0 ;1
L 1.0075 2.8575 1.0075 2.8575 9 P 0 ;1
L 1.0075 2.9075 1.0075 2.9075 9 P 0 ;1
L 1.0075 2.9575 1.0075 2.9575 9 P 0 ;1
L 1.0075 3.0075 1.0075 3.0075 9 P 0 ;1
L 1.0075 3.0575 1.0075 3.0575 9 P 0 ;1
L 1.0075 3.1075 1.0075 3.1075 9 P 0 ;1
L 1.0075 3.1575 1.0075 3.1575 9 P 0 ;1
L 1.0075 3.2075 1.0075 3.2075 9 P 0 ;1
L 1.0075 3.2575 1.0075 3.2575 9 P 0 ;1
L 1.0075 3.3075 1.0075 3.3075 9 P 0 ;1
L 1.0075 3.3575 1.0075 3.3575 9 P 0 ;1
L 1.0075 3.4075 1.0075 3.4075 9 P 0 ;1
L 1.0075 3.4575 1.0075 3.4575 9 P 0 ;1
L 1.0075 3.5075 1.0075 3.5075 9 P 0 ;1
L 1.0075 3.5575 1.0075 3.5575 9 P 0 ;1
L 1.0075 3.6075 1.0075 3.6075 9 P 0 ;1
L 1.0075 3.6575 1.0075 3.6575 9 P 0 ;1
L 1.0075 3.7075 1.0075 3.7075 9 P 0 ;1
L 1.0075 3.7575 1.0075 3.7575 9 P 0 ;1
L 1.0075 3.8075 1.0075 3.8075 9 P 0 ;1
L 1.0075 3.8575 1.0075 3.8575 9 P 0 ;1
L 1.0075 3.9075 1.0075 3.9075 9 P 0 ;1
L 1.0075 3.9575 1.0075 3.9575 9 P 0 ;1
L 1.0075 4.0075 1.0075 4.0075 9 P 0 ;1
L 1.0075 4.4075 1.0075 4.4075 9 P 0 ;1
L 1.0075 4.4575 1.0075 4.4575 9 P 0 ;1
L 1.0075 4.5075 1.0075 4.5075 9 P 0 ;1
L 1.0075 4.5575 1.0075 4.5575 9 P 0 ;1
L 1.0075 4.6075 1.0075 4.6075 9 P 0 ;1
L 1.0075 4.6575 1.0075 4.6575 9 P 0 ;1
L 1.0075 4.7075 1.0075 4.7075 9 P 0 ;1
L 1.0075 4.7575 1.0075 4.7575 9 P 0 ;1
L 1.0075 4.8075 1.0075 4.8075 9 P 0 ;1
L 1.0075 4.8575 1.0075 4.8575 9 P 0 ;1
L 1.0075 5.2575 1.0075 5.2575 9 P 0 ;1
L 1.0075 5.5575 1.0075 5.5575 9 P 0 ;1
L 1.0075 5.6075 1.0075 5.6075 9 P 0 ;1
L 1.0075 5.6575 1.0075 5.6575 9 P 0 ;1
L 1.0075 5.7075 1.0075 5.7075 9 P 0 ;1
L 1.0575 0.1575 1.0575 0.1575 9 P 0 ;1
L 1.0575 0.2075 1.0575 0.2075 9 P 0 ;1
L 1.0575 0.2575 1.0575 0.2575 9 P 0 ;1
L 1.0575 0.3075 1.0575 0.3075 9 P 0 ;1
L 1.0575 0.3575 1.0575 0.3575 9 P 0 ;1
L 1.0575 0.4075 1.0575 0.4075 9 P 0 ;1
L 1.0575 0.4575 1.0575 0.4575 9 P 0 ;1
L 1.0575 0.5075 1.0575 0.5075 9 P 0 ;1
L 1.0575 0.5575 1.0575 0.5575 9 P 0 ;1
L 1.0575 0.6075 1.0575 0.6075 9 P 0 ;1
L 1.0575 0.6575 1.0575 0.6575 9 P 0 ;1
L 1.0575 0.7075 1.0575 0.7075 9 P 0 ;1
L 1.0575 0.7575 1.0575 0.7575 9 P 0 ;1
L 1.0575 0.8075 1.0575 0.8075 9 P 0 ;1
L 1.0575 0.8575 1.0575 0.8575 9 P 0 ;1
L 1.0575 0.9075 1.0575 0.9075 9 P 0 ;1
L 1.0575 0.9575 1.0575 0.9575 9 P 0 ;1
L 1.0575 1.0075 1.0575 1.0075 9 P 0 ;1
L 1.0575 1.0575 1.0575 1.0575 9 P 0 ;1
L 1.0575 1.1075 1.0575 1.1075 9 P 0 ;1
L 1.0575 1.1575 1.0575 1.1575 9 P 0 ;1
L 1.0575 1.2075 1.0575 1.2075 9 P 0 ;1
L 1.0575 1.2575 1.0575 1.2575 9 P 0 ;1
L 1.0575 1.3075 1.0575 1.3075 9 P 0 ;1
L 1.0575 1.3575 1.0575 1.3575 9 P 0 ;1
L 1.0575 1.7075 1.0575 1.7075 9 P 0 ;1
L 1.0575 1.7575 1.0575 1.7575 9 P 0 ;1
L 1.0575 1.8075 1.0575 1.8075 9 P 0 ;1
L 1.0575 1.8575 1.0575 1.8575 9 P 0 ;1
L 1.0575 1.9075 1.0575 1.9075 9 P 0 ;1
L 1.0575 1.9575 1.0575 1.9575 9 P 0 ;1
L 1.0575 2.0075 1.0575 2.0075 9 P 0 ;1
L 1.0575 2.0575 1.0575 2.0575 9 P 0 ;1
L 1.0575 2.1075 1.0575 2.1075 9 P 0 ;1
L 1.0575 2.1575 1.0575 2.1575 9 P 0 ;1
L 1.0575 2.2075 1.0575 2.2075 9 P 0 ;1
L 1.0575 2.2575 1.0575 2.2575 9 P 0 ;1
L 1.0575 2.3075 1.0575 2.3075 9 P 0 ;1
L 1.0575 2.3575 1.0575 2.3575 9 P 0 ;1
L 1.0575 2.4075 1.0575 2.4075 9 P 0 ;1
L 1.0575 2.7575 1.0575 2.7575 9 P 0 ;1
L 1.0575 2.8075 1.0575 2.8075 9 P 0 ;1
L 1.0575 2.8575 1.0575 2.8575 9 P 0 ;1
L 1.0575 2.9075 1.0575 2.9075 9 P 0 ;1
L 1.0575 2.9575 1.0575 2.9575 9 P 0 ;1
L 1.0575 3.0075 1.0575 3.0075 9 P 0 ;1
L 1.0575 3.0575 1.0575 3.0575 9 P 0 ;1
L 1.0575 3.1075 1.0575 3.1075 9 P 0 ;1
L 1.0575 3.1575 1.0575 3.1575 9 P 0 ;1
L 1.0575 3.2075 1.0575 3.2075 9 P 0 ;1
L 1.0575 3.2575 1.0575 3.2575 9 P 0 ;1
L 1.0575 3.3075 1.0575 3.3075 9 P 0 ;1
L 1.0575 3.3575 1.0575 3.3575 9 P 0 ;1
L 1.0575 3.4075 1.0575 3.4075 9 P 0 ;1
L 1.0575 3.4575 1.0575 3.4575 9 P 0 ;1
L 1.0575 3.5075 1.0575 3.5075 9 P 0 ;1
L 1.0575 3.5575 1.0575 3.5575 9 P 0 ;1
L 1.0575 3.6075 1.0575 3.6075 9 P 0 ;1
L 1.0575 3.6575 1.0575 3.6575 9 P 0 ;1
L 1.0575 3.7075 1.0575 3.7075 9 P 0 ;1
L 1.0575 3.7575 1.0575 3.7575 9 P 0 ;1
L 1.0575 3.8075 1.0575 3.8075 9 P 0 ;1
L 1.0575 3.8575 1.0575 3.8575 9 P 0 ;1
L 1.0575 3.9075 1.0575 3.9075 9 P 0 ;1
L 1.0575 3.9575 1.0575 3.9575 9 P 0 ;1
L 1.0575 4.0075 1.0575 4.0075 9 P 0 ;1
L 1.0575 4.4075 1.0575 4.4075 9 P 0 ;1
L 1.0575 4.4575 1.0575 4.4575 9 P 0 ;1
L 1.0575 4.5075 1.0575 4.5075 9 P 0 ;1
L 1.0575 4.5575 1.0575 4.5575 9 P 0 ;1
L 1.0575 4.6075 1.0575 4.6075 9 P 0 ;1
L 1.0575 4.6575 1.0575 4.6575 9 P 0 ;1
L 1.0575 4.7075 1.0575 4.7075 9 P 0 ;1
L 1.0575 4.7575 1.0575 4.7575 9 P 0 ;1
L 1.0575 4.8075 1.0575 4.8075 9 P 0 ;1
L 1.0575 4.8575 1.0575 4.8575 9 P 0 ;1
L 1.0575 5.2575 1.0575 5.2575 9 P 0 ;1
L 1.0575 5.5575 1.0575 5.5575 9 P 0 ;1
L 1.0575 5.6075 1.0575 5.6075 9 P 0 ;1
L 1.0575 5.6575 1.0575 5.6575 9 P 0 ;1
L 1.0575 5.7075 1.0575 5.7075 9 P 0 ;1
L 1.0575 5.7575 1.0575 5.7575 9 P 0 ;1
L 1.1075 0.1575 1.1075 0.1575 9 P 0 ;1
L 1.1075 0.2075 1.1075 0.2075 9 P 0 ;1
L 1.1075 0.2575 1.1075 0.2575 9 P 0 ;1
L 1.1075 0.3075 1.1075 0.3075 9 P 0 ;1
L 1.1075 0.3575 1.1075 0.3575 9 P 0 ;1
L 1.1075 0.4075 1.1075 0.4075 9 P 0 ;1
L 1.1075 0.4575 1.1075 0.4575 9 P 0 ;1
L 1.1075 0.5075 1.1075 0.5075 9 P 0 ;1
L 1.1075 0.5575 1.1075 0.5575 9 P 0 ;1
L 1.1075 0.6075 1.1075 0.6075 9 P 0 ;1
L 1.1075 0.6575 1.1075 0.6575 9 P 0 ;1
L 1.1075 0.7075 1.1075 0.7075 9 P 0 ;1
L 1.1075 0.7575 1.1075 0.7575 9 P 0 ;1
L 1.1075 0.8075 1.1075 0.8075 9 P 0 ;1
L 1.1075 0.8575 1.1075 0.8575 9 P 0 ;1
L 1.1075 0.9075 1.1075 0.9075 9 P 0 ;1
L 1.1075 0.9575 1.1075 0.9575 9 P 0 ;1
L 1.1075 1.0075 1.1075 1.0075 9 P 0 ;1
L 1.1075 1.0575 1.1075 1.0575 9 P 0 ;1
L 1.1075 1.1075 1.1075 1.1075 9 P 0 ;1
L 1.1075 1.1575 1.1075 1.1575 9 P 0 ;1
L 1.1075 1.2075 1.1075 1.2075 9 P 0 ;1
L 1.1075 1.2575 1.1075 1.2575 9 P 0 ;1
L 1.1075 1.3075 1.1075 1.3075 9 P 0 ;1
L 1.1075 1.3575 1.1075 1.3575 9 P 0 ;1
L 1.1075 1.7075 1.1075 1.7075 9 P 0 ;1
L 1.1075 1.7575 1.1075 1.7575 9 P 0 ;1
L 1.1075 1.8075 1.1075 1.8075 9 P 0 ;1
L 1.1075 1.8575 1.1075 1.8575 9 P 0 ;1
L 1.1075 1.9075 1.1075 1.9075 9 P 0 ;1
L 1.1075 1.9575 1.1075 1.9575 9 P 0 ;1
L 1.1075 2.0075 1.1075 2.0075 9 P 0 ;1
L 1.1075 2.0575 1.1075 2.0575 9 P 0 ;1
L 1.1075 2.1075 1.1075 2.1075 9 P 0 ;1
L 1.1075 2.1575 1.1075 2.1575 9 P 0 ;1
L 1.1075 2.2075 1.1075 2.2075 9 P 0 ;1
L 1.1075 2.2575 1.1075 2.2575 9 P 0 ;1
L 1.1075 2.3075 1.1075 2.3075 9 P 0 ;1
L 1.1075 2.3575 1.1075 2.3575 9 P 0 ;1
L 1.1075 2.4075 1.1075 2.4075 9 P 0 ;1
L 1.1075 2.7575 1.1075 2.7575 9 P 0 ;1
L 1.1075 2.8075 1.1075 2.8075 9 P 0 ;1
L 1.1075 2.8575 1.1075 2.8575 9 P 0 ;1
L 1.1075 2.9075 1.1075 2.9075 9 P 0 ;1
L 1.1075 2.9575 1.1075 2.9575 9 P 0 ;1
L 1.1075 3.0075 1.1075 3.0075 9 P 0 ;1
L 1.1075 3.0575 1.1075 3.0575 9 P 0 ;1
L 1.1075 3.1075 1.1075 3.1075 9 P 0 ;1
L 1.1075 3.1575 1.1075 3.1575 9 P 0 ;1
L 1.1075 3.2075 1.1075 3.2075 9 P 0 ;1
L 1.1075 3.2575 1.1075 3.2575 9 P 0 ;1
L 1.1075 3.3075 1.1075 3.3075 9 P 0 ;1
L 1.1075 3.3575 1.1075 3.3575 9 P 0 ;1
L 1.1075 3.4075 1.1075 3.4075 9 P 0 ;1
L 1.1075 3.4575 1.1075 3.4575 9 P 0 ;1
L 1.1075 3.5075 1.1075 3.5075 9 P 0 ;1
L 1.1075 3.5575 1.1075 3.5575 9 P 0 ;1
L 1.1075 3.6075 1.1075 3.6075 9 P 0 ;1
L 1.1075 3.6575 1.1075 3.6575 9 P 0 ;1
L 1.1075 3.7075 1.1075 3.7075 9 P 0 ;1
L 1.1075 3.7575 1.1075 3.7575 9 P 0 ;1
L 1.1075 3.8075 1.1075 3.8075 9 P 0 ;1
L 1.1075 3.8575 1.1075 3.8575 9 P 0 ;1
L 1.1075 3.9075 1.1075 3.9075 9 P 0 ;1
L 1.1075 3.9575 1.1075 3.9575 9 P 0 ;1
L 1.1075 4.0075 1.1075 4.0075 9 P 0 ;1
L 1.1075 4.3575 1.1075 4.3575 9 P 0 ;1
L 1.1075 4.4075 1.1075 4.4075 9 P 0 ;1
L 1.1075 4.4575 1.1075 4.4575 9 P 0 ;1
L 1.1075 4.5075 1.1075 4.5075 9 P 0 ;1
L 1.1075 4.5575 1.1075 4.5575 9 P 0 ;1
L 1.1075 4.6075 1.1075 4.6075 9 P 0 ;1
L 1.1075 4.6575 1.1075 4.6575 9 P 0 ;1
L 1.1075 4.7075 1.1075 4.7075 9 P 0 ;1
L 1.1075 4.7575 1.1075 4.7575 9 P 0 ;1
L 1.1075 4.8075 1.1075 4.8075 9 P 0 ;1
L 1.1075 4.8575 1.1075 4.8575 9 P 0 ;1
L 1.1075 4.9075 1.1075 4.9075 9 P 0 ;1
L 1.1075 5.1075 1.1075 5.1075 9 P 0 ;1
L 1.1075 5.2075 1.1075 5.2075 9 P 0 ;1
L 1.1075 5.2575 1.1075 5.2575 9 P 0 ;1
L 1.1075 5.5575 1.1075 5.5575 9 P 0 ;1
L 1.1075 5.6075 1.1075 5.6075 9 P 0 ;1
L 1.1075 5.6575 1.1075 5.6575 9 P 0 ;1
L 1.1075 5.7075 1.1075 5.7075 9 P 0 ;1
L 1.1075 5.7575 1.1075 5.7575 9 P 0 ;1
L 1.1575 0.1575 1.1575 0.1575 9 P 0 ;1
L 1.1575 0.2075 1.1575 0.2075 9 P 0 ;1
L 1.1575 0.2575 1.1575 0.2575 9 P 0 ;1
L 1.1575 0.3075 1.1575 0.3075 9 P 0 ;1
L 1.1575 0.3575 1.1575 0.3575 9 P 0 ;1
L 1.1575 0.4075 1.1575 0.4075 9 P 0 ;1
L 1.1575 0.4575 1.1575 0.4575 9 P 0 ;1
L 1.1575 0.5075 1.1575 0.5075 9 P 0 ;1
L 1.1575 0.5575 1.1575 0.5575 9 P 0 ;1
L 1.1575 0.6075 1.1575 0.6075 9 P 0 ;1
L 1.1575 0.6575 1.1575 0.6575 9 P 0 ;1
L 1.1575 0.7075 1.1575 0.7075 9 P 0 ;1
L 1.1575 0.7575 1.1575 0.7575 9 P 0 ;1
L 1.1575 0.8075 1.1575 0.8075 9 P 0 ;1
L 1.1575 0.8575 1.1575 0.8575 9 P 0 ;1
L 1.1575 0.9075 1.1575 0.9075 9 P 0 ;1
L 1.1575 0.9575 1.1575 0.9575 9 P 0 ;1
L 1.1575 1.0075 1.1575 1.0075 9 P 0 ;1
L 1.1575 1.0575 1.1575 1.0575 9 P 0 ;1
L 1.1575 1.1075 1.1575 1.1075 9 P 0 ;1
L 1.1575 1.1575 1.1575 1.1575 9 P 0 ;1
L 1.1575 1.2075 1.1575 1.2075 9 P 0 ;1
L 1.1575 1.2575 1.1575 1.2575 9 P 0 ;1
L 1.1575 1.3075 1.1575 1.3075 9 P 0 ;1
L 1.1575 1.3575 1.1575 1.3575 9 P 0 ;1
L 1.1575 1.4075 1.1575 1.4075 9 P 0 ;1
L 1.1575 1.4575 1.1575 1.4575 9 P 0 ;1
L 1.1575 1.6075 1.1575 1.6075 9 P 0 ;1
L 1.1575 1.6575 1.1575 1.6575 9 P 0 ;1
L 1.1575 1.7075 1.1575 1.7075 9 P 0 ;1
L 1.1575 1.7575 1.1575 1.7575 9 P 0 ;1
L 1.1575 1.8075 1.1575 1.8075 9 P 0 ;1
L 1.1575 1.8575 1.1575 1.8575 9 P 0 ;1
L 1.1575 1.9075 1.1575 1.9075 9 P 0 ;1
L 1.1575 1.9575 1.1575 1.9575 9 P 0 ;1
L 1.1575 2.0075 1.1575 2.0075 9 P 0 ;1
L 1.1575 2.0575 1.1575 2.0575 9 P 0 ;1
L 1.1575 2.1075 1.1575 2.1075 9 P 0 ;1
L 1.1575 2.1575 1.1575 2.1575 9 P 0 ;1
L 1.1575 2.2075 1.1575 2.2075 9 P 0 ;1
L 1.1575 2.2575 1.1575 2.2575 9 P 0 ;1
L 1.1575 2.3075 1.1575 2.3075 9 P 0 ;1
L 1.1575 2.3575 1.1575 2.3575 9 P 0 ;1
L 1.1575 2.4075 1.1575 2.4075 9 P 0 ;1
L 1.1575 2.7575 1.1575 2.7575 9 P 0 ;1
L 1.1575 2.8075 1.1575 2.8075 9 P 0 ;1
L 1.1575 2.8575 1.1575 2.8575 9 P 0 ;1
L 1.1575 2.9075 1.1575 2.9075 9 P 0 ;1
L 1.1575 2.9575 1.1575 2.9575 9 P 0 ;1
L 1.1575 3.0075 1.1575 3.0075 9 P 0 ;1
L 1.1575 3.0575 1.1575 3.0575 9 P 0 ;1
L 1.1575 3.1075 1.1575 3.1075 9 P 0 ;1
L 1.1575 3.1575 1.1575 3.1575 9 P 0 ;1
L 1.1575 3.2075 1.1575 3.2075 9 P 0 ;1
L 1.1575 3.2575 1.1575 3.2575 9 P 0 ;1
L 1.1575 3.3075 1.1575 3.3075 9 P 0 ;1
L 1.1575 3.3575 1.1575 3.3575 9 P 0 ;1
L 1.1575 3.4075 1.1575 3.4075 9 P 0 ;1
L 1.1575 3.4575 1.1575 3.4575 9 P 0 ;1
L 1.1575 3.5075 1.1575 3.5075 9 P 0 ;1
L 1.1575 3.5575 1.1575 3.5575 9 P 0 ;1
L 1.1575 3.6075 1.1575 3.6075 9 P 0 ;1
L 1.1575 3.6575 1.1575 3.6575 9 P 0 ;1
L 1.1575 3.7075 1.1575 3.7075 9 P 0 ;1
L 1.1575 3.7575 1.1575 3.7575 9 P 0 ;1
L 1.1575 3.8075 1.1575 3.8075 9 P 0 ;1
L 1.1575 3.8575 1.1575 3.8575 9 P 0 ;1
L 1.1575 3.9075 1.1575 3.9075 9 P 0 ;1
L 1.1575 3.9575 1.1575 3.9575 9 P 0 ;1
L 1.1575 4.0075 1.1575 4.0075 9 P 0 ;1
L 1.1575 4.0575 1.1575 4.0575 9 P 0 ;1
L 1.1575 4.1075 1.1575 4.1075 9 P 0 ;1
L 1.1575 4.1575 1.1575 4.1575 9 P 0 ;1
L 1.1575 4.2575 1.1575 4.2575 9 P 0 ;1
L 1.1575 4.3075 1.1575 4.3075 9 P 0 ;1
L 1.1575 4.3575 1.1575 4.3575 9 P 0 ;1
L 1.1575 4.4075 1.1575 4.4075 9 P 0 ;1
L 1.1575 4.4575 1.1575 4.4575 9 P 0 ;1
L 1.1575 4.5075 1.1575 4.5075 9 P 0 ;1
L 1.1575 4.5575 1.1575 4.5575 9 P 0 ;1
L 1.1575 4.6075 1.1575 4.6075 9 P 0 ;1
L 1.1575 4.6575 1.1575 4.6575 9 P 0 ;1
L 1.1575 4.7075 1.1575 4.7075 9 P 0 ;1
L 1.1575 4.7575 1.1575 4.7575 9 P 0 ;1
L 1.1575 4.8075 1.1575 4.8075 9 P 0 ;1
L 1.1575 4.8575 1.1575 4.8575 9 P 0 ;1
L 1.1575 5.2575 1.1575 5.2575 9 P 0 ;1
L 1.1575 5.5575 1.1575 5.5575 9 P 0 ;1
L 1.1575 5.6075 1.1575 5.6075 9 P 0 ;1
L 1.1575 5.6575 1.1575 5.6575 9 P 0 ;1
L 1.1575 5.7075 1.1575 5.7075 9 P 0 ;1
L 1.2075 0.1575 1.2075 0.1575 9 P 0 ;1
L 1.2075 0.2075 1.2075 0.2075 9 P 0 ;1
L 1.2075 0.2575 1.2075 0.2575 9 P 0 ;1
L 1.2075 0.3075 1.2075 0.3075 9 P 0 ;1
L 1.2075 0.3575 1.2075 0.3575 9 P 0 ;1
L 1.2075 0.4075 1.2075 0.4075 9 P 0 ;1
L 1.2075 0.4575 1.2075 0.4575 9 P 0 ;1
L 1.2075 0.5075 1.2075 0.5075 9 P 0 ;1
L 1.2075 0.5575 1.2075 0.5575 9 P 0 ;1
L 1.2075 0.6075 1.2075 0.6075 9 P 0 ;1
L 1.2075 0.6575 1.2075 0.6575 9 P 0 ;1
L 1.2075 0.7075 1.2075 0.7075 9 P 0 ;1
L 1.2075 0.7575 1.2075 0.7575 9 P 0 ;1
L 1.2075 0.8075 1.2075 0.8075 9 P 0 ;1
L 1.2075 0.8575 1.2075 0.8575 9 P 0 ;1
L 1.2075 0.9075 1.2075 0.9075 9 P 0 ;1
L 1.2075 0.9575 1.2075 0.9575 9 P 0 ;1
L 1.2075 1.0075 1.2075 1.0075 9 P 0 ;1
L 1.2075 1.0575 1.2075 1.0575 9 P 0 ;1
L 1.2075 1.1075 1.2075 1.1075 9 P 0 ;1
L 1.2075 1.1575 1.2075 1.1575 9 P 0 ;1
L 1.2075 1.2075 1.2075 1.2075 9 P 0 ;1
L 1.2075 1.2575 1.2075 1.2575 9 P 0 ;1
L 1.2075 1.3075 1.2075 1.3075 9 P 0 ;1
L 1.2075 1.3575 1.2075 1.3575 9 P 0 ;1
L 1.2075 1.4075 1.2075 1.4075 9 P 0 ;1
L 1.2075 1.4575 1.2075 1.4575 9 P 0 ;1
L 1.2075 1.5075 1.2075 1.5075 9 P 0 ;1
L 1.2075 1.5575 1.2075 1.5575 9 P 0 ;1
L 1.2075 1.6075 1.2075 1.6075 9 P 0 ;1
L 1.2075 1.6575 1.2075 1.6575 9 P 0 ;1
L 1.2075 1.7075 1.2075 1.7075 9 P 0 ;1
L 1.2075 1.7575 1.2075 1.7575 9 P 0 ;1
L 1.2075 1.8075 1.2075 1.8075 9 P 0 ;1
L 1.2075 1.8575 1.2075 1.8575 9 P 0 ;1
L 1.2075 1.9075 1.2075 1.9075 9 P 0 ;1
L 1.2075 1.9575 1.2075 1.9575 9 P 0 ;1
L 1.2075 2.0075 1.2075 2.0075 9 P 0 ;1
L 1.2075 2.0575 1.2075 2.0575 9 P 0 ;1
L 1.2075 2.1075 1.2075 2.1075 9 P 0 ;1
L 1.2075 2.1575 1.2075 2.1575 9 P 0 ;1
L 1.2075 2.2075 1.2075 2.2075 9 P 0 ;1
L 1.2075 2.2575 1.2075 2.2575 9 P 0 ;1
L 1.2075 2.3075 1.2075 2.3075 9 P 0 ;1
L 1.2075 2.3575 1.2075 2.3575 9 P 0 ;1
L 1.2075 2.4075 1.2075 2.4075 9 P 0 ;1
L 1.2075 2.4575 1.2075 2.4575 9 P 0 ;1
L 1.2075 2.7075 1.2075 2.7075 9 P 0 ;1
L 1.2075 2.7575 1.2075 2.7575 9 P 0 ;1
L 1.2075 2.8075 1.2075 2.8075 9 P 0 ;1
L 1.2075 2.8575 1.2075 2.8575 9 P 0 ;1
L 1.2075 2.9075 1.2075 2.9075 9 P 0 ;1
L 1.2075 2.9575 1.2075 2.9575 9 P 0 ;1
L 1.2075 3.0075 1.2075 3.0075 9 P 0 ;1
L 1.2075 3.0575 1.2075 3.0575 9 P 0 ;1
L 1.2075 3.1075 1.2075 3.1075 9 P 0 ;1
L 1.2075 3.1575 1.2075 3.1575 9 P 0 ;1
L 1.2075 3.2075 1.2075 3.2075 9 P 0 ;1
L 1.2075 3.2575 1.2075 3.2575 9 P 0 ;1
L 1.2075 3.3075 1.2075 3.3075 9 P 0 ;1
L 1.2075 3.3575 1.2075 3.3575 9 P 0 ;1
L 1.2075 3.4075 1.2075 3.4075 9 P 0 ;1
L 1.2075 3.4575 1.2075 3.4575 9 P 0 ;1
L 1.2075 3.5075 1.2075 3.5075 9 P 0 ;1
L 1.2075 3.5575 1.2075 3.5575 9 P 0 ;1
L 1.2075 3.6075 1.2075 3.6075 9 P 0 ;1
L 1.2075 3.6575 1.2075 3.6575 9 P 0 ;1
L 1.2075 3.7075 1.2075 3.7075 9 P 0 ;1
L 1.2075 3.7575 1.2075 3.7575 9 P 0 ;1
L 1.2075 3.8075 1.2075 3.8075 9 P 0 ;1
L 1.2075 3.8575 1.2075 3.8575 9 P 0 ;1
L 1.2075 3.9075 1.2075 3.9075 9 P 0 ;1
L 1.2075 3.9575 1.2075 3.9575 9 P 0 ;1
L 1.2075 4.0075 1.2075 4.0075 9 P 0 ;1
L 1.2075 4.0575 1.2075 4.0575 9 P 0 ;1
L 1.2075 4.1075 1.2075 4.1075 9 P 0 ;1
L 1.2075 4.1575 1.2075 4.1575 9 P 0 ;1
L 1.2075 4.2075 1.2075 4.2075 9 P 0 ;1
L 1.2075 4.2575 1.2075 4.2575 9 P 0 ;1
L 1.2075 4.3075 1.2075 4.3075 9 P 0 ;1
L 1.2075 4.3575 1.2075 4.3575 9 P 0 ;1
L 1.2075 4.4075 1.2075 4.4075 9 P 0 ;1
L 1.2075 4.4575 1.2075 4.4575 9 P 0 ;1
L 1.2075 4.5075 1.2075 4.5075 9 P 0 ;1
L 1.2075 4.8075 1.2075 4.8075 9 P 0 ;1
L 1.2075 4.8575 1.2075 4.8575 9 P 0 ;1
L 1.2075 5.2575 1.2075 5.2575 9 P 0 ;1
L 1.2075 5.3075 1.2075 5.3075 9 P 0 ;1
L 1.2075 5.3575 1.2075 5.3575 9 P 0 ;1
L 1.2075 5.5575 1.2075 5.5575 9 P 0 ;1
L 1.2075 5.6075 1.2075 5.6075 9 P 0 ;1
L 1.2075 5.6575 1.2075 5.6575 9 P 0 ;1
L 1.2575 0.1575 1.2575 0.1575 9 P 0 ;1
L 1.2575 0.2075 1.2575 0.2075 9 P 0 ;1
L 1.2575 0.2575 1.2575 0.2575 9 P 0 ;1
L 1.2575 0.3075 1.2575 0.3075 9 P 0 ;1
L 1.2575 0.3575 1.2575 0.3575 9 P 0 ;1
L 1.2575 0.4075 1.2575 0.4075 9 P 0 ;1
L 1.2575 0.4575 1.2575 0.4575 9 P 0 ;1
L 1.2575 0.5075 1.2575 0.5075 9 P 0 ;1
L 1.2575 0.5575 1.2575 0.5575 9 P 0 ;1
L 1.2575 0.6075 1.2575 0.6075 9 P 0 ;1
L 1.2575 0.6575 1.2575 0.6575 9 P 0 ;1
L 1.2575 0.7075 1.2575 0.7075 9 P 0 ;1
L 1.2575 0.7575 1.2575 0.7575 9 P 0 ;1
L 1.2575 0.8075 1.2575 0.8075 9 P 0 ;1
L 1.2575 0.8575 1.2575 0.8575 9 P 0 ;1
L 1.2575 0.9075 1.2575 0.9075 9 P 0 ;1
L 1.2575 0.9575 1.2575 0.9575 9 P 0 ;1
L 1.2575 1.0075 1.2575 1.0075 9 P 0 ;1
L 1.2575 1.0575 1.2575 1.0575 9 P 0 ;1
L 1.2575 1.1075 1.2575 1.1075 9 P 0 ;1
L 1.2575 1.1575 1.2575 1.1575 9 P 0 ;1
L 1.2575 1.2075 1.2575 1.2075 9 P 0 ;1
L 1.2575 1.2575 1.2575 1.2575 9 P 0 ;1
L 1.2575 1.3075 1.2575 1.3075 9 P 0 ;1
L 1.2575 1.3575 1.2575 1.3575 9 P 0 ;1
L 1.2575 1.4075 1.2575 1.4075 9 P 0 ;1
L 1.2575 1.4575 1.2575 1.4575 9 P 0 ;1
L 1.2575 1.5075 1.2575 1.5075 9 P 0 ;1
L 1.2575 1.5575 1.2575 1.5575 9 P 0 ;1
L 1.2575 1.6075 1.2575 1.6075 9 P 0 ;1
L 1.2575 1.6575 1.2575 1.6575 9 P 0 ;1
L 1.2575 1.7075 1.2575 1.7075 9 P 0 ;1
L 1.2575 1.7575 1.2575 1.7575 9 P 0 ;1
L 1.2575 1.8075 1.2575 1.8075 9 P 0 ;1
L 1.2575 1.8575 1.2575 1.8575 9 P 0 ;1
L 1.2575 1.9075 1.2575 1.9075 9 P 0 ;1
L 1.2575 1.9575 1.2575 1.9575 9 P 0 ;1
L 1.2575 2.0075 1.2575 2.0075 9 P 0 ;1
L 1.2575 2.0575 1.2575 2.0575 9 P 0 ;1
L 1.2575 2.1075 1.2575 2.1075 9 P 0 ;1
L 1.2575 2.1575 1.2575 2.1575 9 P 0 ;1
L 1.2575 2.2075 1.2575 2.2075 9 P 0 ;1
L 1.2575 2.2575 1.2575 2.2575 9 P 0 ;1
L 1.2575 2.3075 1.2575 2.3075 9 P 0 ;1
L 1.2575 2.3575 1.2575 2.3575 9 P 0 ;1
L 1.2575 2.4075 1.2575 2.4075 9 P 0 ;1
L 1.2575 2.4575 1.2575 2.4575 9 P 0 ;1
L 1.2575 2.5075 1.2575 2.5075 9 P 0 ;1
L 1.2575 2.5575 1.2575 2.5575 9 P 0 ;1
L 1.2575 2.6075 1.2575 2.6075 9 P 0 ;1
L 1.2575 2.6575 1.2575 2.6575 9 P 0 ;1
L 1.2575 2.7075 1.2575 2.7075 9 P 0 ;1
L 1.2575 2.7575 1.2575 2.7575 9 P 0 ;1
L 1.2575 2.8075 1.2575 2.8075 9 P 0 ;1
L 1.2575 2.8575 1.2575 2.8575 9 P 0 ;1
L 1.2575 2.9075 1.2575 2.9075 9 P 0 ;1
L 1.2575 2.9575 1.2575 2.9575 9 P 0 ;1
L 1.2575 3.0075 1.2575 3.0075 9 P 0 ;1
L 1.2575 3.0575 1.2575 3.0575 9 P 0 ;1
L 1.2575 3.1075 1.2575 3.1075 9 P 0 ;1
L 1.2575 3.1575 1.2575 3.1575 9 P 0 ;1
L 1.2575 3.2075 1.2575 3.2075 9 P 0 ;1
L 1.2575 3.2575 1.2575 3.2575 9 P 0 ;1
L 1.2575 3.3075 1.2575 3.3075 9 P 0 ;1
L 1.2575 3.3575 1.2575 3.3575 9 P 0 ;1
L 1.2575 3.4075 1.2575 3.4075 9 P 0 ;1
L 1.2575 3.4575 1.2575 3.4575 9 P 0 ;1
L 1.2575 3.5075 1.2575 3.5075 9 P 0 ;1
L 1.2575 3.5575 1.2575 3.5575 9 P 0 ;1
L 1.2575 3.6075 1.2575 3.6075 9 P 0 ;1
L 1.2575 3.6575 1.2575 3.6575 9 P 0 ;1
L 1.2575 3.7075 1.2575 3.7075 9 P 0 ;1
L 1.2575 3.7575 1.2575 3.7575 9 P 0 ;1
L 1.2575 3.8075 1.2575 3.8075 9 P 0 ;1
L 1.2575 3.8575 1.2575 3.8575 9 P 0 ;1
L 1.2575 3.9075 1.2575 3.9075 9 P 0 ;1
L 1.2575 3.9575 1.2575 3.9575 9 P 0 ;1
L 1.2575 4.0075 1.2575 4.0075 9 P 0 ;1
L 1.2575 4.0575 1.2575 4.0575 9 P 0 ;1
L 1.2575 4.1075 1.2575 4.1075 9 P 0 ;1
L 1.2575 4.1575 1.2575 4.1575 9 P 0 ;1
L 1.2575 4.2075 1.2575 4.2075 9 P 0 ;1
L 1.2575 4.2575 1.2575 4.2575 9 P 0 ;1
L 1.2575 4.3075 1.2575 4.3075 9 P 0 ;1
L 1.2575 4.3575 1.2575 4.3575 9 P 0 ;1
L 1.2575 4.4075 1.2575 4.4075 9 P 0 ;1
L 1.2575 4.4575 1.2575 4.4575 9 P 0 ;1
L 1.2575 4.5075 1.2575 4.5075 9 P 0 ;1
L 1.2575 4.8075 1.2575 4.8075 9 P 0 ;1
L 1.2575 4.8575 1.2575 4.8575 9 P 0 ;1
L 1.2575 4.9075 1.2575 4.9075 9 P 0 ;1
L 1.2575 5.2575 1.2575 5.2575 9 P 0 ;1
L 1.2575 5.5575 1.2575 5.5575 9 P 0 ;1
L 1.2575 5.6075 1.2575 5.6075 9 P 0 ;1
L 1.2575 5.6575 1.2575 5.6575 9 P 0 ;1
L 1.3075 0.1575 1.3075 0.1575 9 P 0 ;1
L 1.3075 0.2075 1.3075 0.2075 9 P 0 ;1
L 1.3075 0.2575 1.3075 0.2575 9 P 0 ;1
L 1.3075 0.3075 1.3075 0.3075 9 P 0 ;1
L 1.3075 0.3575 1.3075 0.3575 9 P 0 ;1
L 1.3075 0.4075 1.3075 0.4075 9 P 0 ;1
L 1.3075 0.4575 1.3075 0.4575 9 P 0 ;1
L 1.3075 0.5075 1.3075 0.5075 9 P 0 ;1
L 1.3075 0.5575 1.3075 0.5575 9 P 0 ;1
L 1.3075 0.6075 1.3075 0.6075 9 P 0 ;1
L 1.3075 0.6575 1.3075 0.6575 9 P 0 ;1
L 1.3075 0.7075 1.3075 0.7075 9 P 0 ;1
L 1.3075 0.7575 1.3075 0.7575 9 P 0 ;1
L 1.3075 0.8075 1.3075 0.8075 9 P 0 ;1
L 1.3075 0.8575 1.3075 0.8575 9 P 0 ;1
L 1.3075 0.9075 1.3075 0.9075 9 P 0 ;1
L 1.3075 0.9575 1.3075 0.9575 9 P 0 ;1
L 1.3075 1.0075 1.3075 1.0075 9 P 0 ;1
L 1.3075 1.0575 1.3075 1.0575 9 P 0 ;1
L 1.3075 1.1075 1.3075 1.1075 9 P 0 ;1
L 1.3075 1.1575 1.3075 1.1575 9 P 0 ;1
L 1.3075 1.2075 1.3075 1.2075 9 P 0 ;1
L 1.3075 1.2575 1.3075 1.2575 9 P 0 ;1
L 1.3075 1.3075 1.3075 1.3075 9 P 0 ;1
L 1.3075 1.3575 1.3075 1.3575 9 P 0 ;1
L 1.3075 1.4075 1.3075 1.4075 9 P 0 ;1
L 1.3075 1.4575 1.3075 1.4575 9 P 0 ;1
L 1.3075 1.5075 1.3075 1.5075 9 P 0 ;1
L 1.3075 1.5575 1.3075 1.5575 9 P 0 ;1
L 1.3075 1.6075 1.3075 1.6075 9 P 0 ;1
L 1.3075 1.6575 1.3075 1.6575 9 P 0 ;1
L 1.3075 1.7075 1.3075 1.7075 9 P 0 ;1
L 1.3075 1.7575 1.3075 1.7575 9 P 0 ;1
L 1.3075 1.8075 1.3075 1.8075 9 P 0 ;1
L 1.3075 1.8575 1.3075 1.8575 9 P 0 ;1
L 1.3075 1.9075 1.3075 1.9075 9 P 0 ;1
L 1.3075 1.9575 1.3075 1.9575 9 P 0 ;1
L 1.3075 2.0075 1.3075 2.0075 9 P 0 ;1
L 1.3075 2.0575 1.3075 2.0575 9 P 0 ;1
L 1.3075 2.1075 1.3075 2.1075 9 P 0 ;1
L 1.3075 2.1575 1.3075 2.1575 9 P 0 ;1
L 1.3075 2.2075 1.3075 2.2075 9 P 0 ;1
L 1.3075 2.2575 1.3075 2.2575 9 P 0 ;1
L 1.3075 2.3075 1.3075 2.3075 9 P 0 ;1
L 1.3075 2.3575 1.3075 2.3575 9 P 0 ;1
L 1.3075 2.4075 1.3075 2.4075 9 P 0 ;1
L 1.3075 2.4575 1.3075 2.4575 9 P 0 ;1
L 1.3075 2.5075 1.3075 2.5075 9 P 0 ;1
L 1.3075 2.5575 1.3075 2.5575 9 P 0 ;1
L 1.3075 2.6075 1.3075 2.6075 9 P 0 ;1
L 1.3075 2.6575 1.3075 2.6575 9 P 0 ;1
L 1.3075 2.7075 1.3075 2.7075 9 P 0 ;1
L 1.3075 2.7575 1.3075 2.7575 9 P 0 ;1
L 1.3075 2.8075 1.3075 2.8075 9 P 0 ;1
L 1.3075 2.8575 1.3075 2.8575 9 P 0 ;1
L 1.3075 2.9075 1.3075 2.9075 9 P 0 ;1
L 1.3075 2.9575 1.3075 2.9575 9 P 0 ;1
L 1.3075 3.0075 1.3075 3.0075 9 P 0 ;1
L 1.3075 3.0575 1.3075 3.0575 9 P 0 ;1
L 1.3075 3.1075 1.3075 3.1075 9 P 0 ;1
L 1.3075 3.1575 1.3075 3.1575 9 P 0 ;1
L 1.3075 3.2075 1.3075 3.2075 9 P 0 ;1
L 1.3075 3.2575 1.3075 3.2575 9 P 0 ;1
L 1.3075 3.3075 1.3075 3.3075 9 P 0 ;1
L 1.3075 3.3575 1.3075 3.3575 9 P 0 ;1
L 1.3075 3.4075 1.3075 3.4075 9 P 0 ;1
L 1.3075 3.4575 1.3075 3.4575 9 P 0 ;1
L 1.3075 3.5075 1.3075 3.5075 9 P 0 ;1
L 1.3075 3.5575 1.3075 3.5575 9 P 0 ;1
L 1.3075 3.6075 1.3075 3.6075 9 P 0 ;1
L 1.3075 3.6575 1.3075 3.6575 9 P 0 ;1
L 1.3075 3.7075 1.3075 3.7075 9 P 0 ;1
L 1.3075 3.7575 1.3075 3.7575 9 P 0 ;1
L 1.3075 3.8075 1.3075 3.8075 9 P 0 ;1
L 1.3075 3.8575 1.3075 3.8575 9 P 0 ;1
L 1.3075 3.9075 1.3075 3.9075 9 P 0 ;1
L 1.3075 3.9575 1.3075 3.9575 9 P 0 ;1
L 1.3075 4.0075 1.3075 4.0075 9 P 0 ;1
L 1.3075 4.0575 1.3075 4.0575 9 P 0 ;1
L 1.3075 4.1075 1.3075 4.1075 9 P 0 ;1
L 1.3075 4.1575 1.3075 4.1575 9 P 0 ;1
L 1.3075 4.2075 1.3075 4.2075 9 P 0 ;1
L 1.3075 4.2575 1.3075 4.2575 9 P 0 ;1
L 1.3075 4.3075 1.3075 4.3075 9 P 0 ;1
L 1.3075 4.3575 1.3075 4.3575 9 P 0 ;1
L 1.3075 4.4075 1.3075 4.4075 9 P 0 ;1
L 1.3075 4.4575 1.3075 4.4575 9 P 0 ;1
L 1.3075 4.5075 1.3075 4.5075 9 P 0 ;1
L 1.3075 4.9575 1.3075 4.9575 9 P 0 ;1
L 1.3075 5.2575 1.3075 5.2575 9 P 0 ;1
L 1.3075 5.5575 1.3075 5.5575 9 P 0 ;1
L 1.3075 5.6075 1.3075 5.6075 9 P 0 ;1
L 1.3075 5.6575 1.3075 5.6575 9 P 0 ;1
L 1.3575 0.1575 1.3575 0.1575 9 P 0 ;1
L 1.3575 0.2075 1.3575 0.2075 9 P 0 ;1
L 1.3575 0.2575 1.3575 0.2575 9 P 0 ;1
L 1.3575 0.3075 1.3575 0.3075 9 P 0 ;1
L 1.3575 0.3575 1.3575 0.3575 9 P 0 ;1
L 1.3575 0.4075 1.3575 0.4075 9 P 0 ;1
L 1.3575 0.4575 1.3575 0.4575 9 P 0 ;1
L 1.3575 0.5075 1.3575 0.5075 9 P 0 ;1
L 1.3575 0.5575 1.3575 0.5575 9 P 0 ;1
L 1.3575 0.6075 1.3575 0.6075 9 P 0 ;1
L 1.3575 0.6575 1.3575 0.6575 9 P 0 ;1
L 1.3575 0.7075 1.3575 0.7075 9 P 0 ;1
L 1.3575 0.7575 1.3575 0.7575 9 P 0 ;1
L 1.3575 0.8075 1.3575 0.8075 9 P 0 ;1
L 1.3575 0.8575 1.3575 0.8575 9 P 0 ;1
L 1.3575 0.9075 1.3575 0.9075 9 P 0 ;1
L 1.3575 0.9575 1.3575 0.9575 9 P 0 ;1
L 1.3575 1.0075 1.3575 1.0075 9 P 0 ;1
L 1.3575 1.0575 1.3575 1.0575 9 P 0 ;1
L 1.3575 1.1075 1.3575 1.1075 9 P 0 ;1
L 1.3575 1.1575 1.3575 1.1575 9 P 0 ;1
L 1.3575 1.2075 1.3575 1.2075 9 P 0 ;1
L 1.3575 1.2575 1.3575 1.2575 9 P 0 ;1
L 1.3575 1.3075 1.3575 1.3075 9 P 0 ;1
L 1.3575 1.3575 1.3575 1.3575 9 P 0 ;1
L 1.3575 1.4075 1.3575 1.4075 9 P 0 ;1
L 1.3575 1.4575 1.3575 1.4575 9 P 0 ;1
L 1.3575 1.5075 1.3575 1.5075 9 P 0 ;1
L 1.3575 1.5575 1.3575 1.5575 9 P 0 ;1
L 1.3575 1.6075 1.3575 1.6075 9 P 0 ;1
L 1.3575 1.6575 1.3575 1.6575 9 P 0 ;1
L 1.3575 1.7075 1.3575 1.7075 9 P 0 ;1
L 1.3575 1.7575 1.3575 1.7575 9 P 0 ;1
L 1.3575 1.8075 1.3575 1.8075 9 P 0 ;1
L 1.3575 1.8575 1.3575 1.8575 9 P 0 ;1
L 1.3575 1.9075 1.3575 1.9075 9 P 0 ;1
L 1.3575 1.9575 1.3575 1.9575 9 P 0 ;1
L 1.3575 2.0075 1.3575 2.0075 9 P 0 ;1
L 1.3575 2.0575 1.3575 2.0575 9 P 0 ;1
L 1.3575 2.1075 1.3575 2.1075 9 P 0 ;1
L 1.3575 2.1575 1.3575 2.1575 9 P 0 ;1
L 1.3575 2.2075 1.3575 2.2075 9 P 0 ;1
L 1.3575 2.2575 1.3575 2.2575 9 P 0 ;1
L 1.3575 2.3075 1.3575 2.3075 9 P 0 ;1
L 1.3575 2.3575 1.3575 2.3575 9 P 0 ;1
L 1.3575 2.4075 1.3575 2.4075 9 P 0 ;1
L 1.3575 2.4575 1.3575 2.4575 9 P 0 ;1
L 1.3575 2.5075 1.3575 2.5075 9 P 0 ;1
L 1.3575 2.5575 1.3575 2.5575 9 P 0 ;1
L 1.3575 2.6075 1.3575 2.6075 9 P 0 ;1
L 1.3575 2.6575 1.3575 2.6575 9 P 0 ;1
L 1.3575 2.7075 1.3575 2.7075 9 P 0 ;1
L 1.3575 2.7575 1.3575 2.7575 9 P 0 ;1
L 1.3575 2.8075 1.3575 2.8075 9 P 0 ;1
L 1.3575 2.8575 1.3575 2.8575 9 P 0 ;1
L 1.3575 2.9075 1.3575 2.9075 9 P 0 ;1
L 1.3575 2.9575 1.3575 2.9575 9 P 0 ;1
L 1.3575 3.0075 1.3575 3.0075 9 P 0 ;1
L 1.3575 3.0575 1.3575 3.0575 9 P 0 ;1
L 1.3575 3.1075 1.3575 3.1075 9 P 0 ;1
L 1.3575 3.1575 1.3575 3.1575 9 P 0 ;1
L 1.3575 3.2075 1.3575 3.2075 9 P 0 ;1
L 1.3575 3.2575 1.3575 3.2575 9 P 0 ;1
L 1.3575 3.3075 1.3575 3.3075 9 P 0 ;1
L 1.3575 3.3575 1.3575 3.3575 9 P 0 ;1
L 1.3575 3.4075 1.3575 3.4075 9 P 0 ;1
L 1.3575 3.4575 1.3575 3.4575 9 P 0 ;1
L 1.3575 3.5075 1.3575 3.5075 9 P 0 ;1
L 1.3575 3.5575 1.3575 3.5575 9 P 0 ;1
L 1.3575 3.6075 1.3575 3.6075 9 P 0 ;1
L 1.3575 3.6575 1.3575 3.6575 9 P 0 ;1
L 1.3575 3.7075 1.3575 3.7075 9 P 0 ;1
L 1.3575 3.7575 1.3575 3.7575 9 P 0 ;1
L 1.3575 3.8075 1.3575 3.8075 9 P 0 ;1
L 1.3575 3.8575 1.3575 3.8575 9 P 0 ;1
L 1.3575 3.9075 1.3575 3.9075 9 P 0 ;1
L 1.3575 3.9575 1.3575 3.9575 9 P 0 ;1
L 1.3575 4.0075 1.3575 4.0075 9 P 0 ;1
L 1.3575 4.0575 1.3575 4.0575 9 P 0 ;1
L 1.3575 4.1075 1.3575 4.1075 9 P 0 ;1
L 1.3575 4.1575 1.3575 4.1575 9 P 0 ;1
L 1.3575 4.2075 1.3575 4.2075 9 P 0 ;1
L 1.3575 4.2575 1.3575 4.2575 9 P 0 ;1
L 1.3575 4.3075 1.3575 4.3075 9 P 0 ;1
L 1.3575 4.3575 1.3575 4.3575 9 P 0 ;1
L 1.3575 4.4075 1.3575 4.4075 9 P 0 ;1
L 1.3575 4.4575 1.3575 4.4575 9 P 0 ;1
L 1.3575 4.5075 1.3575 4.5075 9 P 0 ;1
L 1.3575 4.9575 1.3575 4.9575 9 P 0 ;1
L 1.3575 5.2575 1.3575 5.2575 9 P 0 ;1
L 1.3575 5.5575 1.3575 5.5575 9 P 0 ;1
L 1.3575 5.6075 1.3575 5.6075 9 P 0 ;1
L 1.3575 5.6575 1.3575 5.6575 9 P 0 ;1
L 1.4075 0.1575 1.4075 0.1575 9 P 0 ;1
L 1.4075 0.2075 1.4075 0.2075 9 P 0 ;1
L 1.4075 0.2575 1.4075 0.2575 9 P 0 ;1
L 1.4075 0.3075 1.4075 0.3075 9 P 0 ;1
L 1.4075 0.3575 1.4075 0.3575 9 P 0 ;1
L 1.4075 0.4075 1.4075 0.4075 9 P 0 ;1
L 1.4075 0.4575 1.4075 0.4575 9 P 0 ;1
L 1.4075 0.5075 1.4075 0.5075 9 P 0 ;1
L 1.4075 0.5575 1.4075 0.5575 9 P 0 ;1
L 1.4075 0.6075 1.4075 0.6075 9 P 0 ;1
L 1.4075 0.6575 1.4075 0.6575 9 P 0 ;1
L 1.4075 0.7075 1.4075 0.7075 9 P 0 ;1
L 1.4075 0.7575 1.4075 0.7575 9 P 0 ;1
L 1.4075 0.8075 1.4075 0.8075 9 P 0 ;1
L 1.4075 0.8575 1.4075 0.8575 9 P 0 ;1
L 1.4075 0.9075 1.4075 0.9075 9 P 0 ;1
L 1.4075 0.9575 1.4075 0.9575 9 P 0 ;1
L 1.4075 1.0075 1.4075 1.0075 9 P 0 ;1
L 1.4075 1.0575 1.4075 1.0575 9 P 0 ;1
L 1.4075 1.1075 1.4075 1.1075 9 P 0 ;1
L 1.4075 1.1575 1.4075 1.1575 9 P 0 ;1
L 1.4075 1.2075 1.4075 1.2075 9 P 0 ;1
L 1.4075 1.2575 1.4075 1.2575 9 P 0 ;1
L 1.4075 1.3075 1.4075 1.3075 9 P 0 ;1
L 1.4075 1.3575 1.4075 1.3575 9 P 0 ;1
L 1.4075 1.4075 1.4075 1.4075 9 P 0 ;1
L 1.4075 1.4575 1.4075 1.4575 9 P 0 ;1
L 1.4075 1.5075 1.4075 1.5075 9 P 0 ;1
L 1.4075 1.5575 1.4075 1.5575 9 P 0 ;1
L 1.4075 1.6075 1.4075 1.6075 9 P 0 ;1
L 1.4075 1.6575 1.4075 1.6575 9 P 0 ;1
L 1.4075 1.7075 1.4075 1.7075 9 P 0 ;1
L 1.4075 1.7575 1.4075 1.7575 9 P 0 ;1
L 1.4075 1.8075 1.4075 1.8075 9 P 0 ;1
L 1.4075 1.8575 1.4075 1.8575 9 P 0 ;1
L 1.4075 1.9075 1.4075 1.9075 9 P 0 ;1
L 1.4075 1.9575 1.4075 1.9575 9 P 0 ;1
L 1.4075 2.0075 1.4075 2.0075 9 P 0 ;1
L 1.4075 2.0575 1.4075 2.0575 9 P 0 ;1
L 1.4075 2.1075 1.4075 2.1075 9 P 0 ;1
L 1.4075 2.1575 1.4075 2.1575 9 P 0 ;1
L 1.4075 2.2075 1.4075 2.2075 9 P 0 ;1
L 1.4075 2.2575 1.4075 2.2575 9 P 0 ;1
L 1.4075 2.3075 1.4075 2.3075 9 P 0 ;1
L 1.4075 2.3575 1.4075 2.3575 9 P 0 ;1
L 1.4075 2.4075 1.4075 2.4075 9 P 0 ;1
L 1.4075 2.4575 1.4075 2.4575 9 P 0 ;1
L 1.4075 2.5075 1.4075 2.5075 9 P 0 ;1
L 1.4075 2.5575 1.4075 2.5575 9 P 0 ;1
L 1.4075 2.6075 1.4075 2.6075 9 P 0 ;1
L 1.4075 2.6575 1.4075 2.6575 9 P 0 ;1
L 1.4075 2.7075 1.4075 2.7075 9 P 0 ;1
L 1.4075 2.7575 1.4075 2.7575 9 P 0 ;1
L 1.4075 2.8075 1.4075 2.8075 9 P 0 ;1
L 1.4075 2.8575 1.4075 2.8575 9 P 0 ;1
L 1.4075 2.9075 1.4075 2.9075 9 P 0 ;1
L 1.4075 2.9575 1.4075 2.9575 9 P 0 ;1
L 1.4075 3.0075 1.4075 3.0075 9 P 0 ;1
L 1.4075 3.0575 1.4075 3.0575 9 P 0 ;1
L 1.4075 3.1075 1.4075 3.1075 9 P 0 ;1
L 1.4075 3.1575 1.4075 3.1575 9 P 0 ;1
L 1.4075 3.2075 1.4075 3.2075 9 P 0 ;1
L 1.4075 3.2575 1.4075 3.2575 9 P 0 ;1
L 1.4075 3.3075 1.4075 3.3075 9 P 0 ;1
L 1.4075 3.3575 1.4075 3.3575 9 P 0 ;1
L 1.4075 3.4075 1.4075 3.4075 9 P 0 ;1
L 1.4075 3.4575 1.4075 3.4575 9 P 0 ;1
L 1.4075 3.5075 1.4075 3.5075 9 P 0 ;1
L 1.4075 3.5575 1.4075 3.5575 9 P 0 ;1
L 1.4075 3.6075 1.4075 3.6075 9 P 0 ;1
L 1.4075 3.6575 1.4075 3.6575 9 P 0 ;1
L 1.4075 3.7075 1.4075 3.7075 9 P 0 ;1
L 1.4075 3.7575 1.4075 3.7575 9 P 0 ;1
L 1.4075 3.8075 1.4075 3.8075 9 P 0 ;1
L 1.4075 3.8575 1.4075 3.8575 9 P 0 ;1
L 1.4075 3.9075 1.4075 3.9075 9 P 0 ;1
L 1.4075 3.9575 1.4075 3.9575 9 P 0 ;1
L 1.4075 4.0075 1.4075 4.0075 9 P 0 ;1
L 1.4075 4.0575 1.4075 4.0575 9 P 0 ;1
L 1.4075 4.1075 1.4075 4.1075 9 P 0 ;1
L 1.4075 4.1575 1.4075 4.1575 9 P 0 ;1
L 1.4075 4.2075 1.4075 4.2075 9 P 0 ;1
L 1.4075 4.2575 1.4075 4.2575 9 P 0 ;1
L 1.4075 4.3075 1.4075 4.3075 9 P 0 ;1
L 1.4075 4.3575 1.4075 4.3575 9 P 0 ;1
L 1.4075 4.4075 1.4075 4.4075 9 P 0 ;1
L 1.4075 4.4575 1.4075 4.4575 9 P 0 ;1
L 1.4075 4.5075 1.4075 4.5075 9 P 0 ;1
L 1.4075 4.5575 1.4075 4.5575 9 P 0 ;1
L 1.4075 4.7575 1.4075 4.7575 9 P 0 ;1
L 1.4075 4.8075 1.4075 4.8075 9 P 0 ;1
L 1.4075 4.9075 1.4075 4.9075 9 P 0 ;1
L 1.4075 4.9575 1.4075 4.9575 9 P 0 ;1
L 1.4075 5.0075 1.4075 5.0075 9 P 0 ;1
L 1.4075 5.0575 1.4075 5.0575 9 P 0 ;1
L 1.4075 5.2575 1.4075 5.2575 9 P 0 ;1
L 1.4575 0.1575 1.4575 0.1575 9 P 0 ;1
L 1.4575 0.2075 1.4575 0.2075 9 P 0 ;1
L 1.4575 0.2575 1.4575 0.2575 9 P 0 ;1
L 1.4575 0.3075 1.4575 0.3075 9 P 0 ;1
L 1.4575 0.3575 1.4575 0.3575 9 P 0 ;1
L 1.4575 0.4075 1.4575 0.4075 9 P 0 ;1
L 1.4575 0.4575 1.4575 0.4575 9 P 0 ;1
L 1.4575 0.5075 1.4575 0.5075 9 P 0 ;1
L 1.4575 0.5575 1.4575 0.5575 9 P 0 ;1
L 1.4575 0.6075 1.4575 0.6075 9 P 0 ;1
L 1.4575 0.6575 1.4575 0.6575 9 P 0 ;1
L 1.4575 0.7075 1.4575 0.7075 9 P 0 ;1
L 1.4575 0.7575 1.4575 0.7575 9 P 0 ;1
L 1.4575 0.8075 1.4575 0.8075 9 P 0 ;1
L 1.4575 0.8575 1.4575 0.8575 9 P 0 ;1
L 1.4575 0.9075 1.4575 0.9075 9 P 0 ;1
L 1.4575 0.9575 1.4575 0.9575 9 P 0 ;1
L 1.4575 1.0075 1.4575 1.0075 9 P 0 ;1
L 1.4575 1.0575 1.4575 1.0575 9 P 0 ;1
L 1.4575 1.1075 1.4575 1.1075 9 P 0 ;1
L 1.4575 1.1575 1.4575 1.1575 9 P 0 ;1
L 1.4575 1.2075 1.4575 1.2075 9 P 0 ;1
L 1.4575 1.2575 1.4575 1.2575 9 P 0 ;1
L 1.4575 1.3075 1.4575 1.3075 9 P 0 ;1
L 1.4575 1.3575 1.4575 1.3575 9 P 0 ;1
L 1.4575 1.4075 1.4575 1.4075 9 P 0 ;1
L 1.4575 1.4575 1.4575 1.4575 9 P 0 ;1
L 1.4575 1.5075 1.4575 1.5075 9 P 0 ;1
L 1.4575 1.5575 1.4575 1.5575 9 P 0 ;1
L 1.4575 1.6075 1.4575 1.6075 9 P 0 ;1
L 1.4575 1.6575 1.4575 1.6575 9 P 0 ;1
L 1.4575 1.7075 1.4575 1.7075 9 P 0 ;1
L 1.4575 1.7575 1.4575 1.7575 9 P 0 ;1
L 1.4575 1.8075 1.4575 1.8075 9 P 0 ;1
L 1.4575 1.8575 1.4575 1.8575 9 P 0 ;1
L 1.4575 1.9075 1.4575 1.9075 9 P 0 ;1
L 1.4575 1.9575 1.4575 1.9575 9 P 0 ;1
L 1.4575 2.0075 1.4575 2.0075 9 P 0 ;1
L 1.4575 2.0575 1.4575 2.0575 9 P 0 ;1
L 1.4575 2.1075 1.4575 2.1075 9 P 0 ;1
L 1.4575 2.1575 1.4575 2.1575 9 P 0 ;1
L 1.4575 2.2075 1.4575 2.2075 9 P 0 ;1
L 1.4575 2.2575 1.4575 2.2575 9 P 0 ;1
L 1.4575 2.3075 1.4575 2.3075 9 P 0 ;1
L 1.4575 2.3575 1.4575 2.3575 9 P 0 ;1
L 1.4575 2.4075 1.4575 2.4075 9 P 0 ;1
L 1.4575 2.4575 1.4575 2.4575 9 P 0 ;1
L 1.4575 2.5075 1.4575 2.5075 9 P 0 ;1
L 1.4575 2.5575 1.4575 2.5575 9 P 0 ;1
L 1.4575 2.6075 1.4575 2.6075 9 P 0 ;1
L 1.4575 2.6575 1.4575 2.6575 9 P 0 ;1
L 1.4575 2.7075 1.4575 2.7075 9 P 0 ;1
L 1.4575 2.7575 1.4575 2.7575 9 P 0 ;1
L 1.4575 2.8075 1.4575 2.8075 9 P 0 ;1
L 1.4575 2.8575 1.4575 2.8575 9 P 0 ;1
L 1.4575 2.9075 1.4575 2.9075 9 P 0 ;1
L 1.4575 2.9575 1.4575 2.9575 9 P 0 ;1
L 1.4575 3.0075 1.4575 3.0075 9 P 0 ;1
L 1.4575 3.0575 1.4575 3.0575 9 P 0 ;1
L 1.4575 3.1075 1.4575 3.1075 9 P 0 ;1
L 1.4575 3.1575 1.4575 3.1575 9 P 0 ;1
L 1.4575 3.2075 1.4575 3.2075 9 P 0 ;1
L 1.4575 3.2575 1.4575 3.2575 9 P 0 ;1
L 1.4575 3.3075 1.4575 3.3075 9 P 0 ;1
L 1.4575 3.3575 1.4575 3.3575 9 P 0 ;1
L 1.4575 3.4075 1.4575 3.4075 9 P 0 ;1
L 1.4575 3.4575 1.4575 3.4575 9 P 0 ;1
L 1.4575 3.5075 1.4575 3.5075 9 P 0 ;1
L 1.4575 3.5575 1.4575 3.5575 9 P 0 ;1
L 1.4575 3.6075 1.4575 3.6075 9 P 0 ;1
L 1.4575 3.6575 1.4575 3.6575 9 P 0 ;1
L 1.4575 3.7075 1.4575 3.7075 9 P 0 ;1
L 1.4575 3.7575 1.4575 3.7575 9 P 0 ;1
L 1.4575 3.8075 1.4575 3.8075 9 P 0 ;1
L 1.4575 3.8575 1.4575 3.8575 9 P 0 ;1
L 1.4575 3.9075 1.4575 3.9075 9 P 0 ;1
L 1.4575 3.9575 1.4575 3.9575 9 P 0 ;1
L 1.4575 4.0075 1.4575 4.0075 9 P 0 ;1
L 1.4575 4.0575 1.4575 4.0575 9 P 0 ;1
L 1.4575 4.1075 1.4575 4.1075 9 P 0 ;1
L 1.4575 4.1575 1.4575 4.1575 9 P 0 ;1
L 1.4575 4.2075 1.4575 4.2075 9 P 0 ;1
L 1.4575 4.2575 1.4575 4.2575 9 P 0 ;1
L 1.4575 4.3075 1.4575 4.3075 9 P 0 ;1
L 1.4575 4.3575 1.4575 4.3575 9 P 0 ;1
L 1.4575 4.4075 1.4575 4.4075 9 P 0 ;1
L 1.4575 4.4575 1.4575 4.4575 9 P 0 ;1
L 1.4575 4.5075 1.4575 4.5075 9 P 0 ;1
L 1.4575 4.5575 1.4575 4.5575 9 P 0 ;1
L 1.4575 4.6075 1.4575 4.6075 9 P 0 ;1
L 1.4575 4.6575 1.4575 4.6575 9 P 0 ;1
L 1.4575 4.7075 1.4575 4.7075 9 P 0 ;1
L 1.4575 4.8575 1.4575 4.8575 9 P 0 ;1
L 1.4575 4.9075 1.4575 4.9075 9 P 0 ;1
L 1.4575 4.9575 1.4575 4.9575 9 P 0 ;1
L 1.4575 5.0075 1.4575 5.0075 9 P 0 ;1
L 1.4575 5.1075 1.4575 5.1075 9 P 0 ;1
L 1.4575 5.2075 1.4575 5.2075 9 P 0 ;1
L 1.4575 5.2575 1.4575 5.2575 9 P 0 ;1
L 1.5075 0.1575 1.5075 0.1575 9 P 0 ;1
L 1.5075 0.2075 1.5075 0.2075 9 P 0 ;1
L 1.5075 0.2575 1.5075 0.2575 9 P 0 ;1
L 1.5075 0.3075 1.5075 0.3075 9 P 0 ;1
L 1.5075 0.3575 1.5075 0.3575 9 P 0 ;1
L 1.5075 0.4075 1.5075 0.4075 9 P 0 ;1
L 1.5075 0.4575 1.5075 0.4575 9 P 0 ;1
L 1.5075 0.5075 1.5075 0.5075 9 P 0 ;1
L 1.5075 0.5575 1.5075 0.5575 9 P 0 ;1
L 1.5075 0.6075 1.5075 0.6075 9 P 0 ;1
L 1.5075 0.6575 1.5075 0.6575 9 P 0 ;1
L 1.5075 0.7075 1.5075 0.7075 9 P 0 ;1
L 1.5075 0.7575 1.5075 0.7575 9 P 0 ;1
L 1.5075 0.8075 1.5075 0.8075 9 P 0 ;1
L 1.5075 0.8575 1.5075 0.8575 9 P 0 ;1
L 1.5075 0.9075 1.5075 0.9075 9 P 0 ;1
L 1.5075 0.9575 1.5075 0.9575 9 P 0 ;1
L 1.5075 1.0075 1.5075 1.0075 9 P 0 ;1
L 1.5075 1.0575 1.5075 1.0575 9 P 0 ;1
L 1.5075 1.1075 1.5075 1.1075 9 P 0 ;1
L 1.5075 1.1575 1.5075 1.1575 9 P 0 ;1
L 1.5075 1.2075 1.5075 1.2075 9 P 0 ;1
L 1.5075 1.2575 1.5075 1.2575 9 P 0 ;1
L 1.5075 1.3075 1.5075 1.3075 9 P 0 ;1
L 1.5075 1.3575 1.5075 1.3575 9 P 0 ;1
L 1.5075 1.4075 1.5075 1.4075 9 P 0 ;1
L 1.5075 1.4575 1.5075 1.4575 9 P 0 ;1
L 1.5075 1.5075 1.5075 1.5075 9 P 0 ;1
L 1.5075 1.5575 1.5075 1.5575 9 P 0 ;1
L 1.5075 1.6075 1.5075 1.6075 9 P 0 ;1
L 1.5075 1.6575 1.5075 1.6575 9 P 0 ;1
L 1.5075 1.7075 1.5075 1.7075 9 P 0 ;1
L 1.5075 1.7575 1.5075 1.7575 9 P 0 ;1
L 1.5075 1.8075 1.5075 1.8075 9 P 0 ;1
L 1.5075 1.8575 1.5075 1.8575 9 P 0 ;1
L 1.5075 1.9075 1.5075 1.9075 9 P 0 ;1
L 1.5075 1.9575 1.5075 1.9575 9 P 0 ;1
L 1.5075 2.0075 1.5075 2.0075 9 P 0 ;1
L 1.5075 2.0575 1.5075 2.0575 9 P 0 ;1
L 1.5075 2.1075 1.5075 2.1075 9 P 0 ;1
L 1.5075 2.1575 1.5075 2.1575 9 P 0 ;1
L 1.5075 2.2075 1.5075 2.2075 9 P 0 ;1
L 1.5075 2.2575 1.5075 2.2575 9 P 0 ;1
L 1.5075 2.3075 1.5075 2.3075 9 P 0 ;1
L 1.5075 2.3575 1.5075 2.3575 9 P 0 ;1
L 1.5075 2.4075 1.5075 2.4075 9 P 0 ;1
L 1.5075 2.4575 1.5075 2.4575 9 P 0 ;1
L 1.5075 2.5075 1.5075 2.5075 9 P 0 ;1
L 1.5075 2.5575 1.5075 2.5575 9 P 0 ;1
L 1.5075 2.6075 1.5075 2.6075 9 P 0 ;1
L 1.5075 2.6575 1.5075 2.6575 9 P 0 ;1
L 1.5075 2.7075 1.5075 2.7075 9 P 0 ;1
L 1.5075 2.7575 1.5075 2.7575 9 P 0 ;1
L 1.5075 2.8075 1.5075 2.8075 9 P 0 ;1
L 1.5075 2.8575 1.5075 2.8575 9 P 0 ;1
L 1.5075 2.9075 1.5075 2.9075 9 P 0 ;1
L 1.5075 2.9575 1.5075 2.9575 9 P 0 ;1
L 1.5075 3.0075 1.5075 3.0075 9 P 0 ;1
L 1.5075 3.0575 1.5075 3.0575 9 P 0 ;1
L 1.5075 3.1075 1.5075 3.1075 9 P 0 ;1
L 1.5075 3.1575 1.5075 3.1575 9 P 0 ;1
L 1.5075 3.2075 1.5075 3.2075 9 P 0 ;1
L 1.5075 3.2575 1.5075 3.2575 9 P 0 ;1
L 1.5075 3.3075 1.5075 3.3075 9 P 0 ;1
L 1.5075 3.3575 1.5075 3.3575 9 P 0 ;1
L 1.5075 3.4075 1.5075 3.4075 9 P 0 ;1
L 1.5075 3.4575 1.5075 3.4575 9 P 0 ;1
L 1.5075 3.5075 1.5075 3.5075 9 P 0 ;1
L 1.5075 3.5575 1.5075 3.5575 9 P 0 ;1
L 1.5075 3.6075 1.5075 3.6075 9 P 0 ;1
L 1.5075 3.6575 1.5075 3.6575 9 P 0 ;1
L 1.5075 3.7075 1.5075 3.7075 9 P 0 ;1
L 1.5075 3.7575 1.5075 3.7575 9 P 0 ;1
L 1.5075 3.8075 1.5075 3.8075 9 P 0 ;1
L 1.5075 3.8575 1.5075 3.8575 9 P 0 ;1
L 1.5075 3.9075 1.5075 3.9075 9 P 0 ;1
L 1.5075 3.9575 1.5075 3.9575 9 P 0 ;1
L 1.5075 4.0075 1.5075 4.0075 9 P 0 ;1
L 1.5075 4.0575 1.5075 4.0575 9 P 0 ;1
L 1.5075 4.1075 1.5075 4.1075 9 P 0 ;1
L 1.5075 4.1575 1.5075 4.1575 9 P 0 ;1
L 1.5075 4.2075 1.5075 4.2075 9 P 0 ;1
L 1.5075 4.2575 1.5075 4.2575 9 P 0 ;1
L 1.5075 4.3075 1.5075 4.3075 9 P 0 ;1
L 1.5075 4.3575 1.5075 4.3575 9 P 0 ;1
L 1.5075 4.4075 1.5075 4.4075 9 P 0 ;1
L 1.5075 4.4575 1.5075 4.4575 9 P 0 ;1
L 1.5075 4.5075 1.5075 4.5075 9 P 0 ;1
L 1.5075 4.5575 1.5075 4.5575 9 P 0 ;1
L 1.5075 4.6075 1.5075 4.6075 9 P 0 ;1
L 1.5075 5.2075 1.5075 5.2075 9 P 0 ;1
L 1.5075 5.2575 1.5075 5.2575 9 P 0 ;1
L 1.5575 0.1575 1.5575 0.1575 9 P 0 ;1
L 1.5575 0.2075 1.5575 0.2075 9 P 0 ;1
L 1.5575 0.2575 1.5575 0.2575 9 P 0 ;1
L 1.5575 0.3075 1.5575 0.3075 9 P 0 ;1
L 1.5575 0.3575 1.5575 0.3575 9 P 0 ;1
L 1.5575 0.4075 1.5575 0.4075 9 P 0 ;1
L 1.5575 0.4575 1.5575 0.4575 9 P 0 ;1
L 1.5575 0.5075 1.5575 0.5075 9 P 0 ;1
L 1.5575 0.5575 1.5575 0.5575 9 P 0 ;1
L 1.5575 0.6075 1.5575 0.6075 9 P 0 ;1
L 1.5575 0.6575 1.5575 0.6575 9 P 0 ;1
L 1.5575 0.7075 1.5575 0.7075 9 P 0 ;1
L 1.5575 0.7575 1.5575 0.7575 9 P 0 ;1
L 1.5575 0.8075 1.5575 0.8075 9 P 0 ;1
L 1.5575 0.8575 1.5575 0.8575 9 P 0 ;1
L 1.5575 0.9075 1.5575 0.9075 9 P 0 ;1
L 1.5575 0.9575 1.5575 0.9575 9 P 0 ;1
L 1.5575 1.0075 1.5575 1.0075 9 P 0 ;1
L 1.5575 1.0575 1.5575 1.0575 9 P 0 ;1
L 1.5575 1.1075 1.5575 1.1075 9 P 0 ;1
L 1.5575 1.1575 1.5575 1.1575 9 P 0 ;1
L 1.5575 1.2075 1.5575 1.2075 9 P 0 ;1
L 1.5575 1.2575 1.5575 1.2575 9 P 0 ;1
L 1.5575 1.3075 1.5575 1.3075 9 P 0 ;1
L 1.5575 1.3575 1.5575 1.3575 9 P 0 ;1
L 1.5575 1.4075 1.5575 1.4075 9 P 0 ;1
L 1.5575 1.4575 1.5575 1.4575 9 P 0 ;1
L 1.5575 1.5075 1.5575 1.5075 9 P 0 ;1
L 1.5575 1.5575 1.5575 1.5575 9 P 0 ;1
L 1.5575 1.6075 1.5575 1.6075 9 P 0 ;1
L 1.5575 1.6575 1.5575 1.6575 9 P 0 ;1
L 1.5575 1.7075 1.5575 1.7075 9 P 0 ;1
L 1.5575 1.7575 1.5575 1.7575 9 P 0 ;1
L 1.5575 1.8075 1.5575 1.8075 9 P 0 ;1
L 1.5575 1.8575 1.5575 1.8575 9 P 0 ;1
L 1.5575 1.9075 1.5575 1.9075 9 P 0 ;1
L 1.5575 1.9575 1.5575 1.9575 9 P 0 ;1
L 1.5575 2.0075 1.5575 2.0075 9 P 0 ;1
L 1.5575 2.0575 1.5575 2.0575 9 P 0 ;1
L 1.5575 2.1075 1.5575 2.1075 9 P 0 ;1
L 1.5575 2.1575 1.5575 2.1575 9 P 0 ;1
L 1.5575 2.2075 1.5575 2.2075 9 P 0 ;1
L 1.5575 2.2575 1.5575 2.2575 9 P 0 ;1
L 1.5575 2.3075 1.5575 2.3075 9 P 0 ;1
L 1.5575 2.3575 1.5575 2.3575 9 P 0 ;1
L 1.5575 2.4075 1.5575 2.4075 9 P 0 ;1
L 1.5575 2.4575 1.5575 2.4575 9 P 0 ;1
L 1.5575 2.5075 1.5575 2.5075 9 P 0 ;1
L 1.5575 2.5575 1.5575 2.5575 9 P 0 ;1
L 1.5575 2.6075 1.5575 2.6075 9 P 0 ;1
L 1.5575 2.6575 1.5575 2.6575 9 P 0 ;1
L 1.5575 2.7075 1.5575 2.7075 9 P 0 ;1
L 1.5575 2.7575 1.5575 2.7575 9 P 0 ;1
L 1.5575 2.8075 1.5575 2.8075 9 P 0 ;1
L 1.5575 2.8575 1.5575 2.8575 9 P 0 ;1
L 1.5575 2.9075 1.5575 2.9075 9 P 0 ;1
L 1.5575 2.9575 1.5575 2.9575 9 P 0 ;1
L 1.5575 3.0075 1.5575 3.0075 9 P 0 ;1
L 1.5575 3.0575 1.5575 3.0575 9 P 0 ;1
L 1.5575 3.1075 1.5575 3.1075 9 P 0 ;1
L 1.5575 3.1575 1.5575 3.1575 9 P 0 ;1
L 1.5575 3.2075 1.5575 3.2075 9 P 0 ;1
L 1.5575 3.2575 1.5575 3.2575 9 P 0 ;1
L 1.5575 3.3075 1.5575 3.3075 9 P 0 ;1
L 1.5575 3.3575 1.5575 3.3575 9 P 0 ;1
L 1.5575 3.4075 1.5575 3.4075 9 P 0 ;1
L 1.5575 3.4575 1.5575 3.4575 9 P 0 ;1
L 1.5575 3.5075 1.5575 3.5075 9 P 0 ;1
L 1.5575 3.5575 1.5575 3.5575 9 P 0 ;1
L 1.5575 3.6075 1.5575 3.6075 9 P 0 ;1
L 1.5575 3.6575 1.5575 3.6575 9 P 0 ;1
L 1.5575 3.7075 1.5575 3.7075 9 P 0 ;1
L 1.5575 3.7575 1.5575 3.7575 9 P 0 ;1
L 1.5575 3.8075 1.5575 3.8075 9 P 0 ;1
L 1.5575 3.8575 1.5575 3.8575 9 P 0 ;1
L 1.5575 3.9075 1.5575 3.9075 9 P 0 ;1
L 1.5575 3.9575 1.5575 3.9575 9 P 0 ;1
L 1.5575 4.0075 1.5575 4.0075 9 P 0 ;1
L 1.5575 4.0575 1.5575 4.0575 9 P 0 ;1
L 1.5575 4.1075 1.5575 4.1075 9 P 0 ;1
L 1.5575 4.1575 1.5575 4.1575 9 P 0 ;1
L 1.5575 4.2075 1.5575 4.2075 9 P 0 ;1
L 1.5575 4.2575 1.5575 4.2575 9 P 0 ;1
L 1.5575 4.3075 1.5575 4.3075 9 P 0 ;1
L 1.5575 4.3575 1.5575 4.3575 9 P 0 ;1
L 1.5575 4.4075 1.5575 4.4075 9 P 0 ;1
L 1.5575 4.4575 1.5575 4.4575 9 P 0 ;1
L 1.5575 4.5075 1.5575 4.5075 9 P 0 ;1
L 1.5575 4.5575 1.5575 4.5575 9 P 0 ;1
L 1.5575 5.2575 1.5575 5.2575 9 P 0 ;1
L 1.5575 5.3075 1.5575 5.3075 9 P 0 ;1
L 1.5575 5.3575 1.5575 5.3575 9 P 0 ;1
L 1.5575 5.5575 1.5575 5.5575 9 P 0 ;1
L 1.5575 5.7075 1.5575 5.7075 9 P 0 ;1
L 1.5575 5.8575 1.5575 5.8575 9 P 0 ;1
L 1.5575 5.9075 1.5575 5.9075 9 P 0 ;1
L 1.6075 0.1575 1.6075 0.1575 9 P 0 ;1
L 1.6075 0.2075 1.6075 0.2075 9 P 0 ;1
L 1.6075 0.2575 1.6075 0.2575 9 P 0 ;1
L 1.6075 0.3075 1.6075 0.3075 9 P 0 ;1
L 1.6075 0.3575 1.6075 0.3575 9 P 0 ;1
L 1.6075 0.4075 1.6075 0.4075 9 P 0 ;1
L 1.6075 0.4575 1.6075 0.4575 9 P 0 ;1
L 1.6075 0.5075 1.6075 0.5075 9 P 0 ;1
L 1.6075 0.5575 1.6075 0.5575 9 P 0 ;1
L 1.6075 0.6075 1.6075 0.6075 9 P 0 ;1
L 1.6075 0.6575 1.6075 0.6575 9 P 0 ;1
L 1.6075 0.7075 1.6075 0.7075 9 P 0 ;1
L 1.6075 0.7575 1.6075 0.7575 9 P 0 ;1
L 1.6075 0.8075 1.6075 0.8075 9 P 0 ;1
L 1.6075 0.8575 1.6075 0.8575 9 P 0 ;1
L 1.6075 0.9075 1.6075 0.9075 9 P 0 ;1
L 1.6075 0.9575 1.6075 0.9575 9 P 0 ;1
L 1.6075 1.0075 1.6075 1.0075 9 P 0 ;1
L 1.6075 1.0575 1.6075 1.0575 9 P 0 ;1
L 1.6075 1.1075 1.6075 1.1075 9 P 0 ;1
L 1.6075 1.1575 1.6075 1.1575 9 P 0 ;1
L 1.6075 1.2075 1.6075 1.2075 9 P 0 ;1
L 1.6075 1.2575 1.6075 1.2575 9 P 0 ;1
L 1.6075 1.3075 1.6075 1.3075 9 P 0 ;1
L 1.6075 1.3575 1.6075 1.3575 9 P 0 ;1
L 1.6075 1.4075 1.6075 1.4075 9 P 0 ;1
L 1.6075 1.4575 1.6075 1.4575 9 P 0 ;1
L 1.6075 1.5075 1.6075 1.5075 9 P 0 ;1
L 1.6075 1.5575 1.6075 1.5575 9 P 0 ;1
L 1.6075 1.6075 1.6075 1.6075 9 P 0 ;1
L 1.6075 1.6575 1.6075 1.6575 9 P 0 ;1
L 1.6075 1.7075 1.6075 1.7075 9 P 0 ;1
L 1.6075 1.7575 1.6075 1.7575 9 P 0 ;1
L 1.6075 1.8075 1.6075 1.8075 9 P 0 ;1
L 1.6075 1.8575 1.6075 1.8575 9 P 0 ;1
L 1.6075 1.9075 1.6075 1.9075 9 P 0 ;1
L 1.6075 1.9575 1.6075 1.9575 9 P 0 ;1
L 1.6075 2.0075 1.6075 2.0075 9 P 0 ;1
L 1.6075 2.0575 1.6075 2.0575 9 P 0 ;1
L 1.6075 2.1075 1.6075 2.1075 9 P 0 ;1
L 1.6075 2.1575 1.6075 2.1575 9 P 0 ;1
L 1.6075 2.2075 1.6075 2.2075 9 P 0 ;1
L 1.6075 2.2575 1.6075 2.2575 9 P 0 ;1
L 1.6075 2.3075 1.6075 2.3075 9 P 0 ;1
L 1.6075 2.3575 1.6075 2.3575 9 P 0 ;1
L 1.6075 2.4075 1.6075 2.4075 9 P 0 ;1
L 1.6075 2.4575 1.6075 2.4575 9 P 0 ;1
L 1.6075 2.5075 1.6075 2.5075 9 P 0 ;1
L 1.6075 2.5575 1.6075 2.5575 9 P 0 ;1
L 1.6075 2.6075 1.6075 2.6075 9 P 0 ;1
L 1.6075 2.6575 1.6075 2.6575 9 P 0 ;1
L 1.6075 2.7075 1.6075 2.7075 9 P 0 ;1
L 1.6075 2.7575 1.6075 2.7575 9 P 0 ;1
L 1.6075 2.8075 1.6075 2.8075 9 P 0 ;1
L 1.6075 2.8575 1.6075 2.8575 9 P 0 ;1
L 1.6075 2.9075 1.6075 2.9075 9 P 0 ;1
L 1.6075 2.9575 1.6075 2.9575 9 P 0 ;1
L 1.6075 3.0075 1.6075 3.0075 9 P 0 ;1
L 1.6075 3.0575 1.6075 3.0575 9 P 0 ;1
L 1.6075 3.1075 1.6075 3.1075 9 P 0 ;1
L 1.6075 3.1575 1.6075 3.1575 9 P 0 ;1
L 1.6075 3.2075 1.6075 3.2075 9 P 0 ;1
L 1.6075 3.2575 1.6075 3.2575 9 P 0 ;1
L 1.6075 3.3075 1.6075 3.3075 9 P 0 ;1
L 1.6075 3.3575 1.6075 3.3575 9 P 0 ;1
L 1.6075 3.4075 1.6075 3.4075 9 P 0 ;1
L 1.6075 3.4575 1.6075 3.4575 9 P 0 ;1
L 1.6075 3.5075 1.6075 3.5075 9 P 0 ;1
L 1.6075 3.5575 1.6075 3.5575 9 P 0 ;1
L 1.6075 3.6075 1.6075 3.6075 9 P 0 ;1
L 1.6075 3.6575 1.6075 3.6575 9 P 0 ;1
L 1.6075 3.7075 1.6075 3.7075 9 P 0 ;1
L 1.6075 3.7575 1.6075 3.7575 9 P 0 ;1
L 1.6075 3.8075 1.6075 3.8075 9 P 0 ;1
L 1.6075 3.8575 1.6075 3.8575 9 P 0 ;1
L 1.6075 3.9075 1.6075 3.9075 9 P 0 ;1
L 1.6075 3.9575 1.6075 3.9575 9 P 0 ;1
L 1.6075 4.0075 1.6075 4.0075 9 P 0 ;1
L 1.6075 4.0575 1.6075 4.0575 9 P 0 ;1
L 1.6075 4.1075 1.6075 4.1075 9 P 0 ;1
L 1.6075 4.1575 1.6075 4.1575 9 P 0 ;1
L 1.6075 4.2075 1.6075 4.2075 9 P 0 ;1
L 1.6075 4.2575 1.6075 4.2575 9 P 0 ;1
L 1.6075 4.3075 1.6075 4.3075 9 P 0 ;1
L 1.6075 4.3575 1.6075 4.3575 9 P 0 ;1
L 1.6075 4.4075 1.6075 4.4075 9 P 0 ;1
L 1.6075 4.4575 1.6075 4.4575 9 P 0 ;1
L 1.6075 4.5075 1.6075 4.5075 9 P 0 ;1
L 1.6075 4.5575 1.6075 4.5575 9 P 0 ;1
L 1.6075 5.2575 1.6075 5.2575 9 P 0 ;1
L 1.6075 5.3075 1.6075 5.3075 9 P 0 ;1
L 1.6075 5.3575 1.6075 5.3575 9 P 0 ;1
L 1.6075 5.4075 1.6075 5.4075 9 P 0 ;1
L 1.6075 5.4575 1.6075 5.4575 9 P 0 ;1
L 1.6075 5.5075 1.6075 5.5075 9 P 0 ;1
L 1.6075 5.5575 1.6075 5.5575 9 P 0 ;1
L 1.6075 5.6075 1.6075 5.6075 9 P 0 ;1
L 1.6075 5.6575 1.6075 5.6575 9 P 0 ;1
L 1.6075 5.7075 1.6075 5.7075 9 P 0 ;1
L 1.6075 5.7575 1.6075 5.7575 9 P 0 ;1
L 1.6075 5.8075 1.6075 5.8075 9 P 0 ;1
L 1.6075 5.8575 1.6075 5.8575 9 P 0 ;1
L 1.6075 5.9075 1.6075 5.9075 9 P 0 ;1
L 1.6575 0.1575 1.6575 0.1575 9 P 0 ;1
L 1.6575 0.2075 1.6575 0.2075 9 P 0 ;1
L 1.6575 0.2575 1.6575 0.2575 9 P 0 ;1
L 1.6575 0.3075 1.6575 0.3075 9 P 0 ;1
L 1.6575 0.3575 1.6575 0.3575 9 P 0 ;1
L 1.6575 0.4075 1.6575 0.4075 9 P 0 ;1
L 1.6575 0.4575 1.6575 0.4575 9 P 0 ;1
L 1.6575 0.5075 1.6575 0.5075 9 P 0 ;1
L 1.6575 0.5575 1.6575 0.5575 9 P 0 ;1
L 1.6575 0.6075 1.6575 0.6075 9 P 0 ;1
L 1.6575 0.6575 1.6575 0.6575 9 P 0 ;1
L 1.6575 0.7075 1.6575 0.7075 9 P 0 ;1
L 1.6575 0.7575 1.6575 0.7575 9 P 0 ;1
L 1.6575 0.8075 1.6575 0.8075 9 P 0 ;1
L 1.6575 0.8575 1.6575 0.8575 9 P 0 ;1
L 1.6575 0.9075 1.6575 0.9075 9 P 0 ;1
L 1.6575 0.9575 1.6575 0.9575 9 P 0 ;1
L 1.6575 1.0075 1.6575 1.0075 9 P 0 ;1
L 1.6575 1.0575 1.6575 1.0575 9 P 0 ;1
L 1.6575 1.1075 1.6575 1.1075 9 P 0 ;1
L 1.6575 1.1575 1.6575 1.1575 9 P 0 ;1
L 1.6575 1.2075 1.6575 1.2075 9 P 0 ;1
L 1.6575 1.2575 1.6575 1.2575 9 P 0 ;1
L 1.6575 1.3075 1.6575 1.3075 9 P 0 ;1
L 1.6575 1.3575 1.6575 1.3575 9 P 0 ;1
L 1.6575 1.4075 1.6575 1.4075 9 P 0 ;1
L 1.6575 1.4575 1.6575 1.4575 9 P 0 ;1
L 1.6575 1.5075 1.6575 1.5075 9 P 0 ;1
L 1.6575 1.5575 1.6575 1.5575 9 P 0 ;1
L 1.6575 1.6075 1.6575 1.6075 9 P 0 ;1
L 1.6575 1.6575 1.6575 1.6575 9 P 0 ;1
L 1.6575 1.7075 1.6575 1.7075 9 P 0 ;1
L 1.6575 1.7575 1.6575 1.7575 9 P 0 ;1
L 1.6575 1.8075 1.6575 1.8075 9 P 0 ;1
L 1.6575 1.8575 1.6575 1.8575 9 P 0 ;1
L 1.6575 1.9075 1.6575 1.9075 9 P 0 ;1
L 1.6575 1.9575 1.6575 1.9575 9 P 0 ;1
L 1.6575 2.0075 1.6575 2.0075 9 P 0 ;1
L 1.6575 2.0575 1.6575 2.0575 9 P 0 ;1
L 1.6575 2.1075 1.6575 2.1075 9 P 0 ;1
L 1.6575 2.1575 1.6575 2.1575 9 P 0 ;1
L 1.6575 2.2075 1.6575 2.2075 9 P 0 ;1
L 1.6575 2.2575 1.6575 2.2575 9 P 0 ;1
L 1.6575 2.3075 1.6575 2.3075 9 P 0 ;1
L 1.6575 2.3575 1.6575 2.3575 9 P 0 ;1
L 1.6575 2.4075 1.6575 2.4075 9 P 0 ;1
L 1.6575 2.4575 1.6575 2.4575 9 P 0 ;1
L 1.6575 2.5075 1.6575 2.5075 9 P 0 ;1
L 1.6575 2.5575 1.6575 2.5575 9 P 0 ;1
L 1.6575 2.6075 1.6575 2.6075 9 P 0 ;1
L 1.6575 2.6575 1.6575 2.6575 9 P 0 ;1
L 1.6575 2.7075 1.6575 2.7075 9 P 0 ;1
L 1.6575 2.7575 1.6575 2.7575 9 P 0 ;1
L 1.6575 2.8075 1.6575 2.8075 9 P 0 ;1
L 1.6575 2.8575 1.6575 2.8575 9 P 0 ;1
L 1.6575 2.9075 1.6575 2.9075 9 P 0 ;1
L 1.6575 2.9575 1.6575 2.9575 9 P 0 ;1
L 1.6575 3.0075 1.6575 3.0075 9 P 0 ;1
L 1.6575 3.0575 1.6575 3.0575 9 P 0 ;1
L 1.6575 3.1075 1.6575 3.1075 9 P 0 ;1
L 1.6575 3.1575 1.6575 3.1575 9 P 0 ;1
L 1.6575 3.2075 1.6575 3.2075 9 P 0 ;1
L 1.6575 3.2575 1.6575 3.2575 9 P 0 ;1
L 1.6575 3.3075 1.6575 3.3075 9 P 0 ;1
L 1.6575 3.3575 1.6575 3.3575 9 P 0 ;1
L 1.6575 3.4075 1.6575 3.4075 9 P 0 ;1
L 1.6575 3.4575 1.6575 3.4575 9 P 0 ;1
L 1.6575 3.5075 1.6575 3.5075 9 P 0 ;1
L 1.6575 3.5575 1.6575 3.5575 9 P 0 ;1
L 1.6575 3.6075 1.6575 3.6075 9 P 0 ;1
L 1.6575 3.6575 1.6575 3.6575 9 P 0 ;1
L 1.6575 3.7075 1.6575 3.7075 9 P 0 ;1
L 1.6575 3.7575 1.6575 3.7575 9 P 0 ;1
L 1.6575 3.8075 1.6575 3.8075 9 P 0 ;1
L 1.6575 3.8575 1.6575 3.8575 9 P 0 ;1
L 1.6575 3.9075 1.6575 3.9075 9 P 0 ;1
L 1.6575 3.9575 1.6575 3.9575 9 P 0 ;1
L 1.6575 4.0075 1.6575 4.0075 9 P 0 ;1
L 1.6575 4.0575 1.6575 4.0575 9 P 0 ;1
L 1.6575 4.1075 1.6575 4.1075 9 P 0 ;1
L 1.6575 4.1575 1.6575 4.1575 9 P 0 ;1
L 1.6575 4.2075 1.6575 4.2075 9 P 0 ;1
L 1.6575 4.2575 1.6575 4.2575 9 P 0 ;1
L 1.6575 4.3075 1.6575 4.3075 9 P 0 ;1
L 1.6575 4.3575 1.6575 4.3575 9 P 0 ;1
L 1.6575 4.4075 1.6575 4.4075 9 P 0 ;1
L 1.6575 4.4575 1.6575 4.4575 9 P 0 ;1
L 1.6575 4.5075 1.6575 4.5075 9 P 0 ;1
L 1.6575 4.5575 1.6575 4.5575 9 P 0 ;1
L 1.6575 5.2575 1.6575 5.2575 9 P 0 ;1
L 1.6575 5.3075 1.6575 5.3075 9 P 0 ;1
L 1.6575 5.3575 1.6575 5.3575 9 P 0 ;1
L 1.6575 5.4075 1.6575 5.4075 9 P 0 ;1
L 1.6575 5.4575 1.6575 5.4575 9 P 0 ;1
L 1.6575 5.5075 1.6575 5.5075 9 P 0 ;1
L 1.6575 5.5575 1.6575 5.5575 9 P 0 ;1
L 1.6575 5.6075 1.6575 5.6075 9 P 0 ;1
L 1.6575 5.6575 1.6575 5.6575 9 P 0 ;1
L 1.6575 5.7075 1.6575 5.7075 9 P 0 ;1
L 1.6575 5.7575 1.6575 5.7575 9 P 0 ;1
L 1.6575 5.8075 1.6575 5.8075 9 P 0 ;1
L 1.6575 5.8575 1.6575 5.8575 9 P 0 ;1
L 1.6575 5.9075 1.6575 5.9075 9 P 0 ;1
L 1.7075 0.1575 1.7075 0.1575 9 P 0 ;1
L 1.7075 0.2075 1.7075 0.2075 9 P 0 ;1
L 1.7075 0.2575 1.7075 0.2575 9 P 0 ;1
L 1.7075 0.3075 1.7075 0.3075 9 P 0 ;1
L 1.7075 0.3575 1.7075 0.3575 9 P 0 ;1
L 1.7075 0.4075 1.7075 0.4075 9 P 0 ;1
L 1.7075 0.4575 1.7075 0.4575 9 P 0 ;1
L 1.7075 0.5075 1.7075 0.5075 9 P 0 ;1
L 1.7075 0.5575 1.7075 0.5575 9 P 0 ;1
L 1.7075 0.6075 1.7075 0.6075 9 P 0 ;1
L 1.7075 0.6575 1.7075 0.6575 9 P 0 ;1
L 1.7075 0.7075 1.7075 0.7075 9 P 0 ;1
L 1.7075 0.7575 1.7075 0.7575 9 P 0 ;1
L 1.7075 0.8075 1.7075 0.8075 9 P 0 ;1
L 1.7075 0.8575 1.7075 0.8575 9 P 0 ;1
L 1.7075 0.9075 1.7075 0.9075 9 P 0 ;1
L 1.7075 0.9575 1.7075 0.9575 9 P 0 ;1
L 1.7075 1.0075 1.7075 1.0075 9 P 0 ;1
L 1.7075 1.0575 1.7075 1.0575 9 P 0 ;1
L 1.7075 1.1075 1.7075 1.1075 9 P 0 ;1
L 1.7075 1.1575 1.7075 1.1575 9 P 0 ;1
L 1.7075 1.2075 1.7075 1.2075 9 P 0 ;1
L 1.7075 1.2575 1.7075 1.2575 9 P 0 ;1
L 1.7075 1.3075 1.7075 1.3075 9 P 0 ;1
L 1.7075 1.3575 1.7075 1.3575 9 P 0 ;1
L 1.7075 1.4075 1.7075 1.4075 9 P 0 ;1
L 1.7075 1.4575 1.7075 1.4575 9 P 0 ;1
L 1.7075 1.5075 1.7075 1.5075 9 P 0 ;1
L 1.7075 1.5575 1.7075 1.5575 9 P 0 ;1
L 1.7075 1.6075 1.7075 1.6075 9 P 0 ;1
L 1.7075 1.6575 1.7075 1.6575 9 P 0 ;1
L 1.7075 1.7075 1.7075 1.7075 9 P 0 ;1
L 1.7075 1.7575 1.7075 1.7575 9 P 0 ;1
L 1.7075 1.8075 1.7075 1.8075 9 P 0 ;1
L 1.7075 1.8575 1.7075 1.8575 9 P 0 ;1
L 1.7075 1.9075 1.7075 1.9075 9 P 0 ;1
L 1.7075 1.9575 1.7075 1.9575 9 P 0 ;1
L 1.7075 2.0075 1.7075 2.0075 9 P 0 ;1
L 1.7075 2.0575 1.7075 2.0575 9 P 0 ;1
L 1.7075 2.1075 1.7075 2.1075 9 P 0 ;1
L 1.7075 2.1575 1.7075 2.1575 9 P 0 ;1
L 1.7075 2.2075 1.7075 2.2075 9 P 0 ;1
L 1.7075 2.2575 1.7075 2.2575 9 P 0 ;1
L 1.7075 2.3075 1.7075 2.3075 9 P 0 ;1
L 1.7075 2.3575 1.7075 2.3575 9 P 0 ;1
L 1.7075 2.4075 1.7075 2.4075 9 P 0 ;1
L 1.7075 2.4575 1.7075 2.4575 9 P 0 ;1
L 1.7075 2.5075 1.7075 2.5075 9 P 0 ;1
L 1.7075 2.5575 1.7075 2.5575 9 P 0 ;1
L 1.7075 2.6075 1.7075 2.6075 9 P 0 ;1
L 1.7075 2.6575 1.7075 2.6575 9 P 0 ;1
L 1.7075 2.7075 1.7075 2.7075 9 P 0 ;1
L 1.7075 2.7575 1.7075 2.7575 9 P 0 ;1
L 1.7075 2.8075 1.7075 2.8075 9 P 0 ;1
L 1.7075 2.8575 1.7075 2.8575 9 P 0 ;1
L 1.7075 2.9075 1.7075 2.9075 9 P 0 ;1
L 1.7075 2.9575 1.7075 2.9575 9 P 0 ;1
L 1.7075 3.0075 1.7075 3.0075 9 P 0 ;1
L 1.7075 3.0575 1.7075 3.0575 9 P 0 ;1
L 1.7075 3.1075 1.7075 3.1075 9 P 0 ;1
L 1.7075 3.1575 1.7075 3.1575 9 P 0 ;1
L 1.7075 3.2075 1.7075 3.2075 9 P 0 ;1
L 1.7075 3.2575 1.7075 3.2575 9 P 0 ;1
L 1.7075 3.3075 1.7075 3.3075 9 P 0 ;1
L 1.7075 3.3575 1.7075 3.3575 9 P 0 ;1
L 1.7075 3.4075 1.7075 3.4075 9 P 0 ;1
L 1.7075 3.4575 1.7075 3.4575 9 P 0 ;1
L 1.7075 3.5075 1.7075 3.5075 9 P 0 ;1
L 1.7075 3.5575 1.7075 3.5575 9 P 0 ;1
L 1.7075 3.6075 1.7075 3.6075 9 P 0 ;1
L 1.7075 3.6575 1.7075 3.6575 9 P 0 ;1
L 1.7075 3.7075 1.7075 3.7075 9 P 0 ;1
L 1.7075 3.7575 1.7075 3.7575 9 P 0 ;1
L 1.7075 3.8075 1.7075 3.8075 9 P 0 ;1
L 1.7075 3.8575 1.7075 3.8575 9 P 0 ;1
L 1.7075 3.9075 1.7075 3.9075 9 P 0 ;1
L 1.7075 3.9575 1.7075 3.9575 9 P 0 ;1
L 1.7075 4.0075 1.7075 4.0075 9 P 0 ;1
L 1.7075 4.0575 1.7075 4.0575 9 P 0 ;1
L 1.7075 4.1075 1.7075 4.1075 9 P 0 ;1
L 1.7075 4.1575 1.7075 4.1575 9 P 0 ;1
L 1.7075 4.2075 1.7075 4.2075 9 P 0 ;1
L 1.7075 4.2575 1.7075 4.2575 9 P 0 ;1
L 1.7075 4.3075 1.7075 4.3075 9 P 0 ;1
L 1.7075 4.3575 1.7075 4.3575 9 P 0 ;1
L 1.7075 4.4075 1.7075 4.4075 9 P 0 ;1
L 1.7075 4.4575 1.7075 4.4575 9 P 0 ;1
L 1.7075 4.5075 1.7075 4.5075 9 P 0 ;1
L 1.7075 4.5575 1.7075 4.5575 9 P 0 ;1
L 1.7075 4.6075 1.7075 4.6075 9 P 0 ;1
L 1.7075 4.6575 1.7075 4.6575 9 P 0 ;1
L 1.7075 5.2075 1.7075 5.2075 9 P 0 ;1
L 1.7075 5.2575 1.7075 5.2575 9 P 0 ;1
L 1.7075 5.3075 1.7075 5.3075 9 P 0 ;1
L 1.7075 5.3575 1.7075 5.3575 9 P 0 ;1
L 1.7075 5.4075 1.7075 5.4075 9 P 0 ;1
L 1.7075 5.4575 1.7075 5.4575 9 P 0 ;1
L 1.7075 5.5075 1.7075 5.5075 9 P 0 ;1
L 1.7075 5.5575 1.7075 5.5575 9 P 0 ;1
L 1.7075 5.6075 1.7075 5.6075 9 P 0 ;1
L 1.7075 5.6575 1.7075 5.6575 9 P 0 ;1
L 1.7075 5.7075 1.7075 5.7075 9 P 0 ;1
L 1.7075 5.7575 1.7075 5.7575 9 P 0 ;1
L 1.7075 5.8075 1.7075 5.8075 9 P 0 ;1
L 1.7075 5.8575 1.7075 5.8575 9 P 0 ;1
L 1.7075 5.9075 1.7075 5.9075 9 P 0 ;1
L 1.7575 0.1575 1.7575 0.1575 9 P 0 ;1
L 1.7575 0.2075 1.7575 0.2075 9 P 0 ;1
L 1.7575 0.2575 1.7575 0.2575 9 P 0 ;1
L 1.7575 0.3075 1.7575 0.3075 9 P 0 ;1
L 1.7575 0.3575 1.7575 0.3575 9 P 0 ;1
L 1.7575 0.4075 1.7575 0.4075 9 P 0 ;1
L 1.7575 0.4575 1.7575 0.4575 9 P 0 ;1
L 1.7575 0.5075 1.7575 0.5075 9 P 0 ;1
L 1.7575 0.5575 1.7575 0.5575 9 P 0 ;1
L 1.7575 0.6075 1.7575 0.6075 9 P 0 ;1
L 1.7575 0.6575 1.7575 0.6575 9 P 0 ;1
L 1.7575 0.7075 1.7575 0.7075 9 P 0 ;1
L 1.7575 0.7575 1.7575 0.7575 9 P 0 ;1
L 1.7575 0.8075 1.7575 0.8075 9 P 0 ;1
L 1.7575 0.8575 1.7575 0.8575 9 P 0 ;1
L 1.7575 0.9075 1.7575 0.9075 9 P 0 ;1
L 1.7575 0.9575 1.7575 0.9575 9 P 0 ;1
L 1.7575 1.0075 1.7575 1.0075 9 P 0 ;1
L 1.7575 1.0575 1.7575 1.0575 9 P 0 ;1
L 1.7575 1.1075 1.7575 1.1075 9 P 0 ;1
L 1.7575 1.1575 1.7575 1.1575 9 P 0 ;1
L 1.7575 1.2075 1.7575 1.2075 9 P 0 ;1
L 1.7575 1.2575 1.7575 1.2575 9 P 0 ;1
L 1.7575 1.3075 1.7575 1.3075 9 P 0 ;1
L 1.7575 1.3575 1.7575 1.3575 9 P 0 ;1
L 1.7575 1.4075 1.7575 1.4075 9 P 0 ;1
L 1.7575 1.4575 1.7575 1.4575 9 P 0 ;1
L 1.7575 1.5075 1.7575 1.5075 9 P 0 ;1
L 1.7575 1.5575 1.7575 1.5575 9 P 0 ;1
L 1.7575 1.6075 1.7575 1.6075 9 P 0 ;1
L 1.7575 1.6575 1.7575 1.6575 9 P 0 ;1
L 1.7575 1.7075 1.7575 1.7075 9 P 0 ;1
L 1.7575 1.7575 1.7575 1.7575 9 P 0 ;1
L 1.7575 1.8075 1.7575 1.8075 9 P 0 ;1
L 1.7575 1.8575 1.7575 1.8575 9 P 0 ;1
L 1.7575 1.9075 1.7575 1.9075 9 P 0 ;1
L 1.7575 1.9575 1.7575 1.9575 9 P 0 ;1
L 1.7575 2.0075 1.7575 2.0075 9 P 0 ;1
L 1.7575 2.0575 1.7575 2.0575 9 P 0 ;1
L 1.7575 2.1075 1.7575 2.1075 9 P 0 ;1
L 1.7575 2.1575 1.7575 2.1575 9 P 0 ;1
L 1.7575 2.2075 1.7575 2.2075 9 P 0 ;1
L 1.7575 2.2575 1.7575 2.2575 9 P 0 ;1
L 1.7575 2.3075 1.7575 2.3075 9 P 0 ;1
L 1.7575 2.3575 1.7575 2.3575 9 P 0 ;1
L 1.7575 2.5575 1.7575 2.5575 9 P 0 ;1
L 1.7575 2.6075 1.7575 2.6075 9 P 0 ;1
L 1.7575 2.6575 1.7575 2.6575 9 P 0 ;1
L 1.7575 2.7075 1.7575 2.7075 9 P 0 ;1
L 1.7575 2.7575 1.7575 2.7575 9 P 0 ;1
L 1.7575 2.8075 1.7575 2.8075 9 P 0 ;1
L 1.7575 2.8575 1.7575 2.8575 9 P 0 ;1
L 1.7575 2.9075 1.7575 2.9075 9 P 0 ;1
L 1.7575 2.9575 1.7575 2.9575 9 P 0 ;1
L 1.7575 3.0075 1.7575 3.0075 9 P 0 ;1
L 1.7575 3.0575 1.7575 3.0575 9 P 0 ;1
L 1.7575 3.1075 1.7575 3.1075 9 P 0 ;1
L 1.7575 3.1575 1.7575 3.1575 9 P 0 ;1
L 1.7575 3.2075 1.7575 3.2075 9 P 0 ;1
L 1.7575 3.2575 1.7575 3.2575 9 P 0 ;1
L 1.7575 3.3075 1.7575 3.3075 9 P 0 ;1
L 1.7575 3.3575 1.7575 3.3575 9 P 0 ;1
L 1.7575 3.4075 1.7575 3.4075 9 P 0 ;1
L 1.7575 3.4575 1.7575 3.4575 9 P 0 ;1
L 1.7575 3.5075 1.7575 3.5075 9 P 0 ;1
L 1.7575 3.5575 1.7575 3.5575 9 P 0 ;1
L 1.7575 3.6075 1.7575 3.6075 9 P 0 ;1
L 1.7575 3.6575 1.7575 3.6575 9 P 0 ;1
L 1.7575 3.7075 1.7575 3.7075 9 P 0 ;1
L 1.7575 3.7575 1.7575 3.7575 9 P 0 ;1
L 1.7575 3.8075 1.7575 3.8075 9 P 0 ;1
L 1.7575 3.8575 1.7575 3.8575 9 P 0 ;1
L 1.7575 3.9075 1.7575 3.9075 9 P 0 ;1
L 1.7575 3.9575 1.7575 3.9575 9 P 0 ;1
L 1.7575 4.0075 1.7575 4.0075 9 P 0 ;1
L 1.7575 4.0575 1.7575 4.0575 9 P 0 ;1
L 1.7575 4.1075 1.7575 4.1075 9 P 0 ;1
L 1.7575 4.1575 1.7575 4.1575 9 P 0 ;1
L 1.7575 4.2075 1.7575 4.2075 9 P 0 ;1
L 1.7575 4.2575 1.7575 4.2575 9 P 0 ;1
L 1.7575 4.3075 1.7575 4.3075 9 P 0 ;1
L 1.7575 4.3575 1.7575 4.3575 9 P 0 ;1
L 1.7575 4.4075 1.7575 4.4075 9 P 0 ;1
L 1.7575 4.5575 1.7575 4.5575 9 P 0 ;1
L 1.7575 4.6075 1.7575 4.6075 9 P 0 ;1
L 1.7575 4.6575 1.7575 4.6575 9 P 0 ;1
L 1.7575 5.1575 1.7575 5.1575 9 P 0 ;1
L 1.7575 5.2075 1.7575 5.2075 9 P 0 ;1
L 1.7575 5.2575 1.7575 5.2575 9 P 0 ;1
L 1.7575 5.3075 1.7575 5.3075 9 P 0 ;1
L 1.7575 5.3575 1.7575 5.3575 9 P 0 ;1
L 1.7575 5.4075 1.7575 5.4075 9 P 0 ;1
L 1.7575 5.4575 1.7575 5.4575 9 P 0 ;1
L 1.7575 5.5075 1.7575 5.5075 9 P 0 ;1
L 1.7575 5.5575 1.7575 5.5575 9 P 0 ;1
L 1.7575 5.6075 1.7575 5.6075 9 P 0 ;1
L 1.7575 5.6575 1.7575 5.6575 9 P 0 ;1
L 1.7575 5.7075 1.7575 5.7075 9 P 0 ;1
L 1.7575 5.7575 1.7575 5.7575 9 P 0 ;1
L 1.7575 5.8075 1.7575 5.8075 9 P 0 ;1
L 1.7575 5.8575 1.7575 5.8575 9 P 0 ;1
L 1.7575 5.9075 1.7575 5.9075 9 P 0 ;1
L 1.8075 0.1575 1.8075 0.1575 9 P 0 ;1
L 1.8075 0.2075 1.8075 0.2075 9 P 0 ;1
L 1.8075 0.2575 1.8075 0.2575 9 P 0 ;1
L 1.8075 0.3075 1.8075 0.3075 9 P 0 ;1
L 1.8075 0.3575 1.8075 0.3575 9 P 0 ;1
L 1.8075 0.4075 1.8075 0.4075 9 P 0 ;1
L 1.8075 0.4575 1.8075 0.4575 9 P 0 ;1
L 1.8075 0.5075 1.8075 0.5075 9 P 0 ;1
L 1.8075 0.5575 1.8075 0.5575 9 P 0 ;1
L 1.8075 0.6075 1.8075 0.6075 9 P 0 ;1
L 1.8075 0.6575 1.8075 0.6575 9 P 0 ;1
L 1.8075 0.7075 1.8075 0.7075 9 P 0 ;1
L 1.8075 0.7575 1.8075 0.7575 9 P 0 ;1
L 1.8075 0.8075 1.8075 0.8075 9 P 0 ;1
L 1.8075 0.8575 1.8075 0.8575 9 P 0 ;1
L 1.8075 0.9075 1.8075 0.9075 9 P 0 ;1
L 1.8075 0.9575 1.8075 0.9575 9 P 0 ;1
L 1.8075 1.0075 1.8075 1.0075 9 P 0 ;1
L 1.8075 1.0575 1.8075 1.0575 9 P 0 ;1
L 1.8075 1.1075 1.8075 1.1075 9 P 0 ;1
L 1.8075 1.1575 1.8075 1.1575 9 P 0 ;1
L 1.8075 1.2075 1.8075 1.2075 9 P 0 ;1
L 1.8075 1.2575 1.8075 1.2575 9 P 0 ;1
L 1.8075 1.3075 1.8075 1.3075 9 P 0 ;1
L 1.8075 1.3575 1.8075 1.3575 9 P 0 ;1
L 1.8075 1.4075 1.8075 1.4075 9 P 0 ;1
L 1.8075 1.4575 1.8075 1.4575 9 P 0 ;1
L 1.8075 1.5075 1.8075 1.5075 9 P 0 ;1
L 1.8075 1.5575 1.8075 1.5575 9 P 0 ;1
L 1.8075 1.6075 1.8075 1.6075 9 P 0 ;1
L 1.8075 1.6575 1.8075 1.6575 9 P 0 ;1
L 1.8075 1.7075 1.8075 1.7075 9 P 0 ;1
L 1.8075 1.7575 1.8075 1.7575 9 P 0 ;1
L 1.8075 1.8075 1.8075 1.8075 9 P 0 ;1
L 1.8075 1.8575 1.8075 1.8575 9 P 0 ;1
L 1.8075 1.9075 1.8075 1.9075 9 P 0 ;1
L 1.8075 1.9575 1.8075 1.9575 9 P 0 ;1
L 1.8075 2.0075 1.8075 2.0075 9 P 0 ;1
L 1.8075 2.0575 1.8075 2.0575 9 P 0 ;1
L 1.8075 2.1075 1.8075 2.1075 9 P 0 ;1
L 1.8075 2.1575 1.8075 2.1575 9 P 0 ;1
L 1.8075 2.2075 1.8075 2.2075 9 P 0 ;1
L 1.8075 2.2575 1.8075 2.2575 9 P 0 ;1
L 1.8075 2.3075 1.8075 2.3075 9 P 0 ;1
L 1.8075 2.3575 1.8075 2.3575 9 P 0 ;1
L 1.8075 2.5575 1.8075 2.5575 9 P 0 ;1
L 1.8075 2.6075 1.8075 2.6075 9 P 0 ;1
L 1.8075 2.6575 1.8075 2.6575 9 P 0 ;1
L 1.8075 2.7075 1.8075 2.7075 9 P 0 ;1
L 1.8075 2.7575 1.8075 2.7575 9 P 0 ;1
L 1.8075 2.8075 1.8075 2.8075 9 P 0 ;1
L 1.8075 2.8575 1.8075 2.8575 9 P 0 ;1
L 1.8075 2.9075 1.8075 2.9075 9 P 0 ;1
L 1.8075 2.9575 1.8075 2.9575 9 P 0 ;1
L 1.8075 3.0075 1.8075 3.0075 9 P 0 ;1
L 1.8075 3.0575 1.8075 3.0575 9 P 0 ;1
L 1.8075 3.1075 1.8075 3.1075 9 P 0 ;1
L 1.8075 3.1575 1.8075 3.1575 9 P 0 ;1
L 1.8075 3.2075 1.8075 3.2075 9 P 0 ;1
L 1.8075 3.2575 1.8075 3.2575 9 P 0 ;1
L 1.8075 3.3075 1.8075 3.3075 9 P 0 ;1
L 1.8075 3.3575 1.8075 3.3575 9 P 0 ;1
L 1.8075 3.4075 1.8075 3.4075 9 P 0 ;1
L 1.8075 3.4575 1.8075 3.4575 9 P 0 ;1
L 1.8075 3.5075 1.8075 3.5075 9 P 0 ;1
L 1.8075 3.5575 1.8075 3.5575 9 P 0 ;1
L 1.8075 3.6075 1.8075 3.6075 9 P 0 ;1
L 1.8075 4.1575 1.8075 4.1575 9 P 0 ;1
L 1.8075 4.2075 1.8075 4.2075 9 P 0 ;1
L 1.8075 4.2575 1.8075 4.2575 9 P 0 ;1
L 1.8075 4.3075 1.8075 4.3075 9 P 0 ;1
L 1.8075 4.3575 1.8075 4.3575 9 P 0 ;1
L 1.8075 5.2575 1.8075 5.2575 9 P 0 ;1
L 1.8075 5.3075 1.8075 5.3075 9 P 0 ;1
L 1.8075 5.3575 1.8075 5.3575 9 P 0 ;1
L 1.8075 5.4075 1.8075 5.4075 9 P 0 ;1
L 1.8075 5.4575 1.8075 5.4575 9 P 0 ;1
L 1.8075 5.5075 1.8075 5.5075 9 P 0 ;1
L 1.8075 5.5575 1.8075 5.5575 9 P 0 ;1
L 1.8075 5.6075 1.8075 5.6075 9 P 0 ;1
L 1.8075 5.6575 1.8075 5.6575 9 P 0 ;1
L 1.8075 5.7075 1.8075 5.7075 9 P 0 ;1
L 1.8075 5.7575 1.8075 5.7575 9 P 0 ;1
L 1.8075 5.8075 1.8075 5.8075 9 P 0 ;1
L 1.8075 5.8575 1.8075 5.8575 9 P 0 ;1
L 1.8075 5.9075 1.8075 5.9075 9 P 0 ;1
L 1.8575 0.1575 1.8575 0.1575 9 P 0 ;1
L 1.8575 0.2075 1.8575 0.2075 9 P 0 ;1
L 1.8575 0.2575 1.8575 0.2575 9 P 0 ;1
L 1.8575 0.3075 1.8575 0.3075 9 P 0 ;1
L 1.8575 0.3575 1.8575 0.3575 9 P 0 ;1
L 1.8575 0.4075 1.8575 0.4075 9 P 0 ;1
L 1.8575 0.4575 1.8575 0.4575 9 P 0 ;1
L 1.8575 0.5075 1.8575 0.5075 9 P 0 ;1
L 1.8575 0.5575 1.8575 0.5575 9 P 0 ;1
L 1.8575 0.6075 1.8575 0.6075 9 P 0 ;1
L 1.8575 0.6575 1.8575 0.6575 9 P 0 ;1
L 1.8575 0.7075 1.8575 0.7075 9 P 0 ;1
L 1.8575 0.7575 1.8575 0.7575 9 P 0 ;1
L 1.8575 0.8075 1.8575 0.8075 9 P 0 ;1
L 1.8575 0.8575 1.8575 0.8575 9 P 0 ;1
L 1.8575 0.9075 1.8575 0.9075 9 P 0 ;1
L 1.8575 0.9575 1.8575 0.9575 9 P 0 ;1
L 1.8575 1.0075 1.8575 1.0075 9 P 0 ;1
L 1.8575 1.0575 1.8575 1.0575 9 P 0 ;1
L 1.8575 1.1075 1.8575 1.1075 9 P 0 ;1
L 1.8575 1.1575 1.8575 1.1575 9 P 0 ;1
L 1.8575 1.2075 1.8575 1.2075 9 P 0 ;1
L 1.8575 1.2575 1.8575 1.2575 9 P 0 ;1
L 1.8575 1.3075 1.8575 1.3075 9 P 0 ;1
L 1.8575 1.3575 1.8575 1.3575 9 P 0 ;1
L 1.8575 1.4075 1.8575 1.4075 9 P 0 ;1
L 1.8575 1.4575 1.8575 1.4575 9 P 0 ;1
L 1.8575 1.5075 1.8575 1.5075 9 P 0 ;1
L 1.8575 1.5575 1.8575 1.5575 9 P 0 ;1
L 1.8575 1.6075 1.8575 1.6075 9 P 0 ;1
L 1.8575 1.6575 1.8575 1.6575 9 P 0 ;1
L 1.8575 1.7075 1.8575 1.7075 9 P 0 ;1
L 1.8575 1.7575 1.8575 1.7575 9 P 0 ;1
L 1.8575 1.8075 1.8575 1.8075 9 P 0 ;1
L 1.8575 1.8575 1.8575 1.8575 9 P 0 ;1
L 1.8575 1.9075 1.8575 1.9075 9 P 0 ;1
L 1.8575 1.9575 1.8575 1.9575 9 P 0 ;1
L 1.8575 2.0075 1.8575 2.0075 9 P 0 ;1
L 1.8575 2.0575 1.8575 2.0575 9 P 0 ;1
L 1.8575 2.1075 1.8575 2.1075 9 P 0 ;1
L 1.8575 2.1575 1.8575 2.1575 9 P 0 ;1
L 1.8575 2.2075 1.8575 2.2075 9 P 0 ;1
L 1.8575 2.2575 1.8575 2.2575 9 P 0 ;1
L 1.8575 2.3075 1.8575 2.3075 9 P 0 ;1
L 1.8575 2.3575 1.8575 2.3575 9 P 0 ;1
L 1.8575 2.4075 1.8575 2.4075 9 P 0 ;1
L 1.8575 2.5575 1.8575 2.5575 9 P 0 ;1
L 1.8575 2.6075 1.8575 2.6075 9 P 0 ;1
L 1.8575 2.6575 1.8575 2.6575 9 P 0 ;1
L 1.8575 2.7075 1.8575 2.7075 9 P 0 ;1
L 1.8575 2.7575 1.8575 2.7575 9 P 0 ;1
L 1.8575 2.8075 1.8575 2.8075 9 P 0 ;1
L 1.8575 2.8575 1.8575 2.8575 9 P 0 ;1
L 1.8575 2.9075 1.8575 2.9075 9 P 0 ;1
L 1.8575 2.9575 1.8575 2.9575 9 P 0 ;1
L 1.8575 3.0075 1.8575 3.0075 9 P 0 ;1
L 1.8575 3.0575 1.8575 3.0575 9 P 0 ;1
L 1.8575 3.1075 1.8575 3.1075 9 P 0 ;1
L 1.8575 3.1575 1.8575 3.1575 9 P 0 ;1
L 1.8575 3.2075 1.8575 3.2075 9 P 0 ;1
L 1.8575 3.2575 1.8575 3.2575 9 P 0 ;1
L 1.8575 3.3075 1.8575 3.3075 9 P 0 ;1
L 1.8575 3.3575 1.8575 3.3575 9 P 0 ;1
L 1.8575 3.4075 1.8575 3.4075 9 P 0 ;1
L 1.8575 3.4575 1.8575 3.4575 9 P 0 ;1
L 1.8575 3.5075 1.8575 3.5075 9 P 0 ;1
L 1.8575 3.5575 1.8575 3.5575 9 P 0 ;1
L 1.8575 4.3575 1.8575 4.3575 9 P 0 ;1
L 1.8575 5.2575 1.8575 5.2575 9 P 0 ;1
L 1.8575 5.3075 1.8575 5.3075 9 P 0 ;1
L 1.8575 5.4575 1.8575 5.4575 9 P 0 ;1
L 1.8575 5.5075 1.8575 5.5075 9 P 0 ;1
L 1.8575 5.5575 1.8575 5.5575 9 P 0 ;1
L 1.8575 5.6075 1.8575 5.6075 9 P 0 ;1
L 1.8575 5.6575 1.8575 5.6575 9 P 0 ;1
L 1.8575 5.7075 1.8575 5.7075 9 P 0 ;1
L 1.8575 5.7575 1.8575 5.7575 9 P 0 ;1
L 1.8575 5.8075 1.8575 5.8075 9 P 0 ;1
L 1.8575 5.8575 1.8575 5.8575 9 P 0 ;1
L 1.8575 5.9075 1.8575 5.9075 9 P 0 ;1
L 1.9075 0.1575 1.9075 0.1575 9 P 0 ;1
L 1.9075 0.2075 1.9075 0.2075 9 P 0 ;1
L 1.9075 0.2575 1.9075 0.2575 9 P 0 ;1
L 1.9075 0.3075 1.9075 0.3075 9 P 0 ;1
L 1.9075 0.3575 1.9075 0.3575 9 P 0 ;1
L 1.9075 0.4075 1.9075 0.4075 9 P 0 ;1
L 1.9075 0.4575 1.9075 0.4575 9 P 0 ;1
L 1.9075 0.5075 1.9075 0.5075 9 P 0 ;1
L 1.9075 0.5575 1.9075 0.5575 9 P 0 ;1
L 1.9075 0.6075 1.9075 0.6075 9 P 0 ;1
L 1.9075 0.6575 1.9075 0.6575 9 P 0 ;1
L 1.9075 0.7075 1.9075 0.7075 9 P 0 ;1
L 1.9075 0.7575 1.9075 0.7575 9 P 0 ;1
L 1.9075 0.8075 1.9075 0.8075 9 P 0 ;1
L 1.9075 0.8575 1.9075 0.8575 9 P 0 ;1
L 1.9075 0.9075 1.9075 0.9075 9 P 0 ;1
L 1.9075 0.9575 1.9075 0.9575 9 P 0 ;1
L 1.9075 1.0075 1.9075 1.0075 9 P 0 ;1
L 1.9075 1.0575 1.9075 1.0575 9 P 0 ;1
L 1.9075 1.1075 1.9075 1.1075 9 P 0 ;1
L 1.9075 1.1575 1.9075 1.1575 9 P 0 ;1
L 1.9075 1.2075 1.9075 1.2075 9 P 0 ;1
L 1.9075 1.2575 1.9075 1.2575 9 P 0 ;1
L 1.9075 1.3075 1.9075 1.3075 9 P 0 ;1
L 1.9075 1.3575 1.9075 1.3575 9 P 0 ;1
L 1.9075 1.4075 1.9075 1.4075 9 P 0 ;1
L 1.9075 1.4575 1.9075 1.4575 9 P 0 ;1
L 1.9075 1.5075 1.9075 1.5075 9 P 0 ;1
L 1.9075 1.5575 1.9075 1.5575 9 P 0 ;1
L 1.9075 1.6075 1.9075 1.6075 9 P 0 ;1
L 1.9075 1.6575 1.9075 1.6575 9 P 0 ;1
L 1.9075 1.7075 1.9075 1.7075 9 P 0 ;1
L 1.9075 1.7575 1.9075 1.7575 9 P 0 ;1
L 1.9075 1.8075 1.9075 1.8075 9 P 0 ;1
L 1.9075 1.8575 1.9075 1.8575 9 P 0 ;1
L 1.9075 1.9075 1.9075 1.9075 9 P 0 ;1
L 1.9075 1.9575 1.9075 1.9575 9 P 0 ;1
L 1.9075 2.0075 1.9075 2.0075 9 P 0 ;1
L 1.9075 2.0575 1.9075 2.0575 9 P 0 ;1
L 1.9075 2.1075 1.9075 2.1075 9 P 0 ;1
L 1.9075 2.1575 1.9075 2.1575 9 P 0 ;1
L 1.9075 2.2075 1.9075 2.2075 9 P 0 ;1
L 1.9075 2.2575 1.9075 2.2575 9 P 0 ;1
L 1.9075 2.3075 1.9075 2.3075 9 P 0 ;1
L 1.9075 2.3575 1.9075 2.3575 9 P 0 ;1
L 1.9075 2.4075 1.9075 2.4075 9 P 0 ;1
L 1.9075 2.4575 1.9075 2.4575 9 P 0 ;1
L 1.9075 2.5075 1.9075 2.5075 9 P 0 ;1
L 1.9075 2.5575 1.9075 2.5575 9 P 0 ;1
L 1.9075 2.6075 1.9075 2.6075 9 P 0 ;1
L 1.9075 2.6575 1.9075 2.6575 9 P 0 ;1
L 1.9075 2.7075 1.9075 2.7075 9 P 0 ;1
L 1.9075 2.7575 1.9075 2.7575 9 P 0 ;1
L 1.9075 2.8075 1.9075 2.8075 9 P 0 ;1
L 1.9075 2.8575 1.9075 2.8575 9 P 0 ;1
L 1.9075 2.9075 1.9075 2.9075 9 P 0 ;1
L 1.9075 2.9575 1.9075 2.9575 9 P 0 ;1
L 1.9075 3.0075 1.9075 3.0075 9 P 0 ;1
L 1.9075 3.0575 1.9075 3.0575 9 P 0 ;1
L 1.9075 3.1075 1.9075 3.1075 9 P 0 ;1
L 1.9075 3.1575 1.9075 3.1575 9 P 0 ;1
L 1.9075 3.2075 1.9075 3.2075 9 P 0 ;1
L 1.9075 3.2575 1.9075 3.2575 9 P 0 ;1
L 1.9075 3.3075 1.9075 3.3075 9 P 0 ;1
L 1.9075 3.3575 1.9075 3.3575 9 P 0 ;1
L 1.9075 3.4075 1.9075 3.4075 9 P 0 ;1
L 1.9075 3.4575 1.9075 3.4575 9 P 0 ;1
L 1.9075 3.5075 1.9075 3.5075 9 P 0 ;1
L 1.9075 5.2575 1.9075 5.2575 9 P 0 ;1
L 1.9075 5.4575 1.9075 5.4575 9 P 0 ;1
L 1.9075 5.5075 1.9075 5.5075 9 P 0 ;1
L 1.9075 5.5575 1.9075 5.5575 9 P 0 ;1
L 1.9075 5.6075 1.9075 5.6075 9 P 0 ;1
L 1.9075 5.6575 1.9075 5.6575 9 P 0 ;1
L 1.9075 5.7075 1.9075 5.7075 9 P 0 ;1
L 1.9075 5.7575 1.9075 5.7575 9 P 0 ;1
L 1.9075 5.8075 1.9075 5.8075 9 P 0 ;1
L 1.9075 5.8575 1.9075 5.8575 9 P 0 ;1
L 1.9075 5.9075 1.9075 5.9075 9 P 0 ;1
L 1.9575 0.1575 1.9575 0.1575 9 P 0 ;1
L 1.9575 0.2075 1.9575 0.2075 9 P 0 ;1
L 1.9575 0.2575 1.9575 0.2575 9 P 0 ;1
L 1.9575 0.3075 1.9575 0.3075 9 P 0 ;1
L 1.9575 0.3575 1.9575 0.3575 9 P 0 ;1
L 1.9575 0.4075 1.9575 0.4075 9 P 0 ;1
L 1.9575 0.4575 1.9575 0.4575 9 P 0 ;1
L 1.9575 0.5075 1.9575 0.5075 9 P 0 ;1
L 1.9575 0.5575 1.9575 0.5575 9 P 0 ;1
L 1.9575 0.6075 1.9575 0.6075 9 P 0 ;1
L 1.9575 0.6575 1.9575 0.6575 9 P 0 ;1
L 1.9575 0.7075 1.9575 0.7075 9 P 0 ;1
L 1.9575 0.7575 1.9575 0.7575 9 P 0 ;1
L 1.9575 0.8075 1.9575 0.8075 9 P 0 ;1
L 1.9575 0.8575 1.9575 0.8575 9 P 0 ;1
L 1.9575 0.9075 1.9575 0.9075 9 P 0 ;1
L 1.9575 0.9575 1.9575 0.9575 9 P 0 ;1
L 1.9575 1.0075 1.9575 1.0075 9 P 0 ;1
L 1.9575 1.0575 1.9575 1.0575 9 P 0 ;1
L 1.9575 1.1075 1.9575 1.1075 9 P 0 ;1
L 1.9575 1.1575 1.9575 1.1575 9 P 0 ;1
L 1.9575 1.2075 1.9575 1.2075 9 P 0 ;1
L 1.9575 1.2575 1.9575 1.2575 9 P 0 ;1
L 1.9575 1.3075 1.9575 1.3075 9 P 0 ;1
L 1.9575 1.3575 1.9575 1.3575 9 P 0 ;1
L 1.9575 1.4075 1.9575 1.4075 9 P 0 ;1
L 1.9575 1.4575 1.9575 1.4575 9 P 0 ;1
L 1.9575 1.5075 1.9575 1.5075 9 P 0 ;1
L 1.9575 1.5575 1.9575 1.5575 9 P 0 ;1
L 1.9575 1.6075 1.9575 1.6075 9 P 0 ;1
L 1.9575 1.6575 1.9575 1.6575 9 P 0 ;1
L 1.9575 1.7075 1.9575 1.7075 9 P 0 ;1
L 1.9575 1.7575 1.9575 1.7575 9 P 0 ;1
L 1.9575 1.8075 1.9575 1.8075 9 P 0 ;1
L 1.9575 1.8575 1.9575 1.8575 9 P 0 ;1
L 1.9575 1.9075 1.9575 1.9075 9 P 0 ;1
L 1.9575 1.9575 1.9575 1.9575 9 P 0 ;1
L 1.9575 2.0075 1.9575 2.0075 9 P 0 ;1
L 1.9575 2.0575 1.9575 2.0575 9 P 0 ;1
L 1.9575 2.1075 1.9575 2.1075 9 P 0 ;1
L 1.9575 2.1575 1.9575 2.1575 9 P 0 ;1
L 1.9575 2.2075 1.9575 2.2075 9 P 0 ;1
L 1.9575 2.2575 1.9575 2.2575 9 P 0 ;1
L 1.9575 2.3075 1.9575 2.3075 9 P 0 ;1
L 1.9575 2.3575 1.9575 2.3575 9 P 0 ;1
L 1.9575 2.4075 1.9575 2.4075 9 P 0 ;1
L 1.9575 2.4575 1.9575 2.4575 9 P 0 ;1
L 1.9575 2.5075 1.9575 2.5075 9 P 0 ;1
L 1.9575 2.5575 1.9575 2.5575 9 P 0 ;1
L 1.9575 2.6075 1.9575 2.6075 9 P 0 ;1
L 1.9575 2.9575 1.9575 2.9575 9 P 0 ;1
L 1.9575 3.0075 1.9575 3.0075 9 P 0 ;1
L 1.9575 3.0575 1.9575 3.0575 9 P 0 ;1
L 1.9575 3.1075 1.9575 3.1075 9 P 0 ;1
L 1.9575 3.1575 1.9575 3.1575 9 P 0 ;1
L 1.9575 3.2075 1.9575 3.2075 9 P 0 ;1
L 1.9575 3.2575 1.9575 3.2575 9 P 0 ;1
L 1.9575 3.3075 1.9575 3.3075 9 P 0 ;1
L 1.9575 4.5075 1.9575 4.5075 9 P 0 ;1
L 1.9575 5.4575 1.9575 5.4575 9 P 0 ;1
L 1.9575 5.5075 1.9575 5.5075 9 P 0 ;1
L 1.9575 5.5575 1.9575 5.5575 9 P 0 ;1
L 1.9575 5.6075 1.9575 5.6075 9 P 0 ;1
L 1.9575 5.6575 1.9575 5.6575 9 P 0 ;1
L 1.9575 5.7075 1.9575 5.7075 9 P 0 ;1
L 1.9575 5.7575 1.9575 5.7575 9 P 0 ;1
L 1.9575 5.8075 1.9575 5.8075 9 P 0 ;1
L 1.9575 5.8575 1.9575 5.8575 9 P 0 ;1
L 1.9575 5.9075 1.9575 5.9075 9 P 0 ;1
L 2.0075 0.1575 2.0075 0.1575 9 P 0 ;1
L 2.0075 0.2075 2.0075 0.2075 9 P 0 ;1
L 2.0075 0.2575 2.0075 0.2575 9 P 0 ;1
L 2.0075 0.3075 2.0075 0.3075 9 P 0 ;1
L 2.0075 0.3575 2.0075 0.3575 9 P 0 ;1
L 2.0075 0.4075 2.0075 0.4075 9 P 0 ;1
L 2.0075 0.4575 2.0075 0.4575 9 P 0 ;1
L 2.0075 0.5075 2.0075 0.5075 9 P 0 ;1
L 2.0075 0.5575 2.0075 0.5575 9 P 0 ;1
L 2.0075 0.6075 2.0075 0.6075 9 P 0 ;1
L 2.0075 0.6575 2.0075 0.6575 9 P 0 ;1
L 2.0075 0.7075 2.0075 0.7075 9 P 0 ;1
L 2.0075 0.7575 2.0075 0.7575 9 P 0 ;1
L 2.0075 0.8075 2.0075 0.8075 9 P 0 ;1
L 2.0075 0.8575 2.0075 0.8575 9 P 0 ;1
L 2.0075 0.9075 2.0075 0.9075 9 P 0 ;1
L 2.0075 0.9575 2.0075 0.9575 9 P 0 ;1
L 2.0075 1.0075 2.0075 1.0075 9 P 0 ;1
L 2.0075 1.0575 2.0075 1.0575 9 P 0 ;1
L 2.0075 1.1075 2.0075 1.1075 9 P 0 ;1
L 2.0075 1.1575 2.0075 1.1575 9 P 0 ;1
L 2.0075 1.2075 2.0075 1.2075 9 P 0 ;1
L 2.0075 1.2575 2.0075 1.2575 9 P 0 ;1
L 2.0075 1.3075 2.0075 1.3075 9 P 0 ;1
L 2.0075 1.3575 2.0075 1.3575 9 P 0 ;1
L 2.0075 1.4075 2.0075 1.4075 9 P 0 ;1
L 2.0075 1.4575 2.0075 1.4575 9 P 0 ;1
L 2.0075 1.5075 2.0075 1.5075 9 P 0 ;1
L 2.0075 1.5575 2.0075 1.5575 9 P 0 ;1
L 2.0075 1.6075 2.0075 1.6075 9 P 0 ;1
L 2.0075 1.6575 2.0075 1.6575 9 P 0 ;1
L 2.0075 1.7075 2.0075 1.7075 9 P 0 ;1
L 2.0075 1.7575 2.0075 1.7575 9 P 0 ;1
L 2.0075 5.4075 2.0075 5.4075 9 P 0 ;1
L 2.0075 5.4575 2.0075 5.4575 9 P 0 ;1
L 2.0075 5.5075 2.0075 5.5075 9 P 0 ;1
L 2.0075 5.5575 2.0075 5.5575 9 P 0 ;1
L 2.0075 5.6075 2.0075 5.6075 9 P 0 ;1
L 2.0075 5.6575 2.0075 5.6575 9 P 0 ;1
L 2.0075 5.7075 2.0075 5.7075 9 P 0 ;1
L 2.0075 5.7575 2.0075 5.7575 9 P 0 ;1
L 2.0075 5.8075 2.0075 5.8075 9 P 0 ;1
L 2.0075 5.8575 2.0075 5.8575 9 P 0 ;1
L 2.0075 5.9075 2.0075 5.9075 9 P 0 ;1
L 2.0575 0.1575 2.0575 0.1575 9 P 0 ;1
L 2.0575 0.2075 2.0575 0.2075 9 P 0 ;1
L 2.0575 0.2575 2.0575 0.2575 9 P 0 ;1
L 2.0575 0.3075 2.0575 0.3075 9 P 0 ;1
L 2.0575 0.3575 2.0575 0.3575 9 P 0 ;1
L 2.0575 0.4075 2.0575 0.4075 9 P 0 ;1
L 2.0575 0.4575 2.0575 0.4575 9 P 0 ;1
L 2.0575 0.5075 2.0575 0.5075 9 P 0 ;1
L 2.0575 0.5575 2.0575 0.5575 9 P 0 ;1
L 2.0575 0.6075 2.0575 0.6075 9 P 0 ;1
L 2.0575 0.6575 2.0575 0.6575 9 P 0 ;1
L 2.0575 0.7075 2.0575 0.7075 9 P 0 ;1
L 2.0575 0.7575 2.0575 0.7575 9 P 0 ;1
L 2.0575 0.8075 2.0575 0.8075 9 P 0 ;1
L 2.0575 0.8575 2.0575 0.8575 9 P 0 ;1
L 2.0575 0.9075 2.0575 0.9075 9 P 0 ;1
L 2.0575 0.9575 2.0575 0.9575 9 P 0 ;1
L 2.0575 1.0075 2.0575 1.0075 9 P 0 ;1
L 2.0575 1.0575 2.0575 1.0575 9 P 0 ;1
L 2.0575 1.1075 2.0575 1.1075 9 P 0 ;1
L 2.0575 1.1575 2.0575 1.1575 9 P 0 ;1
L 2.0575 1.2075 2.0575 1.2075 9 P 0 ;1
L 2.0575 1.2575 2.0575 1.2575 9 P 0 ;1
L 2.0575 1.3075 2.0575 1.3075 9 P 0 ;1
L 2.0575 1.3575 2.0575 1.3575 9 P 0 ;1
L 2.0575 1.4075 2.0575 1.4075 9 P 0 ;1
L 2.0575 1.6075 2.0575 1.6075 9 P 0 ;1
L 2.0575 1.6575 2.0575 1.6575 9 P 0 ;1
L 2.0575 1.7075 2.0575 1.7075 9 P 0 ;1
L 2.0575 1.7575 2.0575 1.7575 9 P 0 ;1
L 2.0575 5.4075 2.0575 5.4075 9 P 0 ;1
L 2.0575 5.4575 2.0575 5.4575 9 P 0 ;1
L 2.0575 5.5075 2.0575 5.5075 9 P 0 ;1
L 2.0575 5.5575 2.0575 5.5575 9 P 0 ;1
L 2.0575 5.6075 2.0575 5.6075 9 P 0 ;1
L 2.0575 5.6575 2.0575 5.6575 9 P 0 ;1
L 2.0575 5.7075 2.0575 5.7075 9 P 0 ;1
L 2.0575 5.7575 2.0575 5.7575 9 P 0 ;1
L 2.0575 5.8075 2.0575 5.8075 9 P 0 ;1
L 2.0575 5.8575 2.0575 5.8575 9 P 0 ;1
L 2.0575 5.9075 2.0575 5.9075 9 P 0 ;1
L 2.1075 0.1575 2.1075 0.1575 9 P 0 ;1
L 2.1075 0.2075 2.1075 0.2075 9 P 0 ;1
L 2.1075 0.2575 2.1075 0.2575 9 P 0 ;1
L 2.1075 0.3075 2.1075 0.3075 9 P 0 ;1
L 2.1075 0.3575 2.1075 0.3575 9 P 0 ;1
L 2.1075 0.4075 2.1075 0.4075 9 P 0 ;1
L 2.1075 0.4575 2.1075 0.4575 9 P 0 ;1
L 2.1075 0.5075 2.1075 0.5075 9 P 0 ;1
L 2.1075 0.5575 2.1075 0.5575 9 P 0 ;1
L 2.1075 0.6075 2.1075 0.6075 9 P 0 ;1
L 2.1075 0.6575 2.1075 0.6575 9 P 0 ;1
L 2.1075 0.7075 2.1075 0.7075 9 P 0 ;1
L 2.1075 0.7575 2.1075 0.7575 9 P 0 ;1
L 2.1075 0.8075 2.1075 0.8075 9 P 0 ;1
L 2.1075 0.8575 2.1075 0.8575 9 P 0 ;1
L 2.1075 0.9075 2.1075 0.9075 9 P 0 ;1
L 2.1075 0.9575 2.1075 0.9575 9 P 0 ;1
L 2.1075 1.0075 2.1075 1.0075 9 P 0 ;1
L 2.1075 1.0575 2.1075 1.0575 9 P 0 ;1
L 2.1075 1.1075 2.1075 1.1075 9 P 0 ;1
L 2.1075 1.1575 2.1075 1.1575 9 P 0 ;1
L 2.1075 1.2075 2.1075 1.2075 9 P 0 ;1
L 2.1075 1.2575 2.1075 1.2575 9 P 0 ;1
L 2.1075 1.3075 2.1075 1.3075 9 P 0 ;1
L 2.1075 1.7075 2.1075 1.7075 9 P 0 ;1
L 2.1075 1.7575 2.1075 1.7575 9 P 0 ;1
L 2.1075 5.4575 2.1075 5.4575 9 P 0 ;1
L 2.1075 5.5075 2.1075 5.5075 9 P 0 ;1
L 2.1075 5.5575 2.1075 5.5575 9 P 0 ;1
L 2.1075 5.6075 2.1075 5.6075 9 P 0 ;1
L 2.1075 5.6575 2.1075 5.6575 9 P 0 ;1
L 2.1075 5.7075 2.1075 5.7075 9 P 0 ;1
L 2.1075 5.7575 2.1075 5.7575 9 P 0 ;1
L 2.1075 5.8075 2.1075 5.8075 9 P 0 ;1
L 2.1075 5.8575 2.1075 5.8575 9 P 0 ;1
L 2.1075 5.9075 2.1075 5.9075 9 P 0 ;1
L 2.1575 0.1575 2.1575 0.1575 9 P 0 ;1
L 2.1575 0.2075 2.1575 0.2075 9 P 0 ;1
L 2.1575 0.2575 2.1575 0.2575 9 P 0 ;1
L 2.1575 0.3075 2.1575 0.3075 9 P 0 ;1
L 2.1575 0.3575 2.1575 0.3575 9 P 0 ;1
L 2.1575 0.4075 2.1575 0.4075 9 P 0 ;1
L 2.1575 0.4575 2.1575 0.4575 9 P 0 ;1
L 2.1575 0.5075 2.1575 0.5075 9 P 0 ;1
L 2.1575 0.5575 2.1575 0.5575 9 P 0 ;1
L 2.1575 0.6075 2.1575 0.6075 9 P 0 ;1
L 2.1575 0.6575 2.1575 0.6575 9 P 0 ;1
L 2.1575 0.7075 2.1575 0.7075 9 P 0 ;1
L 2.1575 0.7575 2.1575 0.7575 9 P 0 ;1
L 2.1575 0.8075 2.1575 0.8075 9 P 0 ;1
L 2.1575 0.8575 2.1575 0.8575 9 P 0 ;1
L 2.1575 0.9075 2.1575 0.9075 9 P 0 ;1
L 2.1575 0.9575 2.1575 0.9575 9 P 0 ;1
L 2.1575 1.0075 2.1575 1.0075 9 P 0 ;1
L 2.1575 1.0575 2.1575 1.0575 9 P 0 ;1
L 2.1575 1.1075 2.1575 1.1075 9 P 0 ;1
L 2.1575 1.1575 2.1575 1.1575 9 P 0 ;1
L 2.1575 1.2075 2.1575 1.2075 9 P 0 ;1
L 2.1575 1.2575 2.1575 1.2575 9 P 0 ;1
L 2.1575 1.3075 2.1575 1.3075 9 P 0 ;1
L 2.1575 1.7075 2.1575 1.7075 9 P 0 ;1
L 2.1575 1.7575 2.1575 1.7575 9 P 0 ;1
L 2.1575 5.2575 2.1575 5.2575 9 P 0 ;1
L 2.1575 5.4575 2.1575 5.4575 9 P 0 ;1
L 2.1575 5.5075 2.1575 5.5075 9 P 0 ;1
L 2.1575 5.5575 2.1575 5.5575 9 P 0 ;1
L 2.1575 5.6075 2.1575 5.6075 9 P 0 ;1
L 2.1575 5.6575 2.1575 5.6575 9 P 0 ;1
L 2.1575 5.7075 2.1575 5.7075 9 P 0 ;1
L 2.1575 5.7575 2.1575 5.7575 9 P 0 ;1
L 2.1575 5.8075 2.1575 5.8075 9 P 0 ;1
L 2.1575 5.8575 2.1575 5.8575 9 P 0 ;1
L 2.1575 5.9075 2.1575 5.9075 9 P 0 ;1
L 2.2075 0.1575 2.2075 0.1575 9 P 0 ;1
L 2.2075 0.2075 2.2075 0.2075 9 P 0 ;1
L 2.2075 0.2575 2.2075 0.2575 9 P 0 ;1
L 2.2075 0.3075 2.2075 0.3075 9 P 0 ;1
L 2.2075 0.3575 2.2075 0.3575 9 P 0 ;1
L 2.2075 0.4075 2.2075 0.4075 9 P 0 ;1
L 2.2075 0.4575 2.2075 0.4575 9 P 0 ;1
L 2.2075 0.5075 2.2075 0.5075 9 P 0 ;1
L 2.2075 0.5575 2.2075 0.5575 9 P 0 ;1
L 2.2075 0.6075 2.2075 0.6075 9 P 0 ;1
L 2.2075 0.6575 2.2075 0.6575 9 P 0 ;1
L 2.2075 0.7075 2.2075 0.7075 9 P 0 ;1
L 2.2075 0.7575 2.2075 0.7575 9 P 0 ;1
L 2.2075 0.8075 2.2075 0.8075 9 P 0 ;1
L 2.2075 0.8575 2.2075 0.8575 9 P 0 ;1
L 2.2075 0.9075 2.2075 0.9075 9 P 0 ;1
L 2.2075 0.9575 2.2075 0.9575 9 P 0 ;1
L 2.2075 1.0075 2.2075 1.0075 9 P 0 ;1
L 2.2075 1.0575 2.2075 1.0575 9 P 0 ;1
L 2.2075 1.1075 2.2075 1.1075 9 P 0 ;1
L 2.2075 1.1575 2.2075 1.1575 9 P 0 ;1
L 2.2075 1.2075 2.2075 1.2075 9 P 0 ;1
L 2.2075 1.2575 2.2075 1.2575 9 P 0 ;1
L 2.2075 1.3075 2.2075 1.3075 9 P 0 ;1
L 2.2075 1.7575 2.2075 1.7575 9 P 0 ;1
L 2.2075 5.2075 2.2075 5.2075 9 P 0 ;1
L 2.2075 5.2575 2.2075 5.2575 9 P 0 ;1
L 2.2075 5.3075 2.2075 5.3075 9 P 0 ;1
L 2.2075 5.4575 2.2075 5.4575 9 P 0 ;1
L 2.2075 5.5075 2.2075 5.5075 9 P 0 ;1
L 2.2075 5.5575 2.2075 5.5575 9 P 0 ;1
L 2.2075 5.6075 2.2075 5.6075 9 P 0 ;1
L 2.2075 5.6575 2.2075 5.6575 9 P 0 ;1
L 2.2075 5.7075 2.2075 5.7075 9 P 0 ;1
L 2.2075 5.7575 2.2075 5.7575 9 P 0 ;1
L 2.2075 5.8075 2.2075 5.8075 9 P 0 ;1
L 2.2075 5.8575 2.2075 5.8575 9 P 0 ;1
L 2.2075 5.9075 2.2075 5.9075 9 P 0 ;1
L 2.2575 0.1575 2.2575 0.1575 9 P 0 ;1
L 2.2575 0.2075 2.2575 0.2075 9 P 0 ;1
L 2.2575 0.2575 2.2575 0.2575 9 P 0 ;1
L 2.2575 0.3075 2.2575 0.3075 9 P 0 ;1
L 2.2575 0.3575 2.2575 0.3575 9 P 0 ;1
L 2.2575 0.4075 2.2575 0.4075 9 P 0 ;1
L 2.2575 0.4575 2.2575 0.4575 9 P 0 ;1
L 2.2575 0.5075 2.2575 0.5075 9 P 0 ;1
L 2.2575 0.5575 2.2575 0.5575 9 P 0 ;1
L 2.2575 0.6075 2.2575 0.6075 9 P 0 ;1
L 2.2575 0.6575 2.2575 0.6575 9 P 0 ;1
L 2.2575 0.7075 2.2575 0.7075 9 P 0 ;1
L 2.2575 0.7575 2.2575 0.7575 9 P 0 ;1
L 2.2575 0.8075 2.2575 0.8075 9 P 0 ;1
L 2.2575 0.8575 2.2575 0.8575 9 P 0 ;1
L 2.2575 0.9075 2.2575 0.9075 9 P 0 ;1
L 2.2575 0.9575 2.2575 0.9575 9 P 0 ;1
L 2.2575 1.0075 2.2575 1.0075 9 P 0 ;1
L 2.2575 1.0575 2.2575 1.0575 9 P 0 ;1
L 2.2575 1.1075 2.2575 1.1075 9 P 0 ;1
L 2.2575 1.1575 2.2575 1.1575 9 P 0 ;1
L 2.2575 1.2075 2.2575 1.2075 9 P 0 ;1
L 2.2575 1.2575 2.2575 1.2575 9 P 0 ;1
L 2.2575 1.7575 2.2575 1.7575 9 P 0 ;1
L 2.2575 5.1575 2.2575 5.1575 9 P 0 ;1
L 2.2575 5.2075 2.2575 5.2075 9 P 0 ;1
L 2.2575 5.2575 2.2575 5.2575 9 P 0 ;1
L 2.2575 5.3075 2.2575 5.3075 9 P 0 ;1
L 2.2575 5.3575 2.2575 5.3575 9 P 0 ;1
L 2.2575 5.4075 2.2575 5.4075 9 P 0 ;1
L 2.2575 5.4575 2.2575 5.4575 9 P 0 ;1
L 2.2575 5.5075 2.2575 5.5075 9 P 0 ;1
L 2.2575 5.5575 2.2575 5.5575 9 P 0 ;1
L 2.2575 5.6075 2.2575 5.6075 9 P 0 ;1
L 2.2575 5.6575 2.2575 5.6575 9 P 0 ;1
L 2.2575 5.7075 2.2575 5.7075 9 P 0 ;1
L 2.2575 5.7575 2.2575 5.7575 9 P 0 ;1
L 2.2575 5.8075 2.2575 5.8075 9 P 0 ;1
L 2.2575 5.8575 2.2575 5.8575 9 P 0 ;1
L 2.2575 5.9075 2.2575 5.9075 9 P 0 ;1
L 2.3075 0.1575 2.3075 0.1575 9 P 0 ;1
L 2.3075 0.2075 2.3075 0.2075 9 P 0 ;1
L 2.3075 0.2575 2.3075 0.2575 9 P 0 ;1
L 2.3075 0.3075 2.3075 0.3075 9 P 0 ;1
L 2.3075 0.3575 2.3075 0.3575 9 P 0 ;1
L 2.3075 0.4075 2.3075 0.4075 9 P 0 ;1
L 2.3075 0.4575 2.3075 0.4575 9 P 0 ;1
L 2.3075 0.5075 2.3075 0.5075 9 P 0 ;1
L 2.3075 0.5575 2.3075 0.5575 9 P 0 ;1
L 2.3075 0.6075 2.3075 0.6075 9 P 0 ;1
L 2.3075 0.6575 2.3075 0.6575 9 P 0 ;1
L 2.3075 0.7075 2.3075 0.7075 9 P 0 ;1
L 2.3075 0.7575 2.3075 0.7575 9 P 0 ;1
L 2.3075 0.8075 2.3075 0.8075 9 P 0 ;1
L 2.3075 0.8575 2.3075 0.8575 9 P 0 ;1
L 2.3075 0.9075 2.3075 0.9075 9 P 0 ;1
L 2.3075 0.9575 2.3075 0.9575 9 P 0 ;1
L 2.3075 1.0075 2.3075 1.0075 9 P 0 ;1
L 2.3075 1.0575 2.3075 1.0575 9 P 0 ;1
L 2.3075 1.1075 2.3075 1.1075 9 P 0 ;1
L 2.3075 1.1575 2.3075 1.1575 9 P 0 ;1
L 2.3075 1.2075 2.3075 1.2075 9 P 0 ;1
L 2.3075 1.2575 2.3075 1.2575 9 P 0 ;1
L 2.3075 1.3075 2.3075 1.3075 9 P 0 ;1
L 2.3075 1.7075 2.3075 1.7075 9 P 0 ;1
L 2.3075 1.7575 2.3075 1.7575 9 P 0 ;1
L 2.3075 5.2575 2.3075 5.2575 9 P 0 ;1
L 2.3075 5.3075 2.3075 5.3075 9 P 0 ;1
L 2.3075 5.3575 2.3075 5.3575 9 P 0 ;1
L 2.3075 5.4075 2.3075 5.4075 9 P 0 ;1
L 2.3075 5.4575 2.3075 5.4575 9 P 0 ;1
L 2.3075 5.5075 2.3075 5.5075 9 P 0 ;1
L 2.3075 5.5575 2.3075 5.5575 9 P 0 ;1
L 2.3075 5.6075 2.3075 5.6075 9 P 0 ;1
L 2.3075 5.6575 2.3075 5.6575 9 P 0 ;1
L 2.3075 5.7075 2.3075 5.7075 9 P 0 ;1
L 2.3075 5.7575 2.3075 5.7575 9 P 0 ;1
L 2.3075 5.8075 2.3075 5.8075 9 P 0 ;1
L 2.3075 5.8575 2.3075 5.8575 9 P 0 ;1
L 2.3075 5.9075 2.3075 5.9075 9 P 0 ;1
L 2.3575 0.1575 2.3575 0.1575 9 P 0 ;1
L 2.3575 0.2075 2.3575 0.2075 9 P 0 ;1
L 2.3575 0.2575 2.3575 0.2575 9 P 0 ;1
L 2.3575 0.3075 2.3575 0.3075 9 P 0 ;1
L 2.3575 0.3575 2.3575 0.3575 9 P 0 ;1
L 2.3575 0.4075 2.3575 0.4075 9 P 0 ;1
L 2.3575 0.4575 2.3575 0.4575 9 P 0 ;1
L 2.3575 0.5075 2.3575 0.5075 9 P 0 ;1
L 2.3575 0.5575 2.3575 0.5575 9 P 0 ;1
L 2.3575 0.6075 2.3575 0.6075 9 P 0 ;1
L 2.3575 0.6575 2.3575 0.6575 9 P 0 ;1
L 2.3575 0.7075 2.3575 0.7075 9 P 0 ;1
L 2.3575 0.7575 2.3575 0.7575 9 P 0 ;1
L 2.3575 0.8075 2.3575 0.8075 9 P 0 ;1
L 2.3575 0.8575 2.3575 0.8575 9 P 0 ;1
L 2.3575 0.9075 2.3575 0.9075 9 P 0 ;1
L 2.3575 0.9575 2.3575 0.9575 9 P 0 ;1
L 2.3575 1.0075 2.3575 1.0075 9 P 0 ;1
L 2.3575 1.0575 2.3575 1.0575 9 P 0 ;1
L 2.3575 1.1075 2.3575 1.1075 9 P 0 ;1
L 2.3575 1.1575 2.3575 1.1575 9 P 0 ;1
L 2.3575 1.2075 2.3575 1.2075 9 P 0 ;1
L 2.3575 1.2575 2.3575 1.2575 9 P 0 ;1
L 2.3575 1.3075 2.3575 1.3075 9 P 0 ;1
L 2.3575 1.7075 2.3575 1.7075 9 P 0 ;1
L 2.3575 1.7575 2.3575 1.7575 9 P 0 ;1
L 2.3575 5.2575 2.3575 5.2575 9 P 0 ;1
L 2.3575 5.3075 2.3575 5.3075 9 P 0 ;1
L 2.3575 5.3575 2.3575 5.3575 9 P 0 ;1
L 2.3575 5.4075 2.3575 5.4075 9 P 0 ;1
L 2.3575 5.4575 2.3575 5.4575 9 P 0 ;1
L 2.3575 5.5075 2.3575 5.5075 9 P 0 ;1
L 2.3575 5.5575 2.3575 5.5575 9 P 0 ;1
L 2.3575 5.6075 2.3575 5.6075 9 P 0 ;1
L 2.3575 5.6575 2.3575 5.6575 9 P 0 ;1
L 2.3575 5.7075 2.3575 5.7075 9 P 0 ;1
L 2.3575 5.7575 2.3575 5.7575 9 P 0 ;1
L 2.3575 5.8075 2.3575 5.8075 9 P 0 ;1
L 2.3575 5.8575 2.3575 5.8575 9 P 0 ;1
L 2.3575 5.9075 2.3575 5.9075 9 P 0 ;1
L 2.4075 0.1575 2.4075 0.1575 9 P 0 ;1
L 2.4075 0.2075 2.4075 0.2075 9 P 0 ;1
L 2.4075 0.2575 2.4075 0.2575 9 P 0 ;1
L 2.4075 0.3075 2.4075 0.3075 9 P 0 ;1
L 2.4075 0.3575 2.4075 0.3575 9 P 0 ;1
L 2.4075 0.4075 2.4075 0.4075 9 P 0 ;1
L 2.4075 0.4575 2.4075 0.4575 9 P 0 ;1
L 2.4075 0.5075 2.4075 0.5075 9 P 0 ;1
L 2.4075 0.5575 2.4075 0.5575 9 P 0 ;1
L 2.4075 0.6075 2.4075 0.6075 9 P 0 ;1
L 2.4075 0.6575 2.4075 0.6575 9 P 0 ;1
L 2.4075 0.7075 2.4075 0.7075 9 P 0 ;1
L 2.4075 0.7575 2.4075 0.7575 9 P 0 ;1
L 2.4075 0.8075 2.4075 0.8075 9 P 0 ;1
L 2.4075 0.8575 2.4075 0.8575 9 P 0 ;1
L 2.4075 0.9075 2.4075 0.9075 9 P 0 ;1
L 2.4075 0.9575 2.4075 0.9575 9 P 0 ;1
L 2.4075 1.0075 2.4075 1.0075 9 P 0 ;1
L 2.4075 1.0575 2.4075 1.0575 9 P 0 ;1
L 2.4075 1.1075 2.4075 1.1075 9 P 0 ;1
L 2.4075 1.1575 2.4075 1.1575 9 P 0 ;1
L 2.4075 1.2075 2.4075 1.2075 9 P 0 ;1
L 2.4075 1.2575 2.4075 1.2575 9 P 0 ;1
L 2.4075 1.3075 2.4075 1.3075 9 P 0 ;1
L 2.4075 1.3575 2.4075 1.3575 9 P 0 ;1
L 2.4075 1.6575 2.4075 1.6575 9 P 0 ;1
L 2.4075 1.7075 2.4075 1.7075 9 P 0 ;1
L 2.4075 1.7575 2.4075 1.7575 9 P 0 ;1
L 2.4075 5.2575 2.4075 5.2575 9 P 0 ;1
L 2.4075 5.3075 2.4075 5.3075 9 P 0 ;1
L 2.4075 5.3575 2.4075 5.3575 9 P 0 ;1
L 2.4075 5.4075 2.4075 5.4075 9 P 0 ;1
L 2.4075 5.4575 2.4075 5.4575 9 P 0 ;1
L 2.4075 5.5075 2.4075 5.5075 9 P 0 ;1
L 2.4075 5.5575 2.4075 5.5575 9 P 0 ;1
L 2.4075 5.6075 2.4075 5.6075 9 P 0 ;1
L 2.4075 5.6575 2.4075 5.6575 9 P 0 ;1
L 2.4075 5.7075 2.4075 5.7075 9 P 0 ;1
L 2.4075 5.7575 2.4075 5.7575 9 P 0 ;1
L 2.4075 5.8075 2.4075 5.8075 9 P 0 ;1
L 2.4075 5.8575 2.4075 5.8575 9 P 0 ;1
L 2.4075 5.9075 2.4075 5.9075 9 P 0 ;1
L 2.4575 0.1575 2.4575 0.1575 9 P 0 ;1
L 2.4575 0.2075 2.4575 0.2075 9 P 0 ;1
L 2.4575 0.2575 2.4575 0.2575 9 P 0 ;1
L 2.4575 0.3075 2.4575 0.3075 9 P 0 ;1
L 2.4575 0.3575 2.4575 0.3575 9 P 0 ;1
L 2.4575 0.4075 2.4575 0.4075 9 P 0 ;1
L 2.4575 0.4575 2.4575 0.4575 9 P 0 ;1
L 2.4575 0.5075 2.4575 0.5075 9 P 0 ;1
L 2.4575 0.5575 2.4575 0.5575 9 P 0 ;1
L 2.4575 0.6075 2.4575 0.6075 9 P 0 ;1
L 2.4575 0.6575 2.4575 0.6575 9 P 0 ;1
L 2.4575 0.7075 2.4575 0.7075 9 P 0 ;1
L 2.4575 0.7575 2.4575 0.7575 9 P 0 ;1
L 2.4575 0.8075 2.4575 0.8075 9 P 0 ;1
L 2.4575 0.8575 2.4575 0.8575 9 P 0 ;1
L 2.4575 0.9075 2.4575 0.9075 9 P 0 ;1
L 2.4575 0.9575 2.4575 0.9575 9 P 0 ;1
L 2.4575 1.0075 2.4575 1.0075 9 P 0 ;1
L 2.4575 1.0575 2.4575 1.0575 9 P 0 ;1
L 2.4575 1.1075 2.4575 1.1075 9 P 0 ;1
L 2.4575 1.1575 2.4575 1.1575 9 P 0 ;1
L 2.4575 1.2075 2.4575 1.2075 9 P 0 ;1
L 2.4575 1.2575 2.4575 1.2575 9 P 0 ;1
L 2.4575 1.3075 2.4575 1.3075 9 P 0 ;1
L 2.4575 1.3575 2.4575 1.3575 9 P 0 ;1
L 2.4575 1.4075 2.4575 1.4075 9 P 0 ;1
L 2.4575 1.4575 2.4575 1.4575 9 P 0 ;1
L 2.4575 1.5075 2.4575 1.5075 9 P 0 ;1
L 2.4575 1.5575 2.4575 1.5575 9 P 0 ;1
L 2.4575 1.6075 2.4575 1.6075 9 P 0 ;1
L 2.4575 1.6575 2.4575 1.6575 9 P 0 ;1
L 2.4575 1.7075 2.4575 1.7075 9 P 0 ;1
L 2.4575 1.7575 2.4575 1.7575 9 P 0 ;1
L 2.4575 5.2575 2.4575 5.2575 9 P 0 ;1
L 2.4575 5.3075 2.4575 5.3075 9 P 0 ;1
L 2.4575 5.3575 2.4575 5.3575 9 P 0 ;1
L 2.4575 5.4075 2.4575 5.4075 9 P 0 ;1
L 2.4575 5.4575 2.4575 5.4575 9 P 0 ;1
L 2.4575 5.5075 2.4575 5.5075 9 P 0 ;1
L 2.4575 5.5575 2.4575 5.5575 9 P 0 ;1
L 2.4575 5.6075 2.4575 5.6075 9 P 0 ;1
L 2.4575 5.6575 2.4575 5.6575 9 P 0 ;1
L 2.4575 5.7075 2.4575 5.7075 9 P 0 ;1
L 2.4575 5.7575 2.4575 5.7575 9 P 0 ;1
L 2.4575 5.8075 2.4575 5.8075 9 P 0 ;1
L 2.4575 5.8575 2.4575 5.8575 9 P 0 ;1
L 2.4575 5.9075 2.4575 5.9075 9 P 0 ;1
L 2.5075 0.1575 2.5075 0.1575 9 P 0 ;1
L 2.5075 0.2075 2.5075 0.2075 9 P 0 ;1
L 2.5075 0.2575 2.5075 0.2575 9 P 0 ;1
L 2.5075 0.3075 2.5075 0.3075 9 P 0 ;1
L 2.5075 0.3575 2.5075 0.3575 9 P 0 ;1
L 2.5075 0.4075 2.5075 0.4075 9 P 0 ;1
L 2.5075 0.4575 2.5075 0.4575 9 P 0 ;1
L 2.5075 0.5075 2.5075 0.5075 9 P 0 ;1
L 2.5075 0.5575 2.5075 0.5575 9 P 0 ;1
L 2.5075 0.6075 2.5075 0.6075 9 P 0 ;1
L 2.5075 0.6575 2.5075 0.6575 9 P 0 ;1
L 2.5075 0.7075 2.5075 0.7075 9 P 0 ;1
L 2.5075 0.7575 2.5075 0.7575 9 P 0 ;1
L 2.5075 0.8075 2.5075 0.8075 9 P 0 ;1
L 2.5075 0.8575 2.5075 0.8575 9 P 0 ;1
L 2.5075 0.9075 2.5075 0.9075 9 P 0 ;1
L 2.5075 0.9575 2.5075 0.9575 9 P 0 ;1
L 2.5075 1.0075 2.5075 1.0075 9 P 0 ;1
L 2.5075 1.0575 2.5075 1.0575 9 P 0 ;1
L 2.5075 1.1075 2.5075 1.1075 9 P 0 ;1
L 2.5075 1.1575 2.5075 1.1575 9 P 0 ;1
L 2.5075 1.2075 2.5075 1.2075 9 P 0 ;1
L 2.5075 1.2575 2.5075 1.2575 9 P 0 ;1
L 2.5075 1.3075 2.5075 1.3075 9 P 0 ;1
L 2.5075 1.3575 2.5075 1.3575 9 P 0 ;1
L 2.5075 1.4075 2.5075 1.4075 9 P 0 ;1
L 2.5075 1.4575 2.5075 1.4575 9 P 0 ;1
L 2.5075 1.5075 2.5075 1.5075 9 P 0 ;1
L 2.5075 1.5575 2.5075 1.5575 9 P 0 ;1
L 2.5075 1.6075 2.5075 1.6075 9 P 0 ;1
L 2.5075 1.6575 2.5075 1.6575 9 P 0 ;1
L 2.5075 1.7075 2.5075 1.7075 9 P 0 ;1
L 2.5075 1.7575 2.5075 1.7575 9 P 0 ;1
L 2.5075 5.1575 2.5075 5.1575 9 P 0 ;1
L 2.5075 5.2075 2.5075 5.2075 9 P 0 ;1
L 2.5075 5.2575 2.5075 5.2575 9 P 0 ;1
L 2.5075 5.3075 2.5075 5.3075 9 P 0 ;1
L 2.5075 5.3575 2.5075 5.3575 9 P 0 ;1
L 2.5075 5.4075 2.5075 5.4075 9 P 0 ;1
L 2.5075 5.4575 2.5075 5.4575 9 P 0 ;1
L 2.5075 5.5075 2.5075 5.5075 9 P 0 ;1
L 2.5075 5.5575 2.5075 5.5575 9 P 0 ;1
L 2.5075 5.6075 2.5075 5.6075 9 P 0 ;1
L 2.5075 5.6575 2.5075 5.6575 9 P 0 ;1
L 2.5075 5.7075 2.5075 5.7075 9 P 0 ;1
L 2.5075 5.7575 2.5075 5.7575 9 P 0 ;1
L 2.5075 5.8075 2.5075 5.8075 9 P 0 ;1
L 2.5075 5.8575 2.5075 5.8575 9 P 0 ;1
L 2.5075 5.9075 2.5075 5.9075 9 P 0 ;1
L 2.5575 0.1575 2.5575 0.1575 9 P 0 ;1
L 2.5575 0.2075 2.5575 0.2075 9 P 0 ;1
L 2.5575 0.2575 2.5575 0.2575 9 P 0 ;1
L 2.5575 0.3075 2.5575 0.3075 9 P 0 ;1
L 2.5575 0.3575 2.5575 0.3575 9 P 0 ;1
L 2.5575 0.4075 2.5575 0.4075 9 P 0 ;1
L 2.5575 0.4575 2.5575 0.4575 9 P 0 ;1
L 2.5575 0.5075 2.5575 0.5075 9 P 0 ;1
L 2.5575 0.5575 2.5575 0.5575 9 P 0 ;1
L 2.5575 0.6075 2.5575 0.6075 9 P 0 ;1
L 2.5575 0.6575 2.5575 0.6575 9 P 0 ;1
L 2.5575 0.7075 2.5575 0.7075 9 P 0 ;1
L 2.5575 0.7575 2.5575 0.7575 9 P 0 ;1
L 2.5575 0.8075 2.5575 0.8075 9 P 0 ;1
L 2.5575 0.8575 2.5575 0.8575 9 P 0 ;1
L 2.5575 0.9075 2.5575 0.9075 9 P 0 ;1
L 2.5575 0.9575 2.5575 0.9575 9 P 0 ;1
L 2.5575 1.0075 2.5575 1.0075 9 P 0 ;1
L 2.5575 1.0575 2.5575 1.0575 9 P 0 ;1
L 2.5575 1.1075 2.5575 1.1075 9 P 0 ;1
L 2.5575 1.1575 2.5575 1.1575 9 P 0 ;1
L 2.5575 1.2075 2.5575 1.2075 9 P 0 ;1
L 2.5575 1.2575 2.5575 1.2575 9 P 0 ;1
L 2.5575 1.3075 2.5575 1.3075 9 P 0 ;1
L 2.5575 1.3575 2.5575 1.3575 9 P 0 ;1
L 2.5575 1.4075 2.5575 1.4075 9 P 0 ;1
L 2.5575 1.4575 2.5575 1.4575 9 P 0 ;1
L 2.5575 1.5075 2.5575 1.5075 9 P 0 ;1
L 2.5575 1.5575 2.5575 1.5575 9 P 0 ;1
L 2.5575 1.6075 2.5575 1.6075 9 P 0 ;1
L 2.5575 1.6575 2.5575 1.6575 9 P 0 ;1
L 2.5575 1.7075 2.5575 1.7075 9 P 0 ;1
L 2.5575 1.7575 2.5575 1.7575 9 P 0 ;1
L 2.5575 1.8075 2.5575 1.8075 9 P 0 ;1
L 2.5575 5.2075 2.5575 5.2075 9 P 0 ;1
L 2.5575 5.2575 2.5575 5.2575 9 P 0 ;1
L 2.5575 5.3075 2.5575 5.3075 9 P 0 ;1
L 2.5575 5.3575 2.5575 5.3575 9 P 0 ;1
L 2.5575 5.4075 2.5575 5.4075 9 P 0 ;1
L 2.5575 5.4575 2.5575 5.4575 9 P 0 ;1
L 2.5575 5.5075 2.5575 5.5075 9 P 0 ;1
L 2.5575 5.5575 2.5575 5.5575 9 P 0 ;1
L 2.5575 5.6075 2.5575 5.6075 9 P 0 ;1
L 2.5575 5.6575 2.5575 5.6575 9 P 0 ;1
L 2.5575 5.7075 2.5575 5.7075 9 P 0 ;1
L 2.5575 5.7575 2.5575 5.7575 9 P 0 ;1
L 2.5575 5.8075 2.5575 5.8075 9 P 0 ;1
L 2.5575 5.8575 2.5575 5.8575 9 P 0 ;1
L 2.5575 5.9075 2.5575 5.9075 9 P 0 ;1
L 2.6075 0.1575 2.6075 0.1575 9 P 0 ;1
L 2.6075 0.2075 2.6075 0.2075 9 P 0 ;1
L 2.6075 0.2575 2.6075 0.2575 9 P 0 ;1
L 2.6075 0.3075 2.6075 0.3075 9 P 0 ;1
L 2.6075 0.3575 2.6075 0.3575 9 P 0 ;1
L 2.6075 0.4075 2.6075 0.4075 9 P 0 ;1
L 2.6075 0.4575 2.6075 0.4575 9 P 0 ;1
L 2.6075 0.5075 2.6075 0.5075 9 P 0 ;1
L 2.6075 0.5575 2.6075 0.5575 9 P 0 ;1
L 2.6075 0.6075 2.6075 0.6075 9 P 0 ;1
L 2.6075 0.6575 2.6075 0.6575 9 P 0 ;1
L 2.6075 0.7075 2.6075 0.7075 9 P 0 ;1
L 2.6075 0.7575 2.6075 0.7575 9 P 0 ;1
L 2.6075 0.8075 2.6075 0.8075 9 P 0 ;1
L 2.6075 0.8575 2.6075 0.8575 9 P 0 ;1
L 2.6075 0.9075 2.6075 0.9075 9 P 0 ;1
L 2.6075 0.9575 2.6075 0.9575 9 P 0 ;1
L 2.6075 1.0075 2.6075 1.0075 9 P 0 ;1
L 2.6075 1.0575 2.6075 1.0575 9 P 0 ;1
L 2.6075 1.1075 2.6075 1.1075 9 P 0 ;1
L 2.6075 1.1575 2.6075 1.1575 9 P 0 ;1
L 2.6075 1.2075 2.6075 1.2075 9 P 0 ;1
L 2.6075 1.2575 2.6075 1.2575 9 P 0 ;1
L 2.6075 1.3075 2.6075 1.3075 9 P 0 ;1
L 2.6075 1.3575 2.6075 1.3575 9 P 0 ;1
L 2.6075 1.4075 2.6075 1.4075 9 P 0 ;1
L 2.6075 1.4575 2.6075 1.4575 9 P 0 ;1
L 2.6075 1.5075 2.6075 1.5075 9 P 0 ;1
L 2.6075 1.5575 2.6075 1.5575 9 P 0 ;1
L 2.6075 1.6075 2.6075 1.6075 9 P 0 ;1
L 2.6075 1.6575 2.6075 1.6575 9 P 0 ;1
L 2.6075 1.7075 2.6075 1.7075 9 P 0 ;1
L 2.6075 1.7575 2.6075 1.7575 9 P 0 ;1
L 2.6075 1.8075 2.6075 1.8075 9 P 0 ;1
L 2.6075 1.8575 2.6075 1.8575 9 P 0 ;1
L 2.6075 1.9075 2.6075 1.9075 9 P 0 ;1
L 2.6075 1.9575 2.6075 1.9575 9 P 0 ;1
L 2.6075 2.0075 2.6075 2.0075 9 P 0 ;1
L 2.6075 2.0575 2.6075 2.0575 9 P 0 ;1
L 2.6075 2.1075 2.6075 2.1075 9 P 0 ;1
L 2.6075 2.1575 2.6075 2.1575 9 P 0 ;1
L 2.6075 2.2075 2.6075 2.2075 9 P 0 ;1
L 2.6075 2.2575 2.6075 2.2575 9 P 0 ;1
L 2.6075 2.3075 2.6075 2.3075 9 P 0 ;1
L 2.6075 2.3575 2.6075 2.3575 9 P 0 ;1
L 2.6075 2.4075 2.6075 2.4075 9 P 0 ;1
L 2.6075 2.4575 2.6075 2.4575 9 P 0 ;1
L 2.6075 2.5075 2.6075 2.5075 9 P 0 ;1
L 2.6075 2.5575 2.6075 2.5575 9 P 0 ;1
L 2.6075 2.6075 2.6075 2.6075 9 P 0 ;1
L 2.6075 2.6575 2.6075 2.6575 9 P 0 ;1
L 2.6075 2.7075 2.6075 2.7075 9 P 0 ;1
L 2.6075 2.7575 2.6075 2.7575 9 P 0 ;1
L 2.6075 2.8075 2.6075 2.8075 9 P 0 ;1
L 2.6075 2.8575 2.6075 2.8575 9 P 0 ;1
L 2.6075 2.9075 2.6075 2.9075 9 P 0 ;1
L 2.6075 2.9575 2.6075 2.9575 9 P 0 ;1
L 2.6075 3.0075 2.6075 3.0075 9 P 0 ;1
L 2.6075 3.0575 2.6075 3.0575 9 P 0 ;1
L 2.6075 3.1075 2.6075 3.1075 9 P 0 ;1
L 2.6075 3.1575 2.6075 3.1575 9 P 0 ;1
L 2.6075 3.2075 2.6075 3.2075 9 P 0 ;1
L 2.6075 3.2575 2.6075 3.2575 9 P 0 ;1
L 2.6075 3.3075 2.6075 3.3075 9 P 0 ;1
L 2.6075 3.3575 2.6075 3.3575 9 P 0 ;1
L 2.6075 3.4075 2.6075 3.4075 9 P 0 ;1
L 2.6075 4.0575 2.6075 4.0575 9 P 0 ;1
L 2.6075 5.2575 2.6075 5.2575 9 P 0 ;1
L 2.6075 5.3075 2.6075 5.3075 9 P 0 ;1
L 2.6075 5.3575 2.6075 5.3575 9 P 0 ;1
L 2.6075 5.4075 2.6075 5.4075 9 P 0 ;1
L 2.6075 5.4575 2.6075 5.4575 9 P 0 ;1
L 2.6075 5.5075 2.6075 5.5075 9 P 0 ;1
L 2.6075 5.5575 2.6075 5.5575 9 P 0 ;1
L 2.6075 5.6075 2.6075 5.6075 9 P 0 ;1
L 2.6075 5.6575 2.6075 5.6575 9 P 0 ;1
L 2.6075 5.7075 2.6075 5.7075 9 P 0 ;1
L 2.6075 5.7575 2.6075 5.7575 9 P 0 ;1
L 2.6075 5.8075 2.6075 5.8075 9 P 0 ;1
L 2.6075 5.8575 2.6075 5.8575 9 P 0 ;1
L 2.6075 5.9075 2.6075 5.9075 9 P 0 ;1
L 2.6575 0.1575 2.6575 0.1575 9 P 0 ;1
L 2.6575 0.2075 2.6575 0.2075 9 P 0 ;1
L 2.6575 0.2575 2.6575 0.2575 9 P 0 ;1
L 2.6575 0.3075 2.6575 0.3075 9 P 0 ;1
L 2.6575 0.3575 2.6575 0.3575 9 P 0 ;1
L 2.6575 0.4075 2.6575 0.4075 9 P 0 ;1
L 2.6575 0.4575 2.6575 0.4575 9 P 0 ;1
L 2.6575 0.5075 2.6575 0.5075 9 P 0 ;1
L 2.6575 0.5575 2.6575 0.5575 9 P 0 ;1
L 2.6575 0.6075 2.6575 0.6075 9 P 0 ;1
L 2.6575 0.6575 2.6575 0.6575 9 P 0 ;1
L 2.6575 0.7075 2.6575 0.7075 9 P 0 ;1
L 2.6575 0.7575 2.6575 0.7575 9 P 0 ;1
L 2.6575 0.8075 2.6575 0.8075 9 P 0 ;1
L 2.6575 0.8575 2.6575 0.8575 9 P 0 ;1
L 2.6575 0.9075 2.6575 0.9075 9 P 0 ;1
L 2.6575 0.9575 2.6575 0.9575 9 P 0 ;1
L 2.6575 1.0075 2.6575 1.0075 9 P 0 ;1
L 2.6575 1.0575 2.6575 1.0575 9 P 0 ;1
L 2.6575 1.1075 2.6575 1.1075 9 P 0 ;1
L 2.6575 1.1575 2.6575 1.1575 9 P 0 ;1
L 2.6575 1.2075 2.6575 1.2075 9 P 0 ;1
L 2.6575 1.2575 2.6575 1.2575 9 P 0 ;1
L 2.6575 1.3075 2.6575 1.3075 9 P 0 ;1
L 2.6575 1.3575 2.6575 1.3575 9 P 0 ;1
L 2.6575 1.4075 2.6575 1.4075 9 P 0 ;1
L 2.6575 1.4575 2.6575 1.4575 9 P 0 ;1
L 2.6575 1.5075 2.6575 1.5075 9 P 0 ;1
L 2.6575 1.5575 2.6575 1.5575 9 P 0 ;1
L 2.6575 1.6075 2.6575 1.6075 9 P 0 ;1
L 2.6575 1.6575 2.6575 1.6575 9 P 0 ;1
L 2.6575 1.7075 2.6575 1.7075 9 P 0 ;1
L 2.6575 1.7575 2.6575 1.7575 9 P 0 ;1
L 2.6575 1.8075 2.6575 1.8075 9 P 0 ;1
L 2.6575 1.8575 2.6575 1.8575 9 P 0 ;1
L 2.6575 1.9075 2.6575 1.9075 9 P 0 ;1
L 2.6575 1.9575 2.6575 1.9575 9 P 0 ;1
L 2.6575 2.0075 2.6575 2.0075 9 P 0 ;1
L 2.6575 2.0575 2.6575 2.0575 9 P 0 ;1
L 2.6575 2.1075 2.6575 2.1075 9 P 0 ;1
L 2.6575 2.1575 2.6575 2.1575 9 P 0 ;1
L 2.6575 2.2075 2.6575 2.2075 9 P 0 ;1
L 2.6575 2.2575 2.6575 2.2575 9 P 0 ;1
L 2.6575 2.3075 2.6575 2.3075 9 P 0 ;1
L 2.6575 2.3575 2.6575 2.3575 9 P 0 ;1
L 2.6575 2.4075 2.6575 2.4075 9 P 0 ;1
L 2.6575 2.4575 2.6575 2.4575 9 P 0 ;1
L 2.6575 2.5075 2.6575 2.5075 9 P 0 ;1
L 2.6575 2.5575 2.6575 2.5575 9 P 0 ;1
L 2.6575 2.6075 2.6575 2.6075 9 P 0 ;1
L 2.6575 2.6575 2.6575 2.6575 9 P 0 ;1
L 2.6575 2.7075 2.6575 2.7075 9 P 0 ;1
L 2.6575 2.7575 2.6575 2.7575 9 P 0 ;1
L 2.6575 2.8075 2.6575 2.8075 9 P 0 ;1
L 2.6575 2.8575 2.6575 2.8575 9 P 0 ;1
L 2.6575 2.9075 2.6575 2.9075 9 P 0 ;1
L 2.6575 2.9575 2.6575 2.9575 9 P 0 ;1
L 2.6575 3.0075 2.6575 3.0075 9 P 0 ;1
L 2.6575 3.0575 2.6575 3.0575 9 P 0 ;1
L 2.6575 3.1075 2.6575 3.1075 9 P 0 ;1
L 2.6575 3.1575 2.6575 3.1575 9 P 0 ;1
L 2.6575 3.2075 2.6575 3.2075 9 P 0 ;1
L 2.6575 3.2575 2.6575 3.2575 9 P 0 ;1
L 2.6575 3.3075 2.6575 3.3075 9 P 0 ;1
L 2.6575 3.3575 2.6575 3.3575 9 P 0 ;1
L 2.6575 3.4075 2.6575 3.4075 9 P 0 ;1
L 2.6575 4.0075 2.6575 4.0075 9 P 0 ;1
L 2.6575 4.0575 2.6575 4.0575 9 P 0 ;1
L 2.6575 5.3075 2.6575 5.3075 9 P 0 ;1
L 2.6575 5.3575 2.6575 5.3575 9 P 0 ;1
L 2.6575 5.4075 2.6575 5.4075 9 P 0 ;1
L 2.6575 5.4575 2.6575 5.4575 9 P 0 ;1
L 2.6575 5.5075 2.6575 5.5075 9 P 0 ;1
L 2.6575 5.5575 2.6575 5.5575 9 P 0 ;1
L 2.6575 5.6075 2.6575 5.6075 9 P 0 ;1
L 2.6575 5.6575 2.6575 5.6575 9 P 0 ;1
L 2.6575 5.7075 2.6575 5.7075 9 P 0 ;1
L 2.6575 5.7575 2.6575 5.7575 9 P 0 ;1
L 2.6575 5.8075 2.6575 5.8075 9 P 0 ;1
L 2.6575 5.8575 2.6575 5.8575 9 P 0 ;1
L 2.6575 5.9075 2.6575 5.9075 9 P 0 ;1
L 2.7075 0.1575 2.7075 0.1575 9 P 0 ;1
L 2.7075 0.2075 2.7075 0.2075 9 P 0 ;1
L 2.7075 0.2575 2.7075 0.2575 9 P 0 ;1
L 2.7075 0.3075 2.7075 0.3075 9 P 0 ;1
L 2.7075 0.3575 2.7075 0.3575 9 P 0 ;1
L 2.7075 0.4075 2.7075 0.4075 9 P 0 ;1
L 2.7075 0.4575 2.7075 0.4575 9 P 0 ;1
L 2.7075 0.5075 2.7075 0.5075 9 P 0 ;1
L 2.7075 0.5575 2.7075 0.5575 9 P 0 ;1
L 2.7075 0.6075 2.7075 0.6075 9 P 0 ;1
L 2.7075 0.6575 2.7075 0.6575 9 P 0 ;1
L 2.7075 0.7075 2.7075 0.7075 9 P 0 ;1
L 2.7075 0.7575 2.7075 0.7575 9 P 0 ;1
L 2.7075 0.8075 2.7075 0.8075 9 P 0 ;1
L 2.7075 0.8575 2.7075 0.8575 9 P 0 ;1
L 2.7075 0.9075 2.7075 0.9075 9 P 0 ;1
L 2.7075 0.9575 2.7075 0.9575 9 P 0 ;1
L 2.7075 1.0075 2.7075 1.0075 9 P 0 ;1
L 2.7075 1.0575 2.7075 1.0575 9 P 0 ;1
L 2.7075 1.1075 2.7075 1.1075 9 P 0 ;1
L 2.7075 1.1575 2.7075 1.1575 9 P 0 ;1
L 2.7075 1.2075 2.7075 1.2075 9 P 0 ;1
L 2.7075 1.2575 2.7075 1.2575 9 P 0 ;1
L 2.7075 1.3075 2.7075 1.3075 9 P 0 ;1
L 2.7075 1.3575 2.7075 1.3575 9 P 0 ;1
L 2.7075 1.4075 2.7075 1.4075 9 P 0 ;1
L 2.7075 1.4575 2.7075 1.4575 9 P 0 ;1
L 2.7075 1.5075 2.7075 1.5075 9 P 0 ;1
L 2.7075 1.5575 2.7075 1.5575 9 P 0 ;1
L 2.7075 1.6075 2.7075 1.6075 9 P 0 ;1
L 2.7075 1.6575 2.7075 1.6575 9 P 0 ;1
L 2.7075 1.7075 2.7075 1.7075 9 P 0 ;1
L 2.7075 1.7575 2.7075 1.7575 9 P 0 ;1
L 2.7075 1.8075 2.7075 1.8075 9 P 0 ;1
L 2.7075 1.8575 2.7075 1.8575 9 P 0 ;1
L 2.7075 1.9075 2.7075 1.9075 9 P 0 ;1
L 2.7075 1.9575 2.7075 1.9575 9 P 0 ;1
L 2.7075 2.0075 2.7075 2.0075 9 P 0 ;1
L 2.7075 2.0575 2.7075 2.0575 9 P 0 ;1
L 2.7075 2.1075 2.7075 2.1075 9 P 0 ;1
L 2.7075 2.1575 2.7075 2.1575 9 P 0 ;1
L 2.7075 2.2075 2.7075 2.2075 9 P 0 ;1
L 2.7075 2.2575 2.7075 2.2575 9 P 0 ;1
L 2.7075 2.3075 2.7075 2.3075 9 P 0 ;1
L 2.7075 2.3575 2.7075 2.3575 9 P 0 ;1
L 2.7075 2.4075 2.7075 2.4075 9 P 0 ;1
L 2.7075 2.4575 2.7075 2.4575 9 P 0 ;1
L 2.7075 2.5075 2.7075 2.5075 9 P 0 ;1
L 2.7075 2.5575 2.7075 2.5575 9 P 0 ;1
L 2.7075 2.6075 2.7075 2.6075 9 P 0 ;1
L 2.7075 2.6575 2.7075 2.6575 9 P 0 ;1
L 2.7075 2.7075 2.7075 2.7075 9 P 0 ;1
L 2.7075 2.7575 2.7075 2.7575 9 P 0 ;1
L 2.7075 2.8075 2.7075 2.8075 9 P 0 ;1
L 2.7075 2.8575 2.7075 2.8575 9 P 0 ;1
L 2.7075 2.9075 2.7075 2.9075 9 P 0 ;1
L 2.7075 2.9575 2.7075 2.9575 9 P 0 ;1
L 2.7075 3.0075 2.7075 3.0075 9 P 0 ;1
L 2.7075 3.0575 2.7075 3.0575 9 P 0 ;1
L 2.7075 3.1075 2.7075 3.1075 9 P 0 ;1
L 2.7075 3.1575 2.7075 3.1575 9 P 0 ;1
L 2.7075 3.2075 2.7075 3.2075 9 P 0 ;1
L 2.7075 3.2575 2.7075 3.2575 9 P 0 ;1
L 2.7075 3.3075 2.7075 3.3075 9 P 0 ;1
L 2.7075 3.3575 2.7075 3.3575 9 P 0 ;1
L 2.7075 3.4075 2.7075 3.4075 9 P 0 ;1
L 2.7075 4.0075 2.7075 4.0075 9 P 0 ;1
L 2.7075 4.0575 2.7075 4.0575 9 P 0 ;1
L 2.7075 5.3075 2.7075 5.3075 9 P 0 ;1
L 2.7075 5.3575 2.7075 5.3575 9 P 0 ;1
L 2.7075 5.4075 2.7075 5.4075 9 P 0 ;1
L 2.7075 5.4575 2.7075 5.4575 9 P 0 ;1
L 2.7075 5.5075 2.7075 5.5075 9 P 0 ;1
L 2.7075 5.5575 2.7075 5.5575 9 P 0 ;1
L 2.7075 5.6075 2.7075 5.6075 9 P 0 ;1
L 2.7075 5.6575 2.7075 5.6575 9 P 0 ;1
L 2.7075 5.7075 2.7075 5.7075 9 P 0 ;1
L 2.7075 5.7575 2.7075 5.7575 9 P 0 ;1
L 2.7075 5.8075 2.7075 5.8075 9 P 0 ;1
L 2.7075 5.8575 2.7075 5.8575 9 P 0 ;1
L 2.7075 5.9075 2.7075 5.9075 9 P 0 ;1
L 2.7575 0.1575 2.7575 0.1575 9 P 0 ;1
L 2.7575 0.2075 2.7575 0.2075 9 P 0 ;1
L 2.7575 0.2575 2.7575 0.2575 9 P 0 ;1
L 2.7575 0.3075 2.7575 0.3075 9 P 0 ;1
L 2.7575 0.3575 2.7575 0.3575 9 P 0 ;1
L 2.7575 0.4075 2.7575 0.4075 9 P 0 ;1
L 2.7575 0.4575 2.7575 0.4575 9 P 0 ;1
L 2.7575 0.5075 2.7575 0.5075 9 P 0 ;1
L 2.7575 0.5575 2.7575 0.5575 9 P 0 ;1
L 2.7575 0.6075 2.7575 0.6075 9 P 0 ;1
L 2.7575 0.6575 2.7575 0.6575 9 P 0 ;1
L 2.7575 0.7075 2.7575 0.7075 9 P 0 ;1
L 2.7575 0.7575 2.7575 0.7575 9 P 0 ;1
L 2.7575 0.8075 2.7575 0.8075 9 P 0 ;1
L 2.7575 0.8575 2.7575 0.8575 9 P 0 ;1
L 2.7575 0.9075 2.7575 0.9075 9 P 0 ;1
L 2.7575 0.9575 2.7575 0.9575 9 P 0 ;1
L 2.7575 1.0075 2.7575 1.0075 9 P 0 ;1
L 2.7575 1.0575 2.7575 1.0575 9 P 0 ;1
L 2.7575 1.1075 2.7575 1.1075 9 P 0 ;1
L 2.7575 1.1575 2.7575 1.1575 9 P 0 ;1
L 2.7575 1.2075 2.7575 1.2075 9 P 0 ;1
L 2.7575 1.2575 2.7575 1.2575 9 P 0 ;1
L 2.7575 1.3075 2.7575 1.3075 9 P 0 ;1
L 2.7575 1.3575 2.7575 1.3575 9 P 0 ;1
L 2.7575 1.4075 2.7575 1.4075 9 P 0 ;1
L 2.7575 1.4575 2.7575 1.4575 9 P 0 ;1
L 2.7575 1.5075 2.7575 1.5075 9 P 0 ;1
L 2.7575 1.5575 2.7575 1.5575 9 P 0 ;1
L 2.7575 1.6075 2.7575 1.6075 9 P 0 ;1
L 2.7575 1.6575 2.7575 1.6575 9 P 0 ;1
L 2.7575 1.7075 2.7575 1.7075 9 P 0 ;1
L 2.7575 1.7575 2.7575 1.7575 9 P 0 ;1
L 2.7575 1.8075 2.7575 1.8075 9 P 0 ;1
L 2.7575 1.8575 2.7575 1.8575 9 P 0 ;1
L 2.7575 1.9075 2.7575 1.9075 9 P 0 ;1
L 2.7575 1.9575 2.7575 1.9575 9 P 0 ;1
L 2.7575 2.0075 2.7575 2.0075 9 P 0 ;1
L 2.7575 2.0575 2.7575 2.0575 9 P 0 ;1
L 2.7575 2.1075 2.7575 2.1075 9 P 0 ;1
L 2.7575 2.1575 2.7575 2.1575 9 P 0 ;1
L 2.7575 2.2075 2.7575 2.2075 9 P 0 ;1
L 2.7575 2.2575 2.7575 2.2575 9 P 0 ;1
L 2.7575 2.3075 2.7575 2.3075 9 P 0 ;1
L 2.7575 2.3575 2.7575 2.3575 9 P 0 ;1
L 2.7575 2.4075 2.7575 2.4075 9 P 0 ;1
L 2.7575 2.4575 2.7575 2.4575 9 P 0 ;1
L 2.7575 2.5075 2.7575 2.5075 9 P 0 ;1
L 2.7575 2.5575 2.7575 2.5575 9 P 0 ;1
L 2.7575 2.6075 2.7575 2.6075 9 P 0 ;1
L 2.7575 2.6575 2.7575 2.6575 9 P 0 ;1
L 2.7575 2.7075 2.7575 2.7075 9 P 0 ;1
L 2.7575 2.7575 2.7575 2.7575 9 P 0 ;1
L 2.7575 2.8075 2.7575 2.8075 9 P 0 ;1
L 2.7575 2.8575 2.7575 2.8575 9 P 0 ;1
L 2.7575 2.9075 2.7575 2.9075 9 P 0 ;1
L 2.7575 2.9575 2.7575 2.9575 9 P 0 ;1
L 2.7575 3.0075 2.7575 3.0075 9 P 0 ;1
L 2.7575 3.0575 2.7575 3.0575 9 P 0 ;1
L 2.7575 3.1075 2.7575 3.1075 9 P 0 ;1
L 2.7575 3.1575 2.7575 3.1575 9 P 0 ;1
L 2.7575 3.2075 2.7575 3.2075 9 P 0 ;1
L 2.7575 3.2575 2.7575 3.2575 9 P 0 ;1
L 2.7575 3.3075 2.7575 3.3075 9 P 0 ;1
L 2.7575 3.3575 2.7575 3.3575 9 P 0 ;1
L 2.7575 3.4075 2.7575 3.4075 9 P 0 ;1
L 2.7575 3.9575 2.7575 3.9575 9 P 0 ;1
L 2.7575 4.0075 2.7575 4.0075 9 P 0 ;1
L 2.7575 5.3075 2.7575 5.3075 9 P 0 ;1
L 2.7575 5.3575 2.7575 5.3575 9 P 0 ;1
L 2.7575 5.4075 2.7575 5.4075 9 P 0 ;1
L 2.7575 5.4575 2.7575 5.4575 9 P 0 ;1
L 2.7575 5.5075 2.7575 5.5075 9 P 0 ;1
L 2.7575 5.5575 2.7575 5.5575 9 P 0 ;1
L 2.7575 5.6075 2.7575 5.6075 9 P 0 ;1
L 2.7575 5.6575 2.7575 5.6575 9 P 0 ;1
L 2.7575 5.7075 2.7575 5.7075 9 P 0 ;1
L 2.7575 5.7575 2.7575 5.7575 9 P 0 ;1
L 2.7575 5.8075 2.7575 5.8075 9 P 0 ;1
L 2.7575 5.8575 2.7575 5.8575 9 P 0 ;1
L 2.7575 5.9075 2.7575 5.9075 9 P 0 ;1
L 2.8075 0.1575 2.8075 0.1575 9 P 0 ;1
L 2.8075 0.2075 2.8075 0.2075 9 P 0 ;1
L 2.8075 0.2575 2.8075 0.2575 9 P 0 ;1
L 2.8075 0.3075 2.8075 0.3075 9 P 0 ;1
L 2.8075 0.3575 2.8075 0.3575 9 P 0 ;1
L 2.8075 0.4075 2.8075 0.4075 9 P 0 ;1
L 2.8075 0.4575 2.8075 0.4575 9 P 0 ;1
L 2.8075 0.5075 2.8075 0.5075 9 P 0 ;1
L 2.8075 0.5575 2.8075 0.5575 9 P 0 ;1
L 2.8075 0.6075 2.8075 0.6075 9 P 0 ;1
L 2.8075 0.6575 2.8075 0.6575 9 P 0 ;1
L 2.8075 0.7075 2.8075 0.7075 9 P 0 ;1
L 2.8075 0.7575 2.8075 0.7575 9 P 0 ;1
L 2.8075 0.8075 2.8075 0.8075 9 P 0 ;1
L 2.8075 0.8575 2.8075 0.8575 9 P 0 ;1
L 2.8075 0.9075 2.8075 0.9075 9 P 0 ;1
L 2.8075 0.9575 2.8075 0.9575 9 P 0 ;1
L 2.8075 1.0075 2.8075 1.0075 9 P 0 ;1
L 2.8075 1.0575 2.8075 1.0575 9 P 0 ;1
L 2.8075 1.1075 2.8075 1.1075 9 P 0 ;1
L 2.8075 1.1575 2.8075 1.1575 9 P 0 ;1
L 2.8075 1.2075 2.8075 1.2075 9 P 0 ;1
L 2.8075 1.2575 2.8075 1.2575 9 P 0 ;1
L 2.8075 1.3075 2.8075 1.3075 9 P 0 ;1
L 2.8075 1.3575 2.8075 1.3575 9 P 0 ;1
L 2.8075 1.4075 2.8075 1.4075 9 P 0 ;1
L 2.8075 1.4575 2.8075 1.4575 9 P 0 ;1
L 2.8075 1.5075 2.8075 1.5075 9 P 0 ;1
L 2.8075 1.5575 2.8075 1.5575 9 P 0 ;1
L 2.8075 1.6075 2.8075 1.6075 9 P 0 ;1
L 2.8075 1.6575 2.8075 1.6575 9 P 0 ;1
L 2.8075 1.7075 2.8075 1.7075 9 P 0 ;1
L 2.8075 1.7575 2.8075 1.7575 9 P 0 ;1
L 2.8075 1.8075 2.8075 1.8075 9 P 0 ;1
L 2.8075 1.8575 2.8075 1.8575 9 P 0 ;1
L 2.8075 1.9075 2.8075 1.9075 9 P 0 ;1
L 2.8075 1.9575 2.8075 1.9575 9 P 0 ;1
L 2.8075 2.0075 2.8075 2.0075 9 P 0 ;1
L 2.8075 2.0575 2.8075 2.0575 9 P 0 ;1
L 2.8075 2.1075 2.8075 2.1075 9 P 0 ;1
L 2.8075 2.1575 2.8075 2.1575 9 P 0 ;1
L 2.8075 2.2075 2.8075 2.2075 9 P 0 ;1
L 2.8075 2.2575 2.8075 2.2575 9 P 0 ;1
L 2.8075 2.3075 2.8075 2.3075 9 P 0 ;1
L 2.8075 2.3575 2.8075 2.3575 9 P 0 ;1
L 2.8075 2.4075 2.8075 2.4075 9 P 0 ;1
L 2.8075 2.4575 2.8075 2.4575 9 P 0 ;1
L 2.8075 2.5075 2.8075 2.5075 9 P 0 ;1
L 2.8075 2.5575 2.8075 2.5575 9 P 0 ;1
L 2.8075 2.6075 2.8075 2.6075 9 P 0 ;1
L 2.8075 2.6575 2.8075 2.6575 9 P 0 ;1
L 2.8075 2.7075 2.8075 2.7075 9 P 0 ;1
L 2.8075 2.7575 2.8075 2.7575 9 P 0 ;1
L 2.8075 2.8075 2.8075 2.8075 9 P 0 ;1
L 2.8075 2.8575 2.8075 2.8575 9 P 0 ;1
L 2.8075 2.9075 2.8075 2.9075 9 P 0 ;1
L 2.8075 2.9575 2.8075 2.9575 9 P 0 ;1
L 2.8075 3.0075 2.8075 3.0075 9 P 0 ;1
L 2.8075 3.0575 2.8075 3.0575 9 P 0 ;1
L 2.8075 3.1075 2.8075 3.1075 9 P 0 ;1
L 2.8075 3.1575 2.8075 3.1575 9 P 0 ;1
L 2.8075 3.2075 2.8075 3.2075 9 P 0 ;1
L 2.8075 3.2575 2.8075 3.2575 9 P 0 ;1
L 2.8075 3.3075 2.8075 3.3075 9 P 0 ;1
L 2.8075 3.3575 2.8075 3.3575 9 P 0 ;1
L 2.8075 3.4075 2.8075 3.4075 9 P 0 ;1
L 2.8075 4.0075 2.8075 4.0075 9 P 0 ;1
L 2.8075 5.3075 2.8075 5.3075 9 P 0 ;1
L 2.8075 5.3575 2.8075 5.3575 9 P 0 ;1
L 2.8075 5.4075 2.8075 5.4075 9 P 0 ;1
L 2.8075 5.4575 2.8075 5.4575 9 P 0 ;1
L 2.8075 5.5075 2.8075 5.5075 9 P 0 ;1
L 2.8075 5.5575 2.8075 5.5575 9 P 0 ;1
L 2.8075 5.6075 2.8075 5.6075 9 P 0 ;1
L 2.8075 5.6575 2.8075 5.6575 9 P 0 ;1
L 2.8075 5.7075 2.8075 5.7075 9 P 0 ;1
L 2.8075 5.7575 2.8075 5.7575 9 P 0 ;1
L 2.8075 5.8075 2.8075 5.8075 9 P 0 ;1
L 2.8075 5.8575 2.8075 5.8575 9 P 0 ;1
L 2.8075 5.9075 2.8075 5.9075 9 P 0 ;1
L 2.8575 0.1575 2.8575 0.1575 9 P 0 ;1
L 2.8575 0.2075 2.8575 0.2075 9 P 0 ;1
L 2.8575 0.2575 2.8575 0.2575 9 P 0 ;1
L 2.8575 0.3075 2.8575 0.3075 9 P 0 ;1
L 2.8575 0.3575 2.8575 0.3575 9 P 0 ;1
L 2.8575 0.4075 2.8575 0.4075 9 P 0 ;1
L 2.8575 0.4575 2.8575 0.4575 9 P 0 ;1
L 2.8575 0.5075 2.8575 0.5075 9 P 0 ;1
L 2.8575 0.5575 2.8575 0.5575 9 P 0 ;1
L 2.8575 0.6075 2.8575 0.6075 9 P 0 ;1
L 2.8575 0.6575 2.8575 0.6575 9 P 0 ;1
L 2.8575 0.7075 2.8575 0.7075 9 P 0 ;1
L 2.8575 0.7575 2.8575 0.7575 9 P 0 ;1
L 2.8575 0.8075 2.8575 0.8075 9 P 0 ;1
L 2.8575 0.8575 2.8575 0.8575 9 P 0 ;1
L 2.8575 0.9075 2.8575 0.9075 9 P 0 ;1
L 2.8575 0.9575 2.8575 0.9575 9 P 0 ;1
L 2.8575 1.0075 2.8575 1.0075 9 P 0 ;1
L 2.8575 1.0575 2.8575 1.0575 9 P 0 ;1
L 2.8575 1.1075 2.8575 1.1075 9 P 0 ;1
L 2.8575 1.1575 2.8575 1.1575 9 P 0 ;1
L 2.8575 1.2075 2.8575 1.2075 9 P 0 ;1
L 2.8575 1.2575 2.8575 1.2575 9 P 0 ;1
L 2.8575 1.3075 2.8575 1.3075 9 P 0 ;1
L 2.8575 1.3575 2.8575 1.3575 9 P 0 ;1
L 2.8575 1.4075 2.8575 1.4075 9 P 0 ;1
L 2.8575 1.4575 2.8575 1.4575 9 P 0 ;1
L 2.8575 1.5075 2.8575 1.5075 9 P 0 ;1
L 2.8575 1.5575 2.8575 1.5575 9 P 0 ;1
L 2.8575 1.6075 2.8575 1.6075 9 P 0 ;1
L 2.8575 1.6575 2.8575 1.6575 9 P 0 ;1
L 2.8575 1.7075 2.8575 1.7075 9 P 0 ;1
L 2.8575 1.7575 2.8575 1.7575 9 P 0 ;1
L 2.8575 1.8075 2.8575 1.8075 9 P 0 ;1
L 2.8575 1.8575 2.8575 1.8575 9 P 0 ;1
L 2.8575 1.9075 2.8575 1.9075 9 P 0 ;1
L 2.8575 1.9575 2.8575 1.9575 9 P 0 ;1
L 2.8575 2.0075 2.8575 2.0075 9 P 0 ;1
L 2.8575 2.0575 2.8575 2.0575 9 P 0 ;1
L 2.8575 2.1075 2.8575 2.1075 9 P 0 ;1
L 2.8575 2.1575 2.8575 2.1575 9 P 0 ;1
L 2.8575 2.2075 2.8575 2.2075 9 P 0 ;1
L 2.8575 2.2575 2.8575 2.2575 9 P 0 ;1
L 2.8575 2.3075 2.8575 2.3075 9 P 0 ;1
L 2.8575 2.3575 2.8575 2.3575 9 P 0 ;1
L 2.8575 2.4075 2.8575 2.4075 9 P 0 ;1
L 2.8575 2.4575 2.8575 2.4575 9 P 0 ;1
L 2.8575 2.5075 2.8575 2.5075 9 P 0 ;1
L 2.8575 2.5575 2.8575 2.5575 9 P 0 ;1
L 2.8575 2.6075 2.8575 2.6075 9 P 0 ;1
L 2.8575 2.6575 2.8575 2.6575 9 P 0 ;1
L 2.8575 2.7075 2.8575 2.7075 9 P 0 ;1
L 2.8575 2.7575 2.8575 2.7575 9 P 0 ;1
L 2.8575 2.8075 2.8575 2.8075 9 P 0 ;1
L 2.8575 2.8575 2.8575 2.8575 9 P 0 ;1
L 2.8575 2.9075 2.8575 2.9075 9 P 0 ;1
L 2.8575 2.9575 2.8575 2.9575 9 P 0 ;1
L 2.8575 3.0075 2.8575 3.0075 9 P 0 ;1
L 2.8575 3.0575 2.8575 3.0575 9 P 0 ;1
L 2.8575 3.1075 2.8575 3.1075 9 P 0 ;1
L 2.8575 3.1575 2.8575 3.1575 9 P 0 ;1
L 2.8575 3.2075 2.8575 3.2075 9 P 0 ;1
L 2.8575 3.2575 2.8575 3.2575 9 P 0 ;1
L 2.8575 3.3075 2.8575 3.3075 9 P 0 ;1
L 2.8575 3.3575 2.8575 3.3575 9 P 0 ;1
L 2.8575 3.4075 2.8575 3.4075 9 P 0 ;1
L 2.8575 4.0075 2.8575 4.0075 9 P 0 ;1
L 2.8575 5.3075 2.8575 5.3075 9 P 0 ;1
L 2.8575 5.3575 2.8575 5.3575 9 P 0 ;1
L 2.8575 5.4075 2.8575 5.4075 9 P 0 ;1
L 2.8575 5.4575 2.8575 5.4575 9 P 0 ;1
L 2.8575 5.5075 2.8575 5.5075 9 P 0 ;1
L 2.8575 5.5575 2.8575 5.5575 9 P 0 ;1
L 2.8575 5.6075 2.8575 5.6075 9 P 0 ;1
L 2.8575 5.6575 2.8575 5.6575 9 P 0 ;1
L 2.8575 5.7075 2.8575 5.7075 9 P 0 ;1
L 2.8575 5.7575 2.8575 5.7575 9 P 0 ;1
L 2.8575 5.8075 2.8575 5.8075 9 P 0 ;1
L 2.8575 5.8575 2.8575 5.8575 9 P 0 ;1
L 2.8575 5.9075 2.8575 5.9075 9 P 0 ;1
L 2.9075 0.1575 2.9075 0.1575 9 P 0 ;1
L 2.9075 0.2075 2.9075 0.2075 9 P 0 ;1
L 2.9075 0.2575 2.9075 0.2575 9 P 0 ;1
L 2.9075 0.3075 2.9075 0.3075 9 P 0 ;1
L 2.9075 0.3575 2.9075 0.3575 9 P 0 ;1
L 2.9075 0.4075 2.9075 0.4075 9 P 0 ;1
L 2.9075 0.4575 2.9075 0.4575 9 P 0 ;1
L 2.9075 0.5075 2.9075 0.5075 9 P 0 ;1
L 2.9075 0.5575 2.9075 0.5575 9 P 0 ;1
L 2.9075 0.6075 2.9075 0.6075 9 P 0 ;1
L 2.9075 0.6575 2.9075 0.6575 9 P 0 ;1
L 2.9075 0.7075 2.9075 0.7075 9 P 0 ;1
L 2.9075 0.7575 2.9075 0.7575 9 P 0 ;1
L 2.9075 0.8075 2.9075 0.8075 9 P 0 ;1
L 2.9075 0.8575 2.9075 0.8575 9 P 0 ;1
L 2.9075 0.9075 2.9075 0.9075 9 P 0 ;1
L 2.9075 0.9575 2.9075 0.9575 9 P 0 ;1
L 2.9075 1.0075 2.9075 1.0075 9 P 0 ;1
L 2.9075 1.0575 2.9075 1.0575 9 P 0 ;1
L 2.9075 1.1075 2.9075 1.1075 9 P 0 ;1
L 2.9075 1.1575 2.9075 1.1575 9 P 0 ;1
L 2.9075 1.2075 2.9075 1.2075 9 P 0 ;1
L 2.9075 1.2575 2.9075 1.2575 9 P 0 ;1
L 2.9075 1.3075 2.9075 1.3075 9 P 0 ;1
L 2.9075 1.3575 2.9075 1.3575 9 P 0 ;1
L 2.9075 1.4075 2.9075 1.4075 9 P 0 ;1
L 2.9075 1.4575 2.9075 1.4575 9 P 0 ;1
L 2.9075 1.5075 2.9075 1.5075 9 P 0 ;1
L 2.9075 1.5575 2.9075 1.5575 9 P 0 ;1
L 2.9075 1.6075 2.9075 1.6075 9 P 0 ;1
L 2.9075 1.6575 2.9075 1.6575 9 P 0 ;1
L 2.9075 1.7075 2.9075 1.7075 9 P 0 ;1
L 2.9075 1.7575 2.9075 1.7575 9 P 0 ;1
L 2.9075 1.8075 2.9075 1.8075 9 P 0 ;1
L 2.9075 1.8575 2.9075 1.8575 9 P 0 ;1
L 2.9075 1.9075 2.9075 1.9075 9 P 0 ;1
L 2.9075 1.9575 2.9075 1.9575 9 P 0 ;1
L 2.9075 2.0075 2.9075 2.0075 9 P 0 ;1
L 2.9075 2.0575 2.9075 2.0575 9 P 0 ;1
L 2.9075 2.1075 2.9075 2.1075 9 P 0 ;1
L 2.9075 2.1575 2.9075 2.1575 9 P 0 ;1
L 2.9075 2.2075 2.9075 2.2075 9 P 0 ;1
L 2.9075 2.2575 2.9075 2.2575 9 P 0 ;1
L 2.9075 2.3075 2.9075 2.3075 9 P 0 ;1
L 2.9075 2.3575 2.9075 2.3575 9 P 0 ;1
L 2.9075 2.4075 2.9075 2.4075 9 P 0 ;1
L 2.9075 2.4575 2.9075 2.4575 9 P 0 ;1
L 2.9075 2.5075 2.9075 2.5075 9 P 0 ;1
L 2.9075 2.5575 2.9075 2.5575 9 P 0 ;1
L 2.9075 2.6075 2.9075 2.6075 9 P 0 ;1
L 2.9075 2.6575 2.9075 2.6575 9 P 0 ;1
L 2.9075 2.7075 2.9075 2.7075 9 P 0 ;1
L 2.9075 3.0075 2.9075 3.0075 9 P 0 ;1
L 2.9075 3.0575 2.9075 3.0575 9 P 0 ;1
L 2.9075 3.1075 2.9075 3.1075 9 P 0 ;1
L 2.9075 3.1575 2.9075 3.1575 9 P 0 ;1
L 2.9075 3.2075 2.9075 3.2075 9 P 0 ;1
L 2.9075 3.2575 2.9075 3.2575 9 P 0 ;1
L 2.9075 3.3075 2.9075 3.3075 9 P 0 ;1
L 2.9075 3.3575 2.9075 3.3575 9 P 0 ;1
L 2.9075 3.4075 2.9075 3.4075 9 P 0 ;1
L 2.9075 5.3075 2.9075 5.3075 9 P 0 ;1
L 2.9075 5.3575 2.9075 5.3575 9 P 0 ;1
L 2.9075 5.4075 2.9075 5.4075 9 P 0 ;1
L 2.9075 5.4575 2.9075 5.4575 9 P 0 ;1
L 2.9075 5.5075 2.9075 5.5075 9 P 0 ;1
L 2.9075 5.5575 2.9075 5.5575 9 P 0 ;1
L 2.9075 5.6075 2.9075 5.6075 9 P 0 ;1
L 2.9075 5.6575 2.9075 5.6575 9 P 0 ;1
L 2.9075 5.7075 2.9075 5.7075 9 P 0 ;1
L 2.9075 5.7575 2.9075 5.7575 9 P 0 ;1
L 2.9075 5.8075 2.9075 5.8075 9 P 0 ;1
L 2.9075 5.8575 2.9075 5.8575 9 P 0 ;1
L 2.9075 5.9075 2.9075 5.9075 9 P 0 ;1
L 2.9575 0.1575 2.9575 0.1575 9 P 0 ;1
L 2.9575 0.2075 2.9575 0.2075 9 P 0 ;1
L 2.9575 0.2575 2.9575 0.2575 9 P 0 ;1
L 2.9575 0.3075 2.9575 0.3075 9 P 0 ;1
L 2.9575 0.3575 2.9575 0.3575 9 P 0 ;1
L 2.9575 0.4075 2.9575 0.4075 9 P 0 ;1
L 2.9575 0.4575 2.9575 0.4575 9 P 0 ;1
L 2.9575 0.5075 2.9575 0.5075 9 P 0 ;1
L 2.9575 0.5575 2.9575 0.5575 9 P 0 ;1
L 2.9575 0.6075 2.9575 0.6075 9 P 0 ;1
L 2.9575 0.6575 2.9575 0.6575 9 P 0 ;1
L 2.9575 0.7075 2.9575 0.7075 9 P 0 ;1
L 2.9575 0.7575 2.9575 0.7575 9 P 0 ;1
L 2.9575 0.8075 2.9575 0.8075 9 P 0 ;1
L 2.9575 0.8575 2.9575 0.8575 9 P 0 ;1
L 2.9575 0.9075 2.9575 0.9075 9 P 0 ;1
L 2.9575 0.9575 2.9575 0.9575 9 P 0 ;1
L 2.9575 1.0075 2.9575 1.0075 9 P 0 ;1
L 2.9575 1.0575 2.9575 1.0575 9 P 0 ;1
L 2.9575 1.1075 2.9575 1.1075 9 P 0 ;1
L 2.9575 1.1575 2.9575 1.1575 9 P 0 ;1
L 2.9575 1.2075 2.9575 1.2075 9 P 0 ;1
L 2.9575 1.2575 2.9575 1.2575 9 P 0 ;1
L 2.9575 1.3075 2.9575 1.3075 9 P 0 ;1
L 2.9575 1.3575 2.9575 1.3575 9 P 0 ;1
L 2.9575 1.4075 2.9575 1.4075 9 P 0 ;1
L 2.9575 1.4575 2.9575 1.4575 9 P 0 ;1
L 2.9575 1.5075 2.9575 1.5075 9 P 0 ;1
L 2.9575 1.5575 2.9575 1.5575 9 P 0 ;1
L 2.9575 1.6075 2.9575 1.6075 9 P 0 ;1
L 2.9575 1.6575 2.9575 1.6575 9 P 0 ;1
L 2.9575 1.7075 2.9575 1.7075 9 P 0 ;1
L 2.9575 1.7575 2.9575 1.7575 9 P 0 ;1
L 2.9575 1.8075 2.9575 1.8075 9 P 0 ;1
L 2.9575 1.8575 2.9575 1.8575 9 P 0 ;1
L 2.9575 1.9075 2.9575 1.9075 9 P 0 ;1
L 2.9575 1.9575 2.9575 1.9575 9 P 0 ;1
L 2.9575 2.0075 2.9575 2.0075 9 P 0 ;1
L 2.9575 2.0575 2.9575 2.0575 9 P 0 ;1
L 2.9575 2.1075 2.9575 2.1075 9 P 0 ;1
L 2.9575 2.1575 2.9575 2.1575 9 P 0 ;1
L 2.9575 2.2075 2.9575 2.2075 9 P 0 ;1
L 2.9575 2.2575 2.9575 2.2575 9 P 0 ;1
L 2.9575 2.3075 2.9575 2.3075 9 P 0 ;1
L 2.9575 2.3575 2.9575 2.3575 9 P 0 ;1
L 2.9575 2.4075 2.9575 2.4075 9 P 0 ;1
L 2.9575 2.4575 2.9575 2.4575 9 P 0 ;1
L 2.9575 2.5075 2.9575 2.5075 9 P 0 ;1
L 2.9575 2.5575 2.9575 2.5575 9 P 0 ;1
L 2.9575 2.6075 2.9575 2.6075 9 P 0 ;1
L 2.9575 2.6575 2.9575 2.6575 9 P 0 ;1
L 2.9575 2.7075 2.9575 2.7075 9 P 0 ;1
L 2.9575 3.0075 2.9575 3.0075 9 P 0 ;1
L 2.9575 3.0575 2.9575 3.0575 9 P 0 ;1
L 2.9575 3.1075 2.9575 3.1075 9 P 0 ;1
L 2.9575 3.1575 2.9575 3.1575 9 P 0 ;1
L 2.9575 3.2075 2.9575 3.2075 9 P 0 ;1
L 2.9575 3.2575 2.9575 3.2575 9 P 0 ;1
L 2.9575 3.3075 2.9575 3.3075 9 P 0 ;1
L 2.9575 3.3575 2.9575 3.3575 9 P 0 ;1
L 2.9575 3.4075 2.9575 3.4075 9 P 0 ;1
L 2.9575 4.0575 2.9575 4.0575 9 P 0 ;1
L 2.9575 5.3075 2.9575 5.3075 9 P 0 ;1
L 2.9575 5.3575 2.9575 5.3575 9 P 0 ;1
L 2.9575 5.4075 2.9575 5.4075 9 P 0 ;1
L 2.9575 5.4575 2.9575 5.4575 9 P 0 ;1
L 2.9575 5.5075 2.9575 5.5075 9 P 0 ;1
L 2.9575 5.5575 2.9575 5.5575 9 P 0 ;1
L 2.9575 5.6075 2.9575 5.6075 9 P 0 ;1
L 2.9575 5.6575 2.9575 5.6575 9 P 0 ;1
L 2.9575 5.7075 2.9575 5.7075 9 P 0 ;1
L 2.9575 5.7575 2.9575 5.7575 9 P 0 ;1
L 2.9575 5.8075 2.9575 5.8075 9 P 0 ;1
L 2.9575 5.8575 2.9575 5.8575 9 P 0 ;1
L 2.9575 5.9075 2.9575 5.9075 9 P 0 ;1
L 3.0075 0.1575 3.0075 0.1575 9 P 0 ;1
L 3.0075 0.2075 3.0075 0.2075 9 P 0 ;1
L 3.0075 0.2575 3.0075 0.2575 9 P 0 ;1
L 3.0075 0.3075 3.0075 0.3075 9 P 0 ;1
L 3.0075 0.3575 3.0075 0.3575 9 P 0 ;1
L 3.0075 0.4075 3.0075 0.4075 9 P 0 ;1
L 3.0075 0.4575 3.0075 0.4575 9 P 0 ;1
L 3.0075 0.5075 3.0075 0.5075 9 P 0 ;1
L 3.0075 0.5575 3.0075 0.5575 9 P 0 ;1
L 3.0075 0.6075 3.0075 0.6075 9 P 0 ;1
L 3.0075 0.6575 3.0075 0.6575 9 P 0 ;1
L 3.0075 0.7075 3.0075 0.7075 9 P 0 ;1
L 3.0075 0.7575 3.0075 0.7575 9 P 0 ;1
L 3.0075 0.8075 3.0075 0.8075 9 P 0 ;1
L 3.0075 0.8575 3.0075 0.8575 9 P 0 ;1
L 3.0075 0.9075 3.0075 0.9075 9 P 0 ;1
L 3.0075 0.9575 3.0075 0.9575 9 P 0 ;1
L 3.0075 1.0075 3.0075 1.0075 9 P 0 ;1
L 3.0075 1.0575 3.0075 1.0575 9 P 0 ;1
L 3.0075 1.1075 3.0075 1.1075 9 P 0 ;1
L 3.0075 1.1575 3.0075 1.1575 9 P 0 ;1
L 3.0075 1.2075 3.0075 1.2075 9 P 0 ;1
L 3.0075 1.2575 3.0075 1.2575 9 P 0 ;1
L 3.0075 1.3075 3.0075 1.3075 9 P 0 ;1
L 3.0075 1.3575 3.0075 1.3575 9 P 0 ;1
L 3.0075 1.4075 3.0075 1.4075 9 P 0 ;1
L 3.0075 1.4575 3.0075 1.4575 9 P 0 ;1
L 3.0075 1.5075 3.0075 1.5075 9 P 0 ;1
L 3.0075 1.5575 3.0075 1.5575 9 P 0 ;1
L 3.0075 1.6075 3.0075 1.6075 9 P 0 ;1
L 3.0075 1.6575 3.0075 1.6575 9 P 0 ;1
L 3.0075 1.7075 3.0075 1.7075 9 P 0 ;1
L 3.0075 1.7575 3.0075 1.7575 9 P 0 ;1
L 3.0075 1.8075 3.0075 1.8075 9 P 0 ;1
L 3.0075 1.8575 3.0075 1.8575 9 P 0 ;1
L 3.0075 1.9075 3.0075 1.9075 9 P 0 ;1
L 3.0075 1.9575 3.0075 1.9575 9 P 0 ;1
L 3.0075 2.0075 3.0075 2.0075 9 P 0 ;1
L 3.0075 2.0575 3.0075 2.0575 9 P 0 ;1
L 3.0075 2.1075 3.0075 2.1075 9 P 0 ;1
L 3.0075 2.1575 3.0075 2.1575 9 P 0 ;1
L 3.0075 2.2075 3.0075 2.2075 9 P 0 ;1
L 3.0075 2.2575 3.0075 2.2575 9 P 0 ;1
L 3.0075 2.3075 3.0075 2.3075 9 P 0 ;1
L 3.0075 2.3575 3.0075 2.3575 9 P 0 ;1
L 3.0075 2.4075 3.0075 2.4075 9 P 0 ;1
L 3.0075 2.4575 3.0075 2.4575 9 P 0 ;1
L 3.0075 2.5075 3.0075 2.5075 9 P 0 ;1
L 3.0075 2.5575 3.0075 2.5575 9 P 0 ;1
L 3.0075 2.6075 3.0075 2.6075 9 P 0 ;1
L 3.0075 2.6575 3.0075 2.6575 9 P 0 ;1
L 3.0075 2.7075 3.0075 2.7075 9 P 0 ;1
L 3.0075 3.0075 3.0075 3.0075 9 P 0 ;1
L 3.0075 3.0575 3.0075 3.0575 9 P 0 ;1
L 3.0075 3.1075 3.0075 3.1075 9 P 0 ;1
L 3.0075 3.1575 3.0075 3.1575 9 P 0 ;1
L 3.0075 3.2075 3.0075 3.2075 9 P 0 ;1
L 3.0075 3.2575 3.0075 3.2575 9 P 0 ;1
L 3.0075 3.3075 3.0075 3.3075 9 P 0 ;1
L 3.0075 3.3575 3.0075 3.3575 9 P 0 ;1
L 3.0075 3.4075 3.0075 3.4075 9 P 0 ;1
L 3.0075 3.4575 3.0075 3.4575 9 P 0 ;1
L 3.0075 4.0575 3.0075 4.0575 9 P 0 ;1
L 3.0075 4.1075 3.0075 4.1075 9 P 0 ;1
L 3.0075 4.1575 3.0075 4.1575 9 P 0 ;1
L 3.0075 5.4075 3.0075 5.4075 9 P 0 ;1
L 3.0075 5.4575 3.0075 5.4575 9 P 0 ;1
L 3.0075 5.5075 3.0075 5.5075 9 P 0 ;1
L 3.0075 5.5575 3.0075 5.5575 9 P 0 ;1
L 3.0075 5.6075 3.0075 5.6075 9 P 0 ;1
L 3.0075 5.6575 3.0075 5.6575 9 P 0 ;1
L 3.0075 5.7075 3.0075 5.7075 9 P 0 ;1
L 3.0075 5.7575 3.0075 5.7575 9 P 0 ;1
L 3.0075 5.8075 3.0075 5.8075 9 P 0 ;1
L 3.0075 5.8575 3.0075 5.8575 9 P 0 ;1
L 3.0075 5.9075 3.0075 5.9075 9 P 0 ;1
L 3.0575 0.1575 3.0575 0.1575 9 P 0 ;1
L 3.0575 0.2075 3.0575 0.2075 9 P 0 ;1
L 3.0575 0.2575 3.0575 0.2575 9 P 0 ;1
L 3.0575 0.3075 3.0575 0.3075 9 P 0 ;1
L 3.0575 0.3575 3.0575 0.3575 9 P 0 ;1
L 3.0575 0.4075 3.0575 0.4075 9 P 0 ;1
L 3.0575 0.4575 3.0575 0.4575 9 P 0 ;1
L 3.0575 0.5075 3.0575 0.5075 9 P 0 ;1
L 3.0575 0.5575 3.0575 0.5575 9 P 0 ;1
L 3.0575 0.6075 3.0575 0.6075 9 P 0 ;1
L 3.0575 0.6575 3.0575 0.6575 9 P 0 ;1
L 3.0575 0.7075 3.0575 0.7075 9 P 0 ;1
L 3.0575 0.7575 3.0575 0.7575 9 P 0 ;1
L 3.0575 0.8075 3.0575 0.8075 9 P 0 ;1
L 3.0575 0.8575 3.0575 0.8575 9 P 0 ;1
L 3.0575 0.9075 3.0575 0.9075 9 P 0 ;1
L 3.0575 0.9575 3.0575 0.9575 9 P 0 ;1
L 3.0575 1.0075 3.0575 1.0075 9 P 0 ;1
L 3.0575 1.0575 3.0575 1.0575 9 P 0 ;1
L 3.0575 1.1075 3.0575 1.1075 9 P 0 ;1
L 3.0575 1.1575 3.0575 1.1575 9 P 0 ;1
L 3.0575 1.2075 3.0575 1.2075 9 P 0 ;1
L 3.0575 1.2575 3.0575 1.2575 9 P 0 ;1
L 3.0575 1.3075 3.0575 1.3075 9 P 0 ;1
L 3.0575 1.3575 3.0575 1.3575 9 P 0 ;1
L 3.0575 1.4075 3.0575 1.4075 9 P 0 ;1
L 3.0575 1.4575 3.0575 1.4575 9 P 0 ;1
L 3.0575 1.5075 3.0575 1.5075 9 P 0 ;1
L 3.0575 1.5575 3.0575 1.5575 9 P 0 ;1
L 3.0575 1.6075 3.0575 1.6075 9 P 0 ;1
L 3.0575 1.6575 3.0575 1.6575 9 P 0 ;1
L 3.0575 1.7075 3.0575 1.7075 9 P 0 ;1
L 3.0575 1.7575 3.0575 1.7575 9 P 0 ;1
L 3.0575 1.8075 3.0575 1.8075 9 P 0 ;1
L 3.0575 1.8575 3.0575 1.8575 9 P 0 ;1
L 3.0575 1.9075 3.0575 1.9075 9 P 0 ;1
L 3.0575 1.9575 3.0575 1.9575 9 P 0 ;1
L 3.0575 2.0075 3.0575 2.0075 9 P 0 ;1
L 3.0575 2.0575 3.0575 2.0575 9 P 0 ;1
L 3.0575 2.1075 3.0575 2.1075 9 P 0 ;1
L 3.0575 2.1575 3.0575 2.1575 9 P 0 ;1
L 3.0575 2.2075 3.0575 2.2075 9 P 0 ;1
L 3.0575 2.2575 3.0575 2.2575 9 P 0 ;1
L 3.0575 2.3075 3.0575 2.3075 9 P 0 ;1
L 3.0575 2.3575 3.0575 2.3575 9 P 0 ;1
L 3.0575 2.4075 3.0575 2.4075 9 P 0 ;1
L 3.0575 2.4575 3.0575 2.4575 9 P 0 ;1
L 3.0575 2.5075 3.0575 2.5075 9 P 0 ;1
L 3.0575 2.5575 3.0575 2.5575 9 P 0 ;1
L 3.0575 2.6075 3.0575 2.6075 9 P 0 ;1
L 3.0575 2.6575 3.0575 2.6575 9 P 0 ;1
L 3.0575 2.7075 3.0575 2.7075 9 P 0 ;1
L 3.0575 2.7575 3.0575 2.7575 9 P 0 ;1
L 3.0575 2.8075 3.0575 2.8075 9 P 0 ;1
L 3.0575 2.8575 3.0575 2.8575 9 P 0 ;1
L 3.0575 2.9075 3.0575 2.9075 9 P 0 ;1
L 3.0575 2.9575 3.0575 2.9575 9 P 0 ;1
L 3.0575 3.0075 3.0575 3.0075 9 P 0 ;1
L 3.0575 3.0575 3.0575 3.0575 9 P 0 ;1
L 3.0575 3.1075 3.0575 3.1075 9 P 0 ;1
L 3.0575 3.1575 3.0575 3.1575 9 P 0 ;1
L 3.0575 3.2075 3.0575 3.2075 9 P 0 ;1
L 3.0575 3.2575 3.0575 3.2575 9 P 0 ;1
L 3.0575 3.3075 3.0575 3.3075 9 P 0 ;1
L 3.0575 3.3575 3.0575 3.3575 9 P 0 ;1
L 3.0575 3.4075 3.0575 3.4075 9 P 0 ;1
L 3.0575 3.4575 3.0575 3.4575 9 P 0 ;1
L 3.0575 4.0575 3.0575 4.0575 9 P 0 ;1
L 3.0575 4.1075 3.0575 4.1075 9 P 0 ;1
L 3.0575 4.1575 3.0575 4.1575 9 P 0 ;1
L 3.0575 4.2075 3.0575 4.2075 9 P 0 ;1
L 3.0575 5.4575 3.0575 5.4575 9 P 0 ;1
L 3.0575 5.5075 3.0575 5.5075 9 P 0 ;1
L 3.0575 5.5575 3.0575 5.5575 9 P 0 ;1
L 3.0575 5.6075 3.0575 5.6075 9 P 0 ;1
L 3.0575 5.6575 3.0575 5.6575 9 P 0 ;1
L 3.0575 5.7075 3.0575 5.7075 9 P 0 ;1
L 3.0575 5.7575 3.0575 5.7575 9 P 0 ;1
L 3.0575 5.8075 3.0575 5.8075 9 P 0 ;1
L 3.0575 5.8575 3.0575 5.8575 9 P 0 ;1
L 3.0575 5.9075 3.0575 5.9075 9 P 0 ;1
L 3.1075 0.1575 3.1075 0.1575 9 P 0 ;1
L 3.1075 0.2075 3.1075 0.2075 9 P 0 ;1
L 3.1075 0.2575 3.1075 0.2575 9 P 0 ;1
L 3.1075 0.3075 3.1075 0.3075 9 P 0 ;1
L 3.1075 0.3575 3.1075 0.3575 9 P 0 ;1
L 3.1075 0.4075 3.1075 0.4075 9 P 0 ;1
L 3.1075 0.4575 3.1075 0.4575 9 P 0 ;1
L 3.1075 0.5075 3.1075 0.5075 9 P 0 ;1
L 3.1075 0.5575 3.1075 0.5575 9 P 0 ;1
L 3.1075 0.6075 3.1075 0.6075 9 P 0 ;1
L 3.1075 0.6575 3.1075 0.6575 9 P 0 ;1
L 3.1075 0.7075 3.1075 0.7075 9 P 0 ;1
L 3.1075 0.7575 3.1075 0.7575 9 P 0 ;1
L 3.1075 0.8075 3.1075 0.8075 9 P 0 ;1
L 3.1075 0.8575 3.1075 0.8575 9 P 0 ;1
L 3.1075 0.9075 3.1075 0.9075 9 P 0 ;1
L 3.1075 0.9575 3.1075 0.9575 9 P 0 ;1
L 3.1075 1.0075 3.1075 1.0075 9 P 0 ;1
L 3.1075 1.0575 3.1075 1.0575 9 P 0 ;1
L 3.1075 1.1075 3.1075 1.1075 9 P 0 ;1
L 3.1075 1.1575 3.1075 1.1575 9 P 0 ;1
L 3.1075 1.2075 3.1075 1.2075 9 P 0 ;1
L 3.1075 1.2575 3.1075 1.2575 9 P 0 ;1
L 3.1075 1.3075 3.1075 1.3075 9 P 0 ;1
L 3.1075 1.3575 3.1075 1.3575 9 P 0 ;1
L 3.1075 1.4075 3.1075 1.4075 9 P 0 ;1
L 3.1075 1.4575 3.1075 1.4575 9 P 0 ;1
L 3.1075 1.5075 3.1075 1.5075 9 P 0 ;1
L 3.1075 1.5575 3.1075 1.5575 9 P 0 ;1
L 3.1075 1.6075 3.1075 1.6075 9 P 0 ;1
L 3.1075 1.6575 3.1075 1.6575 9 P 0 ;1
L 3.1075 1.7075 3.1075 1.7075 9 P 0 ;1
L 3.1075 1.7575 3.1075 1.7575 9 P 0 ;1
L 3.1075 1.8075 3.1075 1.8075 9 P 0 ;1
L 3.1075 1.8575 3.1075 1.8575 9 P 0 ;1
L 3.1075 1.9075 3.1075 1.9075 9 P 0 ;1
L 3.1075 1.9575 3.1075 1.9575 9 P 0 ;1
L 3.1075 2.0075 3.1075 2.0075 9 P 0 ;1
L 3.1075 2.0575 3.1075 2.0575 9 P 0 ;1
L 3.1075 2.1075 3.1075 2.1075 9 P 0 ;1
L 3.1075 2.1575 3.1075 2.1575 9 P 0 ;1
L 3.1075 2.2075 3.1075 2.2075 9 P 0 ;1
L 3.1075 2.2575 3.1075 2.2575 9 P 0 ;1
L 3.1075 2.3075 3.1075 2.3075 9 P 0 ;1
L 3.1075 2.3575 3.1075 2.3575 9 P 0 ;1
L 3.1075 2.4075 3.1075 2.4075 9 P 0 ;1
L 3.1075 2.4575 3.1075 2.4575 9 P 0 ;1
L 3.1075 2.5075 3.1075 2.5075 9 P 0 ;1
L 3.1075 2.5575 3.1075 2.5575 9 P 0 ;1
L 3.1075 2.6075 3.1075 2.6075 9 P 0 ;1
L 3.1075 2.6575 3.1075 2.6575 9 P 0 ;1
L 3.1075 2.7075 3.1075 2.7075 9 P 0 ;1
L 3.1075 2.7575 3.1075 2.7575 9 P 0 ;1
L 3.1075 2.8075 3.1075 2.8075 9 P 0 ;1
L 3.1075 2.8575 3.1075 2.8575 9 P 0 ;1
L 3.1075 2.9075 3.1075 2.9075 9 P 0 ;1
L 3.1075 2.9575 3.1075 2.9575 9 P 0 ;1
L 3.1075 3.0075 3.1075 3.0075 9 P 0 ;1
L 3.1075 3.0575 3.1075 3.0575 9 P 0 ;1
L 3.1075 3.1075 3.1075 3.1075 9 P 0 ;1
L 3.1075 3.1575 3.1075 3.1575 9 P 0 ;1
L 3.1075 3.2075 3.1075 3.2075 9 P 0 ;1
L 3.1075 3.2575 3.1075 3.2575 9 P 0 ;1
L 3.1075 3.3075 3.1075 3.3075 9 P 0 ;1
L 3.1075 3.3575 3.1075 3.3575 9 P 0 ;1
L 3.1075 3.4075 3.1075 3.4075 9 P 0 ;1
L 3.1075 3.4575 3.1075 3.4575 9 P 0 ;1
L 3.1075 3.5075 3.1075 3.5075 9 P 0 ;1
L 3.1075 4.1075 3.1075 4.1075 9 P 0 ;1
L 3.1075 4.1575 3.1075 4.1575 9 P 0 ;1
L 3.1075 4.2075 3.1075 4.2075 9 P 0 ;1
L 3.1075 4.2575 3.1075 4.2575 9 P 0 ;1
L 3.1075 4.3075 3.1075 4.3075 9 P 0 ;1
L 3.1075 5.4075 3.1075 5.4075 9 P 0 ;1
L 3.1075 5.4575 3.1075 5.4575 9 P 0 ;1
L 3.1075 5.5075 3.1075 5.5075 9 P 0 ;1
L 3.1075 5.5575 3.1075 5.5575 9 P 0 ;1
L 3.1075 5.6075 3.1075 5.6075 9 P 0 ;1
L 3.1075 5.6575 3.1075 5.6575 9 P 0 ;1
L 3.1075 5.7075 3.1075 5.7075 9 P 0 ;1
L 3.1075 5.7575 3.1075 5.7575 9 P 0 ;1
L 3.1075 5.8075 3.1075 5.8075 9 P 0 ;1
L 3.1075 5.8575 3.1075 5.8575 9 P 0 ;1
L 3.1075 5.9075 3.1075 5.9075 9 P 0 ;1
L 3.1575 0.1575 3.1575 0.1575 9 P 0 ;1
L 3.1575 0.2075 3.1575 0.2075 9 P 0 ;1
L 3.1575 0.2575 3.1575 0.2575 9 P 0 ;1
L 3.1575 0.3075 3.1575 0.3075 9 P 0 ;1
L 3.1575 0.3575 3.1575 0.3575 9 P 0 ;1
L 3.1575 0.4075 3.1575 0.4075 9 P 0 ;1
L 3.1575 0.4575 3.1575 0.4575 9 P 0 ;1
L 3.1575 0.5075 3.1575 0.5075 9 P 0 ;1
L 3.1575 0.5575 3.1575 0.5575 9 P 0 ;1
L 3.1575 0.6075 3.1575 0.6075 9 P 0 ;1
L 3.1575 0.6575 3.1575 0.6575 9 P 0 ;1
L 3.1575 0.7075 3.1575 0.7075 9 P 0 ;1
L 3.1575 0.7575 3.1575 0.7575 9 P 0 ;1
L 3.1575 0.8075 3.1575 0.8075 9 P 0 ;1
L 3.1575 0.8575 3.1575 0.8575 9 P 0 ;1
L 3.1575 0.9075 3.1575 0.9075 9 P 0 ;1
L 3.1575 0.9575 3.1575 0.9575 9 P 0 ;1
L 3.1575 1.0075 3.1575 1.0075 9 P 0 ;1
L 3.1575 1.0575 3.1575 1.0575 9 P 0 ;1
L 3.1575 1.1075 3.1575 1.1075 9 P 0 ;1
L 3.1575 1.1575 3.1575 1.1575 9 P 0 ;1
L 3.1575 1.2075 3.1575 1.2075 9 P 0 ;1
L 3.1575 1.2575 3.1575 1.2575 9 P 0 ;1
L 3.1575 1.3075 3.1575 1.3075 9 P 0 ;1
L 3.1575 1.3575 3.1575 1.3575 9 P 0 ;1
L 3.1575 1.4075 3.1575 1.4075 9 P 0 ;1
L 3.1575 1.4575 3.1575 1.4575 9 P 0 ;1
L 3.1575 1.5075 3.1575 1.5075 9 P 0 ;1
L 3.1575 1.5575 3.1575 1.5575 9 P 0 ;1
L 3.1575 1.6075 3.1575 1.6075 9 P 0 ;1
L 3.1575 1.6575 3.1575 1.6575 9 P 0 ;1
L 3.1575 1.7075 3.1575 1.7075 9 P 0 ;1
L 3.1575 1.7575 3.1575 1.7575 9 P 0 ;1
L 3.1575 1.8075 3.1575 1.8075 9 P 0 ;1
L 3.1575 1.8575 3.1575 1.8575 9 P 0 ;1
L 3.1575 1.9075 3.1575 1.9075 9 P 0 ;1
L 3.1575 1.9575 3.1575 1.9575 9 P 0 ;1
L 3.1575 2.0075 3.1575 2.0075 9 P 0 ;1
L 3.1575 2.0575 3.1575 2.0575 9 P 0 ;1
L 3.1575 2.1075 3.1575 2.1075 9 P 0 ;1
L 3.1575 2.1575 3.1575 2.1575 9 P 0 ;1
L 3.1575 2.2075 3.1575 2.2075 9 P 0 ;1
L 3.1575 2.2575 3.1575 2.2575 9 P 0 ;1
L 3.1575 2.3075 3.1575 2.3075 9 P 0 ;1
L 3.1575 2.3575 3.1575 2.3575 9 P 0 ;1
L 3.1575 2.4075 3.1575 2.4075 9 P 0 ;1
L 3.1575 2.4575 3.1575 2.4575 9 P 0 ;1
L 3.1575 2.5075 3.1575 2.5075 9 P 0 ;1
L 3.1575 2.5575 3.1575 2.5575 9 P 0 ;1
L 3.1575 2.6075 3.1575 2.6075 9 P 0 ;1
L 3.1575 2.6575 3.1575 2.6575 9 P 0 ;1
L 3.1575 2.7075 3.1575 2.7075 9 P 0 ;1
L 3.1575 2.7575 3.1575 2.7575 9 P 0 ;1
L 3.1575 2.8075 3.1575 2.8075 9 P 0 ;1
L 3.1575 2.8575 3.1575 2.8575 9 P 0 ;1
L 3.1575 2.9075 3.1575 2.9075 9 P 0 ;1
L 3.1575 2.9575 3.1575 2.9575 9 P 0 ;1
L 3.1575 3.0075 3.1575 3.0075 9 P 0 ;1
L 3.1575 3.0575 3.1575 3.0575 9 P 0 ;1
L 3.1575 3.1075 3.1575 3.1075 9 P 0 ;1
L 3.1575 3.1575 3.1575 3.1575 9 P 0 ;1
L 3.1575 3.2075 3.1575 3.2075 9 P 0 ;1
L 3.1575 3.2575 3.1575 3.2575 9 P 0 ;1
L 3.1575 3.3075 3.1575 3.3075 9 P 0 ;1
L 3.1575 3.3575 3.1575 3.3575 9 P 0 ;1
L 3.1575 3.4075 3.1575 3.4075 9 P 0 ;1
L 3.1575 3.4575 3.1575 3.4575 9 P 0 ;1
L 3.1575 3.5075 3.1575 3.5075 9 P 0 ;1
L 3.1575 3.5575 3.1575 3.5575 9 P 0 ;1
L 3.1575 5.3575 3.1575 5.3575 9 P 0 ;1
L 3.1575 5.4075 3.1575 5.4075 9 P 0 ;1
L 3.1575 5.4575 3.1575 5.4575 9 P 0 ;1
L 3.1575 5.5075 3.1575 5.5075 9 P 0 ;1
L 3.1575 5.5575 3.1575 5.5575 9 P 0 ;1
L 3.1575 5.6075 3.1575 5.6075 9 P 0 ;1
L 3.1575 5.6575 3.1575 5.6575 9 P 0 ;1
L 3.1575 5.7075 3.1575 5.7075 9 P 0 ;1
L 3.1575 5.7575 3.1575 5.7575 9 P 0 ;1
L 3.1575 5.8075 3.1575 5.8075 9 P 0 ;1
L 3.1575 5.8575 3.1575 5.8575 9 P 0 ;1
L 3.1575 5.9075 3.1575 5.9075 9 P 0 ;1
L 3.2075 0.1575 3.2075 0.1575 9 P 0 ;1
L 3.2075 0.2075 3.2075 0.2075 9 P 0 ;1
L 3.2075 0.2575 3.2075 0.2575 9 P 0 ;1
L 3.2075 0.3075 3.2075 0.3075 9 P 0 ;1
L 3.2075 0.3575 3.2075 0.3575 9 P 0 ;1
L 3.2075 0.4075 3.2075 0.4075 9 P 0 ;1
L 3.2075 0.4575 3.2075 0.4575 9 P 0 ;1
L 3.2075 0.5075 3.2075 0.5075 9 P 0 ;1
L 3.2075 0.5575 3.2075 0.5575 9 P 0 ;1
L 3.2075 0.6075 3.2075 0.6075 9 P 0 ;1
L 3.2075 0.6575 3.2075 0.6575 9 P 0 ;1
L 3.2075 0.7075 3.2075 0.7075 9 P 0 ;1
L 3.2075 0.7575 3.2075 0.7575 9 P 0 ;1
L 3.2075 0.8075 3.2075 0.8075 9 P 0 ;1
L 3.2075 0.8575 3.2075 0.8575 9 P 0 ;1
L 3.2075 0.9075 3.2075 0.9075 9 P 0 ;1
L 3.2075 0.9575 3.2075 0.9575 9 P 0 ;1
L 3.2075 1.0075 3.2075 1.0075 9 P 0 ;1
L 3.2075 1.0575 3.2075 1.0575 9 P 0 ;1
L 3.2075 1.1075 3.2075 1.1075 9 P 0 ;1
L 3.2075 1.1575 3.2075 1.1575 9 P 0 ;1
L 3.2075 1.2075 3.2075 1.2075 9 P 0 ;1
L 3.2075 1.2575 3.2075 1.2575 9 P 0 ;1
L 3.2075 1.3075 3.2075 1.3075 9 P 0 ;1
L 3.2075 1.3575 3.2075 1.3575 9 P 0 ;1
L 3.2075 1.4075 3.2075 1.4075 9 P 0 ;1
L 3.2075 1.4575 3.2075 1.4575 9 P 0 ;1
L 3.2075 1.5075 3.2075 1.5075 9 P 0 ;1
L 3.2075 1.5575 3.2075 1.5575 9 P 0 ;1
L 3.2075 1.6075 3.2075 1.6075 9 P 0 ;1
L 3.2075 1.6575 3.2075 1.6575 9 P 0 ;1
L 3.2075 1.7075 3.2075 1.7075 9 P 0 ;1
L 3.2075 1.7575 3.2075 1.7575 9 P 0 ;1
L 3.2075 1.8075 3.2075 1.8075 9 P 0 ;1
L 3.2075 1.8575 3.2075 1.8575 9 P 0 ;1
L 3.2075 1.9075 3.2075 1.9075 9 P 0 ;1
L 3.2075 1.9575 3.2075 1.9575 9 P 0 ;1
L 3.2075 2.0075 3.2075 2.0075 9 P 0 ;1
L 3.2075 2.0575 3.2075 2.0575 9 P 0 ;1
L 3.2075 2.1075 3.2075 2.1075 9 P 0 ;1
L 3.2075 2.1575 3.2075 2.1575 9 P 0 ;1
L 3.2075 2.2075 3.2075 2.2075 9 P 0 ;1
L 3.2075 2.2575 3.2075 2.2575 9 P 0 ;1
L 3.2075 2.3075 3.2075 2.3075 9 P 0 ;1
L 3.2075 2.3575 3.2075 2.3575 9 P 0 ;1
L 3.2075 2.4075 3.2075 2.4075 9 P 0 ;1
L 3.2075 2.4575 3.2075 2.4575 9 P 0 ;1
L 3.2075 2.5075 3.2075 2.5075 9 P 0 ;1
L 3.2075 2.5575 3.2075 2.5575 9 P 0 ;1
L 3.2075 2.6075 3.2075 2.6075 9 P 0 ;1
L 3.2075 2.6575 3.2075 2.6575 9 P 0 ;1
L 3.2075 2.7075 3.2075 2.7075 9 P 0 ;1
L 3.2075 2.7575 3.2075 2.7575 9 P 0 ;1
L 3.2075 2.8075 3.2075 2.8075 9 P 0 ;1
L 3.2075 2.8575 3.2075 2.8575 9 P 0 ;1
L 3.2075 2.9075 3.2075 2.9075 9 P 0 ;1
L 3.2075 2.9575 3.2075 2.9575 9 P 0 ;1
L 3.2075 3.0075 3.2075 3.0075 9 P 0 ;1
L 3.2075 3.0575 3.2075 3.0575 9 P 0 ;1
L 3.2075 3.1075 3.2075 3.1075 9 P 0 ;1
L 3.2075 3.1575 3.2075 3.1575 9 P 0 ;1
L 3.2075 3.2075 3.2075 3.2075 9 P 0 ;1
L 3.2075 3.2575 3.2075 3.2575 9 P 0 ;1
L 3.2075 3.3075 3.2075 3.3075 9 P 0 ;1
L 3.2075 3.3575 3.2075 3.3575 9 P 0 ;1
L 3.2075 3.4075 3.2075 3.4075 9 P 0 ;1
L 3.2075 3.4575 3.2075 3.4575 9 P 0 ;1
L 3.2075 3.5075 3.2075 3.5075 9 P 0 ;1
L 3.2075 3.5575 3.2075 3.5575 9 P 0 ;1
L 3.2075 3.6075 3.2075 3.6075 9 P 0 ;1
L 3.2075 5.4075 3.2075 5.4075 9 P 0 ;1
L 3.2075 5.4575 3.2075 5.4575 9 P 0 ;1
L 3.2075 5.5075 3.2075 5.5075 9 P 0 ;1
L 3.2075 5.5575 3.2075 5.5575 9 P 0 ;1
L 3.2075 5.6075 3.2075 5.6075 9 P 0 ;1
L 3.2075 5.6575 3.2075 5.6575 9 P 0 ;1
L 3.2075 5.7075 3.2075 5.7075 9 P 0 ;1
L 3.2075 5.7575 3.2075 5.7575 9 P 0 ;1
L 3.2075 5.8075 3.2075 5.8075 9 P 0 ;1
L 3.2075 5.8575 3.2075 5.8575 9 P 0 ;1
L 3.2075 5.9075 3.2075 5.9075 9 P 0 ;1
L 3.2575 0.1575 3.2575 0.1575 9 P 0 ;1
L 3.2575 0.2075 3.2575 0.2075 9 P 0 ;1
L 3.2575 0.2575 3.2575 0.2575 9 P 0 ;1
L 3.2575 0.3075 3.2575 0.3075 9 P 0 ;1
L 3.2575 0.3575 3.2575 0.3575 9 P 0 ;1
L 3.2575 0.4075 3.2575 0.4075 9 P 0 ;1
L 3.2575 0.4575 3.2575 0.4575 9 P 0 ;1
L 3.2575 0.5075 3.2575 0.5075 9 P 0 ;1
L 3.2575 0.5575 3.2575 0.5575 9 P 0 ;1
L 3.2575 0.6075 3.2575 0.6075 9 P 0 ;1
L 3.2575 0.6575 3.2575 0.6575 9 P 0 ;1
L 3.2575 0.7075 3.2575 0.7075 9 P 0 ;1
L 3.2575 0.7575 3.2575 0.7575 9 P 0 ;1
L 3.2575 0.8075 3.2575 0.8075 9 P 0 ;1
L 3.2575 0.8575 3.2575 0.8575 9 P 0 ;1
L 3.2575 0.9075 3.2575 0.9075 9 P 0 ;1
L 3.2575 0.9575 3.2575 0.9575 9 P 0 ;1
L 3.2575 1.0075 3.2575 1.0075 9 P 0 ;1
L 3.2575 1.0575 3.2575 1.0575 9 P 0 ;1
L 3.2575 1.1075 3.2575 1.1075 9 P 0 ;1
L 3.2575 1.1575 3.2575 1.1575 9 P 0 ;1
L 3.2575 1.2075 3.2575 1.2075 9 P 0 ;1
L 3.2575 1.2575 3.2575 1.2575 9 P 0 ;1
L 3.2575 1.3075 3.2575 1.3075 9 P 0 ;1
L 3.2575 1.3575 3.2575 1.3575 9 P 0 ;1
L 3.2575 1.4075 3.2575 1.4075 9 P 0 ;1
L 3.2575 1.4575 3.2575 1.4575 9 P 0 ;1
L 3.2575 1.5075 3.2575 1.5075 9 P 0 ;1
L 3.2575 1.5575 3.2575 1.5575 9 P 0 ;1
L 3.2575 1.6075 3.2575 1.6075 9 P 0 ;1
L 3.2575 1.6575 3.2575 1.6575 9 P 0 ;1
L 3.2575 1.7075 3.2575 1.7075 9 P 0 ;1
L 3.2575 1.7575 3.2575 1.7575 9 P 0 ;1
L 3.2575 1.8075 3.2575 1.8075 9 P 0 ;1
L 3.2575 1.8575 3.2575 1.8575 9 P 0 ;1
L 3.2575 1.9075 3.2575 1.9075 9 P 0 ;1
L 3.2575 1.9575 3.2575 1.9575 9 P 0 ;1
L 3.2575 2.0075 3.2575 2.0075 9 P 0 ;1
L 3.2575 2.0575 3.2575 2.0575 9 P 0 ;1
L 3.2575 2.1075 3.2575 2.1075 9 P 0 ;1
L 3.2575 2.1575 3.2575 2.1575 9 P 0 ;1
L 3.2575 2.2075 3.2575 2.2075 9 P 0 ;1
L 3.2575 2.2575 3.2575 2.2575 9 P 0 ;1
L 3.2575 2.3075 3.2575 2.3075 9 P 0 ;1
L 3.2575 2.3575 3.2575 2.3575 9 P 0 ;1
L 3.2575 2.4075 3.2575 2.4075 9 P 0 ;1
L 3.2575 2.4575 3.2575 2.4575 9 P 0 ;1
L 3.2575 2.5075 3.2575 2.5075 9 P 0 ;1
L 3.2575 2.5575 3.2575 2.5575 9 P 0 ;1
L 3.2575 2.6075 3.2575 2.6075 9 P 0 ;1
L 3.2575 2.6575 3.2575 2.6575 9 P 0 ;1
L 3.2575 2.7075 3.2575 2.7075 9 P 0 ;1
L 3.2575 2.7575 3.2575 2.7575 9 P 0 ;1
L 3.2575 2.8075 3.2575 2.8075 9 P 0 ;1
L 3.2575 2.8575 3.2575 2.8575 9 P 0 ;1
L 3.2575 2.9075 3.2575 2.9075 9 P 0 ;1
L 3.2575 2.9575 3.2575 2.9575 9 P 0 ;1
L 3.2575 3.0075 3.2575 3.0075 9 P 0 ;1
L 3.2575 3.0575 3.2575 3.0575 9 P 0 ;1
L 3.2575 3.1075 3.2575 3.1075 9 P 0 ;1
L 3.2575 3.1575 3.2575 3.1575 9 P 0 ;1
L 3.2575 3.2075 3.2575 3.2075 9 P 0 ;1
L 3.2575 3.2575 3.2575 3.2575 9 P 0 ;1
L 3.2575 3.3075 3.2575 3.3075 9 P 0 ;1
L 3.2575 3.3575 3.2575 3.3575 9 P 0 ;1
L 3.2575 3.4075 3.2575 3.4075 9 P 0 ;1
L 3.2575 3.4575 3.2575 3.4575 9 P 0 ;1
L 3.2575 3.5075 3.2575 3.5075 9 P 0 ;1
L 3.2575 3.5575 3.2575 3.5575 9 P 0 ;1
L 3.2575 3.6075 3.2575 3.6075 9 P 0 ;1
L 3.2575 5.4575 3.2575 5.4575 9 P 0 ;1
L 3.2575 5.5075 3.2575 5.5075 9 P 0 ;1
L 3.2575 5.5575 3.2575 5.5575 9 P 0 ;1
L 3.2575 5.6075 3.2575 5.6075 9 P 0 ;1
L 3.2575 5.6575 3.2575 5.6575 9 P 0 ;1
L 3.2575 5.7075 3.2575 5.7075 9 P 0 ;1
L 3.2575 5.7575 3.2575 5.7575 9 P 0 ;1
L 3.2575 5.8075 3.2575 5.8075 9 P 0 ;1
L 3.2575 5.8575 3.2575 5.8575 9 P 0 ;1
L 3.2575 5.9075 3.2575 5.9075 9 P 0 ;1
L 3.3075 0.1575 3.3075 0.1575 9 P 0 ;1
L 3.3075 0.2075 3.3075 0.2075 9 P 0 ;1
L 3.3075 0.2575 3.3075 0.2575 9 P 0 ;1
L 3.3075 0.3075 3.3075 0.3075 9 P 0 ;1
L 3.3075 0.3575 3.3075 0.3575 9 P 0 ;1
L 3.3075 0.4075 3.3075 0.4075 9 P 0 ;1
L 3.3075 0.4575 3.3075 0.4575 9 P 0 ;1
L 3.3075 0.5075 3.3075 0.5075 9 P 0 ;1
L 3.3075 0.5575 3.3075 0.5575 9 P 0 ;1
L 3.3075 0.6075 3.3075 0.6075 9 P 0 ;1
L 3.3075 0.6575 3.3075 0.6575 9 P 0 ;1
L 3.3075 0.7075 3.3075 0.7075 9 P 0 ;1
L 3.3075 0.7575 3.3075 0.7575 9 P 0 ;1
L 3.3075 0.8075 3.3075 0.8075 9 P 0 ;1
L 3.3075 0.8575 3.3075 0.8575 9 P 0 ;1
L 3.3075 0.9075 3.3075 0.9075 9 P 0 ;1
L 3.3075 0.9575 3.3075 0.9575 9 P 0 ;1
L 3.3075 1.0075 3.3075 1.0075 9 P 0 ;1
L 3.3075 1.0575 3.3075 1.0575 9 P 0 ;1
L 3.3075 1.1075 3.3075 1.1075 9 P 0 ;1
L 3.3075 1.1575 3.3075 1.1575 9 P 0 ;1
L 3.3075 1.2075 3.3075 1.2075 9 P 0 ;1
L 3.3075 1.2575 3.3075 1.2575 9 P 0 ;1
L 3.3075 1.3075 3.3075 1.3075 9 P 0 ;1
L 3.3075 1.3575 3.3075 1.3575 9 P 0 ;1
L 3.3075 1.4075 3.3075 1.4075 9 P 0 ;1
L 3.3075 1.4575 3.3075 1.4575 9 P 0 ;1
L 3.3075 1.5075 3.3075 1.5075 9 P 0 ;1
L 3.3075 1.5575 3.3075 1.5575 9 P 0 ;1
L 3.3075 1.6075 3.3075 1.6075 9 P 0 ;1
L 3.3075 1.6575 3.3075 1.6575 9 P 0 ;1
L 3.3075 1.7075 3.3075 1.7075 9 P 0 ;1
L 3.3075 1.7575 3.3075 1.7575 9 P 0 ;1
L 3.3075 1.8075 3.3075 1.8075 9 P 0 ;1
L 3.3075 1.8575 3.3075 1.8575 9 P 0 ;1
L 3.3075 1.9075 3.3075 1.9075 9 P 0 ;1
L 3.3075 1.9575 3.3075 1.9575 9 P 0 ;1
L 3.3075 2.0075 3.3075 2.0075 9 P 0 ;1
L 3.3075 2.0575 3.3075 2.0575 9 P 0 ;1
L 3.3075 2.1075 3.3075 2.1075 9 P 0 ;1
L 3.3075 2.1575 3.3075 2.1575 9 P 0 ;1
L 3.3075 2.2075 3.3075 2.2075 9 P 0 ;1
L 3.3075 2.2575 3.3075 2.2575 9 P 0 ;1
L 3.3075 2.3075 3.3075 2.3075 9 P 0 ;1
L 3.3075 2.3575 3.3075 2.3575 9 P 0 ;1
L 3.3075 2.4075 3.3075 2.4075 9 P 0 ;1
L 3.3075 2.4575 3.3075 2.4575 9 P 0 ;1
L 3.3075 2.5075 3.3075 2.5075 9 P 0 ;1
L 3.3075 2.5575 3.3075 2.5575 9 P 0 ;1
L 3.3075 2.6075 3.3075 2.6075 9 P 0 ;1
L 3.3075 2.6575 3.3075 2.6575 9 P 0 ;1
L 3.3075 2.7075 3.3075 2.7075 9 P 0 ;1
L 3.3075 2.7575 3.3075 2.7575 9 P 0 ;1
L 3.3075 2.8075 3.3075 2.8075 9 P 0 ;1
L 3.3075 2.8575 3.3075 2.8575 9 P 0 ;1
L 3.3075 2.9075 3.3075 2.9075 9 P 0 ;1
L 3.3075 2.9575 3.3075 2.9575 9 P 0 ;1
L 3.3075 3.0075 3.3075 3.0075 9 P 0 ;1
L 3.3075 3.0575 3.3075 3.0575 9 P 0 ;1
L 3.3075 3.1075 3.3075 3.1075 9 P 0 ;1
L 3.3075 3.1575 3.3075 3.1575 9 P 0 ;1
L 3.3075 3.2075 3.3075 3.2075 9 P 0 ;1
L 3.3075 3.2575 3.3075 3.2575 9 P 0 ;1
L 3.3075 3.3075 3.3075 3.3075 9 P 0 ;1
L 3.3075 3.3575 3.3075 3.3575 9 P 0 ;1
L 3.3075 3.4075 3.3075 3.4075 9 P 0 ;1
L 3.3075 3.4575 3.3075 3.4575 9 P 0 ;1
L 3.3075 3.5075 3.3075 3.5075 9 P 0 ;1
L 3.3075 3.5575 3.3075 3.5575 9 P 0 ;1
L 3.3075 3.6075 3.3075 3.6075 9 P 0 ;1
L 3.3075 3.6575 3.3075 3.6575 9 P 0 ;1
L 3.3075 5.4075 3.3075 5.4075 9 P 0 ;1
L 3.3075 5.4575 3.3075 5.4575 9 P 0 ;1
L 3.3075 5.5075 3.3075 5.5075 9 P 0 ;1
L 3.3075 5.5575 3.3075 5.5575 9 P 0 ;1
L 3.3075 5.6075 3.3075 5.6075 9 P 0 ;1
L 3.3075 5.6575 3.3075 5.6575 9 P 0 ;1
L 3.3075 5.7075 3.3075 5.7075 9 P 0 ;1
L 3.3075 5.7575 3.3075 5.7575 9 P 0 ;1
L 3.3075 5.8075 3.3075 5.8075 9 P 0 ;1
L 3.3075 5.8575 3.3075 5.8575 9 P 0 ;1
L 3.3075 5.9075 3.3075 5.9075 9 P 0 ;1
L 3.3575 0.1575 3.3575 0.1575 9 P 0 ;1
L 3.3575 0.2075 3.3575 0.2075 9 P 0 ;1
L 3.3575 0.2575 3.3575 0.2575 9 P 0 ;1
L 3.3575 0.3075 3.3575 0.3075 9 P 0 ;1
L 3.3575 0.3575 3.3575 0.3575 9 P 0 ;1
L 3.3575 0.4075 3.3575 0.4075 9 P 0 ;1
L 3.3575 0.4575 3.3575 0.4575 9 P 0 ;1
L 3.3575 0.5075 3.3575 0.5075 9 P 0 ;1
L 3.3575 0.5575 3.3575 0.5575 9 P 0 ;1
L 3.3575 0.6075 3.3575 0.6075 9 P 0 ;1
L 3.3575 0.6575 3.3575 0.6575 9 P 0 ;1
L 3.3575 0.7075 3.3575 0.7075 9 P 0 ;1
L 3.3575 0.7575 3.3575 0.7575 9 P 0 ;1
L 3.3575 0.8075 3.3575 0.8075 9 P 0 ;1
L 3.3575 0.8575 3.3575 0.8575 9 P 0 ;1
L 3.3575 0.9075 3.3575 0.9075 9 P 0 ;1
L 3.3575 0.9575 3.3575 0.9575 9 P 0 ;1
L 3.3575 1.0075 3.3575 1.0075 9 P 0 ;1
L 3.3575 1.0575 3.3575 1.0575 9 P 0 ;1
L 3.3575 1.1075 3.3575 1.1075 9 P 0 ;1
L 3.3575 1.1575 3.3575 1.1575 9 P 0 ;1
L 3.3575 1.2075 3.3575 1.2075 9 P 0 ;1
L 3.3575 1.2575 3.3575 1.2575 9 P 0 ;1
L 3.3575 1.3075 3.3575 1.3075 9 P 0 ;1
L 3.3575 1.3575 3.3575 1.3575 9 P 0 ;1
L 3.3575 1.4075 3.3575 1.4075 9 P 0 ;1
L 3.3575 1.4575 3.3575 1.4575 9 P 0 ;1
L 3.3575 1.5075 3.3575 1.5075 9 P 0 ;1
L 3.3575 1.5575 3.3575 1.5575 9 P 0 ;1
L 3.3575 1.6075 3.3575 1.6075 9 P 0 ;1
L 3.3575 1.6575 3.3575 1.6575 9 P 0 ;1
L 3.3575 1.7075 3.3575 1.7075 9 P 0 ;1
L 3.3575 1.7575 3.3575 1.7575 9 P 0 ;1
L 3.3575 1.8075 3.3575 1.8075 9 P 0 ;1
L 3.3575 1.8575 3.3575 1.8575 9 P 0 ;1
L 3.3575 1.9075 3.3575 1.9075 9 P 0 ;1
L 3.3575 1.9575 3.3575 1.9575 9 P 0 ;1
L 3.3575 2.0075 3.3575 2.0075 9 P 0 ;1
L 3.3575 2.0575 3.3575 2.0575 9 P 0 ;1
L 3.3575 2.1075 3.3575 2.1075 9 P 0 ;1
L 3.3575 2.1575 3.3575 2.1575 9 P 0 ;1
L 3.3575 2.2075 3.3575 2.2075 9 P 0 ;1
L 3.3575 2.2575 3.3575 2.2575 9 P 0 ;1
L 3.3575 2.3075 3.3575 2.3075 9 P 0 ;1
L 3.3575 2.3575 3.3575 2.3575 9 P 0 ;1
L 3.3575 2.4075 3.3575 2.4075 9 P 0 ;1
L 3.3575 2.4575 3.3575 2.4575 9 P 0 ;1
L 3.3575 2.5075 3.3575 2.5075 9 P 0 ;1
L 3.3575 2.5575 3.3575 2.5575 9 P 0 ;1
L 3.3575 2.6075 3.3575 2.6075 9 P 0 ;1
L 3.3575 2.6575 3.3575 2.6575 9 P 0 ;1
L 3.3575 2.7075 3.3575 2.7075 9 P 0 ;1
L 3.3575 2.7575 3.3575 2.7575 9 P 0 ;1
L 3.3575 2.8075 3.3575 2.8075 9 P 0 ;1
L 3.3575 2.8575 3.3575 2.8575 9 P 0 ;1
L 3.3575 2.9075 3.3575 2.9075 9 P 0 ;1
L 3.3575 2.9575 3.3575 2.9575 9 P 0 ;1
L 3.3575 3.0075 3.3575 3.0075 9 P 0 ;1
L 3.3575 3.0575 3.3575 3.0575 9 P 0 ;1
L 3.3575 3.1075 3.3575 3.1075 9 P 0 ;1
L 3.3575 3.1575 3.3575 3.1575 9 P 0 ;1
L 3.3575 3.2075 3.3575 3.2075 9 P 0 ;1
L 3.3575 3.2575 3.3575 3.2575 9 P 0 ;1
L 3.3575 3.3075 3.3575 3.3075 9 P 0 ;1
L 3.3575 3.3575 3.3575 3.3575 9 P 0 ;1
L 3.3575 3.4075 3.3575 3.4075 9 P 0 ;1
L 3.3575 3.4575 3.3575 3.4575 9 P 0 ;1
L 3.3575 3.5075 3.3575 3.5075 9 P 0 ;1
L 3.3575 3.5575 3.3575 3.5575 9 P 0 ;1
L 3.3575 3.6075 3.3575 3.6075 9 P 0 ;1
L 3.3575 3.6575 3.3575 3.6575 9 P 0 ;1
L 3.3575 3.7075 3.3575 3.7075 9 P 0 ;1
L 3.3575 5.4075 3.3575 5.4075 9 P 0 ;1
L 3.3575 5.4575 3.3575 5.4575 9 P 0 ;1
L 3.3575 5.5075 3.3575 5.5075 9 P 0 ;1
L 3.3575 5.5575 3.3575 5.5575 9 P 0 ;1
L 3.3575 5.6075 3.3575 5.6075 9 P 0 ;1
L 3.3575 5.6575 3.3575 5.6575 9 P 0 ;1
L 3.3575 5.7075 3.3575 5.7075 9 P 0 ;1
L 3.3575 5.7575 3.3575 5.7575 9 P 0 ;1
L 3.3575 5.8075 3.3575 5.8075 9 P 0 ;1
L 3.3575 5.8575 3.3575 5.8575 9 P 0 ;1
L 3.3575 5.9075 3.3575 5.9075 9 P 0 ;1
L 3.4075 0.1575 3.4075 0.1575 9 P 0 ;1
L 3.4075 0.2075 3.4075 0.2075 9 P 0 ;1
L 3.4075 0.2575 3.4075 0.2575 9 P 0 ;1
L 3.4075 0.3075 3.4075 0.3075 9 P 0 ;1
L 3.4075 0.3575 3.4075 0.3575 9 P 0 ;1
L 3.4075 0.4075 3.4075 0.4075 9 P 0 ;1
L 3.4075 0.4575 3.4075 0.4575 9 P 0 ;1
L 3.4075 0.5075 3.4075 0.5075 9 P 0 ;1
L 3.4075 0.5575 3.4075 0.5575 9 P 0 ;1
L 3.4075 0.6075 3.4075 0.6075 9 P 0 ;1
L 3.4075 0.6575 3.4075 0.6575 9 P 0 ;1
L 3.4075 0.7075 3.4075 0.7075 9 P 0 ;1
L 3.4075 0.7575 3.4075 0.7575 9 P 0 ;1
L 3.4075 0.8075 3.4075 0.8075 9 P 0 ;1
L 3.4075 0.8575 3.4075 0.8575 9 P 0 ;1
L 3.4075 0.9075 3.4075 0.9075 9 P 0 ;1
L 3.4075 0.9575 3.4075 0.9575 9 P 0 ;1
L 3.4075 1.0075 3.4075 1.0075 9 P 0 ;1
L 3.4075 1.0575 3.4075 1.0575 9 P 0 ;1
L 3.4075 1.1075 3.4075 1.1075 9 P 0 ;1
L 3.4075 1.1575 3.4075 1.1575 9 P 0 ;1
L 3.4075 1.2075 3.4075 1.2075 9 P 0 ;1
L 3.4075 1.2575 3.4075 1.2575 9 P 0 ;1
L 3.4075 1.3075 3.4075 1.3075 9 P 0 ;1
L 3.4075 1.3575 3.4075 1.3575 9 P 0 ;1
L 3.4075 1.4075 3.4075 1.4075 9 P 0 ;1
L 3.4075 1.4575 3.4075 1.4575 9 P 0 ;1
L 3.4075 1.5075 3.4075 1.5075 9 P 0 ;1
L 3.4075 1.5575 3.4075 1.5575 9 P 0 ;1
L 3.4075 1.6075 3.4075 1.6075 9 P 0 ;1
L 3.4075 1.6575 3.4075 1.6575 9 P 0 ;1
L 3.4075 1.7075 3.4075 1.7075 9 P 0 ;1
L 3.4075 1.7575 3.4075 1.7575 9 P 0 ;1
L 3.4075 1.8075 3.4075 1.8075 9 P 0 ;1
L 3.4075 1.8575 3.4075 1.8575 9 P 0 ;1
L 3.4075 1.9075 3.4075 1.9075 9 P 0 ;1
L 3.4075 1.9575 3.4075 1.9575 9 P 0 ;1
L 3.4075 2.0075 3.4075 2.0075 9 P 0 ;1
L 3.4075 2.0575 3.4075 2.0575 9 P 0 ;1
L 3.4075 2.1075 3.4075 2.1075 9 P 0 ;1
L 3.4075 2.1575 3.4075 2.1575 9 P 0 ;1
L 3.4075 2.2075 3.4075 2.2075 9 P 0 ;1
L 3.4075 2.2575 3.4075 2.2575 9 P 0 ;1
L 3.4075 2.3075 3.4075 2.3075 9 P 0 ;1
L 3.4075 2.3575 3.4075 2.3575 9 P 0 ;1
L 3.4075 2.4075 3.4075 2.4075 9 P 0 ;1
L 3.4075 2.4575 3.4075 2.4575 9 P 0 ;1
L 3.4075 2.5075 3.4075 2.5075 9 P 0 ;1
L 3.4075 2.5575 3.4075 2.5575 9 P 0 ;1
L 3.4075 2.6075 3.4075 2.6075 9 P 0 ;1
L 3.4075 2.6575 3.4075 2.6575 9 P 0 ;1
L 3.4075 2.7075 3.4075 2.7075 9 P 0 ;1
L 3.4075 2.7575 3.4075 2.7575 9 P 0 ;1
L 3.4075 2.8075 3.4075 2.8075 9 P 0 ;1
L 3.4075 2.8575 3.4075 2.8575 9 P 0 ;1
L 3.4075 2.9075 3.4075 2.9075 9 P 0 ;1
L 3.4075 2.9575 3.4075 2.9575 9 P 0 ;1
L 3.4075 3.0075 3.4075 3.0075 9 P 0 ;1
L 3.4075 3.0575 3.4075 3.0575 9 P 0 ;1
L 3.4075 3.1075 3.4075 3.1075 9 P 0 ;1
L 3.4075 3.1575 3.4075 3.1575 9 P 0 ;1
L 3.4075 3.2075 3.4075 3.2075 9 P 0 ;1
L 3.4075 3.2575 3.4075 3.2575 9 P 0 ;1
L 3.4075 3.3075 3.4075 3.3075 9 P 0 ;1
L 3.4075 3.3575 3.4075 3.3575 9 P 0 ;1
L 3.4075 3.4075 3.4075 3.4075 9 P 0 ;1
L 3.4075 3.4575 3.4075 3.4575 9 P 0 ;1
L 3.4075 3.5075 3.4075 3.5075 9 P 0 ;1
L 3.4075 3.5575 3.4075 3.5575 9 P 0 ;1
L 3.4075 3.6075 3.4075 3.6075 9 P 0 ;1
L 3.4075 3.6575 3.4075 3.6575 9 P 0 ;1
L 3.4075 3.7075 3.4075 3.7075 9 P 0 ;1
L 3.4075 5.4575 3.4075 5.4575 9 P 0 ;1
L 3.4075 5.5075 3.4075 5.5075 9 P 0 ;1
L 3.4075 5.5575 3.4075 5.5575 9 P 0 ;1
L 3.4075 5.6075 3.4075 5.6075 9 P 0 ;1
L 3.4075 5.6575 3.4075 5.6575 9 P 0 ;1
L 3.4075 5.7075 3.4075 5.7075 9 P 0 ;1
L 3.4075 5.7575 3.4075 5.7575 9 P 0 ;1
L 3.4075 5.8075 3.4075 5.8075 9 P 0 ;1
L 3.4075 5.8575 3.4075 5.8575 9 P 0 ;1
L 3.4075 5.9075 3.4075 5.9075 9 P 0 ;1
L 3.4575 0.1575 3.4575 0.1575 9 P 0 ;1
L 3.4575 0.2075 3.4575 0.2075 9 P 0 ;1
L 3.4575 0.2575 3.4575 0.2575 9 P 0 ;1
L 3.4575 0.3075 3.4575 0.3075 9 P 0 ;1
L 3.4575 0.3575 3.4575 0.3575 9 P 0 ;1
L 3.4575 0.4075 3.4575 0.4075 9 P 0 ;1
L 3.4575 0.4575 3.4575 0.4575 9 P 0 ;1
L 3.4575 0.5075 3.4575 0.5075 9 P 0 ;1
L 3.4575 0.5575 3.4575 0.5575 9 P 0 ;1
L 3.4575 0.6075 3.4575 0.6075 9 P 0 ;1
L 3.4575 0.6575 3.4575 0.6575 9 P 0 ;1
L 3.4575 0.7075 3.4575 0.7075 9 P 0 ;1
L 3.4575 0.7575 3.4575 0.7575 9 P 0 ;1
L 3.4575 0.8075 3.4575 0.8075 9 P 0 ;1
L 3.4575 0.8575 3.4575 0.8575 9 P 0 ;1
L 3.4575 0.9075 3.4575 0.9075 9 P 0 ;1
L 3.4575 0.9575 3.4575 0.9575 9 P 0 ;1
L 3.4575 1.0075 3.4575 1.0075 9 P 0 ;1
L 3.4575 1.0575 3.4575 1.0575 9 P 0 ;1
L 3.4575 1.1075 3.4575 1.1075 9 P 0 ;1
L 3.4575 1.1575 3.4575 1.1575 9 P 0 ;1
L 3.4575 1.2075 3.4575 1.2075 9 P 0 ;1
L 3.4575 1.2575 3.4575 1.2575 9 P 0 ;1
L 3.4575 1.3075 3.4575 1.3075 9 P 0 ;1
L 3.4575 1.3575 3.4575 1.3575 9 P 0 ;1
L 3.4575 1.4075 3.4575 1.4075 9 P 0 ;1
L 3.4575 1.4575 3.4575 1.4575 9 P 0 ;1
L 3.4575 1.5075 3.4575 1.5075 9 P 0 ;1
L 3.4575 1.5575 3.4575 1.5575 9 P 0 ;1
L 3.4575 1.6075 3.4575 1.6075 9 P 0 ;1
L 3.4575 1.6575 3.4575 1.6575 9 P 0 ;1
L 3.4575 1.7075 3.4575 1.7075 9 P 0 ;1
L 3.4575 1.7575 3.4575 1.7575 9 P 0 ;1
L 3.4575 1.8075 3.4575 1.8075 9 P 0 ;1
L 3.4575 1.8575 3.4575 1.8575 9 P 0 ;1
L 3.4575 1.9075 3.4575 1.9075 9 P 0 ;1
L 3.4575 1.9575 3.4575 1.9575 9 P 0 ;1
L 3.4575 2.0075 3.4575 2.0075 9 P 0 ;1
L 3.4575 2.0575 3.4575 2.0575 9 P 0 ;1
L 3.4575 2.1075 3.4575 2.1075 9 P 0 ;1
L 3.4575 2.1575 3.4575 2.1575 9 P 0 ;1
L 3.4575 2.2075 3.4575 2.2075 9 P 0 ;1
L 3.4575 2.2575 3.4575 2.2575 9 P 0 ;1
L 3.4575 2.3075 3.4575 2.3075 9 P 0 ;1
L 3.4575 2.3575 3.4575 2.3575 9 P 0 ;1
L 3.4575 2.4075 3.4575 2.4075 9 P 0 ;1
L 3.4575 2.4575 3.4575 2.4575 9 P 0 ;1
L 3.4575 2.5075 3.4575 2.5075 9 P 0 ;1
L 3.4575 2.5575 3.4575 2.5575 9 P 0 ;1
L 3.4575 2.6075 3.4575 2.6075 9 P 0 ;1
L 3.4575 2.6575 3.4575 2.6575 9 P 0 ;1
L 3.4575 2.7075 3.4575 2.7075 9 P 0 ;1
L 3.4575 2.7575 3.4575 2.7575 9 P 0 ;1
L 3.4575 2.8075 3.4575 2.8075 9 P 0 ;1
L 3.4575 2.8575 3.4575 2.8575 9 P 0 ;1
L 3.4575 2.9075 3.4575 2.9075 9 P 0 ;1
L 3.4575 2.9575 3.4575 2.9575 9 P 0 ;1
L 3.4575 3.0075 3.4575 3.0075 9 P 0 ;1
L 3.4575 3.0575 3.4575 3.0575 9 P 0 ;1
L 3.4575 3.1075 3.4575 3.1075 9 P 0 ;1
L 3.4575 3.1575 3.4575 3.1575 9 P 0 ;1
L 3.4575 3.2075 3.4575 3.2075 9 P 0 ;1
L 3.4575 3.2575 3.4575 3.2575 9 P 0 ;1
L 3.4575 3.3075 3.4575 3.3075 9 P 0 ;1
L 3.4575 3.3575 3.4575 3.3575 9 P 0 ;1
L 3.4575 3.4075 3.4575 3.4075 9 P 0 ;1
L 3.4575 3.4575 3.4575 3.4575 9 P 0 ;1
L 3.4575 3.5075 3.4575 3.5075 9 P 0 ;1
L 3.4575 3.5575 3.4575 3.5575 9 P 0 ;1
L 3.4575 3.6075 3.4575 3.6075 9 P 0 ;1
L 3.4575 3.6575 3.4575 3.6575 9 P 0 ;1
L 3.4575 3.7075 3.4575 3.7075 9 P 0 ;1
L 3.4575 3.7575 3.4575 3.7575 9 P 0 ;1
L 3.4575 5.4075 3.4575 5.4075 9 P 0 ;1
L 3.4575 5.4575 3.4575 5.4575 9 P 0 ;1
L 3.4575 5.5075 3.4575 5.5075 9 P 0 ;1
L 3.4575 5.5575 3.4575 5.5575 9 P 0 ;1
L 3.4575 5.6075 3.4575 5.6075 9 P 0 ;1
L 3.4575 5.6575 3.4575 5.6575 9 P 0 ;1
L 3.4575 5.7075 3.4575 5.7075 9 P 0 ;1
L 3.4575 5.7575 3.4575 5.7575 9 P 0 ;1
L 3.4575 5.8075 3.4575 5.8075 9 P 0 ;1
L 3.4575 5.8575 3.4575 5.8575 9 P 0 ;1
L 3.4575 5.9075 3.4575 5.9075 9 P 0 ;1
L 3.5075 0.1575 3.5075 0.1575 9 P 0 ;1
L 3.5075 0.2075 3.5075 0.2075 9 P 0 ;1
L 3.5075 0.2575 3.5075 0.2575 9 P 0 ;1
L 3.5075 0.3075 3.5075 0.3075 9 P 0 ;1
L 3.5075 0.3575 3.5075 0.3575 9 P 0 ;1
L 3.5075 0.4075 3.5075 0.4075 9 P 0 ;1
L 3.5075 0.5575 3.5075 0.5575 9 P 0 ;1
L 3.5075 0.6075 3.5075 0.6075 9 P 0 ;1
L 3.5075 0.6575 3.5075 0.6575 9 P 0 ;1
L 3.5075 0.7075 3.5075 0.7075 9 P 0 ;1
L 3.5075 0.7575 3.5075 0.7575 9 P 0 ;1
L 3.5075 0.8075 3.5075 0.8075 9 P 0 ;1
L 3.5075 0.8575 3.5075 0.8575 9 P 0 ;1
L 3.5075 0.9075 3.5075 0.9075 9 P 0 ;1
L 3.5075 0.9575 3.5075 0.9575 9 P 0 ;1
L 3.5075 1.0075 3.5075 1.0075 9 P 0 ;1
L 3.5075 1.0575 3.5075 1.0575 9 P 0 ;1
L 3.5075 1.1075 3.5075 1.1075 9 P 0 ;1
L 3.5075 1.1575 3.5075 1.1575 9 P 0 ;1
L 3.5075 1.2075 3.5075 1.2075 9 P 0 ;1
L 3.5075 1.2575 3.5075 1.2575 9 P 0 ;1
L 3.5075 1.3075 3.5075 1.3075 9 P 0 ;1
L 3.5075 1.3575 3.5075 1.3575 9 P 0 ;1
L 3.5075 1.4075 3.5075 1.4075 9 P 0 ;1
L 3.5075 1.4575 3.5075 1.4575 9 P 0 ;1
L 3.5075 1.5075 3.5075 1.5075 9 P 0 ;1
L 3.5075 1.5575 3.5075 1.5575 9 P 0 ;1
L 3.5075 1.6075 3.5075 1.6075 9 P 0 ;1
L 3.5075 1.6575 3.5075 1.6575 9 P 0 ;1
L 3.5075 1.7075 3.5075 1.7075 9 P 0 ;1
L 3.5075 1.7575 3.5075 1.7575 9 P 0 ;1
L 3.5075 1.8075 3.5075 1.8075 9 P 0 ;1
L 3.5075 1.8575 3.5075 1.8575 9 P 0 ;1
L 3.5075 1.9075 3.5075 1.9075 9 P 0 ;1
L 3.5075 1.9575 3.5075 1.9575 9 P 0 ;1
L 3.5075 2.0075 3.5075 2.0075 9 P 0 ;1
L 3.5075 2.0575 3.5075 2.0575 9 P 0 ;1
L 3.5075 2.1075 3.5075 2.1075 9 P 0 ;1
L 3.5075 2.1575 3.5075 2.1575 9 P 0 ;1
L 3.5075 2.2075 3.5075 2.2075 9 P 0 ;1
L 3.5075 2.2575 3.5075 2.2575 9 P 0 ;1
L 3.5075 2.3075 3.5075 2.3075 9 P 0 ;1
L 3.5075 2.3575 3.5075 2.3575 9 P 0 ;1
L 3.5075 2.4075 3.5075 2.4075 9 P 0 ;1
L 3.5075 2.4575 3.5075 2.4575 9 P 0 ;1
L 3.5075 2.5075 3.5075 2.5075 9 P 0 ;1
L 3.5075 2.5575 3.5075 2.5575 9 P 0 ;1
L 3.5075 2.6075 3.5075 2.6075 9 P 0 ;1
L 3.5075 2.6575 3.5075 2.6575 9 P 0 ;1
L 3.5075 2.7075 3.5075 2.7075 9 P 0 ;1
L 3.5075 2.7575 3.5075 2.7575 9 P 0 ;1
L 3.5075 2.8075 3.5075 2.8075 9 P 0 ;1
L 3.5075 2.8575 3.5075 2.8575 9 P 0 ;1
L 3.5075 2.9075 3.5075 2.9075 9 P 0 ;1
L 3.5075 2.9575 3.5075 2.9575 9 P 0 ;1
L 3.5075 3.0075 3.5075 3.0075 9 P 0 ;1
L 3.5075 3.0575 3.5075 3.0575 9 P 0 ;1
L 3.5075 3.1075 3.5075 3.1075 9 P 0 ;1
L 3.5075 3.1575 3.5075 3.1575 9 P 0 ;1
L 3.5075 3.2075 3.5075 3.2075 9 P 0 ;1
L 3.5075 3.2575 3.5075 3.2575 9 P 0 ;1
L 3.5075 3.3075 3.5075 3.3075 9 P 0 ;1
L 3.5075 3.3575 3.5075 3.3575 9 P 0 ;1
L 3.5075 3.4075 3.5075 3.4075 9 P 0 ;1
L 3.5075 3.4575 3.5075 3.4575 9 P 0 ;1
L 3.5075 3.5075 3.5075 3.5075 9 P 0 ;1
L 3.5075 3.5575 3.5075 3.5575 9 P 0 ;1
L 3.5075 3.6075 3.5075 3.6075 9 P 0 ;1
L 3.5075 3.6575 3.5075 3.6575 9 P 0 ;1
L 3.5075 3.7075 3.5075 3.7075 9 P 0 ;1
L 3.5075 3.7575 3.5075 3.7575 9 P 0 ;1
L 3.5075 3.8075 3.5075 3.8075 9 P 0 ;1
L 3.5075 3.8575 3.5075 3.8575 9 P 0 ;1
L 3.5075 5.4075 3.5075 5.4075 9 P 0 ;1
L 3.5075 5.4575 3.5075 5.4575 9 P 0 ;1
L 3.5075 5.5075 3.5075 5.5075 9 P 0 ;1
L 3.5075 5.5575 3.5075 5.5575 9 P 0 ;1
L 3.5075 5.6075 3.5075 5.6075 9 P 0 ;1
L 3.5075 5.6575 3.5075 5.6575 9 P 0 ;1
L 3.5075 5.7075 3.5075 5.7075 9 P 0 ;1
L 3.5075 5.7575 3.5075 5.7575 9 P 0 ;1
L 3.5075 5.8075 3.5075 5.8075 9 P 0 ;1
L 3.5075 5.8575 3.5075 5.8575 9 P 0 ;1
L 3.5075 5.9075 3.5075 5.9075 9 P 0 ;1
L 3.5575 0.1575 3.5575 0.1575 9 P 0 ;1
L 3.5575 0.3075 3.5575 0.3075 9 P 0 ;1
L 3.5575 0.3575 3.5575 0.3575 9 P 0 ;1
L 3.5575 0.4075 3.5575 0.4075 9 P 0 ;1
L 3.5575 0.6075 3.5575 0.6075 9 P 0 ;1
L 3.5575 0.6575 3.5575 0.6575 9 P 0 ;1
L 3.5575 0.7575 3.5575 0.7575 9 P 0 ;1
L 3.5575 0.8075 3.5575 0.8075 9 P 0 ;1
L 3.5575 0.8575 3.5575 0.8575 9 P 0 ;1
L 3.5575 0.9075 3.5575 0.9075 9 P 0 ;1
L 3.5575 0.9575 3.5575 0.9575 9 P 0 ;1
L 3.5575 1.0075 3.5575 1.0075 9 P 0 ;1
L 3.5575 1.0575 3.5575 1.0575 9 P 0 ;1
L 3.5575 1.1075 3.5575 1.1075 9 P 0 ;1
L 3.5575 1.1575 3.5575 1.1575 9 P 0 ;1
L 3.5575 1.2075 3.5575 1.2075 9 P 0 ;1
L 3.5575 1.2575 3.5575 1.2575 9 P 0 ;1
L 3.5575 1.3075 3.5575 1.3075 9 P 0 ;1
L 3.5575 1.3575 3.5575 1.3575 9 P 0 ;1
L 3.5575 1.4075 3.5575 1.4075 9 P 0 ;1
L 3.5575 1.4575 3.5575 1.4575 9 P 0 ;1
L 3.5575 1.5075 3.5575 1.5075 9 P 0 ;1
L 3.5575 1.5575 3.5575 1.5575 9 P 0 ;1
L 3.5575 1.6075 3.5575 1.6075 9 P 0 ;1
L 3.5575 1.6575 3.5575 1.6575 9 P 0 ;1
L 3.5575 1.7075 3.5575 1.7075 9 P 0 ;1
L 3.5575 1.7575 3.5575 1.7575 9 P 0 ;1
L 3.5575 1.8075 3.5575 1.8075 9 P 0 ;1
L 3.5575 1.8575 3.5575 1.8575 9 P 0 ;1
L 3.5575 1.9075 3.5575 1.9075 9 P 0 ;1
L 3.5575 1.9575 3.5575 1.9575 9 P 0 ;1
L 3.5575 2.0075 3.5575 2.0075 9 P 0 ;1
L 3.5575 2.0575 3.5575 2.0575 9 P 0 ;1
L 3.5575 2.1075 3.5575 2.1075 9 P 0 ;1
L 3.5575 2.1575 3.5575 2.1575 9 P 0 ;1
L 3.5575 2.2075 3.5575 2.2075 9 P 0 ;1
L 3.5575 2.2575 3.5575 2.2575 9 P 0 ;1
L 3.5575 2.3075 3.5575 2.3075 9 P 0 ;1
L 3.5575 2.3575 3.5575 2.3575 9 P 0 ;1
L 3.5575 2.4075 3.5575 2.4075 9 P 0 ;1
L 3.5575 2.4575 3.5575 2.4575 9 P 0 ;1
L 3.5575 2.5075 3.5575 2.5075 9 P 0 ;1
L 3.5575 2.5575 3.5575 2.5575 9 P 0 ;1
L 3.5575 2.6075 3.5575 2.6075 9 P 0 ;1
L 3.5575 2.6575 3.5575 2.6575 9 P 0 ;1
L 3.5575 2.7075 3.5575 2.7075 9 P 0 ;1
L 3.5575 2.7575 3.5575 2.7575 9 P 0 ;1
L 3.5575 2.8075 3.5575 2.8075 9 P 0 ;1
L 3.5575 2.8575 3.5575 2.8575 9 P 0 ;1
L 3.5575 2.9075 3.5575 2.9075 9 P 0 ;1
L 3.5575 2.9575 3.5575 2.9575 9 P 0 ;1
L 3.5575 3.0075 3.5575 3.0075 9 P 0 ;1
L 3.5575 3.0575 3.5575 3.0575 9 P 0 ;1
L 3.5575 3.1075 3.5575 3.1075 9 P 0 ;1
L 3.5575 3.1575 3.5575 3.1575 9 P 0 ;1
L 3.5575 3.2075 3.5575 3.2075 9 P 0 ;1
L 3.5575 3.2575 3.5575 3.2575 9 P 0 ;1
L 3.5575 3.3075 3.5575 3.3075 9 P 0 ;1
L 3.5575 3.3575 3.5575 3.3575 9 P 0 ;1
L 3.5575 3.4075 3.5575 3.4075 9 P 0 ;1
L 3.5575 3.4575 3.5575 3.4575 9 P 0 ;1
L 3.5575 3.5075 3.5575 3.5075 9 P 0 ;1
L 3.5575 3.5575 3.5575 3.5575 9 P 0 ;1
L 3.5575 3.6075 3.5575 3.6075 9 P 0 ;1
L 3.5575 3.6575 3.5575 3.6575 9 P 0 ;1
L 3.5575 3.7075 3.5575 3.7075 9 P 0 ;1
L 3.5575 3.7575 3.5575 3.7575 9 P 0 ;1
L 3.5575 3.8075 3.5575 3.8075 9 P 0 ;1
L 3.5575 3.8575 3.5575 3.8575 9 P 0 ;1
L 3.5575 3.9075 3.5575 3.9075 9 P 0 ;1
L 3.5575 5.2575 3.5575 5.2575 9 P 0 ;1
L 3.5575 5.3075 3.5575 5.3075 9 P 0 ;1
L 3.5575 5.3575 3.5575 5.3575 9 P 0 ;1
L 3.5575 5.4075 3.5575 5.4075 9 P 0 ;1
L 3.5575 5.4575 3.5575 5.4575 9 P 0 ;1
L 3.5575 5.5075 3.5575 5.5075 9 P 0 ;1
L 3.5575 5.5575 3.5575 5.5575 9 P 0 ;1
L 3.5575 5.6075 3.5575 5.6075 9 P 0 ;1
L 3.5575 5.6575 3.5575 5.6575 9 P 0 ;1
L 3.5575 5.7075 3.5575 5.7075 9 P 0 ;1
L 3.5575 5.7575 3.5575 5.7575 9 P 0 ;1
L 3.5575 5.8075 3.5575 5.8075 9 P 0 ;1
L 3.5575 5.8575 3.5575 5.8575 9 P 0 ;1
L 3.5575 5.9075 3.5575 5.9075 9 P 0 ;1
L 3.6075 0.1575 3.6075 0.1575 9 P 0 ;1
L 3.6075 0.4075 3.6075 0.4075 9 P 0 ;1
L 3.6075 0.6075 3.6075 0.6075 9 P 0 ;1
L 3.6075 0.8075 3.6075 0.8075 9 P 0 ;1
L 3.6075 0.8575 3.6075 0.8575 9 P 0 ;1
L 3.6075 0.9075 3.6075 0.9075 9 P 0 ;1
L 3.6075 0.9575 3.6075 0.9575 9 P 0 ;1
L 3.6075 1.0075 3.6075 1.0075 9 P 0 ;1
L 3.6075 1.0575 3.6075 1.0575 9 P 0 ;1
L 3.6075 1.1075 3.6075 1.1075 9 P 0 ;1
L 3.6075 1.1575 3.6075 1.1575 9 P 0 ;1
L 3.6075 1.2075 3.6075 1.2075 9 P 0 ;1
L 3.6075 1.2575 3.6075 1.2575 9 P 0 ;1
L 3.6075 1.3075 3.6075 1.3075 9 P 0 ;1
L 3.6075 1.3575 3.6075 1.3575 9 P 0 ;1
L 3.6075 1.4075 3.6075 1.4075 9 P 0 ;1
L 3.6075 1.4575 3.6075 1.4575 9 P 0 ;1
L 3.6075 1.5075 3.6075 1.5075 9 P 0 ;1
L 3.6075 1.5575 3.6075 1.5575 9 P 0 ;1
L 3.6075 1.6075 3.6075 1.6075 9 P 0 ;1
L 3.6075 1.6575 3.6075 1.6575 9 P 0 ;1
L 3.6075 1.7075 3.6075 1.7075 9 P 0 ;1
L 3.6075 1.7575 3.6075 1.7575 9 P 0 ;1
L 3.6075 1.8075 3.6075 1.8075 9 P 0 ;1
L 3.6075 1.8575 3.6075 1.8575 9 P 0 ;1
L 3.6075 1.9075 3.6075 1.9075 9 P 0 ;1
L 3.6075 1.9575 3.6075 1.9575 9 P 0 ;1
L 3.6075 2.0075 3.6075 2.0075 9 P 0 ;1
L 3.6075 2.0575 3.6075 2.0575 9 P 0 ;1
L 3.6075 2.1075 3.6075 2.1075 9 P 0 ;1
L 3.6075 2.1575 3.6075 2.1575 9 P 0 ;1
L 3.6075 2.2075 3.6075 2.2075 9 P 0 ;1
L 3.6075 2.2575 3.6075 2.2575 9 P 0 ;1
L 3.6075 2.3075 3.6075 2.3075 9 P 0 ;1
L 3.6075 2.3575 3.6075 2.3575 9 P 0 ;1
L 3.6075 2.4075 3.6075 2.4075 9 P 0 ;1
L 3.6075 2.4575 3.6075 2.4575 9 P 0 ;1
L 3.6075 2.5075 3.6075 2.5075 9 P 0 ;1
L 3.6075 2.5575 3.6075 2.5575 9 P 0 ;1
L 3.6075 2.6075 3.6075 2.6075 9 P 0 ;1
L 3.6075 2.6575 3.6075 2.6575 9 P 0 ;1
L 3.6075 2.7075 3.6075 2.7075 9 P 0 ;1
L 3.6075 2.7575 3.6075 2.7575 9 P 0 ;1
L 3.6075 2.8075 3.6075 2.8075 9 P 0 ;1
L 3.6075 2.8575 3.6075 2.8575 9 P 0 ;1
L 3.6075 2.9075 3.6075 2.9075 9 P 0 ;1
L 3.6075 2.9575 3.6075 2.9575 9 P 0 ;1
L 3.6075 3.0075 3.6075 3.0075 9 P 0 ;1
L 3.6075 3.0575 3.6075 3.0575 9 P 0 ;1
L 3.6075 3.1075 3.6075 3.1075 9 P 0 ;1
L 3.6075 3.1575 3.6075 3.1575 9 P 0 ;1
L 3.6075 3.2075 3.6075 3.2075 9 P 0 ;1
L 3.6075 3.2575 3.6075 3.2575 9 P 0 ;1
L 3.6075 3.3075 3.6075 3.3075 9 P 0 ;1
L 3.6075 3.3575 3.6075 3.3575 9 P 0 ;1
L 3.6075 3.4075 3.6075 3.4075 9 P 0 ;1
L 3.6075 3.4575 3.6075 3.4575 9 P 0 ;1
L 3.6075 3.5075 3.6075 3.5075 9 P 0 ;1
L 3.6075 3.5575 3.6075 3.5575 9 P 0 ;1
L 3.6075 3.6075 3.6075 3.6075 9 P 0 ;1
L 3.6075 3.6575 3.6075 3.6575 9 P 0 ;1
L 3.6075 3.7075 3.6075 3.7075 9 P 0 ;1
L 3.6075 3.7575 3.6075 3.7575 9 P 0 ;1
L 3.6075 3.8075 3.6075 3.8075 9 P 0 ;1
L 3.6075 3.8575 3.6075 3.8575 9 P 0 ;1
L 3.6075 3.9075 3.6075 3.9075 9 P 0 ;1
L 3.6075 3.9575 3.6075 3.9575 9 P 0 ;1
L 3.6075 5.2575 3.6075 5.2575 9 P 0 ;1
L 3.6075 5.3075 3.6075 5.3075 9 P 0 ;1
L 3.6075 5.3575 3.6075 5.3575 9 P 0 ;1
L 3.6075 5.4075 3.6075 5.4075 9 P 0 ;1
L 3.6075 5.4575 3.6075 5.4575 9 P 0 ;1
L 3.6075 5.5075 3.6075 5.5075 9 P 0 ;1
L 3.6075 5.5575 3.6075 5.5575 9 P 0 ;1
L 3.6075 5.6075 3.6075 5.6075 9 P 0 ;1
L 3.6075 5.6575 3.6075 5.6575 9 P 0 ;1
L 3.6075 5.7075 3.6075 5.7075 9 P 0 ;1
L 3.6075 5.8075 3.6075 5.8075 9 P 0 ;1
L 3.6075 5.8575 3.6075 5.8575 9 P 0 ;1
L 3.6075 5.9075 3.6075 5.9075 9 P 0 ;1
L 3.6575 0.1575 3.6575 0.1575 9 P 0 ;1
L 3.6575 0.6075 3.6575 0.6075 9 P 0 ;1
L 3.6575 0.8575 3.6575 0.8575 9 P 0 ;1
L 3.6575 0.9075 3.6575 0.9075 9 P 0 ;1
L 3.6575 0.9575 3.6575 0.9575 9 P 0 ;1
L 3.6575 1.0075 3.6575 1.0075 9 P 0 ;1
L 3.6575 1.0575 3.6575 1.0575 9 P 0 ;1
L 3.6575 1.1075 3.6575 1.1075 9 P 0 ;1
L 3.6575 1.1575 3.6575 1.1575 9 P 0 ;1
L 3.6575 1.2075 3.6575 1.2075 9 P 0 ;1
L 3.6575 1.2575 3.6575 1.2575 9 P 0 ;1
L 3.6575 1.3075 3.6575 1.3075 9 P 0 ;1
L 3.6575 1.3575 3.6575 1.3575 9 P 0 ;1
L 3.6575 1.4075 3.6575 1.4075 9 P 0 ;1
L 3.6575 1.4575 3.6575 1.4575 9 P 0 ;1
L 3.6575 1.5075 3.6575 1.5075 9 P 0 ;1
L 3.6575 1.5575 3.6575 1.5575 9 P 0 ;1
L 3.6575 1.6075 3.6575 1.6075 9 P 0 ;1
L 3.6575 1.6575 3.6575 1.6575 9 P 0 ;1
L 3.6575 1.7075 3.6575 1.7075 9 P 0 ;1
L 3.6575 1.7575 3.6575 1.7575 9 P 0 ;1
L 3.6575 1.8075 3.6575 1.8075 9 P 0 ;1
L 3.6575 1.8575 3.6575 1.8575 9 P 0 ;1
L 3.6575 1.9075 3.6575 1.9075 9 P 0 ;1
L 3.6575 1.9575 3.6575 1.9575 9 P 0 ;1
L 3.6575 2.0075 3.6575 2.0075 9 P 0 ;1
L 3.6575 2.0575 3.6575 2.0575 9 P 0 ;1
L 3.6575 2.1075 3.6575 2.1075 9 P 0 ;1
L 3.6575 2.1575 3.6575 2.1575 9 P 0 ;1
L 3.6575 2.2075 3.6575 2.2075 9 P 0 ;1
L 3.6575 2.2575 3.6575 2.2575 9 P 0 ;1
L 3.6575 2.3075 3.6575 2.3075 9 P 0 ;1
L 3.6575 2.3575 3.6575 2.3575 9 P 0 ;1
L 3.6575 2.4075 3.6575 2.4075 9 P 0 ;1
L 3.6575 2.4575 3.6575 2.4575 9 P 0 ;1
L 3.6575 2.5075 3.6575 2.5075 9 P 0 ;1
L 3.6575 2.5575 3.6575 2.5575 9 P 0 ;1
L 3.6575 2.6075 3.6575 2.6075 9 P 0 ;1
L 3.6575 2.6575 3.6575 2.6575 9 P 0 ;1
L 3.6575 2.7075 3.6575 2.7075 9 P 0 ;1
L 3.6575 2.7575 3.6575 2.7575 9 P 0 ;1
L 3.6575 2.8075 3.6575 2.8075 9 P 0 ;1
L 3.6575 2.8575 3.6575 2.8575 9 P 0 ;1
L 3.6575 2.9075 3.6575 2.9075 9 P 0 ;1
L 3.6575 2.9575 3.6575 2.9575 9 P 0 ;1
L 3.6575 3.0075 3.6575 3.0075 9 P 0 ;1
L 3.6575 3.0575 3.6575 3.0575 9 P 0 ;1
L 3.6575 3.1075 3.6575 3.1075 9 P 0 ;1
L 3.6575 3.1575 3.6575 3.1575 9 P 0 ;1
L 3.6575 3.2075 3.6575 3.2075 9 P 0 ;1
L 3.6575 3.2575 3.6575 3.2575 9 P 0 ;1
L 3.6575 3.3075 3.6575 3.3075 9 P 0 ;1
L 3.6575 3.3575 3.6575 3.3575 9 P 0 ;1
L 3.6575 3.4075 3.6575 3.4075 9 P 0 ;1
L 3.6575 3.4575 3.6575 3.4575 9 P 0 ;1
L 3.6575 3.5075 3.6575 3.5075 9 P 0 ;1
L 3.6575 3.5575 3.6575 3.5575 9 P 0 ;1
L 3.6575 3.6075 3.6575 3.6075 9 P 0 ;1
L 3.6575 3.6575 3.6575 3.6575 9 P 0 ;1
L 3.6575 3.7075 3.6575 3.7075 9 P 0 ;1
L 3.6575 3.7575 3.6575 3.7575 9 P 0 ;1
L 3.6575 3.8075 3.6575 3.8075 9 P 0 ;1
L 3.6575 3.8575 3.6575 3.8575 9 P 0 ;1
L 3.6575 3.9075 3.6575 3.9075 9 P 0 ;1
L 3.6575 3.9575 3.6575 3.9575 9 P 0 ;1
L 3.6575 4.0075 3.6575 4.0075 9 P 0 ;1
L 3.6575 4.0575 3.6575 4.0575 9 P 0 ;1
L 3.6575 4.1075 3.6575 4.1075 9 P 0 ;1
L 3.6575 4.1575 3.6575 4.1575 9 P 0 ;1
L 3.6575 5.2075 3.6575 5.2075 9 P 0 ;1
L 3.6575 5.2575 3.6575 5.2575 9 P 0 ;1
L 3.6575 5.3075 3.6575 5.3075 9 P 0 ;1
L 3.6575 5.3575 3.6575 5.3575 9 P 0 ;1
L 3.6575 5.4075 3.6575 5.4075 9 P 0 ;1
L 3.6575 5.4575 3.6575 5.4575 9 P 0 ;1
L 3.6575 5.5075 3.6575 5.5075 9 P 0 ;1
L 3.6575 5.5575 3.6575 5.5575 9 P 0 ;1
L 3.6575 5.6075 3.6575 5.6075 9 P 0 ;1
L 3.6575 5.6575 3.6575 5.6575 9 P 0 ;1
L 3.6575 5.8575 3.6575 5.8575 9 P 0 ;1
L 3.6575 5.9075 3.6575 5.9075 9 P 0 ;1
L 3.7075 0.1575 3.7075 0.1575 9 P 0 ;1
L 3.7075 0.5575 3.7075 0.5575 9 P 0 ;1
L 3.7075 0.6075 3.7075 0.6075 9 P 0 ;1
L 3.7075 0.8575 3.7075 0.8575 9 P 0 ;1
L 3.7075 0.9075 3.7075 0.9075 9 P 0 ;1
L 3.7075 0.9575 3.7075 0.9575 9 P 0 ;1
L 3.7075 1.0075 3.7075 1.0075 9 P 0 ;1
L 3.7075 1.0575 3.7075 1.0575 9 P 0 ;1
L 3.7075 1.1075 3.7075 1.1075 9 P 0 ;1
L 3.7075 1.1575 3.7075 1.1575 9 P 0 ;1
L 3.7075 1.2075 3.7075 1.2075 9 P 0 ;1
L 3.7075 1.2575 3.7075 1.2575 9 P 0 ;1
L 3.7075 1.3075 3.7075 1.3075 9 P 0 ;1
L 3.7075 1.3575 3.7075 1.3575 9 P 0 ;1
L 3.7075 1.4075 3.7075 1.4075 9 P 0 ;1
L 3.7075 1.4575 3.7075 1.4575 9 P 0 ;1
L 3.7075 1.5075 3.7075 1.5075 9 P 0 ;1
L 3.7075 1.5575 3.7075 1.5575 9 P 0 ;1
L 3.7075 1.6075 3.7075 1.6075 9 P 0 ;1
L 3.7075 1.6575 3.7075 1.6575 9 P 0 ;1
L 3.7075 1.7075 3.7075 1.7075 9 P 0 ;1
L 3.7075 1.7575 3.7075 1.7575 9 P 0 ;1
L 3.7075 1.8075 3.7075 1.8075 9 P 0 ;1
L 3.7075 1.8575 3.7075 1.8575 9 P 0 ;1
L 3.7075 1.9075 3.7075 1.9075 9 P 0 ;1
L 3.7075 1.9575 3.7075 1.9575 9 P 0 ;1
L 3.7075 2.0075 3.7075 2.0075 9 P 0 ;1
L 3.7075 2.0575 3.7075 2.0575 9 P 0 ;1
L 3.7075 2.1075 3.7075 2.1075 9 P 0 ;1
L 3.7075 2.1575 3.7075 2.1575 9 P 0 ;1
L 3.7075 2.2075 3.7075 2.2075 9 P 0 ;1
L 3.7075 2.2575 3.7075 2.2575 9 P 0 ;1
L 3.7075 2.3075 3.7075 2.3075 9 P 0 ;1
L 3.7075 2.3575 3.7075 2.3575 9 P 0 ;1
L 3.7075 2.4075 3.7075 2.4075 9 P 0 ;1
L 3.7075 2.4575 3.7075 2.4575 9 P 0 ;1
L 3.7075 2.5075 3.7075 2.5075 9 P 0 ;1
L 3.7075 2.5575 3.7075 2.5575 9 P 0 ;1
L 3.7075 2.6075 3.7075 2.6075 9 P 0 ;1
L 3.7075 2.6575 3.7075 2.6575 9 P 0 ;1
L 3.7075 2.7075 3.7075 2.7075 9 P 0 ;1
L 3.7075 2.7575 3.7075 2.7575 9 P 0 ;1
L 3.7075 2.8075 3.7075 2.8075 9 P 0 ;1
L 3.7075 2.8575 3.7075 2.8575 9 P 0 ;1
L 3.7075 2.9075 3.7075 2.9075 9 P 0 ;1
L 3.7075 2.9575 3.7075 2.9575 9 P 0 ;1
L 3.7075 3.0075 3.7075 3.0075 9 P 0 ;1
L 3.7075 3.0575 3.7075 3.0575 9 P 0 ;1
L 3.7075 3.1075 3.7075 3.1075 9 P 0 ;1
L 3.7075 3.1575 3.7075 3.1575 9 P 0 ;1
L 3.7075 3.2075 3.7075 3.2075 9 P 0 ;1
L 3.7075 3.2575 3.7075 3.2575 9 P 0 ;1
L 3.7075 3.3075 3.7075 3.3075 9 P 0 ;1
L 3.7075 3.3575 3.7075 3.3575 9 P 0 ;1
L 3.7075 3.4075 3.7075 3.4075 9 P 0 ;1
L 3.7075 3.4575 3.7075 3.4575 9 P 0 ;1
L 3.7075 3.5075 3.7075 3.5075 9 P 0 ;1
L 3.7075 3.5575 3.7075 3.5575 9 P 0 ;1
L 3.7075 3.6075 3.7075 3.6075 9 P 0 ;1
L 3.7075 3.6575 3.7075 3.6575 9 P 0 ;1
L 3.7075 3.7075 3.7075 3.7075 9 P 0 ;1
L 3.7075 3.7575 3.7075 3.7575 9 P 0 ;1
L 3.7075 3.8075 3.7075 3.8075 9 P 0 ;1
L 3.7075 3.8575 3.7075 3.8575 9 P 0 ;1
L 3.7075 3.9075 3.7075 3.9075 9 P 0 ;1
L 3.7075 3.9575 3.7075 3.9575 9 P 0 ;1
L 3.7075 4.0075 3.7075 4.0075 9 P 0 ;1
L 3.7075 4.0575 3.7075 4.0575 9 P 0 ;1
L 3.7075 4.1075 3.7075 4.1075 9 P 0 ;1
L 3.7075 4.1575 3.7075 4.1575 9 P 0 ;1
L 3.7075 4.2075 3.7075 4.2075 9 P 0 ;1
L 3.7075 4.2575 3.7075 4.2575 9 P 0 ;1
L 3.7075 4.3075 3.7075 4.3075 9 P 0 ;1
L 3.7075 4.3575 3.7075 4.3575 9 P 0 ;1
L 3.7075 5.1575 3.7075 5.1575 9 P 0 ;1
L 3.7075 5.2075 3.7075 5.2075 9 P 0 ;1
L 3.7075 5.3575 3.7075 5.3575 9 P 0 ;1
L 3.7075 5.4075 3.7075 5.4075 9 P 0 ;1
L 3.7075 5.4575 3.7075 5.4575 9 P 0 ;1
L 3.7075 5.5075 3.7075 5.5075 9 P 0 ;1
L 3.7075 5.5575 3.7075 5.5575 9 P 0 ;1
L 3.7075 5.6075 3.7075 5.6075 9 P 0 ;1
L 3.7075 5.6575 3.7075 5.6575 9 P 0 ;1
L 3.7075 5.8575 3.7075 5.8575 9 P 0 ;1
L 3.7075 5.9075 3.7075 5.9075 9 P 0 ;1
L 3.7575 0.1575 3.7575 0.1575 9 P 0 ;1
L 3.7575 0.4575 3.7575 0.4575 9 P 0 ;1
L 3.7575 0.5075 3.7575 0.5075 9 P 0 ;1
L 3.7575 0.5575 3.7575 0.5575 9 P 0 ;1
L 3.7575 0.6075 3.7575 0.6075 9 P 0 ;1
L 3.7575 0.8575 3.7575 0.8575 9 P 0 ;1
L 3.7575 0.9075 3.7575 0.9075 9 P 0 ;1
L 3.7575 0.9575 3.7575 0.9575 9 P 0 ;1
L 3.7575 1.0075 3.7575 1.0075 9 P 0 ;1
L 3.7575 1.0575 3.7575 1.0575 9 P 0 ;1
L 3.7575 1.1075 3.7575 1.1075 9 P 0 ;1
L 3.7575 1.1575 3.7575 1.1575 9 P 0 ;1
L 3.7575 1.2075 3.7575 1.2075 9 P 0 ;1
L 3.7575 1.2575 3.7575 1.2575 9 P 0 ;1
L 3.7575 1.3075 3.7575 1.3075 9 P 0 ;1
L 3.7575 1.3575 3.7575 1.3575 9 P 0 ;1
L 3.7575 1.4075 3.7575 1.4075 9 P 0 ;1
L 3.7575 1.4575 3.7575 1.4575 9 P 0 ;1
L 3.7575 1.5075 3.7575 1.5075 9 P 0 ;1
L 3.7575 1.5575 3.7575 1.5575 9 P 0 ;1
L 3.7575 1.6075 3.7575 1.6075 9 P 0 ;1
L 3.7575 1.6575 3.7575 1.6575 9 P 0 ;1
L 3.7575 1.7075 3.7575 1.7075 9 P 0 ;1
L 3.7575 1.7575 3.7575 1.7575 9 P 0 ;1
L 3.7575 1.8075 3.7575 1.8075 9 P 0 ;1
L 3.7575 1.8575 3.7575 1.8575 9 P 0 ;1
L 3.7575 1.9075 3.7575 1.9075 9 P 0 ;1
L 3.7575 1.9575 3.7575 1.9575 9 P 0 ;1
L 3.7575 2.0075 3.7575 2.0075 9 P 0 ;1
L 3.7575 2.0575 3.7575 2.0575 9 P 0 ;1
L 3.7575 2.1075 3.7575 2.1075 9 P 0 ;1
L 3.7575 2.1575 3.7575 2.1575 9 P 0 ;1
L 3.7575 2.2075 3.7575 2.2075 9 P 0 ;1
L 3.7575 2.2575 3.7575 2.2575 9 P 0 ;1
L 3.7575 2.3075 3.7575 2.3075 9 P 0 ;1
L 3.7575 2.3575 3.7575 2.3575 9 P 0 ;1
L 3.7575 2.4075 3.7575 2.4075 9 P 0 ;1
L 3.7575 2.4575 3.7575 2.4575 9 P 0 ;1
L 3.7575 2.5075 3.7575 2.5075 9 P 0 ;1
L 3.7575 2.5575 3.7575 2.5575 9 P 0 ;1
L 3.7575 2.6075 3.7575 2.6075 9 P 0 ;1
L 3.7575 2.6575 3.7575 2.6575 9 P 0 ;1
L 3.7575 2.7075 3.7575 2.7075 9 P 0 ;1
L 3.7575 2.7575 3.7575 2.7575 9 P 0 ;1
L 3.7575 2.8075 3.7575 2.8075 9 P 0 ;1
L 3.7575 2.8575 3.7575 2.8575 9 P 0 ;1
L 3.7575 2.9075 3.7575 2.9075 9 P 0 ;1
L 3.7575 2.9575 3.7575 2.9575 9 P 0 ;1
L 3.7575 3.0075 3.7575 3.0075 9 P 0 ;1
L 3.7575 3.0575 3.7575 3.0575 9 P 0 ;1
L 3.7575 3.1075 3.7575 3.1075 9 P 0 ;1
L 3.7575 3.1575 3.7575 3.1575 9 P 0 ;1
L 3.7575 3.2075 3.7575 3.2075 9 P 0 ;1
L 3.7575 3.2575 3.7575 3.2575 9 P 0 ;1
L 3.7575 3.3075 3.7575 3.3075 9 P 0 ;1
L 3.7575 3.3575 3.7575 3.3575 9 P 0 ;1
L 3.7575 3.4075 3.7575 3.4075 9 P 0 ;1
L 3.7575 3.4575 3.7575 3.4575 9 P 0 ;1
L 3.7575 3.5075 3.7575 3.5075 9 P 0 ;1
L 3.7575 3.5575 3.7575 3.5575 9 P 0 ;1
L 3.7575 3.6075 3.7575 3.6075 9 P 0 ;1
L 3.7575 3.6575 3.7575 3.6575 9 P 0 ;1
L 3.7575 3.7075 3.7575 3.7075 9 P 0 ;1
L 3.7575 3.7575 3.7575 3.7575 9 P 0 ;1
L 3.7575 3.8075 3.7575 3.8075 9 P 0 ;1
L 3.7575 3.8575 3.7575 3.8575 9 P 0 ;1
L 3.7575 3.9075 3.7575 3.9075 9 P 0 ;1
L 3.7575 3.9575 3.7575 3.9575 9 P 0 ;1
L 3.7575 4.0075 3.7575 4.0075 9 P 0 ;1
L 3.7575 4.0575 3.7575 4.0575 9 P 0 ;1
L 3.7575 4.1075 3.7575 4.1075 9 P 0 ;1
L 3.7575 4.1575 3.7575 4.1575 9 P 0 ;1
L 3.7575 4.2075 3.7575 4.2075 9 P 0 ;1
L 3.7575 4.2575 3.7575 4.2575 9 P 0 ;1
L 3.7575 4.3075 3.7575 4.3075 9 P 0 ;1
L 3.7575 4.3575 3.7575 4.3575 9 P 0 ;1
L 3.7575 4.9575 3.7575 4.9575 9 P 0 ;1
L 3.7575 5.1575 3.7575 5.1575 9 P 0 ;1
L 3.7575 5.2075 3.7575 5.2075 9 P 0 ;1
L 3.7575 5.4075 3.7575 5.4075 9 P 0 ;1
L 3.7575 5.4575 3.7575 5.4575 9 P 0 ;1
L 3.7575 5.5075 3.7575 5.5075 9 P 0 ;1
L 3.7575 5.5575 3.7575 5.5575 9 P 0 ;1
L 3.7575 5.6075 3.7575 5.6075 9 P 0 ;1
L 3.7575 5.6575 3.7575 5.6575 9 P 0 ;1
L 3.7575 5.7075 3.7575 5.7075 9 P 0 ;1
L 3.7575 5.9075 3.7575 5.9075 9 P 0 ;1
L 3.8075 0.1575 3.8075 0.1575 9 P 0 ;1
L 3.8075 0.4575 3.8075 0.4575 9 P 0 ;1
L 3.8075 0.5075 3.8075 0.5075 9 P 0 ;1
L 3.8075 0.5575 3.8075 0.5575 9 P 0 ;1
L 3.8075 0.6075 3.8075 0.6075 9 P 0 ;1
L 3.8075 0.8575 3.8075 0.8575 9 P 0 ;1
L 3.8075 0.9075 3.8075 0.9075 9 P 0 ;1
L 3.8075 0.9575 3.8075 0.9575 9 P 0 ;1
L 3.8075 1.0075 3.8075 1.0075 9 P 0 ;1
L 3.8075 1.0575 3.8075 1.0575 9 P 0 ;1
L 3.8075 1.1075 3.8075 1.1075 9 P 0 ;1
L 3.8075 1.1575 3.8075 1.1575 9 P 0 ;1
L 3.8075 1.2075 3.8075 1.2075 9 P 0 ;1
L 3.8075 1.2575 3.8075 1.2575 9 P 0 ;1
L 3.8075 1.3075 3.8075 1.3075 9 P 0 ;1
L 3.8075 1.3575 3.8075 1.3575 9 P 0 ;1
L 3.8075 1.4075 3.8075 1.4075 9 P 0 ;1
L 3.8075 1.4575 3.8075 1.4575 9 P 0 ;1
L 3.8075 1.5075 3.8075 1.5075 9 P 0 ;1
L 3.8075 1.5575 3.8075 1.5575 9 P 0 ;1
L 3.8075 1.6075 3.8075 1.6075 9 P 0 ;1
L 3.8075 1.6575 3.8075 1.6575 9 P 0 ;1
L 3.8075 1.7075 3.8075 1.7075 9 P 0 ;1
L 3.8075 1.7575 3.8075 1.7575 9 P 0 ;1
L 3.8075 1.8075 3.8075 1.8075 9 P 0 ;1
L 3.8075 1.8575 3.8075 1.8575 9 P 0 ;1
L 3.8075 1.9075 3.8075 1.9075 9 P 0 ;1
L 3.8075 1.9575 3.8075 1.9575 9 P 0 ;1
L 3.8075 2.0075 3.8075 2.0075 9 P 0 ;1
L 3.8075 2.0575 3.8075 2.0575 9 P 0 ;1
L 3.8075 2.1075 3.8075 2.1075 9 P 0 ;1
L 3.8075 2.1575 3.8075 2.1575 9 P 0 ;1
L 3.8075 2.2075 3.8075 2.2075 9 P 0 ;1
L 3.8075 2.2575 3.8075 2.2575 9 P 0 ;1
L 3.8075 2.3075 3.8075 2.3075 9 P 0 ;1
L 3.8075 2.3575 3.8075 2.3575 9 P 0 ;1
L 3.8075 2.4075 3.8075 2.4075 9 P 0 ;1
L 3.8075 2.4575 3.8075 2.4575 9 P 0 ;1
L 3.8075 2.5075 3.8075 2.5075 9 P 0 ;1
L 3.8075 2.5575 3.8075 2.5575 9 P 0 ;1
L 3.8075 2.7075 3.8075 2.7075 9 P 0 ;1
L 3.8075 2.7575 3.8075 2.7575 9 P 0 ;1
L 3.8075 2.8075 3.8075 2.8075 9 P 0 ;1
L 3.8075 2.8575 3.8075 2.8575 9 P 0 ;1
L 3.8075 2.9075 3.8075 2.9075 9 P 0 ;1
L 3.8075 2.9575 3.8075 2.9575 9 P 0 ;1
L 3.8075 3.0075 3.8075 3.0075 9 P 0 ;1
L 3.8075 3.0575 3.8075 3.0575 9 P 0 ;1
L 3.8075 3.1075 3.8075 3.1075 9 P 0 ;1
L 3.8075 3.1575 3.8075 3.1575 9 P 0 ;1
L 3.8075 3.2075 3.8075 3.2075 9 P 0 ;1
L 3.8075 3.2575 3.8075 3.2575 9 P 0 ;1
L 3.8075 3.3075 3.8075 3.3075 9 P 0 ;1
L 3.8075 3.3575 3.8075 3.3575 9 P 0 ;1
L 3.8075 3.4075 3.8075 3.4075 9 P 0 ;1
L 3.8075 3.4575 3.8075 3.4575 9 P 0 ;1
L 3.8075 3.5075 3.8075 3.5075 9 P 0 ;1
L 3.8075 3.5575 3.8075 3.5575 9 P 0 ;1
L 3.8075 3.6075 3.8075 3.6075 9 P 0 ;1
L 3.8075 3.6575 3.8075 3.6575 9 P 0 ;1
L 3.8075 3.7075 3.8075 3.7075 9 P 0 ;1
L 3.8075 3.7575 3.8075 3.7575 9 P 0 ;1
L 3.8075 3.8075 3.8075 3.8075 9 P 0 ;1
L 3.8075 3.8575 3.8075 3.8575 9 P 0 ;1
L 3.8075 3.9075 3.8075 3.9075 9 P 0 ;1
L 3.8075 3.9575 3.8075 3.9575 9 P 0 ;1
L 3.8075 4.0075 3.8075 4.0075 9 P 0 ;1
L 3.8075 4.0575 3.8075 4.0575 9 P 0 ;1
L 3.8075 4.1075 3.8075 4.1075 9 P 0 ;1
L 3.8075 4.1575 3.8075 4.1575 9 P 0 ;1
L 3.8075 4.2075 3.8075 4.2075 9 P 0 ;1
L 3.8075 4.2575 3.8075 4.2575 9 P 0 ;1
L 3.8075 4.3075 3.8075 4.3075 9 P 0 ;1
L 3.8075 4.3575 3.8075 4.3575 9 P 0 ;1
L 3.8075 4.9575 3.8075 4.9575 9 P 0 ;1
L 3.8075 5.0075 3.8075 5.0075 9 P 0 ;1
L 3.8075 5.2075 3.8075 5.2075 9 P 0 ;1
L 3.8075 5.4075 3.8075 5.4075 9 P 0 ;1
L 3.8075 5.4575 3.8075 5.4575 9 P 0 ;1
L 3.8075 5.5075 3.8075 5.5075 9 P 0 ;1
L 3.8075 5.5575 3.8075 5.5575 9 P 0 ;1
L 3.8075 5.6075 3.8075 5.6075 9 P 0 ;1
L 3.8075 5.6575 3.8075 5.6575 9 P 0 ;1
L 3.8075 5.7075 3.8075 5.7075 9 P 0 ;1
L 3.8075 5.9075 3.8075 5.9075 9 P 0 ;1
L 3.8575 0.1575 3.8575 0.1575 9 P 0 ;1
L 3.8575 0.2075 3.8575 0.2075 9 P 0 ;1
L 3.8575 0.2575 3.8575 0.2575 9 P 0 ;1
L 3.8575 0.3075 3.8575 0.3075 9 P 0 ;1
L 3.8575 0.3575 3.8575 0.3575 9 P 0 ;1
L 3.8575 0.4075 3.8575 0.4075 9 P 0 ;1
L 3.8575 0.4575 3.8575 0.4575 9 P 0 ;1
L 3.8575 0.5075 3.8575 0.5075 9 P 0 ;1
L 3.8575 0.5575 3.8575 0.5575 9 P 0 ;1
L 3.8575 0.6075 3.8575 0.6075 9 P 0 ;1
L 3.8575 0.8575 3.8575 0.8575 9 P 0 ;1
L 3.8575 0.9075 3.8575 0.9075 9 P 0 ;1
L 3.8575 0.9575 3.8575 0.9575 9 P 0 ;1
L 3.8575 1.0075 3.8575 1.0075 9 P 0 ;1
L 3.8575 1.0575 3.8575 1.0575 9 P 0 ;1
L 3.8575 1.1075 3.8575 1.1075 9 P 0 ;1
L 3.8575 1.1575 3.8575 1.1575 9 P 0 ;1
L 3.8575 1.2075 3.8575 1.2075 9 P 0 ;1
L 3.8575 1.2575 3.8575 1.2575 9 P 0 ;1
L 3.8575 1.3075 3.8575 1.3075 9 P 0 ;1
L 3.8575 1.3575 3.8575 1.3575 9 P 0 ;1
L 3.8575 1.4075 3.8575 1.4075 9 P 0 ;1
L 3.8575 1.4575 3.8575 1.4575 9 P 0 ;1
L 3.8575 1.5075 3.8575 1.5075 9 P 0 ;1
L 3.8575 1.5575 3.8575 1.5575 9 P 0 ;1
L 3.8575 1.6075 3.8575 1.6075 9 P 0 ;1
L 3.8575 1.6575 3.8575 1.6575 9 P 0 ;1
L 3.8575 1.7075 3.8575 1.7075 9 P 0 ;1
L 3.8575 1.7575 3.8575 1.7575 9 P 0 ;1
L 3.8575 1.8075 3.8575 1.8075 9 P 0 ;1
L 3.8575 4.9575 3.8575 4.9575 9 P 0 ;1
L 3.8575 5.0075 3.8575 5.0075 9 P 0 ;1
L 3.8575 5.2075 3.8575 5.2075 9 P 0 ;1
L 3.8575 5.2575 3.8575 5.2575 9 P 0 ;1
L 3.8575 5.3075 3.8575 5.3075 9 P 0 ;1
L 3.8575 5.6075 3.8575 5.6075 9 P 0 ;1
L 3.8575 5.6575 3.8575 5.6575 9 P 0 ;1
L 3.8575 5.7075 3.8575 5.7075 9 P 0 ;1
L 3.8575 5.9075 3.8575 5.9075 9 P 0 ;1
L 3.9075 0.1575 3.9075 0.1575 9 P 0 ;1
L 3.9075 0.2075 3.9075 0.2075 9 P 0 ;1
L 3.9075 0.2575 3.9075 0.2575 9 P 0 ;1
L 3.9075 0.3075 3.9075 0.3075 9 P 0 ;1
L 3.9075 0.3575 3.9075 0.3575 9 P 0 ;1
L 3.9075 0.4075 3.9075 0.4075 9 P 0 ;1
L 3.9075 0.4575 3.9075 0.4575 9 P 0 ;1
L 3.9075 0.5075 3.9075 0.5075 9 P 0 ;1
L 3.9075 0.5575 3.9075 0.5575 9 P 0 ;1
L 3.9075 0.6075 3.9075 0.6075 9 P 0 ;1
L 3.9075 0.8575 3.9075 0.8575 9 P 0 ;1
L 3.9075 0.9075 3.9075 0.9075 9 P 0 ;1
L 3.9075 0.9575 3.9075 0.9575 9 P 0 ;1
L 3.9075 1.0075 3.9075 1.0075 9 P 0 ;1
L 3.9075 1.0575 3.9075 1.0575 9 P 0 ;1
L 3.9075 1.1075 3.9075 1.1075 9 P 0 ;1
L 3.9075 1.1575 3.9075 1.1575 9 P 0 ;1
L 3.9075 1.2075 3.9075 1.2075 9 P 0 ;1
L 3.9075 1.2575 3.9075 1.2575 9 P 0 ;1
L 3.9075 1.3075 3.9075 1.3075 9 P 0 ;1
L 3.9075 1.3575 3.9075 1.3575 9 P 0 ;1
L 3.9075 1.4075 3.9075 1.4075 9 P 0 ;1
L 3.9075 1.4575 3.9075 1.4575 9 P 0 ;1
L 3.9075 1.5075 3.9075 1.5075 9 P 0 ;1
L 3.9075 1.5575 3.9075 1.5575 9 P 0 ;1
L 3.9075 1.6075 3.9075 1.6075 9 P 0 ;1
L 3.9075 1.6575 3.9075 1.6575 9 P 0 ;1
L 3.9075 1.7075 3.9075 1.7075 9 P 0 ;1
L 3.9075 1.7575 3.9075 1.7575 9 P 0 ;1
L 3.9075 5.0075 3.9075 5.0075 9 P 0 ;1
L 3.9075 5.2075 3.9075 5.2075 9 P 0 ;1
L 3.9075 5.2575 3.9075 5.2575 9 P 0 ;1
L 3.9075 5.6075 3.9075 5.6075 9 P 0 ;1
L 3.9075 5.6575 3.9075 5.6575 9 P 0 ;1
L 3.9075 5.7075 3.9075 5.7075 9 P 0 ;1
L 3.9075 5.7575 3.9075 5.7575 9 P 0 ;1
L 3.9075 5.8075 3.9075 5.8075 9 P 0 ;1
L 3.9075 5.8575 3.9075 5.8575 9 P 0 ;1
L 3.9075 5.9075 3.9075 5.9075 9 P 0 ;1
L 3.9575 0.1575 3.9575 0.1575 9 P 0 ;1
L 3.9575 0.2075 3.9575 0.2075 9 P 0 ;1
L 3.9575 0.2575 3.9575 0.2575 9 P 0 ;1
L 3.9575 0.3075 3.9575 0.3075 9 P 0 ;1
L 3.9575 0.3575 3.9575 0.3575 9 P 0 ;1
L 3.9575 0.4075 3.9575 0.4075 9 P 0 ;1
L 3.9575 0.4575 3.9575 0.4575 9 P 0 ;1
L 3.9575 0.5075 3.9575 0.5075 9 P 0 ;1
L 3.9575 0.5575 3.9575 0.5575 9 P 0 ;1
L 3.9575 0.6075 3.9575 0.6075 9 P 0 ;1
L 3.9575 0.6575 3.9575 0.6575 9 P 0 ;1
L 3.9575 0.7075 3.9575 0.7075 9 P 0 ;1
L 3.9575 0.7575 3.9575 0.7575 9 P 0 ;1
L 3.9575 0.8075 3.9575 0.8075 9 P 0 ;1
L 3.9575 0.8575 3.9575 0.8575 9 P 0 ;1
L 3.9575 0.9075 3.9575 0.9075 9 P 0 ;1
L 3.9575 0.9575 3.9575 0.9575 9 P 0 ;1
L 3.9575 1.0075 3.9575 1.0075 9 P 0 ;1
L 3.9575 1.0575 3.9575 1.0575 9 P 0 ;1
L 3.9575 1.1075 3.9575 1.1075 9 P 0 ;1
L 3.9575 1.1575 3.9575 1.1575 9 P 0 ;1
L 3.9575 1.2075 3.9575 1.2075 9 P 0 ;1
L 3.9575 1.2575 3.9575 1.2575 9 P 0 ;1
L 3.9575 1.3075 3.9575 1.3075 9 P 0 ;1
L 3.9575 1.3575 3.9575 1.3575 9 P 0 ;1
L 3.9575 1.4075 3.9575 1.4075 9 P 0 ;1
L 3.9575 1.4575 3.9575 1.4575 9 P 0 ;1
L 3.9575 1.5075 3.9575 1.5075 9 P 0 ;1
L 3.9575 1.5575 3.9575 1.5575 9 P 0 ;1
L 3.9575 1.6075 3.9575 1.6075 9 P 0 ;1
L 3.9575 1.6575 3.9575 1.6575 9 P 0 ;1
L 3.9575 1.7075 3.9575 1.7075 9 P 0 ;1
L 3.9575 5.6075 3.9575 5.6075 9 P 0 ;1
L 3.9575 5.6575 3.9575 5.6575 9 P 0 ;1
L 3.9575 5.7075 3.9575 5.7075 9 P 0 ;1
L 3.9575 5.7575 3.9575 5.7575 9 P 0 ;1
L 3.9575 5.8075 3.9575 5.8075 9 P 0 ;1
L 3.9575 5.8575 3.9575 5.8575 9 P 0 ;1
L 3.9575 5.9075 3.9575 5.9075 9 P 0 ;1
L 4.0075 0.1575 4.0075 0.1575 9 P 0 ;1
L 4.0075 0.2075 4.0075 0.2075 9 P 0 ;1
L 4.0075 0.2575 4.0075 0.2575 9 P 0 ;1
L 4.0075 0.3075 4.0075 0.3075 9 P 0 ;1
L 4.0075 0.3575 4.0075 0.3575 9 P 0 ;1
L 4.0075 0.4075 4.0075 0.4075 9 P 0 ;1
L 4.0075 0.4575 4.0075 0.4575 9 P 0 ;1
L 4.0075 0.5075 4.0075 0.5075 9 P 0 ;1
L 4.0075 0.5575 4.0075 0.5575 9 P 0 ;1
L 4.0075 0.6075 4.0075 0.6075 9 P 0 ;1
L 4.0075 0.6575 4.0075 0.6575 9 P 0 ;1
L 4.0075 0.7075 4.0075 0.7075 9 P 0 ;1
L 4.0075 0.7575 4.0075 0.7575 9 P 0 ;1
L 4.0075 0.8075 4.0075 0.8075 9 P 0 ;1
L 4.0075 0.8575 4.0075 0.8575 9 P 0 ;1
L 4.0075 0.9075 4.0075 0.9075 9 P 0 ;1
L 4.0075 0.9575 4.0075 0.9575 9 P 0 ;1
L 4.0075 1.0075 4.0075 1.0075 9 P 0 ;1
L 4.0075 1.0575 4.0075 1.0575 9 P 0 ;1
L 4.0075 1.1075 4.0075 1.1075 9 P 0 ;1
L 4.0075 1.1575 4.0075 1.1575 9 P 0 ;1
L 4.0075 1.2075 4.0075 1.2075 9 P 0 ;1
L 4.0075 1.2575 4.0075 1.2575 9 P 0 ;1
L 4.0075 1.3075 4.0075 1.3075 9 P 0 ;1
L 4.0075 1.3575 4.0075 1.3575 9 P 0 ;1
L 4.0075 1.4075 4.0075 1.4075 9 P 0 ;1
L 4.0075 1.4575 4.0075 1.4575 9 P 0 ;1
L 4.0075 1.5075 4.0075 1.5075 9 P 0 ;1
L 4.0075 1.5575 4.0075 1.5575 9 P 0 ;1
L 4.0075 1.6075 4.0075 1.6075 9 P 0 ;1
L 4.0075 1.6575 4.0075 1.6575 9 P 0 ;1
L 4.0075 5.5075 4.0075 5.5075 9 P 0 ;1
L 4.0075 5.5575 4.0075 5.5575 9 P 0 ;1
L 4.0075 5.6075 4.0075 5.6075 9 P 0 ;1
L 4.0075 5.6575 4.0075 5.6575 9 P 0 ;1
L 4.0075 5.7075 4.0075 5.7075 9 P 0 ;1
L 4.0075 5.7575 4.0075 5.7575 9 P 0 ;1
L 4.0075 5.8075 4.0075 5.8075 9 P 0 ;1
L 4.0075 5.8575 4.0075 5.8575 9 P 0 ;1
L 4.0075 5.9075 4.0075 5.9075 9 P 0 ;1
L 4.0575 0.1575 4.0575 0.1575 9 P 0 ;1
L 4.0575 0.2075 4.0575 0.2075 9 P 0 ;1
L 4.0575 0.2575 4.0575 0.2575 9 P 0 ;1
L 4.0575 0.3075 4.0575 0.3075 9 P 0 ;1
L 4.0575 0.3575 4.0575 0.3575 9 P 0 ;1
L 4.0575 0.4075 4.0575 0.4075 9 P 0 ;1
L 4.0575 0.4575 4.0575 0.4575 9 P 0 ;1
L 4.0575 0.5075 4.0575 0.5075 9 P 0 ;1
L 4.0575 0.5575 4.0575 0.5575 9 P 0 ;1
L 4.0575 0.6075 4.0575 0.6075 9 P 0 ;1
L 4.0575 0.6575 4.0575 0.6575 9 P 0 ;1
L 4.0575 0.7075 4.0575 0.7075 9 P 0 ;1
L 4.0575 0.7575 4.0575 0.7575 9 P 0 ;1
L 4.0575 0.8075 4.0575 0.8075 9 P 0 ;1
L 4.0575 0.8575 4.0575 0.8575 9 P 0 ;1
L 4.0575 0.9075 4.0575 0.9075 9 P 0 ;1
L 4.0575 0.9575 4.0575 0.9575 9 P 0 ;1
L 4.0575 1.0075 4.0575 1.0075 9 P 0 ;1
L 4.0575 1.0575 4.0575 1.0575 9 P 0 ;1
L 4.0575 1.1075 4.0575 1.1075 9 P 0 ;1
L 4.0575 1.1575 4.0575 1.1575 9 P 0 ;1
L 4.0575 1.2075 4.0575 1.2075 9 P 0 ;1
L 4.0575 1.2575 4.0575 1.2575 9 P 0 ;1
L 4.0575 1.3075 4.0575 1.3075 9 P 0 ;1
L 4.0575 1.3575 4.0575 1.3575 9 P 0 ;1
L 4.0575 1.4075 4.0575 1.4075 9 P 0 ;1
L 4.0575 1.4575 4.0575 1.4575 9 P 0 ;1
L 4.0575 1.5075 4.0575 1.5075 9 P 0 ;1
L 4.0575 1.5575 4.0575 1.5575 9 P 0 ;1
L 4.0575 1.6075 4.0575 1.6075 9 P 0 ;1
L 4.0575 5.5075 4.0575 5.5075 9 P 0 ;1
L 4.0575 5.5575 4.0575 5.5575 9 P 0 ;1
L 4.0575 5.6075 4.0575 5.6075 9 P 0 ;1
L 4.0575 5.6575 4.0575 5.6575 9 P 0 ;1
L 4.0575 5.7075 4.0575 5.7075 9 P 0 ;1
L 4.0575 5.7575 4.0575 5.7575 9 P 0 ;1
L 4.0575 5.8075 4.0575 5.8075 9 P 0 ;1
L 4.0575 5.8575 4.0575 5.8575 9 P 0 ;1
L 4.0575 5.9075 4.0575 5.9075 9 P 0 ;1
L 4.1075 0.1575 4.1075 0.1575 9 P 0 ;1
L 4.1075 0.2075 4.1075 0.2075 9 P 0 ;1
L 4.1075 0.2575 4.1075 0.2575 9 P 0 ;1
L 4.1075 0.3075 4.1075 0.3075 9 P 0 ;1
L 4.1075 0.3575 4.1075 0.3575 9 P 0 ;1
L 4.1075 0.4075 4.1075 0.4075 9 P 0 ;1
L 4.1075 0.4575 4.1075 0.4575 9 P 0 ;1
L 4.1075 0.5075 4.1075 0.5075 9 P 0 ;1
L 4.1075 0.5575 4.1075 0.5575 9 P 0 ;1
L 4.1075 0.6075 4.1075 0.6075 9 P 0 ;1
L 4.1075 0.6575 4.1075 0.6575 9 P 0 ;1
L 4.1075 0.7075 4.1075 0.7075 9 P 0 ;1
L 4.1075 0.7575 4.1075 0.7575 9 P 0 ;1
L 4.1075 0.8075 4.1075 0.8075 9 P 0 ;1
L 4.1075 0.8575 4.1075 0.8575 9 P 0 ;1
L 4.1075 0.9075 4.1075 0.9075 9 P 0 ;1
L 4.1075 0.9575 4.1075 0.9575 9 P 0 ;1
L 4.1075 1.0075 4.1075 1.0075 9 P 0 ;1
L 4.1075 1.0575 4.1075 1.0575 9 P 0 ;1
L 4.1075 1.1075 4.1075 1.1075 9 P 0 ;1
L 4.1075 1.1575 4.1075 1.1575 9 P 0 ;1
L 4.1075 1.2075 4.1075 1.2075 9 P 0 ;1
L 4.1075 1.2575 4.1075 1.2575 9 P 0 ;1
L 4.1075 1.3075 4.1075 1.3075 9 P 0 ;1
L 4.1075 1.3575 4.1075 1.3575 9 P 0 ;1
L 4.1075 1.4075 4.1075 1.4075 9 P 0 ;1
L 4.1075 1.4575 4.1075 1.4575 9 P 0 ;1
L 4.1075 1.5075 4.1075 1.5075 9 P 0 ;1
L 4.1075 1.5575 4.1075 1.5575 9 P 0 ;1
L 4.1075 1.9575 4.1075 1.9575 9 P 0 ;1
L 4.1075 2.0075 4.1075 2.0075 9 P 0 ;1
L 4.1075 2.0575 4.1075 2.0575 9 P 0 ;1
L 4.1075 2.1075 4.1075 2.1075 9 P 0 ;1
L 4.1075 2.1575 4.1075 2.1575 9 P 0 ;1
L 4.1075 2.2075 4.1075 2.2075 9 P 0 ;1
L 4.1075 2.2575 4.1075 2.2575 9 P 0 ;1
L 4.1075 2.3075 4.1075 2.3075 9 P 0 ;1
L 4.1075 2.3575 4.1075 2.3575 9 P 0 ;1
L 4.1075 2.4075 4.1075 2.4075 9 P 0 ;1
L 4.1075 2.4575 4.1075 2.4575 9 P 0 ;1
L 4.1075 2.8075 4.1075 2.8075 9 P 0 ;1
L 4.1075 2.8575 4.1075 2.8575 9 P 0 ;1
L 4.1075 3.0075 4.1075 3.0075 9 P 0 ;1
L 4.1075 3.0575 4.1075 3.0575 9 P 0 ;1
L 4.1075 3.1075 4.1075 3.1075 9 P 0 ;1
L 4.1075 3.1575 4.1075 3.1575 9 P 0 ;1
L 4.1075 3.2075 4.1075 3.2075 9 P 0 ;1
L 4.1075 3.2575 4.1075 3.2575 9 P 0 ;1
L 4.1075 3.3075 4.1075 3.3075 9 P 0 ;1
L 4.1075 3.3575 4.1075 3.3575 9 P 0 ;1
L 4.1075 3.4075 4.1075 3.4075 9 P 0 ;1
L 4.1075 3.4575 4.1075 3.4575 9 P 0 ;1
L 4.1075 3.5075 4.1075 3.5075 9 P 0 ;1
L 4.1075 3.5575 4.1075 3.5575 9 P 0 ;1
L 4.1075 3.6075 4.1075 3.6075 9 P 0 ;1
L 4.1075 3.6575 4.1075 3.6575 9 P 0 ;1
L 4.1075 3.7075 4.1075 3.7075 9 P 0 ;1
L 4.1075 3.7575 4.1075 3.7575 9 P 0 ;1
L 4.1075 3.8075 4.1075 3.8075 9 P 0 ;1
L 4.1075 3.8575 4.1075 3.8575 9 P 0 ;1
L 4.1075 3.9075 4.1075 3.9075 9 P 0 ;1
L 4.1075 4.1075 4.1075 4.1075 9 P 0 ;1
L 4.1075 4.1575 4.1075 4.1575 9 P 0 ;1
L 4.1075 4.2075 4.1075 4.2075 9 P 0 ;1
L 4.1075 5.5075 4.1075 5.5075 9 P 0 ;1
L 4.1075 5.5575 4.1075 5.5575 9 P 0 ;1
L 4.1075 5.6075 4.1075 5.6075 9 P 0 ;1
L 4.1075 5.6575 4.1075 5.6575 9 P 0 ;1
L 4.1075 5.7075 4.1075 5.7075 9 P 0 ;1
L 4.1075 5.7575 4.1075 5.7575 9 P 0 ;1
L 4.1075 5.8075 4.1075 5.8075 9 P 0 ;1
L 4.1075 5.8575 4.1075 5.8575 9 P 0 ;1
L 4.1075 5.9075 4.1075 5.9075 9 P 0 ;1
L 4.1575 0.1575 4.1575 0.1575 9 P 0 ;1
L 4.1575 0.2075 4.1575 0.2075 9 P 0 ;1
L 4.1575 0.2575 4.1575 0.2575 9 P 0 ;1
L 4.1575 0.3075 4.1575 0.3075 9 P 0 ;1
L 4.1575 0.3575 4.1575 0.3575 9 P 0 ;1
L 4.1575 0.4075 4.1575 0.4075 9 P 0 ;1
L 4.1575 0.4575 4.1575 0.4575 9 P 0 ;1
L 4.1575 0.5075 4.1575 0.5075 9 P 0 ;1
L 4.1575 0.5575 4.1575 0.5575 9 P 0 ;1
L 4.1575 0.6075 4.1575 0.6075 9 P 0 ;1
L 4.1575 0.6575 4.1575 0.6575 9 P 0 ;1
L 4.1575 0.7075 4.1575 0.7075 9 P 0 ;1
L 4.1575 0.7575 4.1575 0.7575 9 P 0 ;1
L 4.1575 0.8075 4.1575 0.8075 9 P 0 ;1
L 4.1575 0.8575 4.1575 0.8575 9 P 0 ;1
L 4.1575 0.9075 4.1575 0.9075 9 P 0 ;1
L 4.1575 0.9575 4.1575 0.9575 9 P 0 ;1
L 4.1575 1.0075 4.1575 1.0075 9 P 0 ;1
L 4.1575 1.0575 4.1575 1.0575 9 P 0 ;1
L 4.1575 1.1075 4.1575 1.1075 9 P 0 ;1
L 4.1575 1.1575 4.1575 1.1575 9 P 0 ;1
L 4.1575 1.2075 4.1575 1.2075 9 P 0 ;1
L 4.1575 1.2575 4.1575 1.2575 9 P 0 ;1
L 4.1575 1.3075 4.1575 1.3075 9 P 0 ;1
L 4.1575 1.3575 4.1575 1.3575 9 P 0 ;1
L 4.1575 1.4075 4.1575 1.4075 9 P 0 ;1
L 4.1575 1.4575 4.1575 1.4575 9 P 0 ;1
L 4.1575 1.5075 4.1575 1.5075 9 P 0 ;1
L 4.1575 1.9075 4.1575 1.9075 9 P 0 ;1
L 4.1575 1.9575 4.1575 1.9575 9 P 0 ;1
L 4.1575 2.0075 4.1575 2.0075 9 P 0 ;1
L 4.1575 2.0575 4.1575 2.0575 9 P 0 ;1
L 4.1575 2.1075 4.1575 2.1075 9 P 0 ;1
L 4.1575 2.1575 4.1575 2.1575 9 P 0 ;1
L 4.1575 2.2075 4.1575 2.2075 9 P 0 ;1
L 4.1575 2.2575 4.1575 2.2575 9 P 0 ;1
L 4.1575 2.3075 4.1575 2.3075 9 P 0 ;1
L 4.1575 2.3575 4.1575 2.3575 9 P 0 ;1
L 4.1575 2.4075 4.1575 2.4075 9 P 0 ;1
L 4.1575 2.4575 4.1575 2.4575 9 P 0 ;1
L 4.1575 2.5075 4.1575 2.5075 9 P 0 ;1
L 4.1575 2.5575 4.1575 2.5575 9 P 0 ;1
L 4.1575 2.6075 4.1575 2.6075 9 P 0 ;1
L 4.1575 2.8075 4.1575 2.8075 9 P 0 ;1
L 4.1575 3.0075 4.1575 3.0075 9 P 0 ;1
L 4.1575 3.0575 4.1575 3.0575 9 P 0 ;1
L 4.1575 3.1075 4.1575 3.1075 9 P 0 ;1
L 4.1575 3.1575 4.1575 3.1575 9 P 0 ;1
L 4.1575 3.2075 4.1575 3.2075 9 P 0 ;1
L 4.1575 3.2575 4.1575 3.2575 9 P 0 ;1
L 4.1575 3.3075 4.1575 3.3075 9 P 0 ;1
L 4.1575 3.3575 4.1575 3.3575 9 P 0 ;1
L 4.1575 3.4075 4.1575 3.4075 9 P 0 ;1
L 4.1575 3.4575 4.1575 3.4575 9 P 0 ;1
L 4.1575 3.5075 4.1575 3.5075 9 P 0 ;1
L 4.1575 3.5575 4.1575 3.5575 9 P 0 ;1
L 4.1575 3.6075 4.1575 3.6075 9 P 0 ;1
L 4.1575 3.6575 4.1575 3.6575 9 P 0 ;1
L 4.1575 3.7075 4.1575 3.7075 9 P 0 ;1
L 4.1575 3.7575 4.1575 3.7575 9 P 0 ;1
L 4.1575 3.8075 4.1575 3.8075 9 P 0 ;1
L 4.1575 3.8575 4.1575 3.8575 9 P 0 ;1
L 4.1575 3.9075 4.1575 3.9075 9 P 0 ;1
L 4.1575 3.9575 4.1575 3.9575 9 P 0 ;1
L 4.1575 4.0075 4.1575 4.0075 9 P 0 ;1
L 4.1575 4.0575 4.1575 4.0575 9 P 0 ;1
L 4.1575 4.1075 4.1575 4.1075 9 P 0 ;1
L 4.1575 4.1575 4.1575 4.1575 9 P 0 ;1
L 4.1575 4.2075 4.1575 4.2075 9 P 0 ;1
L 4.1575 4.2575 4.1575 4.2575 9 P 0 ;1
L 4.1575 5.3075 4.1575 5.3075 9 P 0 ;1
L 4.1575 5.3575 4.1575 5.3575 9 P 0 ;1
L 4.1575 5.4075 4.1575 5.4075 9 P 0 ;1
L 4.1575 5.4575 4.1575 5.4575 9 P 0 ;1
L 4.1575 5.5075 4.1575 5.5075 9 P 0 ;1
L 4.1575 5.5575 4.1575 5.5575 9 P 0 ;1
L 4.1575 5.6075 4.1575 5.6075 9 P 0 ;1
L 4.1575 5.6575 4.1575 5.6575 9 P 0 ;1
L 4.1575 5.7075 4.1575 5.7075 9 P 0 ;1
L 4.1575 5.7575 4.1575 5.7575 9 P 0 ;1
L 4.1575 5.8075 4.1575 5.8075 9 P 0 ;1
L 4.1575 5.8575 4.1575 5.8575 9 P 0 ;1
L 4.1575 5.9075 4.1575 5.9075 9 P 0 ;1
L 4.2075 0.1575 4.2075 0.1575 9 P 0 ;1
L 4.2075 0.2075 4.2075 0.2075 9 P 0 ;1
L 4.2075 0.2575 4.2075 0.2575 9 P 0 ;1
L 4.2075 0.3075 4.2075 0.3075 9 P 0 ;1
L 4.2075 0.3575 4.2075 0.3575 9 P 0 ;1
L 4.2075 0.4075 4.2075 0.4075 9 P 0 ;1
L 4.2075 0.4575 4.2075 0.4575 9 P 0 ;1
L 4.2075 0.5075 4.2075 0.5075 9 P 0 ;1
L 4.2075 0.5575 4.2075 0.5575 9 P 0 ;1
L 4.2075 0.6075 4.2075 0.6075 9 P 0 ;1
L 4.2075 0.6575 4.2075 0.6575 9 P 0 ;1
L 4.2075 0.7075 4.2075 0.7075 9 P 0 ;1
L 4.2075 0.7575 4.2075 0.7575 9 P 0 ;1
L 4.2075 0.8075 4.2075 0.8075 9 P 0 ;1
L 4.2075 0.8575 4.2075 0.8575 9 P 0 ;1
L 4.2075 0.9075 4.2075 0.9075 9 P 0 ;1
L 4.2075 0.9575 4.2075 0.9575 9 P 0 ;1
L 4.2075 1.0075 4.2075 1.0075 9 P 0 ;1
L 4.2075 1.0575 4.2075 1.0575 9 P 0 ;1
L 4.2075 1.1075 4.2075 1.1075 9 P 0 ;1
L 4.2075 1.1575 4.2075 1.1575 9 P 0 ;1
L 4.2075 1.2075 4.2075 1.2075 9 P 0 ;1
L 4.2075 1.2575 4.2075 1.2575 9 P 0 ;1
L 4.2075 1.3075 4.2075 1.3075 9 P 0 ;1
L 4.2075 1.3575 4.2075 1.3575 9 P 0 ;1
L 4.2075 1.4075 4.2075 1.4075 9 P 0 ;1
L 4.2075 1.4575 4.2075 1.4575 9 P 0 ;1
L 4.2075 1.8575 4.2075 1.8575 9 P 0 ;1
L 4.2075 1.9075 4.2075 1.9075 9 P 0 ;1
L 4.2075 1.9575 4.2075 1.9575 9 P 0 ;1
L 4.2075 2.0075 4.2075 2.0075 9 P 0 ;1
L 4.2075 2.0575 4.2075 2.0575 9 P 0 ;1
L 4.2075 2.1075 4.2075 2.1075 9 P 0 ;1
L 4.2075 2.1575 4.2075 2.1575 9 P 0 ;1
L 4.2075 2.2075 4.2075 2.2075 9 P 0 ;1
L 4.2075 2.2575 4.2075 2.2575 9 P 0 ;1
L 4.2075 2.3075 4.2075 2.3075 9 P 0 ;1
L 4.2075 2.3575 4.2075 2.3575 9 P 0 ;1
L 4.2075 2.4075 4.2075 2.4075 9 P 0 ;1
L 4.2075 2.4575 4.2075 2.4575 9 P 0 ;1
L 4.2075 2.5075 4.2075 2.5075 9 P 0 ;1
L 4.2075 2.5575 4.2075 2.5575 9 P 0 ;1
L 4.2075 2.6075 4.2075 2.6075 9 P 0 ;1
L 4.2075 2.6575 4.2075 2.6575 9 P 0 ;1
L 4.2075 2.7075 4.2075 2.7075 9 P 0 ;1
L 4.2075 2.7575 4.2075 2.7575 9 P 0 ;1
L 4.2075 2.8075 4.2075 2.8075 9 P 0 ;1
L 4.2075 2.8575 4.2075 2.8575 9 P 0 ;1
L 4.2075 5.2075 4.2075 5.2075 9 P 0 ;1
L 4.2075 5.2575 4.2075 5.2575 9 P 0 ;1
L 4.2075 5.3075 4.2075 5.3075 9 P 0 ;1
L 4.2075 5.3575 4.2075 5.3575 9 P 0 ;1
L 4.2075 5.4075 4.2075 5.4075 9 P 0 ;1
L 4.2075 5.4575 4.2075 5.4575 9 P 0 ;1
L 4.2075 5.5075 4.2075 5.5075 9 P 0 ;1
L 4.2075 5.5575 4.2075 5.5575 9 P 0 ;1
L 4.2075 5.6075 4.2075 5.6075 9 P 0 ;1
L 4.2075 5.6575 4.2075 5.6575 9 P 0 ;1
L 4.2075 5.7075 4.2075 5.7075 9 P 0 ;1
L 4.2075 5.7575 4.2075 5.7575 9 P 0 ;1
L 4.2075 5.8075 4.2075 5.8075 9 P 0 ;1
L 4.2075 5.8575 4.2075 5.8575 9 P 0 ;1
L 4.2075 5.9075 4.2075 5.9075 9 P 0 ;1
L 4.2575 0.1575 4.2575 0.1575 9 P 0 ;1
L 4.2575 0.2075 4.2575 0.2075 9 P 0 ;1
L 4.2575 0.2575 4.2575 0.2575 9 P 0 ;1
L 4.2575 0.3075 4.2575 0.3075 9 P 0 ;1
L 4.2575 0.3575 4.2575 0.3575 9 P 0 ;1
L 4.2575 0.4075 4.2575 0.4075 9 P 0 ;1
L 4.2575 0.4575 4.2575 0.4575 9 P 0 ;1
L 4.2575 0.5075 4.2575 0.5075 9 P 0 ;1
L 4.2575 0.5575 4.2575 0.5575 9 P 0 ;1
L 4.2575 0.6075 4.2575 0.6075 9 P 0 ;1
L 4.2575 0.6575 4.2575 0.6575 9 P 0 ;1
L 4.2575 0.7075 4.2575 0.7075 9 P 0 ;1
L 4.2575 0.7575 4.2575 0.7575 9 P 0 ;1
L 4.2575 0.8075 4.2575 0.8075 9 P 0 ;1
L 4.2575 0.8575 4.2575 0.8575 9 P 0 ;1
L 4.2575 0.9075 4.2575 0.9075 9 P 0 ;1
L 4.2575 0.9575 4.2575 0.9575 9 P 0 ;1
L 4.2575 1.0075 4.2575 1.0075 9 P 0 ;1
L 4.2575 1.0575 4.2575 1.0575 9 P 0 ;1
L 4.2575 1.1075 4.2575 1.1075 9 P 0 ;1
L 4.2575 1.1575 4.2575 1.1575 9 P 0 ;1
L 4.2575 1.2075 4.2575 1.2075 9 P 0 ;1
L 4.2575 1.2575 4.2575 1.2575 9 P 0 ;1
L 4.2575 1.3075 4.2575 1.3075 9 P 0 ;1
L 4.2575 1.3575 4.2575 1.3575 9 P 0 ;1
L 4.2575 1.4075 4.2575 1.4075 9 P 0 ;1
L 4.2575 1.8575 4.2575 1.8575 9 P 0 ;1
L 4.2575 1.9075 4.2575 1.9075 9 P 0 ;1
L 4.2575 1.9575 4.2575 1.9575 9 P 0 ;1
L 4.2575 2.0075 4.2575 2.0075 9 P 0 ;1
L 4.2575 2.0575 4.2575 2.0575 9 P 0 ;1
L 4.2575 2.1075 4.2575 2.1075 9 P 0 ;1
L 4.2575 2.1575 4.2575 2.1575 9 P 0 ;1
L 4.2575 2.2075 4.2575 2.2075 9 P 0 ;1
L 4.2575 2.2575 4.2575 2.2575 9 P 0 ;1
L 4.2575 2.3075 4.2575 2.3075 9 P 0 ;1
L 4.2575 2.3575 4.2575 2.3575 9 P 0 ;1
L 4.2575 2.4075 4.2575 2.4075 9 P 0 ;1
L 4.2575 2.4575 4.2575 2.4575 9 P 0 ;1
L 4.2575 2.5075 4.2575 2.5075 9 P 0 ;1
L 4.2575 2.5575 4.2575 2.5575 9 P 0 ;1
L 4.2575 2.6075 4.2575 2.6075 9 P 0 ;1
L 4.2575 2.6575 4.2575 2.6575 9 P 0 ;1
L 4.2575 2.7075 4.2575 2.7075 9 P 0 ;1
L 4.2575 2.7575 4.2575 2.7575 9 P 0 ;1
L 4.2575 2.8075 4.2575 2.8075 9 P 0 ;1
L 4.2575 2.8575 4.2575 2.8575 9 P 0 ;1
L 4.2575 5.2075 4.2575 5.2075 9 P 0 ;1
L 4.2575 5.2575 4.2575 5.2575 9 P 0 ;1
L 4.2575 5.3075 4.2575 5.3075 9 P 0 ;1
L 4.2575 5.3575 4.2575 5.3575 9 P 0 ;1
L 4.2575 5.4075 4.2575 5.4075 9 P 0 ;1
L 4.2575 5.4575 4.2575 5.4575 9 P 0 ;1
L 4.2575 5.5075 4.2575 5.5075 9 P 0 ;1
L 4.2575 5.5575 4.2575 5.5575 9 P 0 ;1
L 4.2575 5.6075 4.2575 5.6075 9 P 0 ;1
L 4.2575 5.6575 4.2575 5.6575 9 P 0 ;1
L 4.2575 5.7075 4.2575 5.7075 9 P 0 ;1
L 4.2575 5.7575 4.2575 5.7575 9 P 0 ;1
L 4.2575 5.8075 4.2575 5.8075 9 P 0 ;1
L 4.2575 5.8575 4.2575 5.8575 9 P 0 ;1
L 4.2575 5.9075 4.2575 5.9075 9 P 0 ;1
L 4.3075 0.1575 4.3075 0.1575 9 P 0 ;1
L 4.3075 0.2075 4.3075 0.2075 9 P 0 ;1
L 4.3075 0.2575 4.3075 0.2575 9 P 0 ;1
L 4.3075 0.3075 4.3075 0.3075 9 P 0 ;1
L 4.3075 0.3575 4.3075 0.3575 9 P 0 ;1
L 4.3075 0.4075 4.3075 0.4075 9 P 0 ;1
L 4.3075 0.4575 4.3075 0.4575 9 P 0 ;1
L 4.3075 0.5075 4.3075 0.5075 9 P 0 ;1
L 4.3075 0.5575 4.3075 0.5575 9 P 0 ;1
L 4.3075 0.6075 4.3075 0.6075 9 P 0 ;1
L 4.3075 0.6575 4.3075 0.6575 9 P 0 ;1
L 4.3075 0.7075 4.3075 0.7075 9 P 0 ;1
L 4.3075 0.7575 4.3075 0.7575 9 P 0 ;1
L 4.3075 0.8075 4.3075 0.8075 9 P 0 ;1
L 4.3075 0.8575 4.3075 0.8575 9 P 0 ;1
L 4.3075 0.9075 4.3075 0.9075 9 P 0 ;1
L 4.3075 0.9575 4.3075 0.9575 9 P 0 ;1
L 4.3075 1.0075 4.3075 1.0075 9 P 0 ;1
L 4.3075 1.0575 4.3075 1.0575 9 P 0 ;1
L 4.3075 1.1075 4.3075 1.1075 9 P 0 ;1
L 4.3075 1.1575 4.3075 1.1575 9 P 0 ;1
L 4.3075 1.2075 4.3075 1.2075 9 P 0 ;1
L 4.3075 1.2575 4.3075 1.2575 9 P 0 ;1
L 4.3075 1.3075 4.3075 1.3075 9 P 0 ;1
L 4.3075 1.3575 4.3075 1.3575 9 P 0 ;1
L 4.3075 1.8575 4.3075 1.8575 9 P 0 ;1
L 4.3075 1.9075 4.3075 1.9075 9 P 0 ;1
L 4.3075 1.9575 4.3075 1.9575 9 P 0 ;1
L 4.3075 2.0075 4.3075 2.0075 9 P 0 ;1
L 4.3075 2.0575 4.3075 2.0575 9 P 0 ;1
L 4.3075 2.1075 4.3075 2.1075 9 P 0 ;1
L 4.3075 2.1575 4.3075 2.1575 9 P 0 ;1
L 4.3075 2.2075 4.3075 2.2075 9 P 0 ;1
L 4.3075 2.2575 4.3075 2.2575 9 P 0 ;1
L 4.3075 2.3075 4.3075 2.3075 9 P 0 ;1
L 4.3075 2.3575 4.3075 2.3575 9 P 0 ;1
L 4.3075 2.4075 4.3075 2.4075 9 P 0 ;1
L 4.3075 2.4575 4.3075 2.4575 9 P 0 ;1
L 4.3075 2.5075 4.3075 2.5075 9 P 0 ;1
L 4.3075 2.5575 4.3075 2.5575 9 P 0 ;1
L 4.3075 2.6075 4.3075 2.6075 9 P 0 ;1
L 4.3075 2.6575 4.3075 2.6575 9 P 0 ;1
L 4.3075 2.7075 4.3075 2.7075 9 P 0 ;1
L 4.3075 2.7575 4.3075 2.7575 9 P 0 ;1
L 4.3075 2.8075 4.3075 2.8075 9 P 0 ;1
L 4.3075 2.8575 4.3075 2.8575 9 P 0 ;1
L 4.3075 5.2075 4.3075 5.2075 9 P 0 ;1
L 4.3075 5.2575 4.3075 5.2575 9 P 0 ;1
L 4.3075 5.3075 4.3075 5.3075 9 P 0 ;1
L 4.3075 5.3575 4.3075 5.3575 9 P 0 ;1
L 4.3075 5.4075 4.3075 5.4075 9 P 0 ;1
L 4.3075 5.4575 4.3075 5.4575 9 P 0 ;1
L 4.3075 5.5075 4.3075 5.5075 9 P 0 ;1
L 4.3075 5.5575 4.3075 5.5575 9 P 0 ;1
L 4.3075 5.6075 4.3075 5.6075 9 P 0 ;1
L 4.3075 5.6575 4.3075 5.6575 9 P 0 ;1
L 4.3075 5.7075 4.3075 5.7075 9 P 0 ;1
L 4.3075 5.7575 4.3075 5.7575 9 P 0 ;1
L 4.3075 5.8075 4.3075 5.8075 9 P 0 ;1
L 4.3075 5.8575 4.3075 5.8575 9 P 0 ;1
L 4.3075 5.9075 4.3075 5.9075 9 P 0 ;1
L 4.3575 0.1575 4.3575 0.1575 9 P 0 ;1
L 4.3575 0.2075 4.3575 0.2075 9 P 0 ;1
L 4.3575 0.2575 4.3575 0.2575 9 P 0 ;1
L 4.3575 0.3075 4.3575 0.3075 9 P 0 ;1
L 4.3575 0.3575 4.3575 0.3575 9 P 0 ;1
L 4.3575 0.4075 4.3575 0.4075 9 P 0 ;1
L 4.3575 0.4575 4.3575 0.4575 9 P 0 ;1
L 4.3575 0.5075 4.3575 0.5075 9 P 0 ;1
L 4.3575 0.5575 4.3575 0.5575 9 P 0 ;1
L 4.3575 0.6075 4.3575 0.6075 9 P 0 ;1
L 4.3575 0.6575 4.3575 0.6575 9 P 0 ;1
L 4.3575 0.7075 4.3575 0.7075 9 P 0 ;1
L 4.3575 0.7575 4.3575 0.7575 9 P 0 ;1
L 4.3575 0.8075 4.3575 0.8075 9 P 0 ;1
L 4.3575 0.8575 4.3575 0.8575 9 P 0 ;1
L 4.3575 0.9075 4.3575 0.9075 9 P 0 ;1
L 4.3575 0.9575 4.3575 0.9575 9 P 0 ;1
L 4.3575 1.0075 4.3575 1.0075 9 P 0 ;1
L 4.3575 1.0575 4.3575 1.0575 9 P 0 ;1
L 4.3575 1.1075 4.3575 1.1075 9 P 0 ;1
L 4.3575 1.1575 4.3575 1.1575 9 P 0 ;1
L 4.3575 1.2075 4.3575 1.2075 9 P 0 ;1
L 4.3575 1.2575 4.3575 1.2575 9 P 0 ;1
L 4.3575 1.3075 4.3575 1.3075 9 P 0 ;1
L 4.3575 1.8575 4.3575 1.8575 9 P 0 ;1
L 4.3575 1.9075 4.3575 1.9075 9 P 0 ;1
L 4.3575 1.9575 4.3575 1.9575 9 P 0 ;1
L 4.3575 2.0075 4.3575 2.0075 9 P 0 ;1
L 4.3575 2.0575 4.3575 2.0575 9 P 0 ;1
L 4.3575 2.1075 4.3575 2.1075 9 P 0 ;1
L 4.3575 2.1575 4.3575 2.1575 9 P 0 ;1
L 4.3575 2.2075 4.3575 2.2075 9 P 0 ;1
L 4.3575 2.2575 4.3575 2.2575 9 P 0 ;1
L 4.3575 2.3075 4.3575 2.3075 9 P 0 ;1
L 4.3575 2.3575 4.3575 2.3575 9 P 0 ;1
L 4.3575 2.4075 4.3575 2.4075 9 P 0 ;1
L 4.3575 2.4575 4.3575 2.4575 9 P 0 ;1
L 4.3575 2.5075 4.3575 2.5075 9 P 0 ;1
L 4.3575 2.5575 4.3575 2.5575 9 P 0 ;1
L 4.3575 2.6075 4.3575 2.6075 9 P 0 ;1
L 4.3575 2.6575 4.3575 2.6575 9 P 0 ;1
L 4.3575 2.7075 4.3575 2.7075 9 P 0 ;1
L 4.3575 2.7575 4.3575 2.7575 9 P 0 ;1
L 4.3575 2.8075 4.3575 2.8075 9 P 0 ;1
L 4.3575 2.8575 4.3575 2.8575 9 P 0 ;1
L 4.3575 5.2075 4.3575 5.2075 9 P 0 ;1
L 4.3575 5.2575 4.3575 5.2575 9 P 0 ;1
L 4.3575 5.3075 4.3575 5.3075 9 P 0 ;1
L 4.3575 5.3575 4.3575 5.3575 9 P 0 ;1
L 4.3575 5.4075 4.3575 5.4075 9 P 0 ;1
L 4.3575 5.4575 4.3575 5.4575 9 P 0 ;1
L 4.3575 5.5075 4.3575 5.5075 9 P 0 ;1
L 4.3575 5.5575 4.3575 5.5575 9 P 0 ;1
L 4.3575 5.6075 4.3575 5.6075 9 P 0 ;1
L 4.3575 5.6575 4.3575 5.6575 9 P 0 ;1
L 4.3575 5.7075 4.3575 5.7075 9 P 0 ;1
L 4.3575 5.7575 4.3575 5.7575 9 P 0 ;1
L 4.3575 5.8075 4.3575 5.8075 9 P 0 ;1
L 4.3575 5.8575 4.3575 5.8575 9 P 0 ;1
L 4.3575 5.9075 4.3575 5.9075 9 P 0 ;1
L 4.4075 0.1575 4.4075 0.1575 9 P 0 ;1
L 4.4075 0.2075 4.4075 0.2075 9 P 0 ;1
L 4.4075 0.2575 4.4075 0.2575 9 P 0 ;1
L 4.4075 0.3075 4.4075 0.3075 9 P 0 ;1
L 4.4075 0.3575 4.4075 0.3575 9 P 0 ;1
L 4.4075 0.4075 4.4075 0.4075 9 P 0 ;1
L 4.4075 0.4575 4.4075 0.4575 9 P 0 ;1
L 4.4075 0.5075 4.4075 0.5075 9 P 0 ;1
L 4.4075 0.5575 4.4075 0.5575 9 P 0 ;1
L 4.4075 0.6075 4.4075 0.6075 9 P 0 ;1
L 4.4075 0.6575 4.4075 0.6575 9 P 0 ;1
L 4.4075 0.7075 4.4075 0.7075 9 P 0 ;1
L 4.4075 0.7575 4.4075 0.7575 9 P 0 ;1
L 4.4075 0.8075 4.4075 0.8075 9 P 0 ;1
L 4.4075 0.8575 4.4075 0.8575 9 P 0 ;1
L 4.4075 0.9075 4.4075 0.9075 9 P 0 ;1
L 4.4075 0.9575 4.4075 0.9575 9 P 0 ;1
L 4.4075 1.0075 4.4075 1.0075 9 P 0 ;1
L 4.4075 1.0575 4.4075 1.0575 9 P 0 ;1
L 4.4075 1.1075 4.4075 1.1075 9 P 0 ;1
L 4.4075 1.1575 4.4075 1.1575 9 P 0 ;1
L 4.4075 1.2075 4.4075 1.2075 9 P 0 ;1
L 4.4075 1.2575 4.4075 1.2575 9 P 0 ;1
L 4.4075 1.6575 4.4075 1.6575 9 P 0 ;1
L 4.4075 1.8575 4.4075 1.8575 9 P 0 ;1
L 4.4075 1.9075 4.4075 1.9075 9 P 0 ;1
L 4.4075 1.9575 4.4075 1.9575 9 P 0 ;1
L 4.4075 2.0075 4.4075 2.0075 9 P 0 ;1
L 4.4075 2.0575 4.4075 2.0575 9 P 0 ;1
L 4.4075 2.1075 4.4075 2.1075 9 P 0 ;1
L 4.4075 2.1575 4.4075 2.1575 9 P 0 ;1
L 4.4075 2.2075 4.4075 2.2075 9 P 0 ;1
L 4.4075 2.2575 4.4075 2.2575 9 P 0 ;1
L 4.4075 2.3075 4.4075 2.3075 9 P 0 ;1
L 4.4075 2.3575 4.4075 2.3575 9 P 0 ;1
L 4.4075 2.4075 4.4075 2.4075 9 P 0 ;1
L 4.4075 2.4575 4.4075 2.4575 9 P 0 ;1
L 4.4075 2.5075 4.4075 2.5075 9 P 0 ;1
L 4.4075 2.5575 4.4075 2.5575 9 P 0 ;1
L 4.4075 2.6075 4.4075 2.6075 9 P 0 ;1
L 4.4075 2.6575 4.4075 2.6575 9 P 0 ;1
L 4.4075 2.7075 4.4075 2.7075 9 P 0 ;1
L 4.4075 2.7575 4.4075 2.7575 9 P 0 ;1
L 4.4075 2.8075 4.4075 2.8075 9 P 0 ;1
L 4.4075 2.8575 4.4075 2.8575 9 P 0 ;1
L 4.4075 5.2075 4.4075 5.2075 9 P 0 ;1
L 4.4075 5.2575 4.4075 5.2575 9 P 0 ;1
L 4.4075 5.3075 4.4075 5.3075 9 P 0 ;1
L 4.4075 5.3575 4.4075 5.3575 9 P 0 ;1
L 4.4075 5.4075 4.4075 5.4075 9 P 0 ;1
L 4.4075 5.4575 4.4075 5.4575 9 P 0 ;1
L 4.4075 5.5075 4.4075 5.5075 9 P 0 ;1
L 4.4075 5.5575 4.4075 5.5575 9 P 0 ;1
L 4.4075 5.6075 4.4075 5.6075 9 P 0 ;1
L 4.4075 5.6575 4.4075 5.6575 9 P 0 ;1
L 4.4075 5.7075 4.4075 5.7075 9 P 0 ;1
L 4.4075 5.7575 4.4075 5.7575 9 P 0 ;1
L 4.4075 5.8075 4.4075 5.8075 9 P 0 ;1
L 4.4075 5.8575 4.4075 5.8575 9 P 0 ;1
L 4.4075 5.9075 4.4075 5.9075 9 P 0 ;1
L 4.4575 0.1575 4.4575 0.1575 9 P 0 ;1
L 4.4575 0.2075 4.4575 0.2075 9 P 0 ;1
L 4.4575 0.2575 4.4575 0.2575 9 P 0 ;1
L 4.4575 0.3075 4.4575 0.3075 9 P 0 ;1
L 4.4575 0.3575 4.4575 0.3575 9 P 0 ;1
L 4.4575 0.4075 4.4575 0.4075 9 P 0 ;1
L 4.4575 0.4575 4.4575 0.4575 9 P 0 ;1
L 4.4575 0.5075 4.4575 0.5075 9 P 0 ;1
L 4.4575 0.5575 4.4575 0.5575 9 P 0 ;1
L 4.4575 0.6075 4.4575 0.6075 9 P 0 ;1
L 4.4575 0.6575 4.4575 0.6575 9 P 0 ;1
L 4.4575 0.7075 4.4575 0.7075 9 P 0 ;1
L 4.4575 0.7575 4.4575 0.7575 9 P 0 ;1
L 4.4575 0.8075 4.4575 0.8075 9 P 0 ;1
L 4.4575 0.8575 4.4575 0.8575 9 P 0 ;1
L 4.4575 0.9075 4.4575 0.9075 9 P 0 ;1
L 4.4575 0.9575 4.4575 0.9575 9 P 0 ;1
L 4.4575 1.0075 4.4575 1.0075 9 P 0 ;1
L 4.4575 1.0575 4.4575 1.0575 9 P 0 ;1
L 4.4575 1.1075 4.4575 1.1075 9 P 0 ;1
L 4.4575 1.1575 4.4575 1.1575 9 P 0 ;1
L 4.4575 1.2075 4.4575 1.2075 9 P 0 ;1
L 4.4575 1.6075 4.4575 1.6075 9 P 0 ;1
L 4.4575 1.6575 4.4575 1.6575 9 P 0 ;1
L 4.4575 1.8575 4.4575 1.8575 9 P 0 ;1
L 4.4575 1.9075 4.4575 1.9075 9 P 0 ;1
L 4.4575 1.9575 4.4575 1.9575 9 P 0 ;1
L 4.4575 2.0075 4.4575 2.0075 9 P 0 ;1
L 4.4575 2.0575 4.4575 2.0575 9 P 0 ;1
L 4.4575 2.1075 4.4575 2.1075 9 P 0 ;1
L 4.4575 2.1575 4.4575 2.1575 9 P 0 ;1
L 4.4575 2.2075 4.4575 2.2075 9 P 0 ;1
L 4.4575 2.2575 4.4575 2.2575 9 P 0 ;1
L 4.4575 2.3075 4.4575 2.3075 9 P 0 ;1
L 4.4575 2.3575 4.4575 2.3575 9 P 0 ;1
L 4.4575 2.4075 4.4575 2.4075 9 P 0 ;1
L 4.4575 2.4575 4.4575 2.4575 9 P 0 ;1
L 4.4575 2.5075 4.4575 2.5075 9 P 0 ;1
L 4.4575 2.5575 4.4575 2.5575 9 P 0 ;1
L 4.4575 2.6075 4.4575 2.6075 9 P 0 ;1
L 4.4575 2.6575 4.4575 2.6575 9 P 0 ;1
L 4.4575 2.7075 4.4575 2.7075 9 P 0 ;1
L 4.4575 2.7575 4.4575 2.7575 9 P 0 ;1
L 4.4575 2.8075 4.4575 2.8075 9 P 0 ;1
L 4.4575 2.8575 4.4575 2.8575 9 P 0 ;1
L 4.4575 5.2075 4.4575 5.2075 9 P 0 ;1
L 4.4575 5.2575 4.4575 5.2575 9 P 0 ;1
L 4.4575 5.3075 4.4575 5.3075 9 P 0 ;1
L 4.4575 5.3575 4.4575 5.3575 9 P 0 ;1
L 4.4575 5.4075 4.4575 5.4075 9 P 0 ;1
L 4.4575 5.4575 4.4575 5.4575 9 P 0 ;1
L 4.4575 5.5075 4.4575 5.5075 9 P 0 ;1
L 4.4575 5.5575 4.4575 5.5575 9 P 0 ;1
L 4.4575 5.6075 4.4575 5.6075 9 P 0 ;1
L 4.4575 5.6575 4.4575 5.6575 9 P 0 ;1
L 4.4575 5.7075 4.4575 5.7075 9 P 0 ;1
L 4.4575 5.7575 4.4575 5.7575 9 P 0 ;1
L 4.4575 5.8075 4.4575 5.8075 9 P 0 ;1
L 4.4575 5.8575 4.4575 5.8575 9 P 0 ;1
L 4.4575 5.9075 4.4575 5.9075 9 P 0 ;1
L 4.5075 0.1575 4.5075 0.1575 9 P 0 ;1
L 4.5075 0.2075 4.5075 0.2075 9 P 0 ;1
L 4.5075 0.2575 4.5075 0.2575 9 P 0 ;1
L 4.5075 0.3075 4.5075 0.3075 9 P 0 ;1
L 4.5075 0.3575 4.5075 0.3575 9 P 0 ;1
L 4.5075 0.4075 4.5075 0.4075 9 P 0 ;1
L 4.5075 0.4575 4.5075 0.4575 9 P 0 ;1
L 4.5075 0.5075 4.5075 0.5075 9 P 0 ;1
L 4.5075 0.5575 4.5075 0.5575 9 P 0 ;1
L 4.5075 0.6075 4.5075 0.6075 9 P 0 ;1
L 4.5075 0.6575 4.5075 0.6575 9 P 0 ;1
L 4.5075 0.7075 4.5075 0.7075 9 P 0 ;1
L 4.5075 0.7575 4.5075 0.7575 9 P 0 ;1
L 4.5075 0.8075 4.5075 0.8075 9 P 0 ;1
L 4.5075 0.8575 4.5075 0.8575 9 P 0 ;1
L 4.5075 0.9075 4.5075 0.9075 9 P 0 ;1
L 4.5075 0.9575 4.5075 0.9575 9 P 0 ;1
L 4.5075 1.0075 4.5075 1.0075 9 P 0 ;1
L 4.5075 1.0575 4.5075 1.0575 9 P 0 ;1
L 4.5075 1.1075 4.5075 1.1075 9 P 0 ;1
L 4.5075 1.1575 4.5075 1.1575 9 P 0 ;1
L 4.5075 1.5575 4.5075 1.5575 9 P 0 ;1
L 4.5075 1.6075 4.5075 1.6075 9 P 0 ;1
L 4.5075 1.6575 4.5075 1.6575 9 P 0 ;1
L 4.5075 2.1575 4.5075 2.1575 9 P 0 ;1
L 4.5075 2.8575 4.5075 2.8575 9 P 0 ;1
L 4.5075 5.2075 4.5075 5.2075 9 P 0 ;1
L 4.5075 5.2575 4.5075 5.2575 9 P 0 ;1
L 4.5075 5.3075 4.5075 5.3075 9 P 0 ;1
L 4.5075 5.3575 4.5075 5.3575 9 P 0 ;1
L 4.5075 5.4075 4.5075 5.4075 9 P 0 ;1
L 4.5075 5.4575 4.5075 5.4575 9 P 0 ;1
L 4.5075 5.5075 4.5075 5.5075 9 P 0 ;1
L 4.5075 5.5575 4.5075 5.5575 9 P 0 ;1
L 4.5075 5.6075 4.5075 5.6075 9 P 0 ;1
L 4.5075 5.6575 4.5075 5.6575 9 P 0 ;1
L 4.5075 5.7075 4.5075 5.7075 9 P 0 ;1
L 4.5075 5.7575 4.5075 5.7575 9 P 0 ;1
L 4.5075 5.8075 4.5075 5.8075 9 P 0 ;1
L 4.5075 5.8575 4.5075 5.8575 9 P 0 ;1
L 4.5075 5.9075 4.5075 5.9075 9 P 0 ;1
L 4.5575 0.1575 4.5575 0.1575 9 P 0 ;1
L 4.5575 0.2075 4.5575 0.2075 9 P 0 ;1
L 4.5575 0.2575 4.5575 0.2575 9 P 0 ;1
L 4.5575 0.3075 4.5575 0.3075 9 P 0 ;1
L 4.5575 0.3575 4.5575 0.3575 9 P 0 ;1
L 4.5575 0.4075 4.5575 0.4075 9 P 0 ;1
L 4.5575 0.4575 4.5575 0.4575 9 P 0 ;1
L 4.5575 0.5075 4.5575 0.5075 9 P 0 ;1
L 4.5575 0.5575 4.5575 0.5575 9 P 0 ;1
L 4.5575 0.6075 4.5575 0.6075 9 P 0 ;1
L 4.5575 0.6575 4.5575 0.6575 9 P 0 ;1
L 4.5575 0.7075 4.5575 0.7075 9 P 0 ;1
L 4.5575 0.7575 4.5575 0.7575 9 P 0 ;1
L 4.5575 0.8075 4.5575 0.8075 9 P 0 ;1
L 4.5575 0.8575 4.5575 0.8575 9 P 0 ;1
L 4.5575 0.9075 4.5575 0.9075 9 P 0 ;1
L 4.5575 0.9575 4.5575 0.9575 9 P 0 ;1
L 4.5575 1.0075 4.5575 1.0075 9 P 0 ;1
L 4.5575 1.0575 4.5575 1.0575 9 P 0 ;1
L 4.5575 1.1075 4.5575 1.1075 9 P 0 ;1
L 4.5575 1.5075 4.5575 1.5075 9 P 0 ;1
L 4.5575 1.5575 4.5575 1.5575 9 P 0 ;1
L 4.5575 1.6075 4.5575 1.6075 9 P 0 ;1
L 4.5575 1.6575 4.5575 1.6575 9 P 0 ;1
L 4.5575 4.9575 4.5575 4.9575 9 P 0 ;1
L 4.5575 5.0075 4.5575 5.0075 9 P 0 ;1
L 4.5575 5.0575 4.5575 5.0575 9 P 0 ;1
L 4.5575 5.1075 4.5575 5.1075 9 P 0 ;1
L 4.5575 5.1575 4.5575 5.1575 9 P 0 ;1
L 4.5575 5.2075 4.5575 5.2075 9 P 0 ;1
L 4.5575 5.2575 4.5575 5.2575 9 P 0 ;1
L 4.5575 5.3075 4.5575 5.3075 9 P 0 ;1
L 4.5575 5.3575 4.5575 5.3575 9 P 0 ;1
L 4.5575 5.4075 4.5575 5.4075 9 P 0 ;1
L 4.5575 5.4575 4.5575 5.4575 9 P 0 ;1
L 4.5575 5.5075 4.5575 5.5075 9 P 0 ;1
L 4.5575 5.5575 4.5575 5.5575 9 P 0 ;1
L 4.5575 5.6075 4.5575 5.6075 9 P 0 ;1
L 4.5575 5.6575 4.5575 5.6575 9 P 0 ;1
L 4.5575 5.7075 4.5575 5.7075 9 P 0 ;1
L 4.5575 5.7575 4.5575 5.7575 9 P 0 ;1
L 4.5575 5.8075 4.5575 5.8075 9 P 0 ;1
L 4.5575 5.8575 4.5575 5.8575 9 P 0 ;1
L 4.5575 5.9075 4.5575 5.9075 9 P 0 ;1
L 4.6075 0.1575 4.6075 0.1575 9 P 0 ;1
L 4.6075 0.2075 4.6075 0.2075 9 P 0 ;1
L 4.6075 0.2575 4.6075 0.2575 9 P 0 ;1
L 4.6075 0.3075 4.6075 0.3075 9 P 0 ;1
L 4.6075 0.3575 4.6075 0.3575 9 P 0 ;1
L 4.6075 0.4075 4.6075 0.4075 9 P 0 ;1
L 4.6075 0.4575 4.6075 0.4575 9 P 0 ;1
L 4.6075 0.5075 4.6075 0.5075 9 P 0 ;1
L 4.6075 0.5575 4.6075 0.5575 9 P 0 ;1
L 4.6075 0.6075 4.6075 0.6075 9 P 0 ;1
L 4.6075 0.6575 4.6075 0.6575 9 P 0 ;1
L 4.6075 0.7075 4.6075 0.7075 9 P 0 ;1
L 4.6075 0.7575 4.6075 0.7575 9 P 0 ;1
L 4.6075 0.8075 4.6075 0.8075 9 P 0 ;1
L 4.6075 0.8575 4.6075 0.8575 9 P 0 ;1
L 4.6075 0.9075 4.6075 0.9075 9 P 0 ;1
L 4.6075 0.9575 4.6075 0.9575 9 P 0 ;1
L 4.6075 1.0075 4.6075 1.0075 9 P 0 ;1
L 4.6075 1.0575 4.6075 1.0575 9 P 0 ;1
L 4.6075 1.4575 4.6075 1.4575 9 P 0 ;1
L 4.6075 1.5075 4.6075 1.5075 9 P 0 ;1
L 4.6075 1.5575 4.6075 1.5575 9 P 0 ;1
L 4.6075 1.6075 4.6075 1.6075 9 P 0 ;1
L 4.6075 1.6575 4.6075 1.6575 9 P 0 ;1
L 4.6075 5.2075 4.6075 5.2075 9 P 0 ;1
L 4.6075 5.2575 4.6075 5.2575 9 P 0 ;1
L 4.6075 5.3075 4.6075 5.3075 9 P 0 ;1
L 4.6075 5.3575 4.6075 5.3575 9 P 0 ;1
L 4.6075 5.4075 4.6075 5.4075 9 P 0 ;1
L 4.6075 5.4575 4.6075 5.4575 9 P 0 ;1
L 4.6075 5.5075 4.6075 5.5075 9 P 0 ;1
L 4.6075 5.5575 4.6075 5.5575 9 P 0 ;1
L 4.6075 5.6075 4.6075 5.6075 9 P 0 ;1
L 4.6075 5.6575 4.6075 5.6575 9 P 0 ;1
L 4.6075 5.7075 4.6075 5.7075 9 P 0 ;1
L 4.6075 5.7575 4.6075 5.7575 9 P 0 ;1
L 4.6075 5.8075 4.6075 5.8075 9 P 0 ;1
L 4.6075 5.8575 4.6075 5.8575 9 P 0 ;1
L 4.6075 5.9075 4.6075 5.9075 9 P 0 ;1
L 4.6575 0.1575 4.6575 0.1575 9 P 0 ;1
L 4.6575 0.2075 4.6575 0.2075 9 P 0 ;1
L 4.6575 0.2575 4.6575 0.2575 9 P 0 ;1
L 4.6575 0.3075 4.6575 0.3075 9 P 0 ;1
L 4.6575 0.3575 4.6575 0.3575 9 P 0 ;1
L 4.6575 0.4075 4.6575 0.4075 9 P 0 ;1
L 4.6575 0.4575 4.6575 0.4575 9 P 0 ;1
L 4.6575 0.5075 4.6575 0.5075 9 P 0 ;1
L 4.6575 0.5575 4.6575 0.5575 9 P 0 ;1
L 4.6575 0.6075 4.6575 0.6075 9 P 0 ;1
L 4.6575 0.6575 4.6575 0.6575 9 P 0 ;1
L 4.6575 0.7075 4.6575 0.7075 9 P 0 ;1
L 4.6575 0.7575 4.6575 0.7575 9 P 0 ;1
L 4.6575 0.8075 4.6575 0.8075 9 P 0 ;1
L 4.6575 0.8575 4.6575 0.8575 9 P 0 ;1
L 4.6575 0.9075 4.6575 0.9075 9 P 0 ;1
L 4.6575 0.9575 4.6575 0.9575 9 P 0 ;1
L 4.6575 1.0075 4.6575 1.0075 9 P 0 ;1
L 4.6575 1.4075 4.6575 1.4075 9 P 0 ;1
L 4.6575 1.6075 4.6575 1.6075 9 P 0 ;1
L 4.6575 1.6575 4.6575 1.6575 9 P 0 ;1
L 4.6575 5.2075 4.6575 5.2075 9 P 0 ;1
L 4.6575 5.2575 4.6575 5.2575 9 P 0 ;1
L 4.6575 5.3075 4.6575 5.3075 9 P 0 ;1
L 4.6575 5.3575 4.6575 5.3575 9 P 0 ;1
L 4.6575 5.4075 4.6575 5.4075 9 P 0 ;1
L 4.6575 5.4575 4.6575 5.4575 9 P 0 ;1
L 4.6575 5.6575 4.6575 5.6575 9 P 0 ;1
L 4.6575 5.7075 4.6575 5.7075 9 P 0 ;1
L 4.6575 5.7575 4.6575 5.7575 9 P 0 ;1
L 4.6575 5.8075 4.6575 5.8075 9 P 0 ;1
L 4.6575 5.8575 4.6575 5.8575 9 P 0 ;1
L 4.6575 5.9075 4.6575 5.9075 9 P 0 ;1
L 4.7075 0.1575 4.7075 0.1575 9 P 0 ;1
L 4.7075 0.2075 4.7075 0.2075 9 P 0 ;1
L 4.7075 0.2575 4.7075 0.2575 9 P 0 ;1
L 4.7075 0.3075 4.7075 0.3075 9 P 0 ;1
L 4.7075 0.3575 4.7075 0.3575 9 P 0 ;1
L 4.7075 0.4075 4.7075 0.4075 9 P 0 ;1
L 4.7075 0.4575 4.7075 0.4575 9 P 0 ;1
L 4.7075 0.5075 4.7075 0.5075 9 P 0 ;1
L 4.7075 0.5575 4.7075 0.5575 9 P 0 ;1
L 4.7075 0.6075 4.7075 0.6075 9 P 0 ;1
L 4.7075 0.6575 4.7075 0.6575 9 P 0 ;1
L 4.7075 0.7075 4.7075 0.7075 9 P 0 ;1
L 4.7075 0.7575 4.7075 0.7575 9 P 0 ;1
L 4.7075 0.8075 4.7075 0.8075 9 P 0 ;1
L 4.7075 0.8575 4.7075 0.8575 9 P 0 ;1
L 4.7075 0.9075 4.7075 0.9075 9 P 0 ;1
L 4.7075 0.9575 4.7075 0.9575 9 P 0 ;1
L 4.7075 5.2075 4.7075 5.2075 9 P 0 ;1
L 4.7075 5.2575 4.7075 5.2575 9 P 0 ;1
L 4.7075 5.3075 4.7075 5.3075 9 P 0 ;1
L 4.7075 5.4575 4.7075 5.4575 9 P 0 ;1
L 4.7075 5.6575 4.7075 5.6575 9 P 0 ;1
L 4.7075 5.7075 4.7075 5.7075 9 P 0 ;1
L 4.7075 5.7575 4.7075 5.7575 9 P 0 ;1
L 4.7075 5.8075 4.7075 5.8075 9 P 0 ;1
L 4.7075 5.8575 4.7075 5.8575 9 P 0 ;1
L 4.7075 5.9075 4.7075 5.9075 9 P 0 ;1
L 4.7575 0.4575 4.7575 0.4575 9 P 0 ;1
L 4.7575 0.5075 4.7575 0.5075 9 P 0 ;1
L 4.7575 0.5575 4.7575 0.5575 9 P 0 ;1
L 4.7575 0.6075 4.7575 0.6075 9 P 0 ;1
L 4.7575 0.6575 4.7575 0.6575 9 P 0 ;1
L 4.7575 0.7075 4.7575 0.7075 9 P 0 ;1
L 4.7575 0.7575 4.7575 0.7575 9 P 0 ;1
L 4.7575 0.8075 4.7575 0.8075 9 P 0 ;1
L 4.7575 0.8575 4.7575 0.8575 9 P 0 ;1
L 4.7575 0.9075 4.7575 0.9075 9 P 0 ;1
L 4.7575 1.3075 4.7575 1.3075 9 P 0 ;1
L 4.7575 5.2075 4.7575 5.2075 9 P 0 ;1
L 4.7575 5.2575 4.7575 5.2575 9 P 0 ;1
L 4.7575 5.4575 4.7575 5.4575 9 P 0 ;1
L 4.7575 5.6075 4.7575 5.6075 9 P 0 ;1
L 4.7575 5.6575 4.7575 5.6575 9 P 0 ;1
L 4.7575 5.7075 4.7575 5.7075 9 P 0 ;1
L 4.7575 5.7575 4.7575 5.7575 9 P 0 ;1
L 4.7575 5.8075 4.7575 5.8075 9 P 0 ;1
L 4.7575 5.8575 4.7575 5.8575 9 P 0 ;1
L 4.7575 5.9075 4.7575 5.9075 9 P 0 ;1
L 4.8075 0.5075 4.8075 0.5075 9 P 0 ;1
L 4.8075 0.5575 4.8075 0.5575 9 P 0 ;1
L 4.8075 0.6075 4.8075 0.6075 9 P 0 ;1
L 4.8075 0.6575 4.8075 0.6575 9 P 0 ;1
L 4.8075 0.7075 4.8075 0.7075 9 P 0 ;1
L 4.8075 0.7575 4.8075 0.7575 9 P 0 ;1
L 4.8075 0.8075 4.8075 0.8075 9 P 0 ;1
L 4.8075 0.8575 4.8075 0.8575 9 P 0 ;1
L 4.8075 1.2575 4.8075 1.2575 9 P 0 ;1
L 4.8075 5.2075 4.8075 5.2075 9 P 0 ;1
L 4.8075 5.2575 4.8075 5.2575 9 P 0 ;1
L 4.8075 5.4575 4.8075 5.4575 9 P 0 ;1
L 4.8075 5.5075 4.8075 5.5075 9 P 0 ;1
L 4.8075 5.5575 4.8075 5.5575 9 P 0 ;1
L 4.8075 5.6075 4.8075 5.6075 9 P 0 ;1
L 4.8075 5.6575 4.8075 5.6575 9 P 0 ;1
L 4.8075 5.7075 4.8075 5.7075 9 P 0 ;1
L 4.8075 5.7575 4.8075 5.7575 9 P 0 ;1
L 4.8075 5.8075 4.8075 5.8075 9 P 0 ;1
L 4.8075 5.8575 4.8075 5.8575 9 P 0 ;1
L 4.8075 5.9075 4.8075 5.9075 9 P 0 ;1
L 4.8575 0.5575 4.8575 0.5575 9 P 0 ;1
L 4.8575 0.6075 4.8575 0.6075 9 P 0 ;1
L 4.8575 0.6575 4.8575 0.6575 9 P 0 ;1
L 4.8575 0.7075 4.8575 0.7075 9 P 0 ;1
L 4.8575 0.7575 4.8575 0.7575 9 P 0 ;1
L 4.8575 0.8075 4.8575 0.8075 9 P 0 ;1
L 4.8575 1.2075 4.8575 1.2075 9 P 0 ;1
L 4.8575 1.2575 4.8575 1.2575 9 P 0 ;1
L 4.8575 5.2075 4.8575 5.2075 9 P 0 ;1
L 4.8575 5.2575 4.8575 5.2575 9 P 0 ;1
L 4.8575 5.4575 4.8575 5.4575 9 P 0 ;1
L 4.8575 5.5075 4.8575 5.5075 9 P 0 ;1
L 4.8575 5.5575 4.8575 5.5575 9 P 0 ;1
L 4.8575 5.6075 4.8575 5.6075 9 P 0 ;1
L 4.8575 5.8575 4.8575 5.8575 9 P 0 ;1
L 4.8575 5.9075 4.8575 5.9075 9 P 0 ;1
L 4.9075 0.5575 4.9075 0.5575 9 P 0 ;1
L 4.9075 0.6075 4.9075 0.6075 9 P 0 ;1
L 4.9075 0.6575 4.9075 0.6575 9 P 0 ;1
L 4.9075 0.7075 4.9075 0.7075 9 P 0 ;1
L 4.9075 0.7575 4.9075 0.7575 9 P 0 ;1
L 4.9075 0.8075 4.9075 0.8075 9 P 0 ;1
L 4.9075 1.1575 4.9075 1.1575 9 P 0 ;1
L 4.9075 1.2075 4.9075 1.2075 9 P 0 ;1
L 4.9075 1.2575 4.9075 1.2575 9 P 0 ;1
L 4.9075 1.3075 4.9075 1.3075 9 P 0 ;1
L 4.9075 5.2075 4.9075 5.2075 9 P 0 ;1
L 4.9075 5.2575 4.9075 5.2575 9 P 0 ;1
L 4.9075 5.6075 4.9075 5.6075 9 P 0 ;1
L 4.9075 5.8575 4.9075 5.8575 9 P 0 ;1
L 4.9075 5.9075 4.9075 5.9075 9 P 0 ;1
L 4.9575 0.5575 4.9575 0.5575 9 P 0 ;1
L 4.9575 0.6075 4.9575 0.6075 9 P 0 ;1
L 4.9575 0.6575 4.9575 0.6575 9 P 0 ;1
L 4.9575 0.7075 4.9575 0.7075 9 P 0 ;1
L 4.9575 0.7575 4.9575 0.7575 9 P 0 ;1
L 4.9575 0.8075 4.9575 0.8075 9 P 0 ;1
L 4.9575 1.1075 4.9575 1.1075 9 P 0 ;1
L 4.9575 1.1575 4.9575 1.1575 9 P 0 ;1
L 4.9575 1.2075 4.9575 1.2075 9 P 0 ;1
L 4.9575 1.2575 4.9575 1.2575 9 P 0 ;1
L 4.9575 1.3075 4.9575 1.3075 9 P 0 ;1
L 4.9575 5.2575 4.9575 5.2575 9 P 0 ;1
L 4.9575 5.6075 4.9575 5.6075 9 P 0 ;1
L 4.9575 5.8575 4.9575 5.8575 9 P 0 ;1
L 4.9575 5.9075 4.9575 5.9075 9 P 0 ;1
L 5.0075 0.5575 5.0075 0.5575 9 P 0 ;1
L 5.0075 0.6075 5.0075 0.6075 9 P 0 ;1
L 5.0075 0.6575 5.0075 0.6575 9 P 0 ;1
L 5.0075 0.7075 5.0075 0.7075 9 P 0 ;1
L 5.0075 0.7575 5.0075 0.7575 9 P 0 ;1
L 5.0075 0.8075 5.0075 0.8075 9 P 0 ;1
L 5.0075 1.1075 5.0075 1.1075 9 P 0 ;1
L 5.0075 1.1575 5.0075 1.1575 9 P 0 ;1
L 5.0075 1.2075 5.0075 1.2075 9 P 0 ;1
L 5.0075 1.2575 5.0075 1.2575 9 P 0 ;1
L 5.0075 1.3075 5.0075 1.3075 9 P 0 ;1
L 5.0075 1.3575 5.0075 1.3575 9 P 0 ;1
L 5.0075 1.4075 5.0075 1.4075 9 P 0 ;1
L 5.0075 1.6075 5.0075 1.6075 9 P 0 ;1
L 5.0075 1.6575 5.0075 1.6575 9 P 0 ;1
L 5.0075 5.2575 5.0075 5.2575 9 P 0 ;1
L 5.0075 5.3075 5.0075 5.3075 9 P 0 ;1
L 5.0075 5.7075 5.0075 5.7075 9 P 0 ;1
L 5.0075 5.7575 5.0075 5.7575 9 P 0 ;1
L 5.0075 5.8075 5.0075 5.8075 9 P 0 ;1
L 5.0075 5.8575 5.0075 5.8575 9 P 0 ;1
L 5.0075 5.9075 5.0075 5.9075 9 P 0 ;1
L 5.0575 0.5575 5.0575 0.5575 9 P 0 ;1
L 5.0575 0.6075 5.0575 0.6075 9 P 0 ;1
L 5.0575 0.6575 5.0575 0.6575 9 P 0 ;1
L 5.0575 0.7075 5.0575 0.7075 9 P 0 ;1
L 5.0575 0.7575 5.0575 0.7575 9 P 0 ;1
L 5.0575 0.8075 5.0575 0.8075 9 P 0 ;1
L 5.0575 1.1075 5.0575 1.1075 9 P 0 ;1
L 5.0575 1.1575 5.0575 1.1575 9 P 0 ;1
L 5.0575 1.2075 5.0575 1.2075 9 P 0 ;1
L 5.0575 1.2575 5.0575 1.2575 9 P 0 ;1
L 5.0575 1.3075 5.0575 1.3075 9 P 0 ;1
L 5.0575 1.3575 5.0575 1.3575 9 P 0 ;1
L 5.0575 1.4075 5.0575 1.4075 9 P 0 ;1
L 5.0575 1.4575 5.0575 1.4575 9 P 0 ;1
L 5.0575 1.5075 5.0575 1.5075 9 P 0 ;1
L 5.0575 1.5575 5.0575 1.5575 9 P 0 ;1
L 5.0575 1.6075 5.0575 1.6075 9 P 0 ;1
L 5.0575 1.6575 5.0575 1.6575 9 P 0 ;1
L 5.0575 5.2575 5.0575 5.2575 9 P 0 ;1
L 5.0575 5.3075 5.0575 5.3075 9 P 0 ;1
L 5.0575 5.5075 5.0575 5.5075 9 P 0 ;1
L 5.0575 5.8575 5.0575 5.8575 9 P 0 ;1
L 5.0575 5.9075 5.0575 5.9075 9 P 0 ;1
L 5.1075 0.5575 5.1075 0.5575 9 P 0 ;1
L 5.1075 0.6075 5.1075 0.6075 9 P 0 ;1
L 5.1075 0.6575 5.1075 0.6575 9 P 0 ;1
L 5.1075 0.7075 5.1075 0.7075 9 P 0 ;1
L 5.1075 0.7575 5.1075 0.7575 9 P 0 ;1
L 5.1075 0.8075 5.1075 0.8075 9 P 0 ;1
L 5.1075 1.1075 5.1075 1.1075 9 P 0 ;1
L 5.1075 1.1575 5.1075 1.1575 9 P 0 ;1
L 5.1075 1.2075 5.1075 1.2075 9 P 0 ;1
L 5.1075 1.2575 5.1075 1.2575 9 P 0 ;1
L 5.1075 1.3075 5.1075 1.3075 9 P 0 ;1
L 5.1075 1.3575 5.1075 1.3575 9 P 0 ;1
L 5.1075 1.4075 5.1075 1.4075 9 P 0 ;1
L 5.1075 1.4575 5.1075 1.4575 9 P 0 ;1
L 5.1075 1.5075 5.1075 1.5075 9 P 0 ;1
L 5.1075 1.5575 5.1075 1.5575 9 P 0 ;1
L 5.1075 1.6075 5.1075 1.6075 9 P 0 ;1
L 5.1075 1.6575 5.1075 1.6575 9 P 0 ;1
L 5.1075 5.2575 5.1075 5.2575 9 P 0 ;1
L 5.1075 5.3075 5.1075 5.3075 9 P 0 ;1
L 5.1075 5.8575 5.1075 5.8575 9 P 0 ;1
L 5.1075 5.9075 5.1075 5.9075 9 P 0 ;1
L 5.1575 0.5575 5.1575 0.5575 9 P 0 ;1
L 5.1575 0.6075 5.1575 0.6075 9 P 0 ;1
L 5.1575 0.6575 5.1575 0.6575 9 P 0 ;1
L 5.1575 0.7075 5.1575 0.7075 9 P 0 ;1
L 5.1575 0.7575 5.1575 0.7575 9 P 0 ;1
L 5.1575 0.8075 5.1575 0.8075 9 P 0 ;1
L 5.1575 1.1075 5.1575 1.1075 9 P 0 ;1
L 5.1575 1.1575 5.1575 1.1575 9 P 0 ;1
L 5.1575 1.2075 5.1575 1.2075 9 P 0 ;1
L 5.1575 1.2575 5.1575 1.2575 9 P 0 ;1
L 5.1575 1.3075 5.1575 1.3075 9 P 0 ;1
L 5.1575 1.3575 5.1575 1.3575 9 P 0 ;1
L 5.1575 1.4075 5.1575 1.4075 9 P 0 ;1
L 5.1575 1.4575 5.1575 1.4575 9 P 0 ;1
L 5.1575 1.5075 5.1575 1.5075 9 P 0 ;1
L 5.1575 1.5575 5.1575 1.5575 9 P 0 ;1
L 5.1575 1.6075 5.1575 1.6075 9 P 0 ;1
L 5.1575 1.6575 5.1575 1.6575 9 P 0 ;1
L 5.1575 2.8575 5.1575 2.8575 9 P 0 ;1
L 5.1575 5.2575 5.1575 5.2575 9 P 0 ;1
L 5.1575 5.3075 5.1575 5.3075 9 P 0 ;1
L 5.1575 5.8075 5.1575 5.8075 9 P 0 ;1
L 5.1575 5.8575 5.1575 5.8575 9 P 0 ;1
L 5.1575 5.9075 5.1575 5.9075 9 P 0 ;1
L 5.2075 0.5575 5.2075 0.5575 9 P 0 ;1
L 5.2075 0.6075 5.2075 0.6075 9 P 0 ;1
L 5.2075 0.6575 5.2075 0.6575 9 P 0 ;1
L 5.2075 0.7075 5.2075 0.7075 9 P 0 ;1
L 5.2075 0.7575 5.2075 0.7575 9 P 0 ;1
L 5.2075 0.8075 5.2075 0.8075 9 P 0 ;1
L 5.2075 1.1075 5.2075 1.1075 9 P 0 ;1
L 5.2075 1.1575 5.2075 1.1575 9 P 0 ;1
L 5.2075 1.2075 5.2075 1.2075 9 P 0 ;1
L 5.2075 1.2575 5.2075 1.2575 9 P 0 ;1
L 5.2075 1.3075 5.2075 1.3075 9 P 0 ;1
L 5.2075 1.3575 5.2075 1.3575 9 P 0 ;1
L 5.2075 1.4075 5.2075 1.4075 9 P 0 ;1
L 5.2075 1.4575 5.2075 1.4575 9 P 0 ;1
L 5.2075 1.5075 5.2075 1.5075 9 P 0 ;1
L 5.2075 1.5575 5.2075 1.5575 9 P 0 ;1
L 5.2075 1.6075 5.2075 1.6075 9 P 0 ;1
L 5.2075 1.6575 5.2075 1.6575 9 P 0 ;1
L 5.2075 1.7075 5.2075 1.7075 9 P 0 ;1
L 5.2075 2.8075 5.2075 2.8075 9 P 0 ;1
L 5.2075 2.8575 5.2075 2.8575 9 P 0 ;1
L 5.2075 5.2575 5.2075 5.2575 9 P 0 ;1
L 5.2075 5.3075 5.2075 5.3075 9 P 0 ;1
L 5.2075 5.3575 5.2075 5.3575 9 P 0 ;1
L 5.2075 5.4075 5.2075 5.4075 9 P 0 ;1
L 5.2075 5.4575 5.2075 5.4575 9 P 0 ;1
L 5.2075 5.7575 5.2075 5.7575 9 P 0 ;1
L 5.2075 5.8075 5.2075 5.8075 9 P 0 ;1
L 5.2075 5.8575 5.2075 5.8575 9 P 0 ;1
L 5.2075 5.9075 5.2075 5.9075 9 P 0 ;1
L 5.2575 0.5575 5.2575 0.5575 9 P 0 ;1
L 5.2575 0.6075 5.2575 0.6075 9 P 0 ;1
L 5.2575 0.6575 5.2575 0.6575 9 P 0 ;1
L 5.2575 0.7075 5.2575 0.7075 9 P 0 ;1
L 5.2575 0.7575 5.2575 0.7575 9 P 0 ;1
L 5.2575 0.8075 5.2575 0.8075 9 P 0 ;1
L 5.2575 1.1075 5.2575 1.1075 9 P 0 ;1
L 5.2575 1.1575 5.2575 1.1575 9 P 0 ;1
L 5.2575 1.2075 5.2575 1.2075 9 P 0 ;1
L 5.2575 1.2575 5.2575 1.2575 9 P 0 ;1
L 5.2575 1.3075 5.2575 1.3075 9 P 0 ;1
L 5.2575 1.3575 5.2575 1.3575 9 P 0 ;1
L 5.2575 1.4075 5.2575 1.4075 9 P 0 ;1
L 5.2575 1.4575 5.2575 1.4575 9 P 0 ;1
L 5.2575 1.5075 5.2575 1.5075 9 P 0 ;1
L 5.2575 1.5575 5.2575 1.5575 9 P 0 ;1
L 5.2575 1.6075 5.2575 1.6075 9 P 0 ;1
L 5.2575 1.6575 5.2575 1.6575 9 P 0 ;1
L 5.2575 1.7075 5.2575 1.7075 9 P 0 ;1
L 5.2575 1.7575 5.2575 1.7575 9 P 0 ;1
L 5.2575 1.8075 5.2575 1.8075 9 P 0 ;1
L 5.2575 1.8575 5.2575 1.8575 9 P 0 ;1
L 5.2575 1.9075 5.2575 1.9075 9 P 0 ;1
L 5.2575 1.9575 5.2575 1.9575 9 P 0 ;1
L 5.2575 2.0075 5.2575 2.0075 9 P 0 ;1
L 5.2575 2.0575 5.2575 2.0575 9 P 0 ;1
L 5.2575 2.1075 5.2575 2.1075 9 P 0 ;1
L 5.2575 2.1575 5.2575 2.1575 9 P 0 ;1
L 5.2575 2.2075 5.2575 2.2075 9 P 0 ;1
L 5.2575 2.2575 5.2575 2.2575 9 P 0 ;1
L 5.2575 2.3075 5.2575 2.3075 9 P 0 ;1
L 5.2575 2.3575 5.2575 2.3575 9 P 0 ;1
L 5.2575 2.4075 5.2575 2.4075 9 P 0 ;1
L 5.2575 2.4575 5.2575 2.4575 9 P 0 ;1
L 5.2575 2.5075 5.2575 2.5075 9 P 0 ;1
L 5.2575 2.5575 5.2575 2.5575 9 P 0 ;1
L 5.2575 2.6075 5.2575 2.6075 9 P 0 ;1
L 5.2575 2.6575 5.2575 2.6575 9 P 0 ;1
L 5.2575 2.7075 5.2575 2.7075 9 P 0 ;1
L 5.2575 2.7575 5.2575 2.7575 9 P 0 ;1
L 5.2575 2.8075 5.2575 2.8075 9 P 0 ;1
L 5.2575 2.8575 5.2575 2.8575 9 P 0 ;1
L 5.2575 5.2575 5.2575 5.2575 9 P 0 ;1
L 5.2575 5.3075 5.2575 5.3075 9 P 0 ;1
L 5.2575 5.3575 5.2575 5.3575 9 P 0 ;1
L 5.2575 5.4075 5.2575 5.4075 9 P 0 ;1
L 5.2575 5.4575 5.2575 5.4575 9 P 0 ;1
L 5.2575 5.5075 5.2575 5.5075 9 P 0 ;1
L 5.2575 5.5575 5.2575 5.5575 9 P 0 ;1
L 5.2575 5.6075 5.2575 5.6075 9 P 0 ;1
L 5.2575 5.6575 5.2575 5.6575 9 P 0 ;1
L 5.2575 5.7075 5.2575 5.7075 9 P 0 ;1
L 5.2575 5.7575 5.2575 5.7575 9 P 0 ;1
L 5.2575 5.8075 5.2575 5.8075 9 P 0 ;1
L 5.2575 5.8575 5.2575 5.8575 9 P 0 ;1
L 5.2575 5.9075 5.2575 5.9075 9 P 0 ;1
L 5.3075 0.5575 5.3075 0.5575 9 P 0 ;1
L 5.3075 0.6075 5.3075 0.6075 9 P 0 ;1
L 5.3075 0.6575 5.3075 0.6575 9 P 0 ;1
L 5.3075 0.7075 5.3075 0.7075 9 P 0 ;1
L 5.3075 0.7575 5.3075 0.7575 9 P 0 ;1
L 5.3075 0.8075 5.3075 0.8075 9 P 0 ;1
L 5.3075 1.1075 5.3075 1.1075 9 P 0 ;1
L 5.3075 1.1575 5.3075 1.1575 9 P 0 ;1
L 5.3075 1.2075 5.3075 1.2075 9 P 0 ;1
L 5.3075 1.2575 5.3075 1.2575 9 P 0 ;1
L 5.3075 1.3075 5.3075 1.3075 9 P 0 ;1
L 5.3075 1.3575 5.3075 1.3575 9 P 0 ;1
L 5.3075 1.4075 5.3075 1.4075 9 P 0 ;1
L 5.3075 1.4575 5.3075 1.4575 9 P 0 ;1
L 5.3075 1.5075 5.3075 1.5075 9 P 0 ;1
L 5.3075 1.5575 5.3075 1.5575 9 P 0 ;1
L 5.3075 2.1075 5.3075 2.1075 9 P 0 ;1
L 5.3075 2.6575 5.3075 2.6575 9 P 0 ;1
L 5.3075 2.7075 5.3075 2.7075 9 P 0 ;1
L 5.3075 2.7575 5.3075 2.7575 9 P 0 ;1
L 5.3075 2.8575 5.3075 2.8575 9 P 0 ;1
L 5.3075 3.4075 5.3075 3.4075 9 P 0 ;1
L 5.3075 3.4575 5.3075 3.4575 9 P 0 ;1
L 5.3075 3.5075 5.3075 3.5075 9 P 0 ;1
L 5.3075 3.5575 5.3075 3.5575 9 P 0 ;1
L 5.3075 3.6075 5.3075 3.6075 9 P 0 ;1
L 5.3075 3.6575 5.3075 3.6575 9 P 0 ;1
L 5.3075 3.7075 5.3075 3.7075 9 P 0 ;1
L 5.3075 3.7575 5.3075 3.7575 9 P 0 ;1
L 5.3075 3.8075 5.3075 3.8075 9 P 0 ;1
L 5.3075 3.8575 5.3075 3.8575 9 P 0 ;1
L 5.3075 3.9075 5.3075 3.9075 9 P 0 ;1
L 5.3075 3.9575 5.3075 3.9575 9 P 0 ;1
L 5.3075 4.0075 5.3075 4.0075 9 P 0 ;1
L 5.3075 4.0575 5.3075 4.0575 9 P 0 ;1
L 5.3075 4.1075 5.3075 4.1075 9 P 0 ;1
L 5.3075 4.1575 5.3075 4.1575 9 P 0 ;1
L 5.3075 4.2075 5.3075 4.2075 9 P 0 ;1
L 5.3075 4.2575 5.3075 4.2575 9 P 0 ;1
L 5.3075 4.3075 5.3075 4.3075 9 P 0 ;1
L 5.3075 4.3575 5.3075 4.3575 9 P 0 ;1
L 5.3075 4.4075 5.3075 4.4075 9 P 0 ;1
L 5.3075 4.4575 5.3075 4.4575 9 P 0 ;1
L 5.3075 4.5075 5.3075 4.5075 9 P 0 ;1
L 5.3075 4.5575 5.3075 4.5575 9 P 0 ;1
L 5.3075 4.6075 5.3075 4.6075 9 P 0 ;1
L 5.3075 4.6575 5.3075 4.6575 9 P 0 ;1
L 5.3075 4.7075 5.3075 4.7075 9 P 0 ;1
L 5.3075 4.7575 5.3075 4.7575 9 P 0 ;1
L 5.3075 4.8075 5.3075 4.8075 9 P 0 ;1
L 5.3075 4.8575 5.3075 4.8575 9 P 0 ;1
L 5.3075 4.9075 5.3075 4.9075 9 P 0 ;1
L 5.3075 4.9575 5.3075 4.9575 9 P 0 ;1
L 5.3075 5.0075 5.3075 5.0075 9 P 0 ;1
L 5.3075 5.0575 5.3075 5.0575 9 P 0 ;1
L 5.3075 5.1075 5.3075 5.1075 9 P 0 ;1
L 5.3075 5.1575 5.3075 5.1575 9 P 0 ;1
L 5.3075 5.2075 5.3075 5.2075 9 P 0 ;1
L 5.3075 5.2575 5.3075 5.2575 9 P 0 ;1
L 5.3075 5.3075 5.3075 5.3075 9 P 0 ;1
L 5.3075 5.3575 5.3075 5.3575 9 P 0 ;1
L 5.3075 5.4075 5.3075 5.4075 9 P 0 ;1
L 5.3075 5.4575 5.3075 5.4575 9 P 0 ;1
L 5.3075 5.5075 5.3075 5.5075 9 P 0 ;1
L 5.3075 5.5575 5.3075 5.5575 9 P 0 ;1
L 5.3075 5.6075 5.3075 5.6075 9 P 0 ;1
L 5.3075 5.6575 5.3075 5.6575 9 P 0 ;1
L 5.3075 5.7075 5.3075 5.7075 9 P 0 ;1
L 5.3075 5.7575 5.3075 5.7575 9 P 0 ;1
L 5.3075 5.8075 5.3075 5.8075 9 P 0 ;1
L 5.3075 5.8575 5.3075 5.8575 9 P 0 ;1
L 5.3075 5.9075 5.3075 5.9075 9 P 0 ;1
L 5.3575 0.5575 5.3575 0.5575 9 P 0 ;1
L 5.3575 0.6075 5.3575 0.6075 9 P 0 ;1
L 5.3575 0.6575 5.3575 0.6575 9 P 0 ;1
L 5.3575 0.7075 5.3575 0.7075 9 P 0 ;1
L 5.3575 0.7575 5.3575 0.7575 9 P 0 ;1
L 5.3575 0.8075 5.3575 0.8075 9 P 0 ;1
L 5.3575 1.1075 5.3575 1.1075 9 P 0 ;1
L 5.3575 1.1575 5.3575 1.1575 9 P 0 ;1
L 5.3575 1.2075 5.3575 1.2075 9 P 0 ;1
L 5.3575 1.2575 5.3575 1.2575 9 P 0 ;1
L 5.3575 1.3075 5.3575 1.3075 9 P 0 ;1
L 5.3575 1.3575 5.3575 1.3575 9 P 0 ;1
L 5.3575 1.4075 5.3575 1.4075 9 P 0 ;1
L 5.3575 1.4575 5.3575 1.4575 9 P 0 ;1
L 5.3575 1.5075 5.3575 1.5075 9 P 0 ;1
L 5.3575 2.9075 5.3575 2.9075 9 P 0 ;1
L 5.3575 2.9575 5.3575 2.9575 9 P 0 ;1
L 5.3575 3.0075 5.3575 3.0075 9 P 0 ;1
L 5.3575 3.0575 5.3575 3.0575 9 P 0 ;1
L 5.3575 3.1075 5.3575 3.1075 9 P 0 ;1
L 5.3575 3.1575 5.3575 3.1575 9 P 0 ;1
L 5.3575 3.2075 5.3575 3.2075 9 P 0 ;1
L 5.3575 3.2575 5.3575 3.2575 9 P 0 ;1
L 5.3575 3.3075 5.3575 3.3075 9 P 0 ;1
L 5.3575 3.3575 5.3575 3.3575 9 P 0 ;1
L 5.3575 3.4075 5.3575 3.4075 9 P 0 ;1
L 5.3575 3.4575 5.3575 3.4575 9 P 0 ;1
L 5.3575 3.5075 5.3575 3.5075 9 P 0 ;1
L 5.3575 3.5575 5.3575 3.5575 9 P 0 ;1
L 5.3575 3.6075 5.3575 3.6075 9 P 0 ;1
L 5.3575 3.6575 5.3575 3.6575 9 P 0 ;1
L 5.3575 3.7075 5.3575 3.7075 9 P 0 ;1
L 5.3575 3.7575 5.3575 3.7575 9 P 0 ;1
L 5.3575 3.8075 5.3575 3.8075 9 P 0 ;1
L 5.3575 3.8575 5.3575 3.8575 9 P 0 ;1
L 5.3575 3.9075 5.3575 3.9075 9 P 0 ;1
L 5.3575 3.9575 5.3575 3.9575 9 P 0 ;1
L 5.3575 4.0075 5.3575 4.0075 9 P 0 ;1
L 5.3575 4.0575 5.3575 4.0575 9 P 0 ;1
L 5.3575 4.1075 5.3575 4.1075 9 P 0 ;1
L 5.3575 4.1575 5.3575 4.1575 9 P 0 ;1
L 5.3575 4.2075 5.3575 4.2075 9 P 0 ;1
L 5.3575 4.2575 5.3575 4.2575 9 P 0 ;1
L 5.3575 4.3075 5.3575 4.3075 9 P 0 ;1
L 5.3575 4.3575 5.3575 4.3575 9 P 0 ;1
L 5.3575 4.4075 5.3575 4.4075 9 P 0 ;1
L 5.3575 4.4575 5.3575 4.4575 9 P 0 ;1
L 5.3575 4.5075 5.3575 4.5075 9 P 0 ;1
L 5.3575 4.5575 5.3575 4.5575 9 P 0 ;1
L 5.3575 4.6075 5.3575 4.6075 9 P 0 ;1
L 5.3575 4.6575 5.3575 4.6575 9 P 0 ;1
L 5.3575 4.7075 5.3575 4.7075 9 P 0 ;1
L 5.3575 4.7575 5.3575 4.7575 9 P 0 ;1
L 5.3575 4.8075 5.3575 4.8075 9 P 0 ;1
L 5.3575 4.8575 5.3575 4.8575 9 P 0 ;1
L 5.3575 4.9075 5.3575 4.9075 9 P 0 ;1
L 5.3575 4.9575 5.3575 4.9575 9 P 0 ;1
L 5.3575 5.0075 5.3575 5.0075 9 P 0 ;1
L 5.3575 5.0575 5.3575 5.0575 9 P 0 ;1
L 5.3575 5.1075 5.3575 5.1075 9 P 0 ;1
L 5.3575 5.1575 5.3575 5.1575 9 P 0 ;1
L 5.3575 5.2075 5.3575 5.2075 9 P 0 ;1
L 5.3575 5.2575 5.3575 5.2575 9 P 0 ;1
L 5.3575 5.3075 5.3575 5.3075 9 P 0 ;1
L 5.3575 5.3575 5.3575 5.3575 9 P 0 ;1
L 5.3575 5.4075 5.3575 5.4075 9 P 0 ;1
L 5.3575 5.4575 5.3575 5.4575 9 P 0 ;1
L 5.3575 5.5075 5.3575 5.5075 9 P 0 ;1
L 5.3575 5.5575 5.3575 5.5575 9 P 0 ;1
L 5.3575 5.6075 5.3575 5.6075 9 P 0 ;1
L 5.3575 5.6575 5.3575 5.6575 9 P 0 ;1
L 5.3575 5.7075 5.3575 5.7075 9 P 0 ;1
L 5.3575 5.7575 5.3575 5.7575 9 P 0 ;1
L 5.3575 5.8075 5.3575 5.8075 9 P 0 ;1
L 5.3575 5.8575 5.3575 5.8575 9 P 0 ;1
L 5.3575 5.9075 5.3575 5.9075 9 P 0 ;1
L 5.4075 0.5575 5.4075 0.5575 9 P 0 ;1
L 5.4075 0.6075 5.4075 0.6075 9 P 0 ;1
L 5.4075 0.6575 5.4075 0.6575 9 P 0 ;1
L 5.4075 0.7075 5.4075 0.7075 9 P 0 ;1
L 5.4075 0.7575 5.4075 0.7575 9 P 0 ;1
L 5.4075 0.8075 5.4075 0.8075 9 P 0 ;1
L 5.4075 1.1075 5.4075 1.1075 9 P 0 ;1
L 5.4075 1.1575 5.4075 1.1575 9 P 0 ;1
L 5.4075 1.2075 5.4075 1.2075 9 P 0 ;1
L 5.4075 1.2575 5.4075 1.2575 9 P 0 ;1
L 5.4075 1.3075 5.4075 1.3075 9 P 0 ;1
L 5.4075 1.3575 5.4075 1.3575 9 P 0 ;1
L 5.4075 1.4075 5.4075 1.4075 9 P 0 ;1
L 5.4075 1.4575 5.4075 1.4575 9 P 0 ;1
L 5.4075 1.5075 5.4075 1.5075 9 P 0 ;1
L 5.4075 3.4075 5.4075 3.4075 9 P 0 ;1
L 5.4075 3.4575 5.4075 3.4575 9 P 0 ;1
L 5.4075 3.5075 5.4075 3.5075 9 P 0 ;1
L 5.4075 3.5575 5.4075 3.5575 9 P 0 ;1
L 5.4075 3.6075 5.4075 3.6075 9 P 0 ;1
L 5.4075 3.6575 5.4075 3.6575 9 P 0 ;1
L 5.4075 3.7075 5.4075 3.7075 9 P 0 ;1
L 5.4075 3.7575 5.4075 3.7575 9 P 0 ;1
L 5.4075 3.8075 5.4075 3.8075 9 P 0 ;1
L 5.4075 3.8575 5.4075 3.8575 9 P 0 ;1
L 5.4075 3.9075 5.4075 3.9075 9 P 0 ;1
L 5.4075 3.9575 5.4075 3.9575 9 P 0 ;1
L 5.4075 4.0075 5.4075 4.0075 9 P 0 ;1
L 5.4075 4.0575 5.4075 4.0575 9 P 0 ;1
L 5.4075 4.1075 5.4075 4.1075 9 P 0 ;1
L 5.4075 4.1575 5.4075 4.1575 9 P 0 ;1
L 5.4075 4.2075 5.4075 4.2075 9 P 0 ;1
L 5.4075 4.2575 5.4075 4.2575 9 P 0 ;1
L 5.4075 4.3075 5.4075 4.3075 9 P 0 ;1
L 5.4075 4.3575 5.4075 4.3575 9 P 0 ;1
L 5.4075 4.4075 5.4075 4.4075 9 P 0 ;1
L 5.4075 4.4575 5.4075 4.4575 9 P 0 ;1
L 5.4075 4.5075 5.4075 4.5075 9 P 0 ;1
L 5.4075 4.5575 5.4075 4.5575 9 P 0 ;1
L 5.4075 4.6075 5.4075 4.6075 9 P 0 ;1
L 5.4075 4.6575 5.4075 4.6575 9 P 0 ;1
L 5.4075 4.7075 5.4075 4.7075 9 P 0 ;1
L 5.4075 4.7575 5.4075 4.7575 9 P 0 ;1
L 5.4075 4.8075 5.4075 4.8075 9 P 0 ;1
L 5.4075 4.8575 5.4075 4.8575 9 P 0 ;1
L 5.4075 4.9075 5.4075 4.9075 9 P 0 ;1
L 5.4075 4.9575 5.4075 4.9575 9 P 0 ;1
L 5.4075 5.0075 5.4075 5.0075 9 P 0 ;1
L 5.4075 5.0575 5.4075 5.0575 9 P 0 ;1
L 5.4075 5.1075 5.4075 5.1075 9 P 0 ;1
L 5.4075 5.1575 5.4075 5.1575 9 P 0 ;1
L 5.4075 5.2075 5.4075 5.2075 9 P 0 ;1
L 5.4075 5.2575 5.4075 5.2575 9 P 0 ;1
L 5.4075 5.3075 5.4075 5.3075 9 P 0 ;1
L 5.4075 5.3575 5.4075 5.3575 9 P 0 ;1
L 5.4075 5.4075 5.4075 5.4075 9 P 0 ;1
L 5.4075 5.4575 5.4075 5.4575 9 P 0 ;1
L 5.4075 5.5075 5.4075 5.5075 9 P 0 ;1
L 5.4075 5.5575 5.4075 5.5575 9 P 0 ;1
L 5.4075 5.6075 5.4075 5.6075 9 P 0 ;1
L 5.4075 5.6575 5.4075 5.6575 9 P 0 ;1
L 5.4075 5.7075 5.4075 5.7075 9 P 0 ;1
L 5.4075 5.7575 5.4075 5.7575 9 P 0 ;1
L 5.4075 5.8075 5.4075 5.8075 9 P 0 ;1
L 5.4075 5.8575 5.4075 5.8575 9 P 0 ;1
L 5.4075 5.9075 5.4075 5.9075 9 P 0 ;1
L 5.4575 0.5575 5.4575 0.5575 9 P 0 ;1
L 5.4575 0.6075 5.4575 0.6075 9 P 0 ;1
L 5.4575 0.6575 5.4575 0.6575 9 P 0 ;1
L 5.4575 0.7075 5.4575 0.7075 9 P 0 ;1
L 5.4575 0.7575 5.4575 0.7575 9 P 0 ;1
L 5.4575 0.8075 5.4575 0.8075 9 P 0 ;1
L 5.4575 1.1075 5.4575 1.1075 9 P 0 ;1
L 5.4575 1.1575 5.4575 1.1575 9 P 0 ;1
L 5.4575 1.2075 5.4575 1.2075 9 P 0 ;1
L 5.4575 1.2575 5.4575 1.2575 9 P 0 ;1
L 5.4575 1.3075 5.4575 1.3075 9 P 0 ;1
L 5.4575 1.3575 5.4575 1.3575 9 P 0 ;1
L 5.4575 1.4075 5.4575 1.4075 9 P 0 ;1
L 5.4575 1.4575 5.4575 1.4575 9 P 0 ;1
L 5.4575 1.5075 5.4575 1.5075 9 P 0 ;1
L 5.4575 2.8075 5.4575 2.8075 9 P 0 ;1
L 5.4575 2.8575 5.4575 2.8575 9 P 0 ;1
L 5.4575 3.4075 5.4575 3.4075 9 P 0 ;1
L 5.4575 3.4575 5.4575 3.4575 9 P 0 ;1
L 5.4575 3.5075 5.4575 3.5075 9 P 0 ;1
L 5.4575 3.5575 5.4575 3.5575 9 P 0 ;1
L 5.4575 3.6075 5.4575 3.6075 9 P 0 ;1
L 5.4575 3.6575 5.4575 3.6575 9 P 0 ;1
L 5.4575 3.7075 5.4575 3.7075 9 P 0 ;1
L 5.4575 3.7575 5.4575 3.7575 9 P 0 ;1
L 5.4575 3.8075 5.4575 3.8075 9 P 0 ;1
L 5.4575 3.8575 5.4575 3.8575 9 P 0 ;1
L 5.4575 3.9075 5.4575 3.9075 9 P 0 ;1
L 5.4575 3.9575 5.4575 3.9575 9 P 0 ;1
L 5.4575 4.0075 5.4575 4.0075 9 P 0 ;1
L 5.4575 4.0575 5.4575 4.0575 9 P 0 ;1
L 5.4575 4.1075 5.4575 4.1075 9 P 0 ;1
L 5.4575 4.1575 5.4575 4.1575 9 P 0 ;1
L 5.4575 4.2075 5.4575 4.2075 9 P 0 ;1
L 5.4575 4.2575 5.4575 4.2575 9 P 0 ;1
L 5.4575 4.3075 5.4575 4.3075 9 P 0 ;1
L 5.4575 4.3575 5.4575 4.3575 9 P 0 ;1
L 5.4575 4.4075 5.4575 4.4075 9 P 0 ;1
L 5.4575 4.4575 5.4575 4.4575 9 P 0 ;1
L 5.4575 4.5075 5.4575 4.5075 9 P 0 ;1
L 5.4575 4.5575 5.4575 4.5575 9 P 0 ;1
L 5.4575 4.6075 5.4575 4.6075 9 P 0 ;1
L 5.4575 4.6575 5.4575 4.6575 9 P 0 ;1
L 5.4575 4.7075 5.4575 4.7075 9 P 0 ;1
L 5.4575 4.7575 5.4575 4.7575 9 P 0 ;1
L 5.4575 4.8075 5.4575 4.8075 9 P 0 ;1
L 5.4575 4.8575 5.4575 4.8575 9 P 0 ;1
L 5.4575 4.9075 5.4575 4.9075 9 P 0 ;1
L 5.4575 4.9575 5.4575 4.9575 9 P 0 ;1
L 5.4575 5.0075 5.4575 5.0075 9 P 0 ;1
L 5.4575 5.0575 5.4575 5.0575 9 P 0 ;1
L 5.4575 5.1075 5.4575 5.1075 9 P 0 ;1
L 5.4575 5.1575 5.4575 5.1575 9 P 0 ;1
L 5.4575 5.2075 5.4575 5.2075 9 P 0 ;1
L 5.4575 5.2575 5.4575 5.2575 9 P 0 ;1
L 5.4575 5.3075 5.4575 5.3075 9 P 0 ;1
L 5.4575 5.3575 5.4575 5.3575 9 P 0 ;1
L 5.4575 5.4075 5.4575 5.4075 9 P 0 ;1
L 5.4575 5.4575 5.4575 5.4575 9 P 0 ;1
L 5.4575 5.5075 5.4575 5.5075 9 P 0 ;1
L 5.4575 5.5575 5.4575 5.5575 9 P 0 ;1
L 5.4575 5.6075 5.4575 5.6075 9 P 0 ;1
L 5.4575 5.6575 5.4575 5.6575 9 P 0 ;1
L 5.4575 5.7075 5.4575 5.7075 9 P 0 ;1
L 5.4575 5.7575 5.4575 5.7575 9 P 0 ;1
L 5.4575 5.8075 5.4575 5.8075 9 P 0 ;1
L 5.4575 5.8575 5.4575 5.8575 9 P 0 ;1
L 5.4575 5.9075 5.4575 5.9075 9 P 0 ;1
L 5.5075 0.5575 5.5075 0.5575 9 P 0 ;1
L 5.5075 0.6075 5.5075 0.6075 9 P 0 ;1
L 5.5075 0.6575 5.5075 0.6575 9 P 0 ;1
L 5.5075 0.7075 5.5075 0.7075 9 P 0 ;1
L 5.5075 0.7575 5.5075 0.7575 9 P 0 ;1
L 5.5075 0.8075 5.5075 0.8075 9 P 0 ;1
L 5.5075 1.1075 5.5075 1.1075 9 P 0 ;1
L 5.5075 1.1575 5.5075 1.1575 9 P 0 ;1
L 5.5075 1.2075 5.5075 1.2075 9 P 0 ;1
L 5.5075 1.2575 5.5075 1.2575 9 P 0 ;1
L 5.5075 1.3075 5.5075 1.3075 9 P 0 ;1
L 5.5075 1.3575 5.5075 1.3575 9 P 0 ;1
L 5.5075 1.4075 5.5075 1.4075 9 P 0 ;1
L 5.5075 1.4575 5.5075 1.4575 9 P 0 ;1
L 5.5075 1.5075 5.5075 1.5075 9 P 0 ;1
L 5.5075 1.5575 5.5075 1.5575 9 P 0 ;1
L 5.5075 3.3575 5.5075 3.3575 9 P 0 ;1
L 5.5075 3.4075 5.5075 3.4075 9 P 0 ;1
L 5.5075 3.4575 5.5075 3.4575 9 P 0 ;1
L 5.5075 3.5075 5.5075 3.5075 9 P 0 ;1
L 5.5075 3.5575 5.5075 3.5575 9 P 0 ;1
L 5.5075 3.6075 5.5075 3.6075 9 P 0 ;1
L 5.5075 3.6575 5.5075 3.6575 9 P 0 ;1
L 5.5075 3.7075 5.5075 3.7075 9 P 0 ;1
L 5.5075 3.7575 5.5075 3.7575 9 P 0 ;1
L 5.5075 3.8075 5.5075 3.8075 9 P 0 ;1
L 5.5075 3.8575 5.5075 3.8575 9 P 0 ;1
L 5.5075 3.9075 5.5075 3.9075 9 P 0 ;1
L 5.5075 3.9575 5.5075 3.9575 9 P 0 ;1
L 5.5075 4.0075 5.5075 4.0075 9 P 0 ;1
L 5.5075 4.0575 5.5075 4.0575 9 P 0 ;1
L 5.5075 4.1075 5.5075 4.1075 9 P 0 ;1
L 5.5075 4.1575 5.5075 4.1575 9 P 0 ;1
L 5.5075 4.2075 5.5075 4.2075 9 P 0 ;1
L 5.5075 4.2575 5.5075 4.2575 9 P 0 ;1
L 5.5075 4.3075 5.5075 4.3075 9 P 0 ;1
L 5.5075 4.3575 5.5075 4.3575 9 P 0 ;1
L 5.5075 4.4075 5.5075 4.4075 9 P 0 ;1
L 5.5075 4.4575 5.5075 4.4575 9 P 0 ;1
L 5.5075 4.7575 5.5075 4.7575 9 P 0 ;1
L 5.5075 4.8075 5.5075 4.8075 9 P 0 ;1
L 5.5075 4.8575 5.5075 4.8575 9 P 0 ;1
L 5.5075 4.9075 5.5075 4.9075 9 P 0 ;1
L 5.5075 4.9575 5.5075 4.9575 9 P 0 ;1
L 5.5075 5.0075 5.5075 5.0075 9 P 0 ;1
L 5.5075 5.0575 5.5075 5.0575 9 P 0 ;1
L 5.5075 5.1075 5.5075 5.1075 9 P 0 ;1
L 5.5075 5.1575 5.5075 5.1575 9 P 0 ;1
L 5.5075 5.2075 5.5075 5.2075 9 P 0 ;1
L 5.5075 5.2575 5.5075 5.2575 9 P 0 ;1
L 5.5075 5.3075 5.5075 5.3075 9 P 0 ;1
L 5.5075 5.3575 5.5075 5.3575 9 P 0 ;1
L 5.5075 5.4075 5.5075 5.4075 9 P 0 ;1
L 5.5075 5.4575 5.5075 5.4575 9 P 0 ;1
L 5.5075 5.5075 5.5075 5.5075 9 P 0 ;1
L 5.5075 5.5575 5.5075 5.5575 9 P 0 ;1
L 5.5075 5.6075 5.5075 5.6075 9 P 0 ;1
L 5.5075 5.6575 5.5075 5.6575 9 P 0 ;1
L 5.5075 5.7075 5.5075 5.7075 9 P 0 ;1
L 5.5075 5.7575 5.5075 5.7575 9 P 0 ;1
L 5.5075 5.8075 5.5075 5.8075 9 P 0 ;1
L 5.5075 5.8575 5.5075 5.8575 9 P 0 ;1
L 5.5075 5.9075 5.5075 5.9075 9 P 0 ;1
L 5.5575 0.5575 5.5575 0.5575 9 P 0 ;1
L 5.5575 0.6075 5.5575 0.6075 9 P 0 ;1
L 5.5575 0.6575 5.5575 0.6575 9 P 0 ;1
L 5.5575 0.7075 5.5575 0.7075 9 P 0 ;1
L 5.5575 0.7575 5.5575 0.7575 9 P 0 ;1
L 5.5575 0.8075 5.5575 0.8075 9 P 0 ;1
L 5.5575 1.1075 5.5575 1.1075 9 P 0 ;1
L 5.5575 1.1575 5.5575 1.1575 9 P 0 ;1
L 5.5575 1.2075 5.5575 1.2075 9 P 0 ;1
L 5.5575 1.2575 5.5575 1.2575 9 P 0 ;1
L 5.5575 1.3075 5.5575 1.3075 9 P 0 ;1
L 5.5575 1.3575 5.5575 1.3575 9 P 0 ;1
L 5.5575 1.4075 5.5575 1.4075 9 P 0 ;1
L 5.5575 1.4575 5.5575 1.4575 9 P 0 ;1
L 5.5575 1.5075 5.5575 1.5075 9 P 0 ;1
L 5.5575 1.5575 5.5575 1.5575 9 P 0 ;1
L 5.5575 3.1075 5.5575 3.1075 9 P 0 ;1
L 5.5575 3.1575 5.5575 3.1575 9 P 0 ;1
L 5.5575 3.2075 5.5575 3.2075 9 P 0 ;1
L 5.5575 3.2575 5.5575 3.2575 9 P 0 ;1
L 5.5575 3.3075 5.5575 3.3075 9 P 0 ;1
L 5.5575 3.3575 5.5575 3.3575 9 P 0 ;1
L 5.5575 3.4075 5.5575 3.4075 9 P 0 ;1
L 5.5575 3.4575 5.5575 3.4575 9 P 0 ;1
L 5.5575 3.5075 5.5575 3.5075 9 P 0 ;1
L 5.5575 3.5575 5.5575 3.5575 9 P 0 ;1
L 5.5575 3.6075 5.5575 3.6075 9 P 0 ;1
L 5.5575 3.6575 5.5575 3.6575 9 P 0 ;1
L 5.5575 3.7075 5.5575 3.7075 9 P 0 ;1
L 5.5575 3.7575 5.5575 3.7575 9 P 0 ;1
L 5.5575 3.8075 5.5575 3.8075 9 P 0 ;1
L 5.5575 3.8575 5.5575 3.8575 9 P 0 ;1
L 5.5575 3.9075 5.5575 3.9075 9 P 0 ;1
L 5.5575 3.9575 5.5575 3.9575 9 P 0 ;1
L 5.5575 4.0075 5.5575 4.0075 9 P 0 ;1
L 5.5575 4.0575 5.5575 4.0575 9 P 0 ;1
L 5.5575 4.1075 5.5575 4.1075 9 P 0 ;1
L 5.5575 4.1575 5.5575 4.1575 9 P 0 ;1
L 5.5575 4.2075 5.5575 4.2075 9 P 0 ;1
L 5.5575 4.2575 5.5575 4.2575 9 P 0 ;1
L 5.5575 4.3075 5.5575 4.3075 9 P 0 ;1
L 5.5575 4.3575 5.5575 4.3575 9 P 0 ;1
L 5.5575 4.4075 5.5575 4.4075 9 P 0 ;1
L 5.5575 4.9075 5.5575 4.9075 9 P 0 ;1
L 5.5575 4.9575 5.5575 4.9575 9 P 0 ;1
L 5.5575 5.0075 5.5575 5.0075 9 P 0 ;1
L 5.5575 5.0575 5.5575 5.0575 9 P 0 ;1
L 5.5575 5.1075 5.5575 5.1075 9 P 0 ;1
L 5.5575 5.1575 5.5575 5.1575 9 P 0 ;1
L 5.5575 5.2075 5.5575 5.2075 9 P 0 ;1
L 5.5575 5.2575 5.5575 5.2575 9 P 0 ;1
L 5.5575 5.6075 5.5575 5.6075 9 P 0 ;1
L 5.5575 5.6575 5.5575 5.6575 9 P 0 ;1
L 5.5575 5.7075 5.5575 5.7075 9 P 0 ;1
L 5.5575 5.7575 5.5575 5.7575 9 P 0 ;1
L 5.5575 5.8075 5.5575 5.8075 9 P 0 ;1
L 5.5575 5.8575 5.5575 5.8575 9 P 0 ;1
L 5.5575 5.9075 5.5575 5.9075 9 P 0 ;1
L 5.6075 0.5575 5.6075 0.5575 9 P 0 ;1
L 5.6075 0.6075 5.6075 0.6075 9 P 0 ;1
L 5.6075 0.6575 5.6075 0.6575 9 P 0 ;1
L 5.6075 0.7075 5.6075 0.7075 9 P 0 ;1
L 5.6075 0.7575 5.6075 0.7575 9 P 0 ;1
L 5.6075 0.8075 5.6075 0.8075 9 P 0 ;1
L 5.6075 1.1075 5.6075 1.1075 9 P 0 ;1
L 5.6075 1.1575 5.6075 1.1575 9 P 0 ;1
L 5.6075 1.2075 5.6075 1.2075 9 P 0 ;1
L 5.6075 1.2575 5.6075 1.2575 9 P 0 ;1
L 5.6075 1.3075 5.6075 1.3075 9 P 0 ;1
L 5.6075 1.3575 5.6075 1.3575 9 P 0 ;1
L 5.6075 1.4075 5.6075 1.4075 9 P 0 ;1
L 5.6075 1.4575 5.6075 1.4575 9 P 0 ;1
L 5.6075 1.5075 5.6075 1.5075 9 P 0 ;1
L 5.6075 1.5575 5.6075 1.5575 9 P 0 ;1
L 5.6075 3.1075 5.6075 3.1075 9 P 0 ;1
L 5.6075 3.1575 5.6075 3.1575 9 P 0 ;1
L 5.6075 3.2075 5.6075 3.2075 9 P 0 ;1
L 5.6075 3.2575 5.6075 3.2575 9 P 0 ;1
L 5.6075 3.3075 5.6075 3.3075 9 P 0 ;1
L 5.6075 3.3575 5.6075 3.3575 9 P 0 ;1
L 5.6075 3.4075 5.6075 3.4075 9 P 0 ;1
L 5.6075 3.4575 5.6075 3.4575 9 P 0 ;1
L 5.6075 3.5075 5.6075 3.5075 9 P 0 ;1
L 5.6075 3.5575 5.6075 3.5575 9 P 0 ;1
L 5.6075 3.6075 5.6075 3.6075 9 P 0 ;1
L 5.6075 3.6575 5.6075 3.6575 9 P 0 ;1
L 5.6075 3.7075 5.6075 3.7075 9 P 0 ;1
L 5.6075 3.7575 5.6075 3.7575 9 P 0 ;1
L 5.6075 3.8075 5.6075 3.8075 9 P 0 ;1
L 5.6075 3.8575 5.6075 3.8575 9 P 0 ;1
L 5.6075 3.9075 5.6075 3.9075 9 P 0 ;1
L 5.6075 3.9575 5.6075 3.9575 9 P 0 ;1
L 5.6075 4.0075 5.6075 4.0075 9 P 0 ;1
L 5.6075 4.0575 5.6075 4.0575 9 P 0 ;1
L 5.6075 4.1075 5.6075 4.1075 9 P 0 ;1
L 5.6075 4.1575 5.6075 4.1575 9 P 0 ;1
L 5.6075 4.2075 5.6075 4.2075 9 P 0 ;1
L 5.6075 4.2575 5.6075 4.2575 9 P 0 ;1
L 5.6075 4.3075 5.6075 4.3075 9 P 0 ;1
L 5.6075 4.3575 5.6075 4.3575 9 P 0 ;1
L 5.6075 4.4075 5.6075 4.4075 9 P 0 ;1
L 5.6075 4.9075 5.6075 4.9075 9 P 0 ;1
L 5.6075 4.9575 5.6075 4.9575 9 P 0 ;1
L 5.6075 5.0075 5.6075 5.0075 9 P 0 ;1
L 5.6075 5.0575 5.6075 5.0575 9 P 0 ;1
L 5.6075 5.1075 5.6075 5.1075 9 P 0 ;1
L 5.6075 5.1575 5.6075 5.1575 9 P 0 ;1
L 5.6075 5.2075 5.6075 5.2075 9 P 0 ;1
L 5.6075 5.6575 5.6075 5.6575 9 P 0 ;1
L 5.6075 5.7075 5.6075 5.7075 9 P 0 ;1
L 5.6075 5.7575 5.6075 5.7575 9 P 0 ;1
L 5.6075 5.8075 5.6075 5.8075 9 P 0 ;1
L 5.6075 5.8575 5.6075 5.8575 9 P 0 ;1
L 5.6075 5.9075 5.6075 5.9075 9 P 0 ;1
L 5.6575 0.5575 5.6575 0.5575 9 P 0 ;1
L 5.6575 0.6075 5.6575 0.6075 9 P 0 ;1
L 5.6575 0.6575 5.6575 0.6575 9 P 0 ;1
L 5.6575 0.7075 5.6575 0.7075 9 P 0 ;1
L 5.6575 0.7575 5.6575 0.7575 9 P 0 ;1
L 5.6575 0.8075 5.6575 0.8075 9 P 0 ;1
L 5.6575 1.1075 5.6575 1.1075 9 P 0 ;1
L 5.6575 1.1575 5.6575 1.1575 9 P 0 ;1
L 5.6575 1.2075 5.6575 1.2075 9 P 0 ;1
L 5.6575 1.2575 5.6575 1.2575 9 P 0 ;1
L 5.6575 1.3075 5.6575 1.3075 9 P 0 ;1
L 5.6575 1.3575 5.6575 1.3575 9 P 0 ;1
L 5.6575 1.4075 5.6575 1.4075 9 P 0 ;1
L 5.6575 1.4575 5.6575 1.4575 9 P 0 ;1
L 5.6575 1.5075 5.6575 1.5075 9 P 0 ;1
L 5.6575 1.5575 5.6575 1.5575 9 P 0 ;1
L 5.6575 1.6075 5.6575 1.6075 9 P 0 ;1
L 5.6575 1.6575 5.6575 1.6575 9 P 0 ;1
L 5.6575 1.7075 5.6575 1.7075 9 P 0 ;1
L 5.6575 1.7575 5.6575 1.7575 9 P 0 ;1
L 5.6575 1.8075 5.6575 1.8075 9 P 0 ;1
L 5.6575 1.8575 5.6575 1.8575 9 P 0 ;1
L 5.6575 1.9075 5.6575 1.9075 9 P 0 ;1
L 5.6575 1.9575 5.6575 1.9575 9 P 0 ;1
L 5.6575 2.0075 5.6575 2.0075 9 P 0 ;1
L 5.6575 2.0575 5.6575 2.0575 9 P 0 ;1
L 5.6575 2.1075 5.6575 2.1075 9 P 0 ;1
L 5.6575 2.1575 5.6575 2.1575 9 P 0 ;1
L 5.6575 2.2075 5.6575 2.2075 9 P 0 ;1
L 5.6575 2.2575 5.6575 2.2575 9 P 0 ;1
L 5.6575 2.3075 5.6575 2.3075 9 P 0 ;1
L 5.6575 2.3575 5.6575 2.3575 9 P 0 ;1
L 5.6575 2.4075 5.6575 2.4075 9 P 0 ;1
L 5.6575 2.4575 5.6575 2.4575 9 P 0 ;1
L 5.6575 2.5075 5.6575 2.5075 9 P 0 ;1
L 5.6575 2.5575 5.6575 2.5575 9 P 0 ;1
L 5.6575 2.6075 5.6575 2.6075 9 P 0 ;1
L 5.6575 2.6575 5.6575 2.6575 9 P 0 ;1
L 5.6575 2.7075 5.6575 2.7075 9 P 0 ;1
L 5.6575 2.7575 5.6575 2.7575 9 P 0 ;1
L 5.6575 2.9575 5.6575 2.9575 9 P 0 ;1
L 5.6575 3.0075 5.6575 3.0075 9 P 0 ;1
L 5.6575 3.0575 5.6575 3.0575 9 P 0 ;1
L 5.6575 3.1075 5.6575 3.1075 9 P 0 ;1
L 5.6575 3.1575 5.6575 3.1575 9 P 0 ;1
L 5.6575 3.2075 5.6575 3.2075 9 P 0 ;1
L 5.6575 3.2575 5.6575 3.2575 9 P 0 ;1
L 5.6575 3.3075 5.6575 3.3075 9 P 0 ;1
L 5.6575 3.3575 5.6575 3.3575 9 P 0 ;1
L 5.6575 3.4075 5.6575 3.4075 9 P 0 ;1
L 5.6575 3.4575 5.6575 3.4575 9 P 0 ;1
L 5.6575 3.5075 5.6575 3.5075 9 P 0 ;1
L 5.6575 3.5575 5.6575 3.5575 9 P 0 ;1
L 5.6575 3.6075 5.6575 3.6075 9 P 0 ;1
L 5.6575 3.6575 5.6575 3.6575 9 P 0 ;1
L 5.6575 3.7075 5.6575 3.7075 9 P 0 ;1
L 5.6575 3.7575 5.6575 3.7575 9 P 0 ;1
L 5.6575 3.8075 5.6575 3.8075 9 P 0 ;1
L 5.6575 3.8575 5.6575 3.8575 9 P 0 ;1
L 5.6575 3.9075 5.6575 3.9075 9 P 0 ;1
L 5.6575 3.9575 5.6575 3.9575 9 P 0 ;1
L 5.6575 4.0075 5.6575 4.0075 9 P 0 ;1
L 5.6575 4.0575 5.6575 4.0575 9 P 0 ;1
L 5.6575 4.1075 5.6575 4.1075 9 P 0 ;1
L 5.6575 4.1575 5.6575 4.1575 9 P 0 ;1
L 5.6575 4.2075 5.6575 4.2075 9 P 0 ;1
L 5.6575 4.2575 5.6575 4.2575 9 P 0 ;1
L 5.6575 4.3075 5.6575 4.3075 9 P 0 ;1
L 5.6575 4.3575 5.6575 4.3575 9 P 0 ;1
L 5.6575 4.4075 5.6575 4.4075 9 P 0 ;1
L 5.6575 4.9075 5.6575 4.9075 9 P 0 ;1
L 5.6575 4.9575 5.6575 4.9575 9 P 0 ;1
L 5.6575 5.0075 5.6575 5.0075 9 P 0 ;1
L 5.6575 5.0575 5.6575 5.0575 9 P 0 ;1
L 5.6575 5.1075 5.6575 5.1075 9 P 0 ;1
L 5.6575 5.1575 5.6575 5.1575 9 P 0 ;1
L 5.6575 5.7075 5.6575 5.7075 9 P 0 ;1
L 5.6575 5.7575 5.6575 5.7575 9 P 0 ;1
L 5.6575 5.8075 5.6575 5.8075 9 P 0 ;1
L 5.6575 5.8575 5.6575 5.8575 9 P 0 ;1
L 5.6575 5.9075 5.6575 5.9075 9 P 0 ;1
L 5.7075 0.5575 5.7075 0.5575 9 P 0 ;1
L 5.7075 0.6075 5.7075 0.6075 9 P 0 ;1
L 5.7075 0.6575 5.7075 0.6575 9 P 0 ;1
L 5.7075 0.7075 5.7075 0.7075 9 P 0 ;1
L 5.7075 0.7575 5.7075 0.7575 9 P 0 ;1
L 5.7075 0.8075 5.7075 0.8075 9 P 0 ;1
L 5.7075 1.1075 5.7075 1.1075 9 P 0 ;1
L 5.7075 1.1575 5.7075 1.1575 9 P 0 ;1
L 5.7075 1.2075 5.7075 1.2075 9 P 0 ;1
L 5.7075 1.2575 5.7075 1.2575 9 P 0 ;1
L 5.7075 1.3075 5.7075 1.3075 9 P 0 ;1
L 5.7075 1.3575 5.7075 1.3575 9 P 0 ;1
L 5.7075 1.4075 5.7075 1.4075 9 P 0 ;1
L 5.7075 1.4575 5.7075 1.4575 9 P 0 ;1
L 5.7075 1.5075 5.7075 1.5075 9 P 0 ;1
L 5.7075 1.5575 5.7075 1.5575 9 P 0 ;1
L 5.7075 1.6075 5.7075 1.6075 9 P 0 ;1
L 5.7075 1.6575 5.7075 1.6575 9 P 0 ;1
L 5.7075 1.7075 5.7075 1.7075 9 P 0 ;1
L 5.7075 1.7575 5.7075 1.7575 9 P 0 ;1
L 5.7075 1.8075 5.7075 1.8075 9 P 0 ;1
L 5.7075 1.8575 5.7075 1.8575 9 P 0 ;1
L 5.7075 1.9075 5.7075 1.9075 9 P 0 ;1
L 5.7075 1.9575 5.7075 1.9575 9 P 0 ;1
L 5.7075 2.0075 5.7075 2.0075 9 P 0 ;1
L 5.7075 2.0575 5.7075 2.0575 9 P 0 ;1
L 5.7075 2.1075 5.7075 2.1075 9 P 0 ;1
L 5.7075 2.1575 5.7075 2.1575 9 P 0 ;1
L 5.7075 2.2075 5.7075 2.2075 9 P 0 ;1
L 5.7075 2.2575 5.7075 2.2575 9 P 0 ;1
L 5.7075 2.3075 5.7075 2.3075 9 P 0 ;1
L 5.7075 2.3575 5.7075 2.3575 9 P 0 ;1
L 5.7075 2.4075 5.7075 2.4075 9 P 0 ;1
L 5.7075 2.4575 5.7075 2.4575 9 P 0 ;1
L 5.7075 2.5075 5.7075 2.5075 9 P 0 ;1
L 5.7075 2.5575 5.7075 2.5575 9 P 0 ;1
L 5.7075 2.7575 5.7075 2.7575 9 P 0 ;1
L 5.7075 2.9575 5.7075 2.9575 9 P 0 ;1
L 5.7075 3.1075 5.7075 3.1075 9 P 0 ;1
L 5.7075 3.1575 5.7075 3.1575 9 P 0 ;1
L 5.7075 3.2075 5.7075 3.2075 9 P 0 ;1
L 5.7075 3.2575 5.7075 3.2575 9 P 0 ;1
L 5.7075 3.3075 5.7075 3.3075 9 P 0 ;1
L 5.7075 3.3575 5.7075 3.3575 9 P 0 ;1
L 5.7075 3.4075 5.7075 3.4075 9 P 0 ;1
L 5.7075 3.4575 5.7075 3.4575 9 P 0 ;1
L 5.7075 3.5075 5.7075 3.5075 9 P 0 ;1
L 5.7075 3.5575 5.7075 3.5575 9 P 0 ;1
L 5.7075 3.6075 5.7075 3.6075 9 P 0 ;1
L 5.7075 3.6575 5.7075 3.6575 9 P 0 ;1
L 5.7075 3.7075 5.7075 3.7075 9 P 0 ;1
L 5.7075 3.7575 5.7075 3.7575 9 P 0 ;1
L 5.7075 3.8075 5.7075 3.8075 9 P 0 ;1
L 5.7075 3.8575 5.7075 3.8575 9 P 0 ;1
L 5.7075 3.9075 5.7075 3.9075 9 P 0 ;1
L 5.7075 3.9575 5.7075 3.9575 9 P 0 ;1
L 5.7075 4.0075 5.7075 4.0075 9 P 0 ;1
L 5.7075 4.0575 5.7075 4.0575 9 P 0 ;1
L 5.7075 4.1075 5.7075 4.1075 9 P 0 ;1
L 5.7075 4.1575 5.7075 4.1575 9 P 0 ;1
L 5.7075 4.2075 5.7075 4.2075 9 P 0 ;1
L 5.7075 4.2575 5.7075 4.2575 9 P 0 ;1
L 5.7075 4.3075 5.7075 4.3075 9 P 0 ;1
L 5.7075 4.3575 5.7075 4.3575 9 P 0 ;1
L 5.7075 4.4075 5.7075 4.4075 9 P 0 ;1
L 5.7075 4.9075 5.7075 4.9075 9 P 0 ;1
L 5.7075 4.9575 5.7075 4.9575 9 P 0 ;1
L 5.7075 5.0075 5.7075 5.0075 9 P 0 ;1
L 5.7075 5.0575 5.7075 5.0575 9 P 0 ;1
L 5.7075 5.1075 5.7075 5.1075 9 P 0 ;1
L 5.7075 5.1575 5.7075 5.1575 9 P 0 ;1
L 5.7075 5.7075 5.7075 5.7075 9 P 0 ;1
L 5.7075 5.7575 5.7075 5.7575 9 P 0 ;1
L 5.7075 5.8075 5.7075 5.8075 9 P 0 ;1
L 5.7075 5.8575 5.7075 5.8575 9 P 0 ;1
L 5.7075 5.9075 5.7075 5.9075 9 P 0 ;1
L 5.7575 0.5575 5.7575 0.5575 9 P 0 ;1
L 5.7575 0.6075 5.7575 0.6075 9 P 0 ;1
L 5.7575 0.6575 5.7575 0.6575 9 P 0 ;1
L 5.7575 0.7075 5.7575 0.7075 9 P 0 ;1
L 5.7575 0.7575 5.7575 0.7575 9 P 0 ;1
L 5.7575 0.8075 5.7575 0.8075 9 P 0 ;1
L 5.7575 1.1075 5.7575 1.1075 9 P 0 ;1
L 5.7575 1.1575 5.7575 1.1575 9 P 0 ;1
L 5.7575 1.2075 5.7575 1.2075 9 P 0 ;1
L 5.7575 1.2575 5.7575 1.2575 9 P 0 ;1
L 5.7575 1.3075 5.7575 1.3075 9 P 0 ;1
L 5.7575 1.3575 5.7575 1.3575 9 P 0 ;1
L 5.7575 1.4075 5.7575 1.4075 9 P 0 ;1
L 5.7575 1.4575 5.7575 1.4575 9 P 0 ;1
L 5.7575 1.5075 5.7575 1.5075 9 P 0 ;1
L 5.7575 1.5575 5.7575 1.5575 9 P 0 ;1
L 5.7575 1.6075 5.7575 1.6075 9 P 0 ;1
L 5.7575 1.6575 5.7575 1.6575 9 P 0 ;1
L 5.7575 1.7075 5.7575 1.7075 9 P 0 ;1
L 5.7575 1.7575 5.7575 1.7575 9 P 0 ;1
L 5.7575 1.8075 5.7575 1.8075 9 P 0 ;1
L 5.7575 1.8575 5.7575 1.8575 9 P 0 ;1
L 5.7575 1.9075 5.7575 1.9075 9 P 0 ;1
L 5.7575 1.9575 5.7575 1.9575 9 P 0 ;1
L 5.7575 2.0075 5.7575 2.0075 9 P 0 ;1
L 5.7575 2.0575 5.7575 2.0575 9 P 0 ;1
L 5.7575 2.1075 5.7575 2.1075 9 P 0 ;1
L 5.7575 2.1575 5.7575 2.1575 9 P 0 ;1
L 5.7575 2.2075 5.7575 2.2075 9 P 0 ;1
L 5.7575 2.2575 5.7575 2.2575 9 P 0 ;1
L 5.7575 2.3075 5.7575 2.3075 9 P 0 ;1
L 5.7575 2.3575 5.7575 2.3575 9 P 0 ;1
L 5.7575 2.4075 5.7575 2.4075 9 P 0 ;1
L 5.7575 2.4575 5.7575 2.4575 9 P 0 ;1
L 5.7575 2.5075 5.7575 2.5075 9 P 0 ;1
L 5.7575 2.5575 5.7575 2.5575 9 P 0 ;1
L 5.7575 2.7575 5.7575 2.7575 9 P 0 ;1
L 5.7575 2.8075 5.7575 2.8075 9 P 0 ;1
L 5.7575 2.8575 5.7575 2.8575 9 P 0 ;1
L 5.7575 2.9075 5.7575 2.9075 9 P 0 ;1
L 5.7575 3.1075 5.7575 3.1075 9 P 0 ;1
L 5.7575 3.1575 5.7575 3.1575 9 P 0 ;1
L 5.7575 3.2075 5.7575 3.2075 9 P 0 ;1
L 5.7575 3.2575 5.7575 3.2575 9 P 0 ;1
L 5.7575 3.3075 5.7575 3.3075 9 P 0 ;1
L 5.7575 3.3575 5.7575 3.3575 9 P 0 ;1
L 5.7575 3.4075 5.7575 3.4075 9 P 0 ;1
L 5.7575 3.4575 5.7575 3.4575 9 P 0 ;1
L 5.7575 3.5075 5.7575 3.5075 9 P 0 ;1
L 5.7575 3.5575 5.7575 3.5575 9 P 0 ;1
L 5.7575 3.6075 5.7575 3.6075 9 P 0 ;1
L 5.7575 3.6575 5.7575 3.6575 9 P 0 ;1
L 5.7575 3.7075 5.7575 3.7075 9 P 0 ;1
L 5.7575 3.7575 5.7575 3.7575 9 P 0 ;1
L 5.7575 3.8075 5.7575 3.8075 9 P 0 ;1
L 5.7575 3.8575 5.7575 3.8575 9 P 0 ;1
L 5.7575 3.9075 5.7575 3.9075 9 P 0 ;1
L 5.7575 3.9575 5.7575 3.9575 9 P 0 ;1
L 5.7575 4.0075 5.7575 4.0075 9 P 0 ;1
L 5.7575 4.0575 5.7575 4.0575 9 P 0 ;1
L 5.7575 4.1075 5.7575 4.1075 9 P 0 ;1
L 5.7575 4.1575 5.7575 4.1575 9 P 0 ;1
L 5.7575 4.2075 5.7575 4.2075 9 P 0 ;1
L 5.7575 4.2575 5.7575 4.2575 9 P 0 ;1
L 5.7575 4.3075 5.7575 4.3075 9 P 0 ;1
L 5.7575 4.3575 5.7575 4.3575 9 P 0 ;1
L 5.7575 4.4075 5.7575 4.4075 9 P 0 ;1
L 5.7575 4.9075 5.7575 4.9075 9 P 0 ;1
L 5.7575 4.9575 5.7575 4.9575 9 P 0 ;1
L 5.7575 5.0075 5.7575 5.0075 9 P 0 ;1
L 5.7575 5.0575 5.7575 5.0575 9 P 0 ;1
L 5.7575 5.1075 5.7575 5.1075 9 P 0 ;1
L 5.7575 5.1575 5.7575 5.1575 9 P 0 ;1
L 5.7575 5.7575 5.7575 5.7575 9 P 0 ;1
L 5.7575 5.8075 5.7575 5.8075 9 P 0 ;1
L 5.7575 5.8575 5.7575 5.8575 9 P 0 ;1
L 5.7575 5.9075 5.7575 5.9075 9 P 0 ;1
L 5.8075 0.5575 5.8075 0.5575 9 P 0 ;1
L 5.8075 0.6075 5.8075 0.6075 9 P 0 ;1
L 5.8075 0.6575 5.8075 0.6575 9 P 0 ;1
L 5.8075 0.7075 5.8075 0.7075 9 P 0 ;1
L 5.8075 0.7575 5.8075 0.7575 9 P 0 ;1
L 5.8075 0.8075 5.8075 0.8075 9 P 0 ;1
L 5.8075 1.1075 5.8075 1.1075 9 P 0 ;1
L 5.8075 1.1575 5.8075 1.1575 9 P 0 ;1
L 5.8075 1.2075 5.8075 1.2075 9 P 0 ;1
L 5.8075 1.2575 5.8075 1.2575 9 P 0 ;1
L 5.8075 1.3075 5.8075 1.3075 9 P 0 ;1
L 5.8075 1.3575 5.8075 1.3575 9 P 0 ;1
L 5.8075 1.4075 5.8075 1.4075 9 P 0 ;1
L 5.8075 1.4575 5.8075 1.4575 9 P 0 ;1
L 5.8075 1.5075 5.8075 1.5075 9 P 0 ;1
L 5.8075 1.5575 5.8075 1.5575 9 P 0 ;1
L 5.8075 1.6075 5.8075 1.6075 9 P 0 ;1
L 5.8075 1.6575 5.8075 1.6575 9 P 0 ;1
L 5.8075 1.7075 5.8075 1.7075 9 P 0 ;1
L 5.8075 1.7575 5.8075 1.7575 9 P 0 ;1
L 5.8075 1.8075 5.8075 1.8075 9 P 0 ;1
L 5.8075 1.8575 5.8075 1.8575 9 P 0 ;1
L 5.8075 1.9075 5.8075 1.9075 9 P 0 ;1
L 5.8075 1.9575 5.8075 1.9575 9 P 0 ;1
L 5.8075 2.0075 5.8075 2.0075 9 P 0 ;1
L 5.8075 2.0575 5.8075 2.0575 9 P 0 ;1
L 5.8075 2.1075 5.8075 2.1075 9 P 0 ;1
L 5.8075 2.1575 5.8075 2.1575 9 P 0 ;1
L 5.8075 2.2075 5.8075 2.2075 9 P 0 ;1
L 5.8075 2.2575 5.8075 2.2575 9 P 0 ;1
L 5.8075 2.3075 5.8075 2.3075 9 P 0 ;1
L 5.8075 2.3575 5.8075 2.3575 9 P 0 ;1
L 5.8075 2.4075 5.8075 2.4075 9 P 0 ;1
L 5.8075 2.4575 5.8075 2.4575 9 P 0 ;1
L 5.8075 2.5075 5.8075 2.5075 9 P 0 ;1
L 5.8075 2.5575 5.8075 2.5575 9 P 0 ;1
L 5.8075 2.7575 5.8075 2.7575 9 P 0 ;1
L 5.8075 3.1575 5.8075 3.1575 9 P 0 ;1
L 5.8075 3.2075 5.8075 3.2075 9 P 0 ;1
L 5.8075 3.2575 5.8075 3.2575 9 P 0 ;1
L 5.8075 3.3075 5.8075 3.3075 9 P 0 ;1
L 5.8075 3.3575 5.8075 3.3575 9 P 0 ;1
L 5.8075 3.4075 5.8075 3.4075 9 P 0 ;1
L 5.8075 3.4575 5.8075 3.4575 9 P 0 ;1
L 5.8075 3.5075 5.8075 3.5075 9 P 0 ;1
L 5.8075 3.5575 5.8075 3.5575 9 P 0 ;1
L 5.8075 3.6075 5.8075 3.6075 9 P 0 ;1
L 5.8075 3.6575 5.8075 3.6575 9 P 0 ;1
L 5.8075 3.7075 5.8075 3.7075 9 P 0 ;1
L 5.8075 3.7575 5.8075 3.7575 9 P 0 ;1
L 5.8075 3.8075 5.8075 3.8075 9 P 0 ;1
L 5.8075 3.8575 5.8075 3.8575 9 P 0 ;1
L 5.8075 3.9075 5.8075 3.9075 9 P 0 ;1
L 5.8075 3.9575 5.8075 3.9575 9 P 0 ;1
L 5.8075 4.0075 5.8075 4.0075 9 P 0 ;1
L 5.8075 4.0575 5.8075 4.0575 9 P 0 ;1
L 5.8075 4.1075 5.8075 4.1075 9 P 0 ;1
L 5.8075 4.1575 5.8075 4.1575 9 P 0 ;1
L 5.8075 4.2075 5.8075 4.2075 9 P 0 ;1
L 5.8075 4.2575 5.8075 4.2575 9 P 0 ;1
L 5.8075 4.3075 5.8075 4.3075 9 P 0 ;1
L 5.8075 4.3575 5.8075 4.3575 9 P 0 ;1
L 5.8075 4.4075 5.8075 4.4075 9 P 0 ;1
L 5.8075 4.9075 5.8075 4.9075 9 P 0 ;1
L 5.8075 4.9575 5.8075 4.9575 9 P 0 ;1
L 5.8075 5.0075 5.8075 5.0075 9 P 0 ;1
L 5.8075 5.0575 5.8075 5.0575 9 P 0 ;1
L 5.8075 5.1075 5.8075 5.1075 9 P 0 ;1
L 5.8075 5.1575 5.8075 5.1575 9 P 0 ;1
L 5.8075 5.7575 5.8075 5.7575 9 P 0 ;1
L 5.8075 5.8075 5.8075 5.8075 9 P 0 ;1
L 5.8075 5.8575 5.8075 5.8575 9 P 0 ;1
L 5.8075 5.9075 5.8075 5.9075 9 P 0 ;1
L 5.8575 0.5575 5.8575 0.5575 9 P 0 ;1
L 5.8575 0.6075 5.8575 0.6075 9 P 0 ;1
L 5.8575 0.6575 5.8575 0.6575 9 P 0 ;1
L 5.8575 0.7075 5.8575 0.7075 9 P 0 ;1
L 5.8575 0.7575 5.8575 0.7575 9 P 0 ;1
L 5.8575 0.8075 5.8575 0.8075 9 P 0 ;1
L 5.8575 1.1075 5.8575 1.1075 9 P 0 ;1
L 5.8575 1.1575 5.8575 1.1575 9 P 0 ;1
L 5.8575 1.2075 5.8575 1.2075 9 P 0 ;1
L 5.8575 1.2575 5.8575 1.2575 9 P 0 ;1
L 5.8575 1.3075 5.8575 1.3075 9 P 0 ;1
L 5.8575 1.3575 5.8575 1.3575 9 P 0 ;1
L 5.8575 1.4075 5.8575 1.4075 9 P 0 ;1
L 5.8575 1.4575 5.8575 1.4575 9 P 0 ;1
L 5.8575 1.5075 5.8575 1.5075 9 P 0 ;1
L 5.8575 1.5575 5.8575 1.5575 9 P 0 ;1
L 5.8575 1.6075 5.8575 1.6075 9 P 0 ;1
L 5.8575 1.6575 5.8575 1.6575 9 P 0 ;1
L 5.8575 1.7075 5.8575 1.7075 9 P 0 ;1
L 5.8575 1.7575 5.8575 1.7575 9 P 0 ;1
L 5.8575 1.8075 5.8575 1.8075 9 P 0 ;1
L 5.8575 1.8575 5.8575 1.8575 9 P 0 ;1
L 5.8575 1.9075 5.8575 1.9075 9 P 0 ;1
L 5.8575 1.9575 5.8575 1.9575 9 P 0 ;1
L 5.8575 2.0075 5.8575 2.0075 9 P 0 ;1
L 5.8575 2.0575 5.8575 2.0575 9 P 0 ;1
L 5.8575 2.1075 5.8575 2.1075 9 P 0 ;1
L 5.8575 2.1575 5.8575 2.1575 9 P 0 ;1
L 5.8575 2.2075 5.8575 2.2075 9 P 0 ;1
L 5.8575 2.2575 5.8575 2.2575 9 P 0 ;1
L 5.8575 2.3075 5.8575 2.3075 9 P 0 ;1
L 5.8575 2.3575 5.8575 2.3575 9 P 0 ;1
L 5.8575 2.4075 5.8575 2.4075 9 P 0 ;1
L 5.8575 2.4575 5.8575 2.4575 9 P 0 ;1
L 5.8575 2.5075 5.8575 2.5075 9 P 0 ;1
L 5.8575 2.5575 5.8575 2.5575 9 P 0 ;1
L 5.8575 2.6075 5.8575 2.6075 9 P 0 ;1
L 5.8575 2.6575 5.8575 2.6575 9 P 0 ;1
L 5.8575 2.7075 5.8575 2.7075 9 P 0 ;1
L 5.8575 2.7575 5.8575 2.7575 9 P 0 ;1
L 5.8575 3.1575 5.8575 3.1575 9 P 0 ;1
L 5.8575 3.2075 5.8575 3.2075 9 P 0 ;1
L 5.8575 3.2575 5.8575 3.2575 9 P 0 ;1
L 5.8575 3.3075 5.8575 3.3075 9 P 0 ;1
L 5.8575 3.3575 5.8575 3.3575 9 P 0 ;1
L 5.8575 3.4075 5.8575 3.4075 9 P 0 ;1
L 5.8575 3.4575 5.8575 3.4575 9 P 0 ;1
L 5.8575 3.5075 5.8575 3.5075 9 P 0 ;1
L 5.8575 3.5575 5.8575 3.5575 9 P 0 ;1
L 5.8575 3.6075 5.8575 3.6075 9 P 0 ;1
L 5.8575 3.6575 5.8575 3.6575 9 P 0 ;1
L 5.8575 3.7075 5.8575 3.7075 9 P 0 ;1
L 5.8575 3.7575 5.8575 3.7575 9 P 0 ;1
L 5.8575 3.8075 5.8575 3.8075 9 P 0 ;1
L 5.8575 3.8575 5.8575 3.8575 9 P 0 ;1
L 5.8575 3.9075 5.8575 3.9075 9 P 0 ;1
L 5.8575 3.9575 5.8575 3.9575 9 P 0 ;1
L 5.8575 4.0075 5.8575 4.0075 9 P 0 ;1
L 5.8575 4.0575 5.8575 4.0575 9 P 0 ;1
L 5.8575 4.1075 5.8575 4.1075 9 P 0 ;1
L 5.8575 4.1575 5.8575 4.1575 9 P 0 ;1
L 5.8575 4.2075 5.8575 4.2075 9 P 0 ;1
L 5.8575 4.2575 5.8575 4.2575 9 P 0 ;1
L 5.8575 4.3075 5.8575 4.3075 9 P 0 ;1
L 5.8575 4.3575 5.8575 4.3575 9 P 0 ;1
L 5.8575 4.4075 5.8575 4.4075 9 P 0 ;1
L 5.8575 4.9075 5.8575 4.9075 9 P 0 ;1
L 5.8575 4.9575 5.8575 4.9575 9 P 0 ;1
L 5.8575 5.0075 5.8575 5.0075 9 P 0 ;1
L 5.8575 5.0575 5.8575 5.0575 9 P 0 ;1
L 5.8575 5.1075 5.8575 5.1075 9 P 0 ;1
L 5.8575 5.1575 5.8575 5.1575 9 P 0 ;1
L 5.8575 5.7075 5.8575 5.7075 9 P 0 ;1
L 5.8575 5.7575 5.8575 5.7575 9 P 0 ;1
L 5.8575 5.8075 5.8575 5.8075 9 P 0 ;1
L 5.8575 5.8575 5.8575 5.8575 9 P 0 ;1
L 5.8575 5.9075 5.8575 5.9075 9 P 0 ;1
L 5.9075 0.5575 5.9075 0.5575 9 P 0 ;1
L 5.9075 0.6075 5.9075 0.6075 9 P 0 ;1
L 5.9075 0.6575 5.9075 0.6575 9 P 0 ;1
L 5.9075 0.7075 5.9075 0.7075 9 P 0 ;1
L 5.9075 0.7575 5.9075 0.7575 9 P 0 ;1
L 5.9075 0.8075 5.9075 0.8075 9 P 0 ;1
L 5.9075 1.1075 5.9075 1.1075 9 P 0 ;1
L 5.9075 1.1575 5.9075 1.1575 9 P 0 ;1
L 5.9075 1.2075 5.9075 1.2075 9 P 0 ;1
L 5.9075 1.2575 5.9075 1.2575 9 P 0 ;1
L 5.9075 1.3075 5.9075 1.3075 9 P 0 ;1
L 5.9075 1.3575 5.9075 1.3575 9 P 0 ;1
L 5.9075 1.4075 5.9075 1.4075 9 P 0 ;1
L 5.9075 1.4575 5.9075 1.4575 9 P 0 ;1
L 5.9075 1.5075 5.9075 1.5075 9 P 0 ;1
L 5.9075 1.5575 5.9075 1.5575 9 P 0 ;1
L 5.9075 1.6075 5.9075 1.6075 9 P 0 ;1
L 5.9075 1.6575 5.9075 1.6575 9 P 0 ;1
L 5.9075 1.7075 5.9075 1.7075 9 P 0 ;1
L 5.9075 1.7575 5.9075 1.7575 9 P 0 ;1
L 5.9075 1.8075 5.9075 1.8075 9 P 0 ;1
L 5.9075 1.8575 5.9075 1.8575 9 P 0 ;1
L 5.9075 1.9075 5.9075 1.9075 9 P 0 ;1
L 5.9075 1.9575 5.9075 1.9575 9 P 0 ;1
L 5.9075 2.0075 5.9075 2.0075 9 P 0 ;1
L 5.9075 2.0575 5.9075 2.0575 9 P 0 ;1
L 5.9075 2.1075 5.9075 2.1075 9 P 0 ;1
L 5.9075 2.1575 5.9075 2.1575 9 P 0 ;1
L 5.9075 2.2075 5.9075 2.2075 9 P 0 ;1
L 5.9075 2.2575 5.9075 2.2575 9 P 0 ;1
L 5.9075 2.3075 5.9075 2.3075 9 P 0 ;1
L 5.9075 2.3575 5.9075 2.3575 9 P 0 ;1
L 5.9075 2.4075 5.9075 2.4075 9 P 0 ;1
L 5.9075 2.4575 5.9075 2.4575 9 P 0 ;1
L 5.9075 2.5075 5.9075 2.5075 9 P 0 ;1
L 5.9075 2.5575 5.9075 2.5575 9 P 0 ;1
L 5.9075 2.6075 5.9075 2.6075 9 P 0 ;1
L 5.9075 2.6575 5.9075 2.6575 9 P 0 ;1
L 5.9075 2.7075 5.9075 2.7075 9 P 0 ;1
L 5.9075 2.7575 5.9075 2.7575 9 P 0 ;1
L 5.9075 3.1575 5.9075 3.1575 9 P 0 ;1
L 5.9075 3.2075 5.9075 3.2075 9 P 0 ;1
L 5.9075 3.2575 5.9075 3.2575 9 P 0 ;1
L 5.9075 3.3075 5.9075 3.3075 9 P 0 ;1
L 5.9075 3.3575 5.9075 3.3575 9 P 0 ;1
L 5.9075 3.4075 5.9075 3.4075 9 P 0 ;1
L 5.9075 3.4575 5.9075 3.4575 9 P 0 ;1
L 5.9075 3.5075 5.9075 3.5075 9 P 0 ;1
L 5.9075 3.5575 5.9075 3.5575 9 P 0 ;1
L 5.9075 3.6075 5.9075 3.6075 9 P 0 ;1
L 5.9075 3.6575 5.9075 3.6575 9 P 0 ;1
L 5.9075 3.7075 5.9075 3.7075 9 P 0 ;1
L 5.9075 3.7575 5.9075 3.7575 9 P 0 ;1
L 5.9075 3.8075 5.9075 3.8075 9 P 0 ;1
L 5.9075 3.8575 5.9075 3.8575 9 P 0 ;1
L 5.9075 3.9075 5.9075 3.9075 9 P 0 ;1
L 5.9075 3.9575 5.9075 3.9575 9 P 0 ;1
L 5.9075 4.0075 5.9075 4.0075 9 P 0 ;1
L 5.9075 4.0575 5.9075 4.0575 9 P 0 ;1
L 5.9075 4.1075 5.9075 4.1075 9 P 0 ;1
L 5.9075 4.1575 5.9075 4.1575 9 P 0 ;1
L 5.9075 4.2075 5.9075 4.2075 9 P 0 ;1
L 5.9075 4.2575 5.9075 4.2575 9 P 0 ;1
L 5.9075 4.3075 5.9075 4.3075 9 P 0 ;1
L 5.9075 4.3575 5.9075 4.3575 9 P 0 ;1
L 5.9075 4.4075 5.9075 4.4075 9 P 0 ;1
L 5.9075 4.9075 5.9075 4.9075 9 P 0 ;1
L 5.9075 4.9575 5.9075 4.9575 9 P 0 ;1
L 5.9075 5.0075 5.9075 5.0075 9 P 0 ;1
L 5.9075 5.0575 5.9075 5.0575 9 P 0 ;1
L 5.9075 5.1075 5.9075 5.1075 9 P 0 ;1
L 5.9075 5.1575 5.9075 5.1575 9 P 0 ;1
L 5.9075 5.7075 5.9075 5.7075 9 P 0 ;1
L 5.9075 5.7575 5.9075 5.7575 9 P 0 ;1
L 5.9075 5.8075 5.9075 5.8075 9 P 0 ;1
L 5.9075 5.8575 5.9075 5.8575 9 P 0 ;1
L 5.9075 5.9075 5.9075 5.9075 9 P 0 ;1
L 5.9575 0.5575 5.9575 0.5575 9 P 0 ;1
L 5.9575 0.6075 5.9575 0.6075 9 P 0 ;1
L 5.9575 0.6575 5.9575 0.6575 9 P 0 ;1
L 5.9575 0.7075 5.9575 0.7075 9 P 0 ;1
L 5.9575 0.7575 5.9575 0.7575 9 P 0 ;1
L 5.9575 0.8075 5.9575 0.8075 9 P 0 ;1
L 5.9575 0.8575 5.9575 0.8575 9 P 0 ;1
L 5.9575 1.1075 5.9575 1.1075 9 P 0 ;1
L 5.9575 1.1575 5.9575 1.1575 9 P 0 ;1
L 5.9575 1.2075 5.9575 1.2075 9 P 0 ;1
L 5.9575 1.2575 5.9575 1.2575 9 P 0 ;1
L 5.9575 1.3075 5.9575 1.3075 9 P 0 ;1
L 5.9575 1.3575 5.9575 1.3575 9 P 0 ;1
L 5.9575 1.6575 5.9575 1.6575 9 P 0 ;1
L 5.9575 1.7075 5.9575 1.7075 9 P 0 ;1
L 5.9575 1.7575 5.9575 1.7575 9 P 0 ;1
L 5.9575 1.8075 5.9575 1.8075 9 P 0 ;1
L 5.9575 1.8575 5.9575 1.8575 9 P 0 ;1
L 5.9575 1.9075 5.9575 1.9075 9 P 0 ;1
L 5.9575 1.9575 5.9575 1.9575 9 P 0 ;1
L 5.9575 2.0075 5.9575 2.0075 9 P 0 ;1
L 5.9575 2.0575 5.9575 2.0575 9 P 0 ;1
L 5.9575 2.1075 5.9575 2.1075 9 P 0 ;1
L 5.9575 2.1575 5.9575 2.1575 9 P 0 ;1
L 5.9575 2.2075 5.9575 2.2075 9 P 0 ;1
L 5.9575 2.2575 5.9575 2.2575 9 P 0 ;1
L 5.9575 2.3075 5.9575 2.3075 9 P 0 ;1
L 5.9575 2.3575 5.9575 2.3575 9 P 0 ;1
L 5.9575 2.4075 5.9575 2.4075 9 P 0 ;1
L 5.9575 2.4575 5.9575 2.4575 9 P 0 ;1
L 5.9575 2.7075 5.9575 2.7075 9 P 0 ;1
L 5.9575 2.7575 5.9575 2.7575 9 P 0 ;1
L 5.9575 2.8075 5.9575 2.8075 9 P 0 ;1
L 5.9575 2.8575 5.9575 2.8575 9 P 0 ;1
L 5.9575 3.0575 5.9575 3.0575 9 P 0 ;1
L 5.9575 3.1075 5.9575 3.1075 9 P 0 ;1
L 5.9575 3.1575 5.9575 3.1575 9 P 0 ;1
L 5.9575 3.2075 5.9575 3.2075 9 P 0 ;1
L 5.9575 3.2575 5.9575 3.2575 9 P 0 ;1
L 5.9575 3.3075 5.9575 3.3075 9 P 0 ;1
L 5.9575 3.3575 5.9575 3.3575 9 P 0 ;1
L 5.9575 3.4075 5.9575 3.4075 9 P 0 ;1
L 5.9575 3.4575 5.9575 3.4575 9 P 0 ;1
L 5.9575 3.5075 5.9575 3.5075 9 P 0 ;1
L 5.9575 3.5575 5.9575 3.5575 9 P 0 ;1
L 5.9575 3.6075 5.9575 3.6075 9 P 0 ;1
L 5.9575 3.6575 5.9575 3.6575 9 P 0 ;1
L 5.9575 3.7075 5.9575 3.7075 9 P 0 ;1
L 5.9575 3.7575 5.9575 3.7575 9 P 0 ;1
L 5.9575 3.8075 5.9575 3.8075 9 P 0 ;1
L 5.9575 3.8575 5.9575 3.8575 9 P 0 ;1
L 5.9575 3.9075 5.9575 3.9075 9 P 0 ;1
L 5.9575 3.9575 5.9575 3.9575 9 P 0 ;1
L 5.9575 4.0075 5.9575 4.0075 9 P 0 ;1
L 5.9575 4.0575 5.9575 4.0575 9 P 0 ;1
L 5.9575 4.3575 5.9575 4.3575 9 P 0 ;1
L 5.9575 4.4075 5.9575 4.4075 9 P 0 ;1
L 5.9575 4.9075 5.9575 4.9075 9 P 0 ;1
L 5.9575 4.9575 5.9575 4.9575 9 P 0 ;1
L 5.9575 5.0075 5.9575 5.0075 9 P 0 ;1
L 5.9575 5.0575 5.9575 5.0575 9 P 0 ;1
L 5.9575 5.1075 5.9575 5.1075 9 P 0 ;1
L 5.9575 5.1575 5.9575 5.1575 9 P 0 ;1
L 5.9575 5.2075 5.9575 5.2075 9 P 0 ;1
L 5.9575 5.6575 5.9575 5.6575 9 P 0 ;1
L 5.9575 5.7075 5.9575 5.7075 9 P 0 ;1
L 5.9575 5.7575 5.9575 5.7575 9 P 0 ;1
L 5.9575 5.8075 5.9575 5.8075 9 P 0 ;1
L 5.9575 5.8575 5.9575 5.8575 9 P 0 ;1
L 5.9575 5.9075 5.9575 5.9075 9 P 0 ;1
L 6.0075 0.5575 6.0075 0.5575 9 P 0 ;1
L 6.0075 0.6075 6.0075 0.6075 9 P 0 ;1
L 6.0075 0.6575 6.0075 0.6575 9 P 0 ;1
L 6.0075 0.7075 6.0075 0.7075 9 P 0 ;1
L 6.0075 0.7575 6.0075 0.7575 9 P 0 ;1
L 6.0075 0.8075 6.0075 0.8075 9 P 0 ;1
L 6.0075 0.8575 6.0075 0.8575 9 P 0 ;1
L 6.0075 1.1575 6.0075 1.1575 9 P 0 ;1
L 6.0075 1.2075 6.0075 1.2075 9 P 0 ;1
L 6.0075 1.2575 6.0075 1.2575 9 P 0 ;1
L 6.0075 1.3075 6.0075 1.3075 9 P 0 ;1
L 6.0075 1.3575 6.0075 1.3575 9 P 0 ;1
L 6.0075 1.7075 6.0075 1.7075 9 P 0 ;1
L 6.0075 1.7575 6.0075 1.7575 9 P 0 ;1
L 6.0075 1.8075 6.0075 1.8075 9 P 0 ;1
L 6.0075 1.8575 6.0075 1.8575 9 P 0 ;1
L 6.0075 1.9075 6.0075 1.9075 9 P 0 ;1
L 6.0075 1.9575 6.0075 1.9575 9 P 0 ;1
L 6.0075 2.0075 6.0075 2.0075 9 P 0 ;1
L 6.0075 2.0575 6.0075 2.0575 9 P 0 ;1
L 6.0075 2.1075 6.0075 2.1075 9 P 0 ;1
L 6.0075 2.1575 6.0075 2.1575 9 P 0 ;1
L 6.0075 2.2075 6.0075 2.2075 9 P 0 ;1
L 6.0075 2.2575 6.0075 2.2575 9 P 0 ;1
L 6.0075 2.3075 6.0075 2.3075 9 P 0 ;1
L 6.0075 2.3575 6.0075 2.3575 9 P 0 ;1
L 6.0075 2.4075 6.0075 2.4075 9 P 0 ;1
L 6.0075 2.7575 6.0075 2.7575 9 P 0 ;1
L 6.0075 2.8075 6.0075 2.8075 9 P 0 ;1
L 6.0075 2.8575 6.0075 2.8575 9 P 0 ;1
L 6.0075 2.9075 6.0075 2.9075 9 P 0 ;1
L 6.0075 2.9575 6.0075 2.9575 9 P 0 ;1
L 6.0075 3.0075 6.0075 3.0075 9 P 0 ;1
L 6.0075 3.0575 6.0075 3.0575 9 P 0 ;1
L 6.0075 3.1075 6.0075 3.1075 9 P 0 ;1
L 6.0075 3.1575 6.0075 3.1575 9 P 0 ;1
L 6.0075 3.2075 6.0075 3.2075 9 P 0 ;1
L 6.0075 3.2575 6.0075 3.2575 9 P 0 ;1
L 6.0075 3.3075 6.0075 3.3075 9 P 0 ;1
L 6.0075 3.3575 6.0075 3.3575 9 P 0 ;1
L 6.0075 3.4075 6.0075 3.4075 9 P 0 ;1
L 6.0075 3.4575 6.0075 3.4575 9 P 0 ;1
L 6.0075 3.5075 6.0075 3.5075 9 P 0 ;1
L 6.0075 3.5575 6.0075 3.5575 9 P 0 ;1
L 6.0075 3.6075 6.0075 3.6075 9 P 0 ;1
L 6.0075 3.6575 6.0075 3.6575 9 P 0 ;1
L 6.0075 3.7075 6.0075 3.7075 9 P 0 ;1
L 6.0075 3.7575 6.0075 3.7575 9 P 0 ;1
L 6.0075 3.8075 6.0075 3.8075 9 P 0 ;1
L 6.0075 3.8575 6.0075 3.8575 9 P 0 ;1
L 6.0075 3.9075 6.0075 3.9075 9 P 0 ;1
L 6.0075 3.9575 6.0075 3.9575 9 P 0 ;1
L 6.0075 4.0075 6.0075 4.0075 9 P 0 ;1
L 6.0075 4.4075 6.0075 4.4075 9 P 0 ;1
L 6.0075 4.9075 6.0075 4.9075 9 P 0 ;1
L 6.0075 4.9575 6.0075 4.9575 9 P 0 ;1
L 6.0075 5.0075 6.0075 5.0075 9 P 0 ;1
L 6.0075 5.0575 6.0075 5.0575 9 P 0 ;1
L 6.0075 5.1075 6.0075 5.1075 9 P 0 ;1
L 6.0075 5.1575 6.0075 5.1575 9 P 0 ;1
L 6.0075 5.2075 6.0075 5.2075 9 P 0 ;1
L 6.0075 5.2575 6.0075 5.2575 9 P 0 ;1
L 6.0075 5.6075 6.0075 5.6075 9 P 0 ;1
L 6.0075 5.6575 6.0075 5.6575 9 P 0 ;1
L 6.0075 5.7075 6.0075 5.7075 9 P 0 ;1
L 6.0075 5.7575 6.0075 5.7575 9 P 0 ;1
L 6.0075 5.8075 6.0075 5.8075 9 P 0 ;1
L 6.0075 5.8575 6.0075 5.8575 9 P 0 ;1
L 6.0075 5.9075 6.0075 5.9075 9 P 0 ;1
L 6.0575 0.5575 6.0575 0.5575 9 P 0 ;1
L 6.0575 0.6075 6.0575 0.6075 9 P 0 ;1
L 6.0575 0.6575 6.0575 0.6575 9 P 0 ;1
L 6.0575 0.7075 6.0575 0.7075 9 P 0 ;1
L 6.0575 0.7575 6.0575 0.7575 9 P 0 ;1
L 6.0575 0.8075 6.0575 0.8075 9 P 0 ;1
L 6.0575 0.8575 6.0575 0.8575 9 P 0 ;1
L 6.0575 1.2075 6.0575 1.2075 9 P 0 ;1
L 6.0575 1.2575 6.0575 1.2575 9 P 0 ;1
L 6.0575 1.3075 6.0575 1.3075 9 P 0 ;1
L 6.0575 1.7575 6.0575 1.7575 9 P 0 ;1
L 6.0575 1.8075 6.0575 1.8075 9 P 0 ;1
L 6.0575 1.8575 6.0575 1.8575 9 P 0 ;1
L 6.0575 1.9075 6.0575 1.9075 9 P 0 ;1
L 6.0575 1.9575 6.0575 1.9575 9 P 0 ;1
L 6.0575 2.0075 6.0575 2.0075 9 P 0 ;1
L 6.0575 2.0575 6.0575 2.0575 9 P 0 ;1
L 6.0575 2.1075 6.0575 2.1075 9 P 0 ;1
L 6.0575 2.1575 6.0575 2.1575 9 P 0 ;1
L 6.0575 2.2075 6.0575 2.2075 9 P 0 ;1
L 6.0575 2.2575 6.0575 2.2575 9 P 0 ;1
L 6.0575 2.3075 6.0575 2.3075 9 P 0 ;1
L 6.0575 2.3575 6.0575 2.3575 9 P 0 ;1
L 6.0575 2.4075 6.0575 2.4075 9 P 0 ;1
L 6.0575 2.7575 6.0575 2.7575 9 P 0 ;1
L 6.0575 2.8075 6.0575 2.8075 9 P 0 ;1
L 6.0575 2.8575 6.0575 2.8575 9 P 0 ;1
L 6.0575 2.9075 6.0575 2.9075 9 P 0 ;1
L 6.0575 2.9575 6.0575 2.9575 9 P 0 ;1
L 6.0575 3.0075 6.0575 3.0075 9 P 0 ;1
L 6.0575 3.0575 6.0575 3.0575 9 P 0 ;1
L 6.0575 3.1075 6.0575 3.1075 9 P 0 ;1
L 6.0575 3.1575 6.0575 3.1575 9 P 0 ;1
L 6.0575 3.2075 6.0575 3.2075 9 P 0 ;1
L 6.0575 3.2575 6.0575 3.2575 9 P 0 ;1
L 6.0575 3.3075 6.0575 3.3075 9 P 0 ;1
L 6.0575 3.3575 6.0575 3.3575 9 P 0 ;1
L 6.0575 3.4075 6.0575 3.4075 9 P 0 ;1
L 6.0575 3.4575 6.0575 3.4575 9 P 0 ;1
L 6.0575 3.5075 6.0575 3.5075 9 P 0 ;1
L 6.0575 3.5575 6.0575 3.5575 9 P 0 ;1
L 6.0575 3.6075 6.0575 3.6075 9 P 0 ;1
L 6.0575 3.6575 6.0575 3.6575 9 P 0 ;1
L 6.0575 3.7075 6.0575 3.7075 9 P 0 ;1
L 6.0575 3.7575 6.0575 3.7575 9 P 0 ;1
L 6.0575 3.8075 6.0575 3.8075 9 P 0 ;1
L 6.0575 3.8575 6.0575 3.8575 9 P 0 ;1
L 6.0575 3.9075 6.0575 3.9075 9 P 0 ;1
L 6.0575 3.9575 6.0575 3.9575 9 P 0 ;1
L 6.0575 4.0075 6.0575 4.0075 9 P 0 ;1
L 6.0575 4.4075 6.0575 4.4075 9 P 0 ;1
L 6.0575 4.9075 6.0575 4.9075 9 P 0 ;1
L 6.0575 4.9575 6.0575 4.9575 9 P 0 ;1
L 6.0575 5.0075 6.0575 5.0075 9 P 0 ;1
L 6.0575 5.0575 6.0575 5.0575 9 P 0 ;1
L 6.0575 5.1075 6.0575 5.1075 9 P 0 ;1
L 6.0575 5.1575 6.0575 5.1575 9 P 0 ;1
L 6.0575 5.2075 6.0575 5.2075 9 P 0 ;1
L 6.0575 5.2575 6.0575 5.2575 9 P 0 ;1
L 6.0575 5.3075 6.0575 5.3075 9 P 0 ;1
L 6.0575 5.3575 6.0575 5.3575 9 P 0 ;1
L 6.0575 5.4075 6.0575 5.4075 9 P 0 ;1
L 6.0575 5.4575 6.0575 5.4575 9 P 0 ;1
L 6.0575 5.5075 6.0575 5.5075 9 P 0 ;1
L 6.0575 5.5575 6.0575 5.5575 9 P 0 ;1
L 6.0575 5.6075 6.0575 5.6075 9 P 0 ;1
L 6.0575 5.6575 6.0575 5.6575 9 P 0 ;1
L 6.0575 5.7075 6.0575 5.7075 9 P 0 ;1
L 6.0575 5.7575 6.0575 5.7575 9 P 0 ;1
L 6.0575 5.8075 6.0575 5.8075 9 P 0 ;1
L 6.0575 5.8575 6.0575 5.8575 9 P 0 ;1
L 6.0575 5.9075 6.0575 5.9075 9 P 0 ;1
L 6.1075 0.5575 6.1075 0.5575 9 P 0 ;1
L 6.1075 0.6075 6.1075 0.6075 9 P 0 ;1
L 6.1075 0.6575 6.1075 0.6575 9 P 0 ;1
L 6.1075 0.7075 6.1075 0.7075 9 P 0 ;1
L 6.1075 0.7575 6.1075 0.7575 9 P 0 ;1
L 6.1075 0.8075 6.1075 0.8075 9 P 0 ;1
L 6.1075 0.8575 6.1075 0.8575 9 P 0 ;1
L 6.1075 1.2575 6.1075 1.2575 9 P 0 ;1
L 6.1075 1.3075 6.1075 1.3075 9 P 0 ;1
L 6.1075 1.7575 6.1075 1.7575 9 P 0 ;1
L 6.1075 1.8075 6.1075 1.8075 9 P 0 ;1
L 6.1075 1.8575 6.1075 1.8575 9 P 0 ;1
L 6.1075 1.9075 6.1075 1.9075 9 P 0 ;1
L 6.1075 1.9575 6.1075 1.9575 9 P 0 ;1
L 6.1075 2.0075 6.1075 2.0075 9 P 0 ;1
L 6.1075 2.0575 6.1075 2.0575 9 P 0 ;1
L 6.1075 2.1075 6.1075 2.1075 9 P 0 ;1
L 6.1075 2.1575 6.1075 2.1575 9 P 0 ;1
L 6.1075 2.2075 6.1075 2.2075 9 P 0 ;1
L 6.1075 2.2575 6.1075 2.2575 9 P 0 ;1
L 6.1075 2.3075 6.1075 2.3075 9 P 0 ;1
L 6.1075 2.3575 6.1075 2.3575 9 P 0 ;1
L 6.1075 2.4075 6.1075 2.4075 9 P 0 ;1
L 6.1075 2.7575 6.1075 2.7575 9 P 0 ;1
L 6.1075 2.8075 6.1075 2.8075 9 P 0 ;1
L 6.1075 2.8575 6.1075 2.8575 9 P 0 ;1
L 6.1075 2.9075 6.1075 2.9075 9 P 0 ;1
L 6.1075 2.9575 6.1075 2.9575 9 P 0 ;1
L 6.1075 3.0075 6.1075 3.0075 9 P 0 ;1
L 6.1075 3.0575 6.1075 3.0575 9 P 0 ;1
L 6.1075 3.1075 6.1075 3.1075 9 P 0 ;1
L 6.1075 3.1575 6.1075 3.1575 9 P 0 ;1
L 6.1075 3.2075 6.1075 3.2075 9 P 0 ;1
L 6.1075 3.2575 6.1075 3.2575 9 P 0 ;1
L 6.1075 3.3075 6.1075 3.3075 9 P 0 ;1
L 6.1075 3.3575 6.1075 3.3575 9 P 0 ;1
L 6.1075 3.4075 6.1075 3.4075 9 P 0 ;1
L 6.1075 3.4575 6.1075 3.4575 9 P 0 ;1
L 6.1075 3.5075 6.1075 3.5075 9 P 0 ;1
L 6.1075 3.5575 6.1075 3.5575 9 P 0 ;1
L 6.1075 3.6075 6.1075 3.6075 9 P 0 ;1
L 6.1075 3.6575 6.1075 3.6575 9 P 0 ;1
L 6.1075 3.7075 6.1075 3.7075 9 P 0 ;1
L 6.1075 3.7575 6.1075 3.7575 9 P 0 ;1
L 6.1075 3.8075 6.1075 3.8075 9 P 0 ;1
L 6.1075 3.8575 6.1075 3.8575 9 P 0 ;1
L 6.1075 3.9075 6.1075 3.9075 9 P 0 ;1
L 6.1075 3.9575 6.1075 3.9575 9 P 0 ;1
L 6.1075 5.0075 6.1075 5.0075 9 P 0 ;1
L 6.1075 5.0575 6.1075 5.0575 9 P 0 ;1
L 6.1075 5.1075 6.1075 5.1075 9 P 0 ;1
L 6.1075 5.1575 6.1075 5.1575 9 P 0 ;1
L 6.1075 5.2075 6.1075 5.2075 9 P 0 ;1
L 6.1075 5.2575 6.1075 5.2575 9 P 0 ;1
L 6.1075 5.3075 6.1075 5.3075 9 P 0 ;1
L 6.1075 5.3575 6.1075 5.3575 9 P 0 ;1
L 6.1075 5.4075 6.1075 5.4075 9 P 0 ;1
L 6.1075 5.4575 6.1075 5.4575 9 P 0 ;1
L 6.1075 5.5075 6.1075 5.5075 9 P 0 ;1
L 6.1075 5.5575 6.1075 5.5575 9 P 0 ;1
L 6.1075 5.6075 6.1075 5.6075 9 P 0 ;1
L 6.1075 5.6575 6.1075 5.6575 9 P 0 ;1
L 6.1075 5.7075 6.1075 5.7075 9 P 0 ;1
L 6.1075 5.7575 6.1075 5.7575 9 P 0 ;1
L 6.1075 5.8075 6.1075 5.8075 9 P 0 ;1
L 6.1075 5.8575 6.1075 5.8575 9 P 0 ;1
L 6.1075 5.9075 6.1075 5.9075 9 P 0 ;1
L 6.1575 0.5575 6.1575 0.5575 9 P 0 ;1
L 6.1575 0.6075 6.1575 0.6075 9 P 0 ;1
L 6.1575 0.6575 6.1575 0.6575 9 P 0 ;1
L 6.1575 0.7075 6.1575 0.7075 9 P 0 ;1
L 6.1575 0.7575 6.1575 0.7575 9 P 0 ;1
L 6.1575 0.8075 6.1575 0.8075 9 P 0 ;1
L 6.1575 0.8575 6.1575 0.8575 9 P 0 ;1
L 6.1575 1.3075 6.1575 1.3075 9 P 0 ;1
L 6.1575 1.7575 6.1575 1.7575 9 P 0 ;1
L 6.1575 1.8075 6.1575 1.8075 9 P 0 ;1
L 6.1575 1.8575 6.1575 1.8575 9 P 0 ;1
L 6.1575 1.9075 6.1575 1.9075 9 P 0 ;1
L 6.1575 1.9575 6.1575 1.9575 9 P 0 ;1
L 6.1575 2.0075 6.1575 2.0075 9 P 0 ;1
L 6.1575 2.0575 6.1575 2.0575 9 P 0 ;1
L 6.1575 2.1075 6.1575 2.1075 9 P 0 ;1
L 6.1575 2.1575 6.1575 2.1575 9 P 0 ;1
L 6.1575 2.2075 6.1575 2.2075 9 P 0 ;1
L 6.1575 2.2575 6.1575 2.2575 9 P 0 ;1
L 6.1575 2.3075 6.1575 2.3075 9 P 0 ;1
L 6.1575 2.3575 6.1575 2.3575 9 P 0 ;1
L 6.1575 2.4075 6.1575 2.4075 9 P 0 ;1
L 6.1575 2.4575 6.1575 2.4575 9 P 0 ;1
L 6.1575 2.7075 6.1575 2.7075 9 P 0 ;1
L 6.1575 2.7575 6.1575 2.7575 9 P 0 ;1
L 6.1575 2.8075 6.1575 2.8075 9 P 0 ;1
L 6.1575 2.8575 6.1575 2.8575 9 P 0 ;1
L 6.1575 2.9075 6.1575 2.9075 9 P 0 ;1
L 6.1575 2.9575 6.1575 2.9575 9 P 0 ;1
L 6.1575 3.0075 6.1575 3.0075 9 P 0 ;1
L 6.1575 3.0575 6.1575 3.0575 9 P 0 ;1
L 6.1575 3.1075 6.1575 3.1075 9 P 0 ;1
L 6.1575 3.1575 6.1575 3.1575 9 P 0 ;1
L 6.1575 3.2075 6.1575 3.2075 9 P 0 ;1
L 6.1575 3.2575 6.1575 3.2575 9 P 0 ;1
L 6.1575 3.3075 6.1575 3.3075 9 P 0 ;1
L 6.1575 3.3575 6.1575 3.3575 9 P 0 ;1
L 6.1575 3.4075 6.1575 3.4075 9 P 0 ;1
L 6.1575 3.4575 6.1575 3.4575 9 P 0 ;1
L 6.1575 3.5075 6.1575 3.5075 9 P 0 ;1
L 6.1575 3.5575 6.1575 3.5575 9 P 0 ;1
L 6.1575 3.6075 6.1575 3.6075 9 P 0 ;1
L 6.1575 3.6575 6.1575 3.6575 9 P 0 ;1
L 6.1575 3.7075 6.1575 3.7075 9 P 0 ;1
L 6.1575 3.7575 6.1575 3.7575 9 P 0 ;1
L 6.1575 3.8075 6.1575 3.8075 9 P 0 ;1
L 6.1575 3.8575 6.1575 3.8575 9 P 0 ;1
L 6.1575 3.9075 6.1575 3.9075 9 P 0 ;1
L 6.1575 3.9575 6.1575 3.9575 9 P 0 ;1
L 6.1575 4.4075 6.1575 4.4075 9 P 0 ;1
L 6.1575 5.0075 6.1575 5.0075 9 P 0 ;1
L 6.1575 5.0575 6.1575 5.0575 9 P 0 ;1
L 6.1575 5.1075 6.1575 5.1075 9 P 0 ;1
L 6.1575 5.1575 6.1575 5.1575 9 P 0 ;1
L 6.1575 5.2075 6.1575 5.2075 9 P 0 ;1
L 6.1575 5.2575 6.1575 5.2575 9 P 0 ;1
L 6.1575 5.3075 6.1575 5.3075 9 P 0 ;1
L 6.1575 5.3575 6.1575 5.3575 9 P 0 ;1
L 6.1575 5.4075 6.1575 5.4075 9 P 0 ;1
L 6.1575 5.4575 6.1575 5.4575 9 P 0 ;1
L 6.1575 5.5075 6.1575 5.5075 9 P 0 ;1
L 6.1575 5.5575 6.1575 5.5575 9 P 0 ;1
L 6.1575 5.6075 6.1575 5.6075 9 P 0 ;1
L 6.1575 5.6575 6.1575 5.6575 9 P 0 ;1
L 6.1575 5.7075 6.1575 5.7075 9 P 0 ;1
L 6.1575 5.7575 6.1575 5.7575 9 P 0 ;1
L 6.1575 5.8075 6.1575 5.8075 9 P 0 ;1
L 6.1575 5.8575 6.1575 5.8575 9 P 0 ;1
L 6.1575 5.9075 6.1575 5.9075 9 P 0 ;1
L 6.2075 0.5575 6.2075 0.5575 9 P 0 ;1
L 6.2075 0.6075 6.2075 0.6075 9 P 0 ;1
L 6.2075 0.6575 6.2075 0.6575 9 P 0 ;1
L 6.2075 0.7075 6.2075 0.7075 9 P 0 ;1
L 6.2075 0.7575 6.2075 0.7575 9 P 0 ;1
L 6.2075 0.8075 6.2075 0.8075 9 P 0 ;1
L 6.2075 0.8575 6.2075 0.8575 9 P 0 ;1
L 6.2075 1.3575 6.2075 1.3575 9 P 0 ;1
L 6.2075 1.7075 6.2075 1.7075 9 P 0 ;1
L 6.2075 1.7575 6.2075 1.7575 9 P 0 ;1
L 6.2075 1.8075 6.2075 1.8075 9 P 0 ;1
L 6.2075 1.8575 6.2075 1.8575 9 P 0 ;1
L 6.2075 1.9075 6.2075 1.9075 9 P 0 ;1
L 6.2075 1.9575 6.2075 1.9575 9 P 0 ;1
L 6.2075 2.0075 6.2075 2.0075 9 P 0 ;1
L 6.2075 2.0575 6.2075 2.0575 9 P 0 ;1
L 6.2075 2.1075 6.2075 2.1075 9 P 0 ;1
L 6.2075 2.1575 6.2075 2.1575 9 P 0 ;1
L 6.2075 2.2075 6.2075 2.2075 9 P 0 ;1
L 6.2075 2.2575 6.2075 2.2575 9 P 0 ;1
L 6.2075 2.3075 6.2075 2.3075 9 P 0 ;1
L 6.2075 2.3575 6.2075 2.3575 9 P 0 ;1
L 6.2075 2.4075 6.2075 2.4075 9 P 0 ;1
L 6.2075 2.4575 6.2075 2.4575 9 P 0 ;1
L 6.2075 2.5075 6.2075 2.5075 9 P 0 ;1
L 6.2075 2.5575 6.2075 2.5575 9 P 0 ;1
L 6.2075 2.6075 6.2075 2.6075 9 P 0 ;1
L 6.2075 2.6575 6.2075 2.6575 9 P 0 ;1
L 6.2075 2.7075 6.2075 2.7075 9 P 0 ;1
L 6.2075 2.7575 6.2075 2.7575 9 P 0 ;1
L 6.2075 2.8075 6.2075 2.8075 9 P 0 ;1
L 6.2075 2.8575 6.2075 2.8575 9 P 0 ;1
L 6.2075 2.9075 6.2075 2.9075 9 P 0 ;1
L 6.2075 2.9575 6.2075 2.9575 9 P 0 ;1
L 6.2075 3.0075 6.2075 3.0075 9 P 0 ;1
L 6.2075 3.0575 6.2075 3.0575 9 P 0 ;1
L 6.2075 3.1075 6.2075 3.1075 9 P 0 ;1
L 6.2075 3.1575 6.2075 3.1575 9 P 0 ;1
L 6.2075 3.2075 6.2075 3.2075 9 P 0 ;1
L 6.2075 3.2575 6.2075 3.2575 9 P 0 ;1
L 6.2075 3.3075 6.2075 3.3075 9 P 0 ;1
L 6.2075 3.3575 6.2075 3.3575 9 P 0 ;1
L 6.2075 3.4075 6.2075 3.4075 9 P 0 ;1
L 6.2075 3.4575 6.2075 3.4575 9 P 0 ;1
L 6.2075 3.5075 6.2075 3.5075 9 P 0 ;1
L 6.2075 3.5575 6.2075 3.5575 9 P 0 ;1
L 6.2075 3.6075 6.2075 3.6075 9 P 0 ;1
L 6.2075 3.6575 6.2075 3.6575 9 P 0 ;1
L 6.2075 3.7075 6.2075 3.7075 9 P 0 ;1
L 6.2075 3.7575 6.2075 3.7575 9 P 0 ;1
L 6.2075 3.8075 6.2075 3.8075 9 P 0 ;1
L 6.2075 3.8575 6.2075 3.8575 9 P 0 ;1
L 6.2075 3.9075 6.2075 3.9075 9 P 0 ;1
L 6.2075 3.9575 6.2075 3.9575 9 P 0 ;1
L 6.2075 4.0075 6.2075 4.0075 9 P 0 ;1
L 6.2075 4.4075 6.2075 4.4075 9 P 0 ;1
L 6.2075 4.4575 6.2075 4.4575 9 P 0 ;1
L 6.2075 4.5075 6.2075 4.5075 9 P 0 ;1
L 6.2075 4.5575 6.2075 4.5575 9 P 0 ;1
L 6.2075 5.0075 6.2075 5.0075 9 P 0 ;1
L 6.2075 5.0575 6.2075 5.0575 9 P 0 ;1
L 6.2075 5.1075 6.2075 5.1075 9 P 0 ;1
L 6.2075 5.1575 6.2075 5.1575 9 P 0 ;1
L 6.2075 5.2075 6.2075 5.2075 9 P 0 ;1
L 6.2075 5.2575 6.2075 5.2575 9 P 0 ;1
L 6.2075 5.3075 6.2075 5.3075 9 P 0 ;1
L 6.2075 5.3575 6.2075 5.3575 9 P 0 ;1
L 6.2075 5.4075 6.2075 5.4075 9 P 0 ;1
L 6.2075 5.4575 6.2075 5.4575 9 P 0 ;1
L 6.2075 5.5075 6.2075 5.5075 9 P 0 ;1
L 6.2075 5.5575 6.2075 5.5575 9 P 0 ;1
L 6.2075 5.6075 6.2075 5.6075 9 P 0 ;1
L 6.2075 5.6575 6.2075 5.6575 9 P 0 ;1
L 6.2075 5.7075 6.2075 5.7075 9 P 0 ;1
L 6.2075 5.7575 6.2075 5.7575 9 P 0 ;1
L 6.2075 5.8075 6.2075 5.8075 9 P 0 ;1
L 6.2075 5.8575 6.2075 5.8575 9 P 0 ;1
L 6.2075 5.9075 6.2075 5.9075 9 P 0 ;1
L 6.2575 0.5575 6.2575 0.5575 9 P 0 ;1
L 6.2575 0.6075 6.2575 0.6075 9 P 0 ;1
L 6.2575 0.6575 6.2575 0.6575 9 P 0 ;1
L 6.2575 0.7075 6.2575 0.7075 9 P 0 ;1
L 6.2575 0.7575 6.2575 0.7575 9 P 0 ;1
L 6.2575 0.8075 6.2575 0.8075 9 P 0 ;1
L 6.2575 0.8575 6.2575 0.8575 9 P 0 ;1
L 6.2575 1.0575 6.2575 1.0575 9 P 0 ;1
L 6.2575 1.7075 6.2575 1.7075 9 P 0 ;1
L 6.2575 1.7575 6.2575 1.7575 9 P 0 ;1
L 6.2575 1.8075 6.2575 1.8075 9 P 0 ;1
L 6.2575 1.8575 6.2575 1.8575 9 P 0 ;1
L 6.2575 1.9075 6.2575 1.9075 9 P 0 ;1
L 6.2575 1.9575 6.2575 1.9575 9 P 0 ;1
L 6.2575 2.0075 6.2575 2.0075 9 P 0 ;1
L 6.2575 2.0575 6.2575 2.0575 9 P 0 ;1
L 6.2575 2.1075 6.2575 2.1075 9 P 0 ;1
L 6.2575 2.1575 6.2575 2.1575 9 P 0 ;1
L 6.2575 2.2075 6.2575 2.2075 9 P 0 ;1
L 6.2575 2.2575 6.2575 2.2575 9 P 0 ;1
L 6.2575 2.3075 6.2575 2.3075 9 P 0 ;1
L 6.2575 2.3575 6.2575 2.3575 9 P 0 ;1
L 6.2575 2.4075 6.2575 2.4075 9 P 0 ;1
L 6.2575 2.4575 6.2575 2.4575 9 P 0 ;1
L 6.2575 2.5075 6.2575 2.5075 9 P 0 ;1
L 6.2575 2.5575 6.2575 2.5575 9 P 0 ;1
L 6.2575 2.6075 6.2575 2.6075 9 P 0 ;1
L 6.2575 2.6575 6.2575 2.6575 9 P 0 ;1
L 6.2575 2.7075 6.2575 2.7075 9 P 0 ;1
L 6.2575 2.7575 6.2575 2.7575 9 P 0 ;1
L 6.2575 2.8075 6.2575 2.8075 9 P 0 ;1
L 6.2575 2.8575 6.2575 2.8575 9 P 0 ;1
L 6.2575 2.9075 6.2575 2.9075 9 P 0 ;1
L 6.2575 2.9575 6.2575 2.9575 9 P 0 ;1
L 6.2575 3.0075 6.2575 3.0075 9 P 0 ;1
L 6.2575 3.0575 6.2575 3.0575 9 P 0 ;1
L 6.2575 3.1075 6.2575 3.1075 9 P 0 ;1
L 6.2575 3.1575 6.2575 3.1575 9 P 0 ;1
L 6.2575 3.2075 6.2575 3.2075 9 P 0 ;1
L 6.2575 3.2575 6.2575 3.2575 9 P 0 ;1
L 6.2575 3.3075 6.2575 3.3075 9 P 0 ;1
L 6.2575 3.3575 6.2575 3.3575 9 P 0 ;1
L 6.2575 3.4075 6.2575 3.4075 9 P 0 ;1
L 6.2575 3.4575 6.2575 3.4575 9 P 0 ;1
L 6.2575 3.5075 6.2575 3.5075 9 P 0 ;1
L 6.2575 3.5575 6.2575 3.5575 9 P 0 ;1
L 6.2575 3.6075 6.2575 3.6075 9 P 0 ;1
L 6.2575 3.6575 6.2575 3.6575 9 P 0 ;1
L 6.2575 3.7075 6.2575 3.7075 9 P 0 ;1
L 6.2575 3.7575 6.2575 3.7575 9 P 0 ;1
L 6.2575 3.8075 6.2575 3.8075 9 P 0 ;1
L 6.2575 3.8575 6.2575 3.8575 9 P 0 ;1
L 6.2575 3.9075 6.2575 3.9075 9 P 0 ;1
L 6.2575 3.9575 6.2575 3.9575 9 P 0 ;1
L 6.2575 4.0075 6.2575 4.0075 9 P 0 ;1
L 6.2575 4.4075 6.2575 4.4075 9 P 0 ;1
L 6.2575 4.4575 6.2575 4.4575 9 P 0 ;1
L 6.2575 4.5075 6.2575 4.5075 9 P 0 ;1
L 6.2575 4.5575 6.2575 4.5575 9 P 0 ;1
L 6.2575 5.0575 6.2575 5.0575 9 P 0 ;1
L 6.2575 5.1075 6.2575 5.1075 9 P 0 ;1
L 6.2575 5.1575 6.2575 5.1575 9 P 0 ;1
L 6.2575 5.2075 6.2575 5.2075 9 P 0 ;1
L 6.2575 5.2575 6.2575 5.2575 9 P 0 ;1
L 6.2575 5.3075 6.2575 5.3075 9 P 0 ;1
L 6.2575 5.3575 6.2575 5.3575 9 P 0 ;1
L 6.2575 5.4075 6.2575 5.4075 9 P 0 ;1
L 6.2575 5.4575 6.2575 5.4575 9 P 0 ;1
L 6.2575 5.5075 6.2575 5.5075 9 P 0 ;1
L 6.2575 5.5575 6.2575 5.5575 9 P 0 ;1
L 6.2575 5.6075 6.2575 5.6075 9 P 0 ;1
L 6.2575 5.6575 6.2575 5.6575 9 P 0 ;1
L 6.2575 5.7075 6.2575 5.7075 9 P 0 ;1
L 6.2575 5.7575 6.2575 5.7575 9 P 0 ;1
L 6.2575 5.8075 6.2575 5.8075 9 P 0 ;1
L 6.2575 5.8575 6.2575 5.8575 9 P 0 ;1
L 6.2575 5.9075 6.2575 5.9075 9 P 0 ;1
L 6.3075 0.5575 6.3075 0.5575 9 P 0 ;1
L 6.3075 0.6075 6.3075 0.6075 9 P 0 ;1
L 6.3075 0.6575 6.3075 0.6575 9 P 0 ;1
L 6.3075 0.7075 6.3075 0.7075 9 P 0 ;1
L 6.3075 0.7575 6.3075 0.7575 9 P 0 ;1
L 6.3075 0.8075 6.3075 0.8075 9 P 0 ;1
L 6.3075 0.8575 6.3075 0.8575 9 P 0 ;1
L 6.3075 1.0575 6.3075 1.0575 9 P 0 ;1
L 6.3075 1.1075 6.3075 1.1075 9 P 0 ;1
L 6.3075 1.4575 6.3075 1.4575 9 P 0 ;1
L 6.3075 1.6075 6.3075 1.6075 9 P 0 ;1
L 6.3075 1.6575 6.3075 1.6575 9 P 0 ;1
L 6.3075 1.7075 6.3075 1.7075 9 P 0 ;1
L 6.3075 1.7575 6.3075 1.7575 9 P 0 ;1
L 6.3075 1.8075 6.3075 1.8075 9 P 0 ;1
L 6.3075 1.8575 6.3075 1.8575 9 P 0 ;1
L 6.3075 1.9075 6.3075 1.9075 9 P 0 ;1
L 6.3075 1.9575 6.3075 1.9575 9 P 0 ;1
L 6.3075 2.0075 6.3075 2.0075 9 P 0 ;1
L 6.3075 2.0575 6.3075 2.0575 9 P 0 ;1
L 6.3075 2.1075 6.3075 2.1075 9 P 0 ;1
L 6.3075 2.1575 6.3075 2.1575 9 P 0 ;1
L 6.3075 2.2075 6.3075 2.2075 9 P 0 ;1
L 6.3075 2.2575 6.3075 2.2575 9 P 0 ;1
L 6.3075 2.3075 6.3075 2.3075 9 P 0 ;1
L 6.3075 2.3575 6.3075 2.3575 9 P 0 ;1
L 6.3075 2.4075 6.3075 2.4075 9 P 0 ;1
L 6.3075 2.4575 6.3075 2.4575 9 P 0 ;1
L 6.3075 2.5075 6.3075 2.5075 9 P 0 ;1
L 6.3075 2.5575 6.3075 2.5575 9 P 0 ;1
L 6.3075 2.6075 6.3075 2.6075 9 P 0 ;1
L 6.3075 2.6575 6.3075 2.6575 9 P 0 ;1
L 6.3075 2.7075 6.3075 2.7075 9 P 0 ;1
L 6.3075 2.7575 6.3075 2.7575 9 P 0 ;1
L 6.3075 2.8075 6.3075 2.8075 9 P 0 ;1
L 6.3075 2.8575 6.3075 2.8575 9 P 0 ;1
L 6.3075 2.9075 6.3075 2.9075 9 P 0 ;1
L 6.3075 2.9575 6.3075 2.9575 9 P 0 ;1
L 6.3075 3.0075 6.3075 3.0075 9 P 0 ;1
L 6.3075 3.0575 6.3075 3.0575 9 P 0 ;1
L 6.3075 3.1075 6.3075 3.1075 9 P 0 ;1
L 6.3075 3.1575 6.3075 3.1575 9 P 0 ;1
L 6.3075 3.2075 6.3075 3.2075 9 P 0 ;1
L 6.3075 3.2575 6.3075 3.2575 9 P 0 ;1
L 6.3075 3.3075 6.3075 3.3075 9 P 0 ;1
L 6.3075 3.3575 6.3075 3.3575 9 P 0 ;1
L 6.3075 3.4075 6.3075 3.4075 9 P 0 ;1
L 6.3075 3.4575 6.3075 3.4575 9 P 0 ;1
L 6.3075 3.5075 6.3075 3.5075 9 P 0 ;1
L 6.3075 3.5575 6.3075 3.5575 9 P 0 ;1
L 6.3075 3.6075 6.3075 3.6075 9 P 0 ;1
L 6.3075 3.6575 6.3075 3.6575 9 P 0 ;1
L 6.3075 3.7075 6.3075 3.7075 9 P 0 ;1
L 6.3075 3.7575 6.3075 3.7575 9 P 0 ;1
L 6.3075 3.8075 6.3075 3.8075 9 P 0 ;1
L 6.3075 3.8575 6.3075 3.8575 9 P 0 ;1
L 6.3075 3.9075 6.3075 3.9075 9 P 0 ;1
L 6.3075 3.9575 6.3075 3.9575 9 P 0 ;1
L 6.3075 4.0075 6.3075 4.0075 9 P 0 ;1
L 6.3075 4.0575 6.3075 4.0575 9 P 0 ;1
L 6.3075 4.1075 6.3075 4.1075 9 P 0 ;1
L 6.3075 4.3075 6.3075 4.3075 9 P 0 ;1
L 6.3075 4.3575 6.3075 4.3575 9 P 0 ;1
L 6.3075 4.4075 6.3075 4.4075 9 P 0 ;1
L 6.3075 4.4575 6.3075 4.4575 9 P 0 ;1
L 6.3075 4.5075 6.3075 4.5075 9 P 0 ;1
L 6.3075 5.1075 6.3075 5.1075 9 P 0 ;1
L 6.3075 5.1575 6.3075 5.1575 9 P 0 ;1
L 6.3075 5.2075 6.3075 5.2075 9 P 0 ;1
L 6.3075 5.2575 6.3075 5.2575 9 P 0 ;1
L 6.3075 5.3075 6.3075 5.3075 9 P 0 ;1
L 6.3075 5.3575 6.3075 5.3575 9 P 0 ;1
L 6.3075 5.4075 6.3075 5.4075 9 P 0 ;1
L 6.3075 5.4575 6.3075 5.4575 9 P 0 ;1
L 6.3075 5.5075 6.3075 5.5075 9 P 0 ;1
L 6.3075 5.5575 6.3075 5.5575 9 P 0 ;1
L 6.3075 5.6075 6.3075 5.6075 9 P 0 ;1
L 6.3075 5.6575 6.3075 5.6575 9 P 0 ;1
L 6.3075 5.7075 6.3075 5.7075 9 P 0 ;1
L 6.3075 5.7575 6.3075 5.7575 9 P 0 ;1
L 6.3075 5.8075 6.3075 5.8075 9 P 0 ;1
L 6.3075 5.8575 6.3075 5.8575 9 P 0 ;1
L 6.3075 5.9075 6.3075 5.9075 9 P 0 ;1
L 6.3575 0.5575 6.3575 0.5575 9 P 0 ;1
L 6.3575 0.6075 6.3575 0.6075 9 P 0 ;1
L 6.3575 0.6575 6.3575 0.6575 9 P 0 ;1
L 6.3575 0.7075 6.3575 0.7075 9 P 0 ;1
L 6.3575 0.7575 6.3575 0.7575 9 P 0 ;1
L 6.3575 0.8075 6.3575 0.8075 9 P 0 ;1
L 6.3575 0.8575 6.3575 0.8575 9 P 0 ;1
L 6.3575 1.0575 6.3575 1.0575 9 P 0 ;1
L 6.3575 1.1075 6.3575 1.1075 9 P 0 ;1
L 6.3575 1.1575 6.3575 1.1575 9 P 0 ;1
L 6.3575 1.5075 6.3575 1.5075 9 P 0 ;1
L 6.3575 1.5575 6.3575 1.5575 9 P 0 ;1
L 6.3575 1.6075 6.3575 1.6075 9 P 0 ;1
L 6.3575 1.6575 6.3575 1.6575 9 P 0 ;1
L 6.3575 1.7075 6.3575 1.7075 9 P 0 ;1
L 6.3575 1.7575 6.3575 1.7575 9 P 0 ;1
L 6.3575 1.8075 6.3575 1.8075 9 P 0 ;1
L 6.3575 1.8575 6.3575 1.8575 9 P 0 ;1
L 6.3575 1.9075 6.3575 1.9075 9 P 0 ;1
L 6.3575 1.9575 6.3575 1.9575 9 P 0 ;1
L 6.3575 2.0075 6.3575 2.0075 9 P 0 ;1
L 6.3575 2.0575 6.3575 2.0575 9 P 0 ;1
L 6.3575 2.1075 6.3575 2.1075 9 P 0 ;1
L 6.3575 2.1575 6.3575 2.1575 9 P 0 ;1
L 6.3575 2.2075 6.3575 2.2075 9 P 0 ;1
L 6.3575 2.2575 6.3575 2.2575 9 P 0 ;1
L 6.3575 2.3075 6.3575 2.3075 9 P 0 ;1
L 6.3575 2.3575 6.3575 2.3575 9 P 0 ;1
L 6.3575 2.4075 6.3575 2.4075 9 P 0 ;1
L 6.3575 2.4575 6.3575 2.4575 9 P 0 ;1
L 6.3575 2.5075 6.3575 2.5075 9 P 0 ;1
L 6.3575 2.5575 6.3575 2.5575 9 P 0 ;1
L 6.3575 2.6075 6.3575 2.6075 9 P 0 ;1
L 6.3575 2.6575 6.3575 2.6575 9 P 0 ;1
L 6.3575 2.7075 6.3575 2.7075 9 P 0 ;1
L 6.3575 2.7575 6.3575 2.7575 9 P 0 ;1
L 6.3575 2.8075 6.3575 2.8075 9 P 0 ;1
L 6.3575 2.8575 6.3575 2.8575 9 P 0 ;1
L 6.3575 2.9075 6.3575 2.9075 9 P 0 ;1
L 6.3575 2.9575 6.3575 2.9575 9 P 0 ;1
L 6.3575 3.0075 6.3575 3.0075 9 P 0 ;1
L 6.3575 3.0575 6.3575 3.0575 9 P 0 ;1
L 6.3575 3.1075 6.3575 3.1075 9 P 0 ;1
L 6.3575 3.1575 6.3575 3.1575 9 P 0 ;1
L 6.3575 3.2075 6.3575 3.2075 9 P 0 ;1
L 6.3575 3.2575 6.3575 3.2575 9 P 0 ;1
L 6.3575 3.3075 6.3575 3.3075 9 P 0 ;1
L 6.3575 3.3575 6.3575 3.3575 9 P 0 ;1
L 6.3575 3.4075 6.3575 3.4075 9 P 0 ;1
L 6.3575 3.4575 6.3575 3.4575 9 P 0 ;1
L 6.3575 3.5075 6.3575 3.5075 9 P 0 ;1
L 6.3575 3.5575 6.3575 3.5575 9 P 0 ;1
L 6.3575 3.6075 6.3575 3.6075 9 P 0 ;1
L 6.3575 3.6575 6.3575 3.6575 9 P 0 ;1
L 6.3575 3.7075 6.3575 3.7075 9 P 0 ;1
L 6.3575 3.7575 6.3575 3.7575 9 P 0 ;1
L 6.3575 3.8075 6.3575 3.8075 9 P 0 ;1
L 6.3575 3.8575 6.3575 3.8575 9 P 0 ;1
L 6.3575 3.9075 6.3575 3.9075 9 P 0 ;1
L 6.3575 3.9575 6.3575 3.9575 9 P 0 ;1
L 6.3575 4.0075 6.3575 4.0075 9 P 0 ;1
L 6.3575 4.0575 6.3575 4.0575 9 P 0 ;1
L 6.3575 4.1075 6.3575 4.1075 9 P 0 ;1
L 6.3575 4.1575 6.3575 4.1575 9 P 0 ;1
L 6.3575 4.2075 6.3575 4.2075 9 P 0 ;1
L 6.3575 4.2575 6.3575 4.2575 9 P 0 ;1
L 6.3575 4.3075 6.3575 4.3075 9 P 0 ;1
L 6.3575 4.3575 6.3575 4.3575 9 P 0 ;1
L 6.3575 4.4075 6.3575 4.4075 9 P 0 ;1
L 6.3575 4.4575 6.3575 4.4575 9 P 0 ;1
L 6.3575 4.5075 6.3575 4.5075 9 P 0 ;1
L 6.3575 5.1575 6.3575 5.1575 9 P 0 ;1
L 6.3575 5.2075 6.3575 5.2075 9 P 0 ;1
L 6.3575 5.2575 6.3575 5.2575 9 P 0 ;1
L 6.3575 5.3075 6.3575 5.3075 9 P 0 ;1
L 6.3575 5.3575 6.3575 5.3575 9 P 0 ;1
L 6.3575 5.4075 6.3575 5.4075 9 P 0 ;1
L 6.3575 5.4575 6.3575 5.4575 9 P 0 ;1
L 6.3575 5.5075 6.3575 5.5075 9 P 0 ;1
L 6.3575 5.5575 6.3575 5.5575 9 P 0 ;1
L 6.3575 5.6075 6.3575 5.6075 9 P 0 ;1
L 6.3575 5.6575 6.3575 5.6575 9 P 0 ;1
L 6.3575 5.7075 6.3575 5.7075 9 P 0 ;1
L 6.3575 5.7575 6.3575 5.7575 9 P 0 ;1
L 6.3575 5.8075 6.3575 5.8075 9 P 0 ;1
L 6.3575 5.8575 6.3575 5.8575 9 P 0 ;1
L 6.3575 5.9075 6.3575 5.9075 9 P 0 ;1
L 6.4075 0.5575 6.4075 0.5575 9 P 0 ;1
L 6.4075 0.6075 6.4075 0.6075 9 P 0 ;1
L 6.4075 0.6575 6.4075 0.6575 9 P 0 ;1
L 6.4075 0.7075 6.4075 0.7075 9 P 0 ;1
L 6.4075 0.7575 6.4075 0.7575 9 P 0 ;1
L 6.4075 0.8075 6.4075 0.8075 9 P 0 ;1
L 6.4075 0.8575 6.4075 0.8575 9 P 0 ;1
L 6.4075 1.0575 6.4075 1.0575 9 P 0 ;1
L 6.4075 1.1075 6.4075 1.1075 9 P 0 ;1
L 6.4075 1.1575 6.4075 1.1575 9 P 0 ;1
L 6.4075 1.2075 6.4075 1.2075 9 P 0 ;1
L 6.4075 1.5575 6.4075 1.5575 9 P 0 ;1
L 6.4075 1.6075 6.4075 1.6075 9 P 0 ;1
L 6.4075 1.6575 6.4075 1.6575 9 P 0 ;1
L 6.4075 1.7075 6.4075 1.7075 9 P 0 ;1
L 6.4075 1.7575 6.4075 1.7575 9 P 0 ;1
L 6.4075 1.8075 6.4075 1.8075 9 P 0 ;1
L 6.4075 1.8575 6.4075 1.8575 9 P 0 ;1
L 6.4075 1.9075 6.4075 1.9075 9 P 0 ;1
L 6.4075 1.9575 6.4075 1.9575 9 P 0 ;1
L 6.4075 2.0075 6.4075 2.0075 9 P 0 ;1
L 6.4075 2.0575 6.4075 2.0575 9 P 0 ;1
L 6.4075 2.1075 6.4075 2.1075 9 P 0 ;1
L 6.4075 2.1575 6.4075 2.1575 9 P 0 ;1
L 6.4075 2.2075 6.4075 2.2075 9 P 0 ;1
L 6.4075 2.2575 6.4075 2.2575 9 P 0 ;1
L 6.4075 2.3075 6.4075 2.3075 9 P 0 ;1
L 6.4075 2.3575 6.4075 2.3575 9 P 0 ;1
L 6.4075 2.4075 6.4075 2.4075 9 P 0 ;1
L 6.4075 2.4575 6.4075 2.4575 9 P 0 ;1
L 6.4075 2.5075 6.4075 2.5075 9 P 0 ;1
L 6.4075 2.5575 6.4075 2.5575 9 P 0 ;1
L 6.4075 2.6075 6.4075 2.6075 9 P 0 ;1
L 6.4075 2.6575 6.4075 2.6575 9 P 0 ;1
L 6.4075 2.7075 6.4075 2.7075 9 P 0 ;1
L 6.4075 2.7575 6.4075 2.7575 9 P 0 ;1
L 6.4075 2.8075 6.4075 2.8075 9 P 0 ;1
L 6.4075 2.8575 6.4075 2.8575 9 P 0 ;1
L 6.4075 2.9075 6.4075 2.9075 9 P 0 ;1
L 6.4075 2.9575 6.4075 2.9575 9 P 0 ;1
L 6.4075 3.0075 6.4075 3.0075 9 P 0 ;1
L 6.4075 3.0575 6.4075 3.0575 9 P 0 ;1
L 6.4075 3.1075 6.4075 3.1075 9 P 0 ;1
L 6.4075 3.1575 6.4075 3.1575 9 P 0 ;1
L 6.4075 3.2075 6.4075 3.2075 9 P 0 ;1
L 6.4075 3.2575 6.4075 3.2575 9 P 0 ;1
L 6.4075 3.3075 6.4075 3.3075 9 P 0 ;1
L 6.4075 3.3575 6.4075 3.3575 9 P 0 ;1
L 6.4075 3.4075 6.4075 3.4075 9 P 0 ;1
L 6.4075 3.4575 6.4075 3.4575 9 P 0 ;1
L 6.4075 3.5075 6.4075 3.5075 9 P 0 ;1
L 6.4075 3.5575 6.4075 3.5575 9 P 0 ;1
L 6.4075 3.6075 6.4075 3.6075 9 P 0 ;1
L 6.4075 3.6575 6.4075 3.6575 9 P 0 ;1
L 6.4075 3.7075 6.4075 3.7075 9 P 0 ;1
L 6.4075 3.7575 6.4075 3.7575 9 P 0 ;1
L 6.4075 3.8075 6.4075 3.8075 9 P 0 ;1
L 6.4075 3.8575 6.4075 3.8575 9 P 0 ;1
L 6.4075 3.9075 6.4075 3.9075 9 P 0 ;1
L 6.4075 3.9575 6.4075 3.9575 9 P 0 ;1
L 6.4075 4.0075 6.4075 4.0075 9 P 0 ;1
L 6.4075 4.0575 6.4075 4.0575 9 P 0 ;1
L 6.4075 4.1075 6.4075 4.1075 9 P 0 ;1
L 6.4075 4.1575 6.4075 4.1575 9 P 0 ;1
L 6.4075 4.2075 6.4075 4.2075 9 P 0 ;1
L 6.4075 4.2575 6.4075 4.2575 9 P 0 ;1
L 6.4075 4.3075 6.4075 4.3075 9 P 0 ;1
L 6.4075 4.3575 6.4075 4.3575 9 P 0 ;1
L 6.4075 4.4075 6.4075 4.4075 9 P 0 ;1
L 6.4075 4.4575 6.4075 4.4575 9 P 0 ;1
L 6.4075 4.5075 6.4075 4.5075 9 P 0 ;1
L 6.4075 4.5575 6.4075 4.5575 9 P 0 ;1
L 6.4075 4.6075 6.4075 4.6075 9 P 0 ;1
L 6.4075 4.6575 6.4075 4.6575 9 P 0 ;1
L 6.4075 4.7075 6.4075 4.7075 9 P 0 ;1
L 6.4075 4.7575 6.4075 4.7575 9 P 0 ;1
L 6.4075 4.8075 6.4075 4.8075 9 P 0 ;1
L 6.4075 4.8575 6.4075 4.8575 9 P 0 ;1
L 6.4075 4.9075 6.4075 4.9075 9 P 0 ;1
L 6.4075 5.1575 6.4075 5.1575 9 P 0 ;1
L 6.4075 5.2075 6.4075 5.2075 9 P 0 ;1
L 6.4075 5.2575 6.4075 5.2575 9 P 0 ;1
L 6.4075 5.3075 6.4075 5.3075 9 P 0 ;1
L 6.4075 5.3575 6.4075 5.3575 9 P 0 ;1
L 6.4075 5.4075 6.4075 5.4075 9 P 0 ;1
L 6.4075 5.4575 6.4075 5.4575 9 P 0 ;1
L 6.4075 5.5075 6.4075 5.5075 9 P 0 ;1
L 6.4075 5.5575 6.4075 5.5575 9 P 0 ;1
L 6.4075 5.6075 6.4075 5.6075 9 P 0 ;1
L 6.4075 5.6575 6.4075 5.6575 9 P 0 ;1
L 6.4075 5.7075 6.4075 5.7075 9 P 0 ;1
L 6.4075 5.7575 6.4075 5.7575 9 P 0 ;1
L 6.4075 5.8075 6.4075 5.8075 9 P 0 ;1
L 6.4075 5.8575 6.4075 5.8575 9 P 0 ;1
L 6.4075 5.9075 6.4075 5.9075 9 P 0 ;1
L 6.4575 0.5575 6.4575 0.5575 9 P 0 ;1
L 6.4575 0.6075 6.4575 0.6075 9 P 0 ;1
L 6.4575 0.6575 6.4575 0.6575 9 P 0 ;1
L 6.4575 0.7075 6.4575 0.7075 9 P 0 ;1
L 6.4575 0.7575 6.4575 0.7575 9 P 0 ;1
L 6.4575 0.8075 6.4575 0.8075 9 P 0 ;1
L 6.4575 0.8575 6.4575 0.8575 9 P 0 ;1
L 6.4575 1.0575 6.4575 1.0575 9 P 0 ;1
L 6.4575 1.1075 6.4575 1.1075 9 P 0 ;1
L 6.4575 1.1575 6.4575 1.1575 9 P 0 ;1
L 6.4575 1.2075 6.4575 1.2075 9 P 0 ;1
L 6.4575 1.2575 6.4575 1.2575 9 P 0 ;1
L 6.4575 1.6075 6.4575 1.6075 9 P 0 ;1
L 6.4575 1.6575 6.4575 1.6575 9 P 0 ;1
L 6.4575 1.7075 6.4575 1.7075 9 P 0 ;1
L 6.4575 1.7575 6.4575 1.7575 9 P 0 ;1
L 6.4575 1.8075 6.4575 1.8075 9 P 0 ;1
L 6.4575 1.8575 6.4575 1.8575 9 P 0 ;1
L 6.4575 1.9075 6.4575 1.9075 9 P 0 ;1
L 6.4575 1.9575 6.4575 1.9575 9 P 0 ;1
L 6.4575 2.0075 6.4575 2.0075 9 P 0 ;1
L 6.4575 2.0575 6.4575 2.0575 9 P 0 ;1
L 6.4575 2.1075 6.4575 2.1075 9 P 0 ;1
L 6.4575 2.1575 6.4575 2.1575 9 P 0 ;1
L 6.4575 2.2075 6.4575 2.2075 9 P 0 ;1
L 6.4575 2.2575 6.4575 2.2575 9 P 0 ;1
L 6.4575 2.3075 6.4575 2.3075 9 P 0 ;1
L 6.4575 2.3575 6.4575 2.3575 9 P 0 ;1
L 6.4575 2.4075 6.4575 2.4075 9 P 0 ;1
L 6.4575 2.4575 6.4575 2.4575 9 P 0 ;1
L 6.4575 2.5075 6.4575 2.5075 9 P 0 ;1
L 6.4575 2.5575 6.4575 2.5575 9 P 0 ;1
L 6.4575 2.6075 6.4575 2.6075 9 P 0 ;1
L 6.4575 2.6575 6.4575 2.6575 9 P 0 ;1
L 6.4575 2.7075 6.4575 2.7075 9 P 0 ;1
L 6.4575 2.7575 6.4575 2.7575 9 P 0 ;1
L 6.4575 2.8075 6.4575 2.8075 9 P 0 ;1
L 6.4575 2.8575 6.4575 2.8575 9 P 0 ;1
L 6.4575 2.9075 6.4575 2.9075 9 P 0 ;1
L 6.4575 2.9575 6.4575 2.9575 9 P 0 ;1
L 6.4575 3.0075 6.4575 3.0075 9 P 0 ;1
L 6.4575 3.0575 6.4575 3.0575 9 P 0 ;1
L 6.4575 3.1075 6.4575 3.1075 9 P 0 ;1
L 6.4575 3.1575 6.4575 3.1575 9 P 0 ;1
L 6.4575 3.2075 6.4575 3.2075 9 P 0 ;1
L 6.4575 3.2575 6.4575 3.2575 9 P 0 ;1
L 6.4575 3.3075 6.4575 3.3075 9 P 0 ;1
L 6.4575 3.3575 6.4575 3.3575 9 P 0 ;1
L 6.4575 3.4075 6.4575 3.4075 9 P 0 ;1
L 6.4575 3.4575 6.4575 3.4575 9 P 0 ;1
L 6.4575 3.5075 6.4575 3.5075 9 P 0 ;1
L 6.4575 3.5575 6.4575 3.5575 9 P 0 ;1
L 6.4575 3.6075 6.4575 3.6075 9 P 0 ;1
L 6.4575 3.6575 6.4575 3.6575 9 P 0 ;1
L 6.4575 3.7075 6.4575 3.7075 9 P 0 ;1
L 6.4575 3.7575 6.4575 3.7575 9 P 0 ;1
L 6.4575 3.8075 6.4575 3.8075 9 P 0 ;1
L 6.4575 3.8575 6.4575 3.8575 9 P 0 ;1
L 6.4575 3.9075 6.4575 3.9075 9 P 0 ;1
L 6.4575 3.9575 6.4575 3.9575 9 P 0 ;1
L 6.4575 4.0075 6.4575 4.0075 9 P 0 ;1
L 6.4575 4.0575 6.4575 4.0575 9 P 0 ;1
L 6.4575 4.1075 6.4575 4.1075 9 P 0 ;1
L 6.4575 4.1575 6.4575 4.1575 9 P 0 ;1
L 6.4575 4.2075 6.4575 4.2075 9 P 0 ;1
L 6.4575 4.2575 6.4575 4.2575 9 P 0 ;1
L 6.4575 4.3075 6.4575 4.3075 9 P 0 ;1
L 6.4575 4.3575 6.4575 4.3575 9 P 0 ;1
L 6.4575 4.4075 6.4575 4.4075 9 P 0 ;1
L 6.4575 4.4575 6.4575 4.4575 9 P 0 ;1
L 6.4575 4.5075 6.4575 4.5075 9 P 0 ;1
L 6.4575 4.5575 6.4575 4.5575 9 P 0 ;1
L 6.4575 4.6075 6.4575 4.6075 9 P 0 ;1
L 6.4575 4.6575 6.4575 4.6575 9 P 0 ;1
L 6.4575 4.7075 6.4575 4.7075 9 P 0 ;1
L 6.4575 4.7575 6.4575 4.7575 9 P 0 ;1
L 6.4575 4.8075 6.4575 4.8075 9 P 0 ;1
L 6.4575 4.8575 6.4575 4.8575 9 P 0 ;1
L 6.4575 5.2075 6.4575 5.2075 9 P 0 ;1
L 6.4575 5.2575 6.4575 5.2575 9 P 0 ;1
L 6.4575 5.3075 6.4575 5.3075 9 P 0 ;1
L 6.4575 5.3575 6.4575 5.3575 9 P 0 ;1
L 6.4575 5.4075 6.4575 5.4075 9 P 0 ;1
L 6.4575 5.4575 6.4575 5.4575 9 P 0 ;1
L 6.4575 5.5075 6.4575 5.5075 9 P 0 ;1
L 6.4575 5.5575 6.4575 5.5575 9 P 0 ;1
L 6.4575 5.6075 6.4575 5.6075 9 P 0 ;1
L 6.4575 5.6575 6.4575 5.6575 9 P 0 ;1
L 6.4575 5.7075 6.4575 5.7075 9 P 0 ;1
L 6.4575 5.7575 6.4575 5.7575 9 P 0 ;1
L 6.4575 5.8075 6.4575 5.8075 9 P 0 ;1
L 6.4575 5.8575 6.4575 5.8575 9 P 0 ;1
L 6.4575 5.9075 6.4575 5.9075 9 P 0 ;1
L 6.5075 0.5575 6.5075 0.5575 9 P 0 ;1
L 6.5075 0.6075 6.5075 0.6075 9 P 0 ;1
L 6.5075 0.6575 6.5075 0.6575 9 P 0 ;1
L 6.5075 0.7075 6.5075 0.7075 9 P 0 ;1
L 6.5075 0.7575 6.5075 0.7575 9 P 0 ;1
L 6.5075 0.8075 6.5075 0.8075 9 P 0 ;1
L 6.5075 0.8575 6.5075 0.8575 9 P 0 ;1
L 6.5075 1.0575 6.5075 1.0575 9 P 0 ;1
L 6.5075 1.1075 6.5075 1.1075 9 P 0 ;1
L 6.5075 1.1575 6.5075 1.1575 9 P 0 ;1
L 6.5075 1.2075 6.5075 1.2075 9 P 0 ;1
L 6.5075 1.2575 6.5075 1.2575 9 P 0 ;1
L 6.5075 1.3075 6.5075 1.3075 9 P 0 ;1
L 6.5075 1.6575 6.5075 1.6575 9 P 0 ;1
L 6.5075 1.7075 6.5075 1.7075 9 P 0 ;1
L 6.5075 1.7575 6.5075 1.7575 9 P 0 ;1
L 6.5075 1.8075 6.5075 1.8075 9 P 0 ;1
L 6.5075 1.8575 6.5075 1.8575 9 P 0 ;1
L 6.5075 1.9075 6.5075 1.9075 9 P 0 ;1
L 6.5075 1.9575 6.5075 1.9575 9 P 0 ;1
L 6.5075 2.0075 6.5075 2.0075 9 P 0 ;1
L 6.5075 2.0575 6.5075 2.0575 9 P 0 ;1
L 6.5075 2.1075 6.5075 2.1075 9 P 0 ;1
L 6.5075 2.1575 6.5075 2.1575 9 P 0 ;1
L 6.5075 2.2075 6.5075 2.2075 9 P 0 ;1
L 6.5075 2.2575 6.5075 2.2575 9 P 0 ;1
L 6.5075 2.3075 6.5075 2.3075 9 P 0 ;1
L 6.5075 2.3575 6.5075 2.3575 9 P 0 ;1
L 6.5075 2.4075 6.5075 2.4075 9 P 0 ;1
L 6.5075 2.4575 6.5075 2.4575 9 P 0 ;1
L 6.5075 2.5075 6.5075 2.5075 9 P 0 ;1
L 6.5075 2.5575 6.5075 2.5575 9 P 0 ;1
L 6.5075 2.6075 6.5075 2.6075 9 P 0 ;1
L 6.5075 2.6575 6.5075 2.6575 9 P 0 ;1
L 6.5075 2.7075 6.5075 2.7075 9 P 0 ;1
L 6.5075 2.7575 6.5075 2.7575 9 P 0 ;1
L 6.5075 2.8075 6.5075 2.8075 9 P 0 ;1
L 6.5075 2.8575 6.5075 2.8575 9 P 0 ;1
L 6.5075 2.9075 6.5075 2.9075 9 P 0 ;1
L 6.5075 2.9575 6.5075 2.9575 9 P 0 ;1
L 6.5075 3.0075 6.5075 3.0075 9 P 0 ;1
L 6.5075 3.0575 6.5075 3.0575 9 P 0 ;1
L 6.5075 3.1075 6.5075 3.1075 9 P 0 ;1
L 6.5075 3.1575 6.5075 3.1575 9 P 0 ;1
L 6.5075 3.2075 6.5075 3.2075 9 P 0 ;1
L 6.5075 3.2575 6.5075 3.2575 9 P 0 ;1
L 6.5075 3.3075 6.5075 3.3075 9 P 0 ;1
L 6.5075 3.3575 6.5075 3.3575 9 P 0 ;1
L 6.5075 3.4075 6.5075 3.4075 9 P 0 ;1
L 6.5075 3.4575 6.5075 3.4575 9 P 0 ;1
L 6.5075 3.5075 6.5075 3.5075 9 P 0 ;1
L 6.5075 3.5575 6.5075 3.5575 9 P 0 ;1
L 6.5075 3.6075 6.5075 3.6075 9 P 0 ;1
L 6.5075 3.6575 6.5075 3.6575 9 P 0 ;1
L 6.5075 3.7075 6.5075 3.7075 9 P 0 ;1
L 6.5075 3.7575 6.5075 3.7575 9 P 0 ;1
L 6.5075 3.8075 6.5075 3.8075 9 P 0 ;1
L 6.5075 3.8575 6.5075 3.8575 9 P 0 ;1
L 6.5075 3.9075 6.5075 3.9075 9 P 0 ;1
L 6.5075 3.9575 6.5075 3.9575 9 P 0 ;1
L 6.5075 4.0075 6.5075 4.0075 9 P 0 ;1
L 6.5075 4.0575 6.5075 4.0575 9 P 0 ;1
L 6.5075 4.1075 6.5075 4.1075 9 P 0 ;1
L 6.5075 4.1575 6.5075 4.1575 9 P 0 ;1
L 6.5075 4.2075 6.5075 4.2075 9 P 0 ;1
L 6.5075 4.2575 6.5075 4.2575 9 P 0 ;1
L 6.5075 4.3075 6.5075 4.3075 9 P 0 ;1
L 6.5075 4.3575 6.5075 4.3575 9 P 0 ;1
L 6.5075 4.4075 6.5075 4.4075 9 P 0 ;1
L 6.5075 4.4575 6.5075 4.4575 9 P 0 ;1
L 6.5075 4.5075 6.5075 4.5075 9 P 0 ;1
L 6.5075 4.5575 6.5075 4.5575 9 P 0 ;1
L 6.5075 4.6075 6.5075 4.6075 9 P 0 ;1
L 6.5075 4.6575 6.5075 4.6575 9 P 0 ;1
L 6.5075 4.7075 6.5075 4.7075 9 P 0 ;1
L 6.5075 4.7575 6.5075 4.7575 9 P 0 ;1
L 6.5075 4.8075 6.5075 4.8075 9 P 0 ;1
L 6.5075 5.2075 6.5075 5.2075 9 P 0 ;1
L 6.5075 5.2575 6.5075 5.2575 9 P 0 ;1
L 6.5075 5.3075 6.5075 5.3075 9 P 0 ;1
L 6.5075 5.3575 6.5075 5.3575 9 P 0 ;1
L 6.5075 5.4075 6.5075 5.4075 9 P 0 ;1
L 6.5075 5.4575 6.5075 5.4575 9 P 0 ;1
L 6.5075 5.5075 6.5075 5.5075 9 P 0 ;1
L 6.5075 5.5575 6.5075 5.5575 9 P 0 ;1
L 6.5075 5.6075 6.5075 5.6075 9 P 0 ;1
L 6.5075 5.6575 6.5075 5.6575 9 P 0 ;1
L 6.5075 5.7075 6.5075 5.7075 9 P 0 ;1
L 6.5075 5.7575 6.5075 5.7575 9 P 0 ;1
L 6.5075 5.8075 6.5075 5.8075 9 P 0 ;1
L 6.5075 5.8575 6.5075 5.8575 9 P 0 ;1
L 6.5075 5.9075 6.5075 5.9075 9 P 0 ;1
L 6.5575 0.5575 6.5575 0.5575 9 P 0 ;1
L 6.5575 0.6075 6.5575 0.6075 9 P 0 ;1
L 6.5575 0.6575 6.5575 0.6575 9 P 0 ;1
L 6.5575 0.7075 6.5575 0.7075 9 P 0 ;1
L 6.5575 0.7575 6.5575 0.7575 9 P 0 ;1
L 6.5575 0.8075 6.5575 0.8075 9 P 0 ;1
L 6.5575 0.8575 6.5575 0.8575 9 P 0 ;1
L 6.5575 1.0575 6.5575 1.0575 9 P 0 ;1
L 6.5575 1.1075 6.5575 1.1075 9 P 0 ;1
L 6.5575 1.1575 6.5575 1.1575 9 P 0 ;1
L 6.5575 1.2075 6.5575 1.2075 9 P 0 ;1
L 6.5575 1.2575 6.5575 1.2575 9 P 0 ;1
L 6.5575 1.3075 6.5575 1.3075 9 P 0 ;1
L 6.5575 1.3575 6.5575 1.3575 9 P 0 ;1
L 6.5575 1.7075 6.5575 1.7075 9 P 0 ;1
L 6.5575 1.7575 6.5575 1.7575 9 P 0 ;1
L 6.5575 1.8075 6.5575 1.8075 9 P 0 ;1
L 6.5575 1.8575 6.5575 1.8575 9 P 0 ;1
L 6.5575 1.9075 6.5575 1.9075 9 P 0 ;1
L 6.5575 1.9575 6.5575 1.9575 9 P 0 ;1
L 6.5575 2.0075 6.5575 2.0075 9 P 0 ;1
L 6.5575 2.0575 6.5575 2.0575 9 P 0 ;1
L 6.5575 2.1075 6.5575 2.1075 9 P 0 ;1
L 6.5575 2.1575 6.5575 2.1575 9 P 0 ;1
L 6.5575 2.2075 6.5575 2.2075 9 P 0 ;1
L 6.5575 2.2575 6.5575 2.2575 9 P 0 ;1
L 6.5575 2.3075 6.5575 2.3075 9 P 0 ;1
L 6.5575 2.3575 6.5575 2.3575 9 P 0 ;1
L 6.5575 2.4075 6.5575 2.4075 9 P 0 ;1
L 6.5575 2.4575 6.5575 2.4575 9 P 0 ;1
L 6.5575 2.5075 6.5575 2.5075 9 P 0 ;1
L 6.5575 2.5575 6.5575 2.5575 9 P 0 ;1
L 6.5575 2.6075 6.5575 2.6075 9 P 0 ;1
L 6.5575 2.6575 6.5575 2.6575 9 P 0 ;1
L 6.5575 2.7075 6.5575 2.7075 9 P 0 ;1
L 6.5575 2.7575 6.5575 2.7575 9 P 0 ;1
L 6.5575 2.8075 6.5575 2.8075 9 P 0 ;1
L 6.5575 2.8575 6.5575 2.8575 9 P 0 ;1
L 6.5575 2.9075 6.5575 2.9075 9 P 0 ;1
L 6.5575 2.9575 6.5575 2.9575 9 P 0 ;1
L 6.5575 3.0075 6.5575 3.0075 9 P 0 ;1
L 6.5575 3.0575 6.5575 3.0575 9 P 0 ;1
L 6.5575 3.1075 6.5575 3.1075 9 P 0 ;1
L 6.5575 3.1575 6.5575 3.1575 9 P 0 ;1
L 6.5575 3.2075 6.5575 3.2075 9 P 0 ;1
L 6.5575 3.2575 6.5575 3.2575 9 P 0 ;1
L 6.5575 3.3075 6.5575 3.3075 9 P 0 ;1
L 6.5575 3.3575 6.5575 3.3575 9 P 0 ;1
L 6.5575 3.4075 6.5575 3.4075 9 P 0 ;1
L 6.5575 3.4575 6.5575 3.4575 9 P 0 ;1
L 6.5575 3.5075 6.5575 3.5075 9 P 0 ;1
L 6.5575 3.5575 6.5575 3.5575 9 P 0 ;1
L 6.5575 3.6075 6.5575 3.6075 9 P 0 ;1
L 6.5575 3.6575 6.5575 3.6575 9 P 0 ;1
L 6.5575 3.7075 6.5575 3.7075 9 P 0 ;1
L 6.5575 3.7575 6.5575 3.7575 9 P 0 ;1
L 6.5575 3.8075 6.5575 3.8075 9 P 0 ;1
L 6.5575 3.8575 6.5575 3.8575 9 P 0 ;1
L 6.5575 3.9075 6.5575 3.9075 9 P 0 ;1
L 6.5575 3.9575 6.5575 3.9575 9 P 0 ;1
L 6.5575 4.0075 6.5575 4.0075 9 P 0 ;1
L 6.5575 4.0575 6.5575 4.0575 9 P 0 ;1
L 6.5575 4.1075 6.5575 4.1075 9 P 0 ;1
L 6.5575 4.1575 6.5575 4.1575 9 P 0 ;1
L 6.5575 4.2075 6.5575 4.2075 9 P 0 ;1
L 6.5575 4.2575 6.5575 4.2575 9 P 0 ;1
L 6.5575 4.3075 6.5575 4.3075 9 P 0 ;1
L 6.5575 4.3575 6.5575 4.3575 9 P 0 ;1
L 6.5575 4.4075 6.5575 4.4075 9 P 0 ;1
L 6.5575 4.4575 6.5575 4.4575 9 P 0 ;1
L 6.5575 4.5075 6.5575 4.5075 9 P 0 ;1
L 6.5575 4.5575 6.5575 4.5575 9 P 0 ;1
L 6.5575 5.1575 6.5575 5.1575 9 P 0 ;1
L 6.5575 5.2075 6.5575 5.2075 9 P 0 ;1
L 6.5575 5.2575 6.5575 5.2575 9 P 0 ;1
L 6.5575 5.3075 6.5575 5.3075 9 P 0 ;1
L 6.5575 5.3575 6.5575 5.3575 9 P 0 ;1
L 6.5575 5.4075 6.5575 5.4075 9 P 0 ;1
L 6.5575 5.4575 6.5575 5.4575 9 P 0 ;1
L 6.5575 5.5075 6.5575 5.5075 9 P 0 ;1
L 6.5575 5.5575 6.5575 5.5575 9 P 0 ;1
L 6.5575 5.6075 6.5575 5.6075 9 P 0 ;1
L 6.5575 5.6575 6.5575 5.6575 9 P 0 ;1
L 6.5575 5.7075 6.5575 5.7075 9 P 0 ;1
L 6.5575 5.7575 6.5575 5.7575 9 P 0 ;1
L 6.5575 5.8075 6.5575 5.8075 9 P 0 ;1
L 6.5575 5.8575 6.5575 5.8575 9 P 0 ;1
L 6.5575 5.9075 6.5575 5.9075 9 P 0 ;1
L 6.6075 0.5575 6.6075 0.5575 9 P 0 ;1
L 6.6075 0.6075 6.6075 0.6075 9 P 0 ;1
L 6.6075 0.6575 6.6075 0.6575 9 P 0 ;1
L 6.6075 0.7075 6.6075 0.7075 9 P 0 ;1
L 6.6075 0.7575 6.6075 0.7575 9 P 0 ;1
L 6.6075 0.8075 6.6075 0.8075 9 P 0 ;1
L 6.6075 0.8575 6.6075 0.8575 9 P 0 ;1
L 6.6075 1.0575 6.6075 1.0575 9 P 0 ;1
L 6.6075 1.1075 6.6075 1.1075 9 P 0 ;1
L 6.6075 1.1575 6.6075 1.1575 9 P 0 ;1
L 6.6075 1.2075 6.6075 1.2075 9 P 0 ;1
L 6.6075 1.2575 6.6075 1.2575 9 P 0 ;1
L 6.6075 1.3075 6.6075 1.3075 9 P 0 ;1
L 6.6075 1.3575 6.6075 1.3575 9 P 0 ;1
L 6.6075 1.4075 6.6075 1.4075 9 P 0 ;1
L 6.6075 1.7575 6.6075 1.7575 9 P 0 ;1
L 6.6075 1.8075 6.6075 1.8075 9 P 0 ;1
L 6.6075 1.8575 6.6075 1.8575 9 P 0 ;1
L 6.6075 1.9075 6.6075 1.9075 9 P 0 ;1
L 6.6075 1.9575 6.6075 1.9575 9 P 0 ;1
L 6.6075 2.0075 6.6075 2.0075 9 P 0 ;1
L 6.6075 2.0575 6.6075 2.0575 9 P 0 ;1
L 6.6075 2.1075 6.6075 2.1075 9 P 0 ;1
L 6.6075 2.1575 6.6075 2.1575 9 P 0 ;1
L 6.6075 2.2075 6.6075 2.2075 9 P 0 ;1
L 6.6075 2.2575 6.6075 2.2575 9 P 0 ;1
L 6.6075 2.3075 6.6075 2.3075 9 P 0 ;1
L 6.6075 2.3575 6.6075 2.3575 9 P 0 ;1
L 6.6075 2.4075 6.6075 2.4075 9 P 0 ;1
L 6.6075 2.4575 6.6075 2.4575 9 P 0 ;1
L 6.6075 2.5075 6.6075 2.5075 9 P 0 ;1
L 6.6075 2.5575 6.6075 2.5575 9 P 0 ;1
L 6.6075 2.6075 6.6075 2.6075 9 P 0 ;1
L 6.6075 2.6575 6.6075 2.6575 9 P 0 ;1
L 6.6075 2.7075 6.6075 2.7075 9 P 0 ;1
L 6.6075 2.7575 6.6075 2.7575 9 P 0 ;1
L 6.6075 2.8075 6.6075 2.8075 9 P 0 ;1
L 6.6075 2.8575 6.6075 2.8575 9 P 0 ;1
L 6.6075 2.9075 6.6075 2.9075 9 P 0 ;1
L 6.6075 2.9575 6.6075 2.9575 9 P 0 ;1
L 6.6075 3.0075 6.6075 3.0075 9 P 0 ;1
L 6.6075 3.0575 6.6075 3.0575 9 P 0 ;1
L 6.6075 3.1075 6.6075 3.1075 9 P 0 ;1
L 6.6075 3.1575 6.6075 3.1575 9 P 0 ;1
L 6.6075 3.2075 6.6075 3.2075 9 P 0 ;1
L 6.6075 3.2575 6.6075 3.2575 9 P 0 ;1
L 6.6075 3.3075 6.6075 3.3075 9 P 0 ;1
L 6.6075 3.3575 6.6075 3.3575 9 P 0 ;1
L 6.6075 3.4075 6.6075 3.4075 9 P 0 ;1
L 6.6075 3.4575 6.6075 3.4575 9 P 0 ;1
L 6.6075 3.5075 6.6075 3.5075 9 P 0 ;1
L 6.6075 3.5575 6.6075 3.5575 9 P 0 ;1
L 6.6075 3.6075 6.6075 3.6075 9 P 0 ;1
L 6.6075 3.6575 6.6075 3.6575 9 P 0 ;1
L 6.6075 3.7075 6.6075 3.7075 9 P 0 ;1
L 6.6075 3.7575 6.6075 3.7575 9 P 0 ;1
L 6.6075 3.8075 6.6075 3.8075 9 P 0 ;1
L 6.6075 3.8575 6.6075 3.8575 9 P 0 ;1
L 6.6075 3.9075 6.6075 3.9075 9 P 0 ;1
L 6.6075 3.9575 6.6075 3.9575 9 P 0 ;1
L 6.6075 4.0075 6.6075 4.0075 9 P 0 ;1
L 6.6075 4.0575 6.6075 4.0575 9 P 0 ;1
L 6.6075 4.1075 6.6075 4.1075 9 P 0 ;1
L 6.6075 4.1575 6.6075 4.1575 9 P 0 ;1
L 6.6075 4.2075 6.6075 4.2075 9 P 0 ;1
L 6.6075 4.2575 6.6075 4.2575 9 P 0 ;1
L 6.6075 4.3075 6.6075 4.3075 9 P 0 ;1
L 6.6075 4.3575 6.6075 4.3575 9 P 0 ;1
L 6.6075 4.4075 6.6075 4.4075 9 P 0 ;1
L 6.6075 4.4575 6.6075 4.4575 9 P 0 ;1
L 6.6075 4.5075 6.6075 4.5075 9 P 0 ;1
L 6.6075 5.1575 6.6075 5.1575 9 P 0 ;1
L 6.6075 5.2075 6.6075 5.2075 9 P 0 ;1
L 6.6075 5.2575 6.6075 5.2575 9 P 0 ;1
L 6.6075 5.3075 6.6075 5.3075 9 P 0 ;1
L 6.6075 5.3575 6.6075 5.3575 9 P 0 ;1
L 6.6075 5.4075 6.6075 5.4075 9 P 0 ;1
L 6.6075 5.4575 6.6075 5.4575 9 P 0 ;1
L 6.6075 5.5075 6.6075 5.5075 9 P 0 ;1
L 6.6075 5.5575 6.6075 5.5575 9 P 0 ;1
L 6.6075 5.6075 6.6075 5.6075 9 P 0 ;1
L 6.6075 5.6575 6.6075 5.6575 9 P 0 ;1
L 6.6075 5.7075 6.6075 5.7075 9 P 0 ;1
L 6.6075 5.7575 6.6075 5.7575 9 P 0 ;1
L 6.6075 5.8075 6.6075 5.8075 9 P 0 ;1
L 6.6075 5.8575 6.6075 5.8575 9 P 0 ;1
L 6.6075 5.9075 6.6075 5.9075 9 P 0 ;1
L 6.6575 0.5075 6.6575 0.5075 9 P 0 ;1
L 6.6575 0.5575 6.6575 0.5575 9 P 0 ;1
L 6.6575 0.6075 6.6575 0.6075 9 P 0 ;1
L 6.6575 0.6575 6.6575 0.6575 9 P 0 ;1
L 6.6575 0.7075 6.6575 0.7075 9 P 0 ;1
L 6.6575 0.7575 6.6575 0.7575 9 P 0 ;1
L 6.6575 0.8075 6.6575 0.8075 9 P 0 ;1
L 6.6575 0.8575 6.6575 0.8575 9 P 0 ;1
L 6.6575 1.0575 6.6575 1.0575 9 P 0 ;1
L 6.6575 1.1075 6.6575 1.1075 9 P 0 ;1
L 6.6575 1.1575 6.6575 1.1575 9 P 0 ;1
L 6.6575 1.2075 6.6575 1.2075 9 P 0 ;1
L 6.6575 1.2575 6.6575 1.2575 9 P 0 ;1
L 6.6575 1.3075 6.6575 1.3075 9 P 0 ;1
L 6.6575 1.3575 6.6575 1.3575 9 P 0 ;1
L 6.6575 1.4075 6.6575 1.4075 9 P 0 ;1
L 6.6575 1.4575 6.6575 1.4575 9 P 0 ;1
L 6.6575 1.8075 6.6575 1.8075 9 P 0 ;1
L 6.6575 1.8575 6.6575 1.8575 9 P 0 ;1
L 6.6575 1.9075 6.6575 1.9075 9 P 0 ;1
L 6.6575 1.9575 6.6575 1.9575 9 P 0 ;1
L 6.6575 2.0075 6.6575 2.0075 9 P 0 ;1
L 6.6575 2.0575 6.6575 2.0575 9 P 0 ;1
L 6.6575 2.1075 6.6575 2.1075 9 P 0 ;1
L 6.6575 2.1575 6.6575 2.1575 9 P 0 ;1
L 6.6575 2.2075 6.6575 2.2075 9 P 0 ;1
L 6.6575 2.2575 6.6575 2.2575 9 P 0 ;1
L 6.6575 2.3075 6.6575 2.3075 9 P 0 ;1
L 6.6575 2.3575 6.6575 2.3575 9 P 0 ;1
L 6.6575 2.4075 6.6575 2.4075 9 P 0 ;1
L 6.6575 2.4575 6.6575 2.4575 9 P 0 ;1
L 6.6575 2.5075 6.6575 2.5075 9 P 0 ;1
L 6.6575 2.5575 6.6575 2.5575 9 P 0 ;1
L 6.6575 2.6075 6.6575 2.6075 9 P 0 ;1
L 6.6575 2.6575 6.6575 2.6575 9 P 0 ;1
L 6.6575 2.7075 6.6575 2.7075 9 P 0 ;1
L 6.6575 2.7575 6.6575 2.7575 9 P 0 ;1
L 6.6575 2.8075 6.6575 2.8075 9 P 0 ;1
L 6.6575 2.8575 6.6575 2.8575 9 P 0 ;1
L 6.6575 2.9075 6.6575 2.9075 9 P 0 ;1
L 6.6575 2.9575 6.6575 2.9575 9 P 0 ;1
L 6.6575 3.0075 6.6575 3.0075 9 P 0 ;1
L 6.6575 3.0575 6.6575 3.0575 9 P 0 ;1
L 6.6575 3.1075 6.6575 3.1075 9 P 0 ;1
L 6.6575 3.1575 6.6575 3.1575 9 P 0 ;1
L 6.6575 3.2075 6.6575 3.2075 9 P 0 ;1
L 6.6575 3.2575 6.6575 3.2575 9 P 0 ;1
L 6.6575 3.3075 6.6575 3.3075 9 P 0 ;1
L 6.6575 3.3575 6.6575 3.3575 9 P 0 ;1
L 6.6575 3.4075 6.6575 3.4075 9 P 0 ;1
L 6.6575 3.4575 6.6575 3.4575 9 P 0 ;1
L 6.6575 3.5075 6.6575 3.5075 9 P 0 ;1
L 6.6575 3.5575 6.6575 3.5575 9 P 0 ;1
L 6.6575 3.6075 6.6575 3.6075 9 P 0 ;1
L 6.6575 3.6575 6.6575 3.6575 9 P 0 ;1
L 6.6575 3.7075 6.6575 3.7075 9 P 0 ;1
L 6.6575 3.7575 6.6575 3.7575 9 P 0 ;1
L 6.6575 3.8075 6.6575 3.8075 9 P 0 ;1
L 6.6575 3.8575 6.6575 3.8575 9 P 0 ;1
L 6.6575 3.9075 6.6575 3.9075 9 P 0 ;1
L 6.6575 3.9575 6.6575 3.9575 9 P 0 ;1
L 6.6575 4.0075 6.6575 4.0075 9 P 0 ;1
L 6.6575 4.0575 6.6575 4.0575 9 P 0 ;1
L 6.6575 4.1075 6.6575 4.1075 9 P 0 ;1
L 6.6575 4.1575 6.6575 4.1575 9 P 0 ;1
L 6.6575 4.2075 6.6575 4.2075 9 P 0 ;1
L 6.6575 4.2575 6.6575 4.2575 9 P 0 ;1
L 6.6575 4.3075 6.6575 4.3075 9 P 0 ;1
L 6.6575 4.3575 6.6575 4.3575 9 P 0 ;1
L 6.6575 4.4075 6.6575 4.4075 9 P 0 ;1
L 6.6575 4.4575 6.6575 4.4575 9 P 0 ;1
L 6.6575 4.5075 6.6575 4.5075 9 P 0 ;1
L 6.6575 5.1575 6.6575 5.1575 9 P 0 ;1
L 6.6575 5.2075 6.6575 5.2075 9 P 0 ;1
L 6.6575 5.2575 6.6575 5.2575 9 P 0 ;1
L 6.6575 5.3075 6.6575 5.3075 9 P 0 ;1
L 6.6575 5.3575 6.6575 5.3575 9 P 0 ;1
L 6.6575 5.4075 6.6575 5.4075 9 P 0 ;1
L 6.6575 5.4575 6.6575 5.4575 9 P 0 ;1
L 6.6575 5.5075 6.6575 5.5075 9 P 0 ;1
L 6.6575 5.5575 6.6575 5.5575 9 P 0 ;1
L 6.6575 5.6075 6.6575 5.6075 9 P 0 ;1
L 6.6575 5.6575 6.6575 5.6575 9 P 0 ;1
L 6.6575 5.7075 6.6575 5.7075 9 P 0 ;1
L 6.6575 5.7575 6.6575 5.7575 9 P 0 ;1
L 6.6575 5.8075 6.6575 5.8075 9 P 0 ;1
L 6.6575 5.8575 6.6575 5.8575 9 P 0 ;1
L 6.6575 5.9075 6.6575 5.9075 9 P 0 ;1
L 6.7075 0.1575 6.7075 0.1575 9 P 0 ;1
L 6.7075 0.2075 6.7075 0.2075 9 P 0 ;1
L 6.7075 0.2575 6.7075 0.2575 9 P 0 ;1
L 6.7075 0.3075 6.7075 0.3075 9 P 0 ;1
L 6.7075 0.3575 6.7075 0.3575 9 P 0 ;1
L 6.7075 0.4075 6.7075 0.4075 9 P 0 ;1
L 6.7075 0.4575 6.7075 0.4575 9 P 0 ;1
L 6.7075 0.5075 6.7075 0.5075 9 P 0 ;1
L 6.7075 0.5575 6.7075 0.5575 9 P 0 ;1
L 6.7075 0.6075 6.7075 0.6075 9 P 0 ;1
L 6.7075 0.6575 6.7075 0.6575 9 P 0 ;1
L 6.7075 0.7075 6.7075 0.7075 9 P 0 ;1
L 6.7075 0.7575 6.7075 0.7575 9 P 0 ;1
L 6.7075 0.8075 6.7075 0.8075 9 P 0 ;1
L 6.7075 0.8575 6.7075 0.8575 9 P 0 ;1
L 6.7075 1.0575 6.7075 1.0575 9 P 0 ;1
L 6.7075 1.1075 6.7075 1.1075 9 P 0 ;1
L 6.7075 1.1575 6.7075 1.1575 9 P 0 ;1
L 6.7075 1.2075 6.7075 1.2075 9 P 0 ;1
L 6.7075 1.2575 6.7075 1.2575 9 P 0 ;1
L 6.7075 1.3075 6.7075 1.3075 9 P 0 ;1
L 6.7075 1.3575 6.7075 1.3575 9 P 0 ;1
L 6.7075 1.4075 6.7075 1.4075 9 P 0 ;1
L 6.7075 1.4575 6.7075 1.4575 9 P 0 ;1
L 6.7075 1.5075 6.7075 1.5075 9 P 0 ;1
L 6.7075 1.8575 6.7075 1.8575 9 P 0 ;1
L 6.7075 1.9075 6.7075 1.9075 9 P 0 ;1
L 6.7075 1.9575 6.7075 1.9575 9 P 0 ;1
L 6.7075 2.0075 6.7075 2.0075 9 P 0 ;1
L 6.7075 2.0575 6.7075 2.0575 9 P 0 ;1
L 6.7075 2.1075 6.7075 2.1075 9 P 0 ;1
L 6.7075 2.1575 6.7075 2.1575 9 P 0 ;1
L 6.7075 2.2075 6.7075 2.2075 9 P 0 ;1
L 6.7075 2.2575 6.7075 2.2575 9 P 0 ;1
L 6.7075 2.3075 6.7075 2.3075 9 P 0 ;1
L 6.7075 2.3575 6.7075 2.3575 9 P 0 ;1
L 6.7075 2.4075 6.7075 2.4075 9 P 0 ;1
L 6.7075 2.4575 6.7075 2.4575 9 P 0 ;1
L 6.7075 2.5075 6.7075 2.5075 9 P 0 ;1
L 6.7075 2.5575 6.7075 2.5575 9 P 0 ;1
L 6.7075 2.6075 6.7075 2.6075 9 P 0 ;1
L 6.7075 2.6575 6.7075 2.6575 9 P 0 ;1
L 6.7075 2.7075 6.7075 2.7075 9 P 0 ;1
L 6.7075 2.7575 6.7075 2.7575 9 P 0 ;1
L 6.7075 2.8075 6.7075 2.8075 9 P 0 ;1
L 6.7075 2.8575 6.7075 2.8575 9 P 0 ;1
L 6.7075 2.9075 6.7075 2.9075 9 P 0 ;1
L 6.7075 2.9575 6.7075 2.9575 9 P 0 ;1
L 6.7075 3.0075 6.7075 3.0075 9 P 0 ;1
L 6.7075 3.0575 6.7075 3.0575 9 P 0 ;1
L 6.7075 3.1075 6.7075 3.1075 9 P 0 ;1
L 6.7075 3.1575 6.7075 3.1575 9 P 0 ;1
L 6.7075 3.2075 6.7075 3.2075 9 P 0 ;1
L 6.7075 3.2575 6.7075 3.2575 9 P 0 ;1
L 6.7075 3.3075 6.7075 3.3075 9 P 0 ;1
L 6.7075 3.3575 6.7075 3.3575 9 P 0 ;1
L 6.7075 3.4075 6.7075 3.4075 9 P 0 ;1
L 6.7075 3.4575 6.7075 3.4575 9 P 0 ;1
L 6.7075 3.5075 6.7075 3.5075 9 P 0 ;1
L 6.7075 3.5575 6.7075 3.5575 9 P 0 ;1
L 6.7075 3.6075 6.7075 3.6075 9 P 0 ;1
L 6.7075 3.6575 6.7075 3.6575 9 P 0 ;1
L 6.7075 3.7075 6.7075 3.7075 9 P 0 ;1
L 6.7075 3.7575 6.7075 3.7575 9 P 0 ;1
L 6.7075 3.8075 6.7075 3.8075 9 P 0 ;1
L 6.7075 3.8575 6.7075 3.8575 9 P 0 ;1
L 6.7075 3.9075 6.7075 3.9075 9 P 0 ;1
L 6.7075 3.9575 6.7075 3.9575 9 P 0 ;1
L 6.7075 4.0075 6.7075 4.0075 9 P 0 ;1
L 6.7075 4.0575 6.7075 4.0575 9 P 0 ;1
L 6.7075 4.1075 6.7075 4.1075 9 P 0 ;1
L 6.7075 4.1575 6.7075 4.1575 9 P 0 ;1
L 6.7075 4.2075 6.7075 4.2075 9 P 0 ;1
L 6.7075 4.2575 6.7075 4.2575 9 P 0 ;1
L 6.7075 4.3075 6.7075 4.3075 9 P 0 ;1
L 6.7075 4.3575 6.7075 4.3575 9 P 0 ;1
L 6.7075 4.4075 6.7075 4.4075 9 P 0 ;1
L 6.7075 4.4575 6.7075 4.4575 9 P 0 ;1
L 6.7075 4.6575 6.7075 4.6575 9 P 0 ;1
L 6.7075 5.1575 6.7075 5.1575 9 P 0 ;1
L 6.7075 5.2075 6.7075 5.2075 9 P 0 ;1
L 6.7075 5.2575 6.7075 5.2575 9 P 0 ;1
L 6.7075 5.3075 6.7075 5.3075 9 P 0 ;1
L 6.7075 5.3575 6.7075 5.3575 9 P 0 ;1
L 6.7075 5.4075 6.7075 5.4075 9 P 0 ;1
L 6.7075 5.4575 6.7075 5.4575 9 P 0 ;1
L 6.7075 5.5075 6.7075 5.5075 9 P 0 ;1
L 6.7075 5.5575 6.7075 5.5575 9 P 0 ;1
L 6.7075 5.6075 6.7075 5.6075 9 P 0 ;1
L 6.7075 5.6575 6.7075 5.6575 9 P 0 ;1
L 6.7075 5.7075 6.7075 5.7075 9 P 0 ;1
L 6.7075 5.7575 6.7075 5.7575 9 P 0 ;1
L 6.7075 5.8075 6.7075 5.8075 9 P 0 ;1
L 6.7075 5.8575 6.7075 5.8575 9 P 0 ;1
L 6.7075 5.9075 6.7075 5.9075 9 P 0 ;1
L 6.7575 0.1575 6.7575 0.1575 9 P 0 ;1
L 6.7575 0.2075 6.7575 0.2075 9 P 0 ;1
L 6.7575 0.2575 6.7575 0.2575 9 P 0 ;1
L 6.7575 0.3075 6.7575 0.3075 9 P 0 ;1
L 6.7575 0.3575 6.7575 0.3575 9 P 0 ;1
L 6.7575 0.4075 6.7575 0.4075 9 P 0 ;1
L 6.7575 0.4575 6.7575 0.4575 9 P 0 ;1
L 6.7575 0.5075 6.7575 0.5075 9 P 0 ;1
L 6.7575 0.5575 6.7575 0.5575 9 P 0 ;1
L 6.7575 0.6075 6.7575 0.6075 9 P 0 ;1
L 6.7575 0.6575 6.7575 0.6575 9 P 0 ;1
L 6.7575 0.7075 6.7575 0.7075 9 P 0 ;1
L 6.7575 0.7575 6.7575 0.7575 9 P 0 ;1
L 6.7575 0.8075 6.7575 0.8075 9 P 0 ;1
L 6.7575 0.8575 6.7575 0.8575 9 P 0 ;1
L 6.7575 1.0575 6.7575 1.0575 9 P 0 ;1
L 6.7575 1.1075 6.7575 1.1075 9 P 0 ;1
L 6.7575 1.1575 6.7575 1.1575 9 P 0 ;1
L 6.7575 1.2075 6.7575 1.2075 9 P 0 ;1
L 6.7575 1.2575 6.7575 1.2575 9 P 0 ;1
L 6.7575 1.3075 6.7575 1.3075 9 P 0 ;1
L 6.7575 1.3575 6.7575 1.3575 9 P 0 ;1
L 6.7575 1.4075 6.7575 1.4075 9 P 0 ;1
L 6.7575 1.4575 6.7575 1.4575 9 P 0 ;1
L 6.7575 1.5075 6.7575 1.5075 9 P 0 ;1
L 6.7575 1.5575 6.7575 1.5575 9 P 0 ;1
L 6.7575 1.9075 6.7575 1.9075 9 P 0 ;1
L 6.7575 1.9575 6.7575 1.9575 9 P 0 ;1
L 6.7575 2.0075 6.7575 2.0075 9 P 0 ;1
L 6.7575 2.0575 6.7575 2.0575 9 P 0 ;1
L 6.7575 2.1075 6.7575 2.1075 9 P 0 ;1
L 6.7575 2.1575 6.7575 2.1575 9 P 0 ;1
L 6.7575 2.2075 6.7575 2.2075 9 P 0 ;1
L 6.7575 2.2575 6.7575 2.2575 9 P 0 ;1
L 6.7575 2.3075 6.7575 2.3075 9 P 0 ;1
L 6.7575 2.3575 6.7575 2.3575 9 P 0 ;1
L 6.7575 2.4075 6.7575 2.4075 9 P 0 ;1
L 6.7575 2.4575 6.7575 2.4575 9 P 0 ;1
L 6.7575 2.5075 6.7575 2.5075 9 P 0 ;1
L 6.7575 2.5575 6.7575 2.5575 9 P 0 ;1
L 6.7575 2.6075 6.7575 2.6075 9 P 0 ;1
L 6.7575 2.6575 6.7575 2.6575 9 P 0 ;1
L 6.7575 2.7075 6.7575 2.7075 9 P 0 ;1
L 6.7575 2.7575 6.7575 2.7575 9 P 0 ;1
L 6.7575 2.8075 6.7575 2.8075 9 P 0 ;1
L 6.7575 2.8575 6.7575 2.8575 9 P 0 ;1
L 6.7575 2.9075 6.7575 2.9075 9 P 0 ;1
L 6.7575 2.9575 6.7575 2.9575 9 P 0 ;1
L 6.7575 3.0075 6.7575 3.0075 9 P 0 ;1
L 6.7575 3.0575 6.7575 3.0575 9 P 0 ;1
L 6.7575 3.1075 6.7575 3.1075 9 P 0 ;1
L 6.7575 3.1575 6.7575 3.1575 9 P 0 ;1
L 6.7575 3.2075 6.7575 3.2075 9 P 0 ;1
L 6.7575 3.2575 6.7575 3.2575 9 P 0 ;1
L 6.7575 3.3075 6.7575 3.3075 9 P 0 ;1
L 6.7575 3.3575 6.7575 3.3575 9 P 0 ;1
L 6.7575 3.4075 6.7575 3.4075 9 P 0 ;1
L 6.7575 3.4575 6.7575 3.4575 9 P 0 ;1
L 6.7575 3.5075 6.7575 3.5075 9 P 0 ;1
L 6.7575 3.5575 6.7575 3.5575 9 P 0 ;1
L 6.7575 3.6075 6.7575 3.6075 9 P 0 ;1
L 6.7575 3.6575 6.7575 3.6575 9 P 0 ;1
L 6.7575 3.7075 6.7575 3.7075 9 P 0 ;1
L 6.7575 3.7575 6.7575 3.7575 9 P 0 ;1
L 6.7575 3.8075 6.7575 3.8075 9 P 0 ;1
L 6.7575 3.8575 6.7575 3.8575 9 P 0 ;1
L 6.7575 3.9075 6.7575 3.9075 9 P 0 ;1
L 6.7575 3.9575 6.7575 3.9575 9 P 0 ;1
L 6.7575 4.0075 6.7575 4.0075 9 P 0 ;1
L 6.7575 4.0575 6.7575 4.0575 9 P 0 ;1
L 6.7575 4.1075 6.7575 4.1075 9 P 0 ;1
L 6.7575 4.1575 6.7575 4.1575 9 P 0 ;1
L 6.7575 4.2575 6.7575 4.2575 9 P 0 ;1
L 6.7575 4.3075 6.7575 4.3075 9 P 0 ;1
L 6.7575 4.3575 6.7575 4.3575 9 P 0 ;1
L 6.7575 4.4075 6.7575 4.4075 9 P 0 ;1
L 6.7575 4.4575 6.7575 4.4575 9 P 0 ;1
L 6.7575 5.1075 6.7575 5.1075 9 P 0 ;1
L 6.7575 5.1575 6.7575 5.1575 9 P 0 ;1
L 6.7575 5.2075 6.7575 5.2075 9 P 0 ;1
L 6.7575 5.2575 6.7575 5.2575 9 P 0 ;1
L 6.7575 5.3075 6.7575 5.3075 9 P 0 ;1
L 6.7575 5.3575 6.7575 5.3575 9 P 0 ;1
L 6.7575 5.4075 6.7575 5.4075 9 P 0 ;1
L 6.7575 5.4575 6.7575 5.4575 9 P 0 ;1
L 6.7575 5.5075 6.7575 5.5075 9 P 0 ;1
L 6.7575 5.5575 6.7575 5.5575 9 P 0 ;1
L 6.7575 5.6075 6.7575 5.6075 9 P 0 ;1
L 6.7575 5.6575 6.7575 5.6575 9 P 0 ;1
L 6.7575 5.7075 6.7575 5.7075 9 P 0 ;1
L 6.7575 5.7575 6.7575 5.7575 9 P 0 ;1
L 6.7575 5.8075 6.7575 5.8075 9 P 0 ;1
L 6.7575 5.8575 6.7575 5.8575 9 P 0 ;1
L 6.7575 5.9075 6.7575 5.9075 9 P 0 ;1
L 6.8075 0.1575 6.8075 0.1575 9 P 0 ;1
L 6.8075 0.2075 6.8075 0.2075 9 P 0 ;1
L 6.8075 0.2575 6.8075 0.2575 9 P 0 ;1
L 6.8075 0.3075 6.8075 0.3075 9 P 0 ;1
L 6.8075 0.3575 6.8075 0.3575 9 P 0 ;1
L 6.8075 0.4075 6.8075 0.4075 9 P 0 ;1
L 6.8075 0.4575 6.8075 0.4575 9 P 0 ;1
L 6.8075 0.5075 6.8075 0.5075 9 P 0 ;1
L 6.8075 0.5575 6.8075 0.5575 9 P 0 ;1
L 6.8075 0.6075 6.8075 0.6075 9 P 0 ;1
L 6.8075 0.6575 6.8075 0.6575 9 P 0 ;1
L 6.8075 0.7075 6.8075 0.7075 9 P 0 ;1
L 6.8075 0.7575 6.8075 0.7575 9 P 0 ;1
L 6.8075 0.8075 6.8075 0.8075 9 P 0 ;1
L 6.8075 0.8575 6.8075 0.8575 9 P 0 ;1
L 6.8075 1.0575 6.8075 1.0575 9 P 0 ;1
L 6.8075 1.1075 6.8075 1.1075 9 P 0 ;1
L 6.8075 1.1575 6.8075 1.1575 9 P 0 ;1
L 6.8075 1.2075 6.8075 1.2075 9 P 0 ;1
L 6.8075 1.2575 6.8075 1.2575 9 P 0 ;1
L 6.8075 1.3075 6.8075 1.3075 9 P 0 ;1
L 6.8075 1.3575 6.8075 1.3575 9 P 0 ;1
L 6.8075 1.9075 6.8075 1.9075 9 P 0 ;1
L 6.8075 1.9575 6.8075 1.9575 9 P 0 ;1
L 6.8075 2.0075 6.8075 2.0075 9 P 0 ;1
L 6.8075 2.0575 6.8075 2.0575 9 P 0 ;1
L 6.8075 2.1075 6.8075 2.1075 9 P 0 ;1
L 6.8075 2.1575 6.8075 2.1575 9 P 0 ;1
L 6.8075 2.2075 6.8075 2.2075 9 P 0 ;1
L 6.8075 2.2575 6.8075 2.2575 9 P 0 ;1
L 6.8075 2.3075 6.8075 2.3075 9 P 0 ;1
L 6.8075 2.3575 6.8075 2.3575 9 P 0 ;1
L 6.8075 2.4075 6.8075 2.4075 9 P 0 ;1
L 6.8075 2.4575 6.8075 2.4575 9 P 0 ;1
L 6.8075 2.5075 6.8075 2.5075 9 P 0 ;1
L 6.8075 2.5575 6.8075 2.5575 9 P 0 ;1
L 6.8075 2.6075 6.8075 2.6075 9 P 0 ;1
L 6.8075 2.6575 6.8075 2.6575 9 P 0 ;1
L 6.8075 2.7075 6.8075 2.7075 9 P 0 ;1
L 6.8075 2.7575 6.8075 2.7575 9 P 0 ;1
L 6.8075 2.8075 6.8075 2.8075 9 P 0 ;1
L 6.8075 2.8575 6.8075 2.8575 9 P 0 ;1
L 6.8075 2.9075 6.8075 2.9075 9 P 0 ;1
L 6.8075 2.9575 6.8075 2.9575 9 P 0 ;1
L 6.8075 3.0075 6.8075 3.0075 9 P 0 ;1
L 6.8075 3.0575 6.8075 3.0575 9 P 0 ;1
L 6.8075 3.1075 6.8075 3.1075 9 P 0 ;1
L 6.8075 3.1575 6.8075 3.1575 9 P 0 ;1
L 6.8075 3.2075 6.8075 3.2075 9 P 0 ;1
L 6.8075 3.2575 6.8075 3.2575 9 P 0 ;1
L 6.8075 3.3075 6.8075 3.3075 9 P 0 ;1
L 6.8075 3.3575 6.8075 3.3575 9 P 0 ;1
L 6.8075 3.4075 6.8075 3.4075 9 P 0 ;1
L 6.8075 3.4575 6.8075 3.4575 9 P 0 ;1
L 6.8075 3.5075 6.8075 3.5075 9 P 0 ;1
L 6.8075 3.5575 6.8075 3.5575 9 P 0 ;1
L 6.8075 3.6075 6.8075 3.6075 9 P 0 ;1
L 6.8075 3.6575 6.8075 3.6575 9 P 0 ;1
L 6.8075 3.7075 6.8075 3.7075 9 P 0 ;1
L 6.8075 3.7575 6.8075 3.7575 9 P 0 ;1
L 6.8075 3.8075 6.8075 3.8075 9 P 0 ;1
L 6.8075 3.8575 6.8075 3.8575 9 P 0 ;1
L 6.8075 3.9075 6.8075 3.9075 9 P 0 ;1
L 6.8075 3.9575 6.8075 3.9575 9 P 0 ;1
L 6.8075 4.0075 6.8075 4.0075 9 P 0 ;1
L 6.8075 4.0575 6.8075 4.0575 9 P 0 ;1
L 6.8075 4.3575 6.8075 4.3575 9 P 0 ;1
L 6.8075 4.4075 6.8075 4.4075 9 P 0 ;1
L 6.8075 4.4575 6.8075 4.4575 9 P 0 ;1
L 6.8075 5.0575 6.8075 5.0575 9 P 0 ;1
L 6.8075 5.1075 6.8075 5.1075 9 P 0 ;1
L 6.8075 5.1575 6.8075 5.1575 9 P 0 ;1
L 6.8075 5.2075 6.8075 5.2075 9 P 0 ;1
L 6.8075 5.2575 6.8075 5.2575 9 P 0 ;1
L 6.8075 5.3075 6.8075 5.3075 9 P 0 ;1
L 6.8075 5.3575 6.8075 5.3575 9 P 0 ;1
L 6.8075 5.4075 6.8075 5.4075 9 P 0 ;1
L 6.8075 5.4575 6.8075 5.4575 9 P 0 ;1
L 6.8075 5.5075 6.8075 5.5075 9 P 0 ;1
L 6.8075 5.5575 6.8075 5.5575 9 P 0 ;1
L 6.8075 5.6075 6.8075 5.6075 9 P 0 ;1
L 6.8075 5.6575 6.8075 5.6575 9 P 0 ;1
L 6.8075 5.7075 6.8075 5.7075 9 P 0 ;1
L 6.8075 5.7575 6.8075 5.7575 9 P 0 ;1
L 6.8075 5.8075 6.8075 5.8075 9 P 0 ;1
L 6.8075 5.8575 6.8075 5.8575 9 P 0 ;1
L 6.8075 5.9075 6.8075 5.9075 9 P 0 ;1
L 6.8575 0.1575 6.8575 0.1575 9 P 0 ;1
L 6.8575 0.2075 6.8575 0.2075 9 P 0 ;1
L 6.8575 0.2575 6.8575 0.2575 9 P 0 ;1
L 6.8575 0.3075 6.8575 0.3075 9 P 0 ;1
L 6.8575 0.3575 6.8575 0.3575 9 P 0 ;1
L 6.8575 0.4075 6.8575 0.4075 9 P 0 ;1
L 6.8575 0.4575 6.8575 0.4575 9 P 0 ;1
L 6.8575 0.5075 6.8575 0.5075 9 P 0 ;1
L 6.8575 0.5575 6.8575 0.5575 9 P 0 ;1
L 6.8575 0.6075 6.8575 0.6075 9 P 0 ;1
L 6.8575 0.6575 6.8575 0.6575 9 P 0 ;1
L 6.8575 0.7075 6.8575 0.7075 9 P 0 ;1
L 6.8575 0.7575 6.8575 0.7575 9 P 0 ;1
L 6.8575 0.8075 6.8575 0.8075 9 P 0 ;1
L 6.8575 0.8575 6.8575 0.8575 9 P 0 ;1
L 6.8575 1.0575 6.8575 1.0575 9 P 0 ;1
L 6.8575 1.1075 6.8575 1.1075 9 P 0 ;1
L 6.8575 1.1575 6.8575 1.1575 9 P 0 ;1
L 6.8575 1.2075 6.8575 1.2075 9 P 0 ;1
L 6.8575 1.2575 6.8575 1.2575 9 P 0 ;1
L 6.8575 1.3075 6.8575 1.3075 9 P 0 ;1
L 6.8575 1.3575 6.8575 1.3575 9 P 0 ;1
L 6.8575 1.9075 6.8575 1.9075 9 P 0 ;1
L 6.8575 1.9575 6.8575 1.9575 9 P 0 ;1
L 6.8575 2.0075 6.8575 2.0075 9 P 0 ;1
L 6.8575 2.0575 6.8575 2.0575 9 P 0 ;1
L 6.8575 2.1075 6.8575 2.1075 9 P 0 ;1
L 6.8575 2.1575 6.8575 2.1575 9 P 0 ;1
L 6.8575 2.2075 6.8575 2.2075 9 P 0 ;1
L 6.8575 2.2575 6.8575 2.2575 9 P 0 ;1
L 6.8575 2.3075 6.8575 2.3075 9 P 0 ;1
L 6.8575 2.3575 6.8575 2.3575 9 P 0 ;1
L 6.8575 2.4075 6.8575 2.4075 9 P 0 ;1
L 6.8575 2.4575 6.8575 2.4575 9 P 0 ;1
L 6.8575 2.5075 6.8575 2.5075 9 P 0 ;1
L 6.8575 2.5575 6.8575 2.5575 9 P 0 ;1
L 6.8575 2.6075 6.8575 2.6075 9 P 0 ;1
L 6.8575 2.6575 6.8575 2.6575 9 P 0 ;1
L 6.8575 2.7075 6.8575 2.7075 9 P 0 ;1
L 6.8575 2.7575 6.8575 2.7575 9 P 0 ;1
L 6.8575 2.8075 6.8575 2.8075 9 P 0 ;1
L 6.8575 2.8575 6.8575 2.8575 9 P 0 ;1
L 6.8575 2.9075 6.8575 2.9075 9 P 0 ;1
L 6.8575 2.9575 6.8575 2.9575 9 P 0 ;1
L 6.8575 3.0075 6.8575 3.0075 9 P 0 ;1
L 6.8575 3.0575 6.8575 3.0575 9 P 0 ;1
L 6.8575 3.1075 6.8575 3.1075 9 P 0 ;1
L 6.8575 3.1575 6.8575 3.1575 9 P 0 ;1
L 6.8575 3.2075 6.8575 3.2075 9 P 0 ;1
L 6.8575 3.2575 6.8575 3.2575 9 P 0 ;1
L 6.8575 3.3075 6.8575 3.3075 9 P 0 ;1
L 6.8575 3.3575 6.8575 3.3575 9 P 0 ;1
L 6.8575 3.4075 6.8575 3.4075 9 P 0 ;1
L 6.8575 3.4575 6.8575 3.4575 9 P 0 ;1
L 6.8575 3.5075 6.8575 3.5075 9 P 0 ;1
L 6.8575 3.5575 6.8575 3.5575 9 P 0 ;1
L 6.8575 3.6075 6.8575 3.6075 9 P 0 ;1
L 6.8575 3.6575 6.8575 3.6575 9 P 0 ;1
L 6.8575 3.7075 6.8575 3.7075 9 P 0 ;1
L 6.8575 3.7575 6.8575 3.7575 9 P 0 ;1
L 6.8575 3.8075 6.8575 3.8075 9 P 0 ;1
L 6.8575 3.8575 6.8575 3.8575 9 P 0 ;1
L 6.8575 3.9075 6.8575 3.9075 9 P 0 ;1
L 6.8575 3.9575 6.8575 3.9575 9 P 0 ;1
L 6.8575 4.0075 6.8575 4.0075 9 P 0 ;1
L 6.8575 4.4075 6.8575 4.4075 9 P 0 ;1
L 6.8575 4.4575 6.8575 4.4575 9 P 0 ;1
L 6.8575 5.1075 6.8575 5.1075 9 P 0 ;1
L 6.8575 5.1575 6.8575 5.1575 9 P 0 ;1
L 6.8575 5.2075 6.8575 5.2075 9 P 0 ;1
L 6.8575 5.2575 6.8575 5.2575 9 P 0 ;1
L 6.8575 5.3075 6.8575 5.3075 9 P 0 ;1
L 6.8575 5.3575 6.8575 5.3575 9 P 0 ;1
L 6.8575 5.4075 6.8575 5.4075 9 P 0 ;1
L 6.8575 5.4575 6.8575 5.4575 9 P 0 ;1
L 6.8575 5.5075 6.8575 5.5075 9 P 0 ;1
L 6.8575 5.5575 6.8575 5.5575 9 P 0 ;1
L 6.8575 5.6075 6.8575 5.6075 9 P 0 ;1
L 6.8575 5.6575 6.8575 5.6575 9 P 0 ;1
L 6.8575 5.7075 6.8575 5.7075 9 P 0 ;1
L 6.8575 5.7575 6.8575 5.7575 9 P 0 ;1
L 6.8575 5.8075 6.8575 5.8075 9 P 0 ;1
L 6.8575 5.8575 6.8575 5.8575 9 P 0 ;1
L 6.8575 5.9075 6.8575 5.9075 9 P 0 ;1
L 6.9075 0.1575 6.9075 0.1575 9 P 0 ;1
L 6.9075 0.2075 6.9075 0.2075 9 P 0 ;1
L 6.9075 0.2575 6.9075 0.2575 9 P 0 ;1
L 6.9075 0.3075 6.9075 0.3075 9 P 0 ;1
L 6.9075 0.3575 6.9075 0.3575 9 P 0 ;1
L 6.9075 0.4075 6.9075 0.4075 9 P 0 ;1
L 6.9075 0.4575 6.9075 0.4575 9 P 0 ;1
L 6.9075 0.5075 6.9075 0.5075 9 P 0 ;1
L 6.9075 0.5575 6.9075 0.5575 9 P 0 ;1
L 6.9075 0.6075 6.9075 0.6075 9 P 0 ;1
L 6.9075 0.6575 6.9075 0.6575 9 P 0 ;1
L 6.9075 0.7075 6.9075 0.7075 9 P 0 ;1
L 6.9075 0.7575 6.9075 0.7575 9 P 0 ;1
L 6.9075 0.8075 6.9075 0.8075 9 P 0 ;1
L 6.9075 0.8575 6.9075 0.8575 9 P 0 ;1
L 6.9075 1.0575 6.9075 1.0575 9 P 0 ;1
L 6.9075 1.1075 6.9075 1.1075 9 P 0 ;1
L 6.9075 1.1575 6.9075 1.1575 9 P 0 ;1
L 6.9075 1.2075 6.9075 1.2075 9 P 0 ;1
L 6.9075 1.2575 6.9075 1.2575 9 P 0 ;1
L 6.9075 1.3075 6.9075 1.3075 9 P 0 ;1
L 6.9075 1.9075 6.9075 1.9075 9 P 0 ;1
L 6.9075 1.9575 6.9075 1.9575 9 P 0 ;1
L 6.9075 2.0075 6.9075 2.0075 9 P 0 ;1
L 6.9075 2.0575 6.9075 2.0575 9 P 0 ;1
L 6.9075 2.1075 6.9075 2.1075 9 P 0 ;1
L 6.9075 2.1575 6.9075 2.1575 9 P 0 ;1
L 6.9075 2.2075 6.9075 2.2075 9 P 0 ;1
L 6.9075 2.2575 6.9075 2.2575 9 P 0 ;1
L 6.9075 2.3075 6.9075 2.3075 9 P 0 ;1
L 6.9075 2.3575 6.9075 2.3575 9 P 0 ;1
L 6.9075 2.4075 6.9075 2.4075 9 P 0 ;1
L 6.9075 2.4575 6.9075 2.4575 9 P 0 ;1
L 6.9075 2.5075 6.9075 2.5075 9 P 0 ;1
L 6.9075 2.6575 6.9075 2.6575 9 P 0 ;1
L 6.9075 2.7075 6.9075 2.7075 9 P 0 ;1
L 6.9075 2.7575 6.9075 2.7575 9 P 0 ;1
L 6.9075 2.8075 6.9075 2.8075 9 P 0 ;1
L 6.9075 2.8575 6.9075 2.8575 9 P 0 ;1
L 6.9075 2.9075 6.9075 2.9075 9 P 0 ;1
L 6.9075 2.9575 6.9075 2.9575 9 P 0 ;1
L 6.9075 3.0075 6.9075 3.0075 9 P 0 ;1
L 6.9075 3.0575 6.9075 3.0575 9 P 0 ;1
L 6.9075 3.1075 6.9075 3.1075 9 P 0 ;1
L 6.9075 3.1575 6.9075 3.1575 9 P 0 ;1
L 6.9075 3.2075 6.9075 3.2075 9 P 0 ;1
L 6.9075 3.2575 6.9075 3.2575 9 P 0 ;1
L 6.9075 3.3075 6.9075 3.3075 9 P 0 ;1
L 6.9075 3.3575 6.9075 3.3575 9 P 0 ;1
L 6.9075 3.4075 6.9075 3.4075 9 P 0 ;1
L 6.9075 3.4575 6.9075 3.4575 9 P 0 ;1
L 6.9075 3.5075 6.9075 3.5075 9 P 0 ;1
L 6.9075 3.5575 6.9075 3.5575 9 P 0 ;1
L 6.9075 3.6075 6.9075 3.6075 9 P 0 ;1
L 6.9075 3.6575 6.9075 3.6575 9 P 0 ;1
L 6.9075 3.7075 6.9075 3.7075 9 P 0 ;1
L 6.9075 3.7575 6.9075 3.7575 9 P 0 ;1
L 6.9075 3.8075 6.9075 3.8075 9 P 0 ;1
L 6.9075 3.8575 6.9075 3.8575 9 P 0 ;1
L 6.9075 3.9075 6.9075 3.9075 9 P 0 ;1
L 6.9075 3.9575 6.9075 3.9575 9 P 0 ;1
L 6.9075 4.0075 6.9075 4.0075 9 P 0 ;1
L 6.9075 4.4075 6.9075 4.4075 9 P 0 ;1
L 6.9075 4.4575 6.9075 4.4575 9 P 0 ;1
L 6.9075 5.1075 6.9075 5.1075 9 P 0 ;1
L 6.9075 5.1575 6.9075 5.1575 9 P 0 ;1
L 6.9075 5.2075 6.9075 5.2075 9 P 0 ;1
L 6.9075 5.2575 6.9075 5.2575 9 P 0 ;1
L 6.9075 5.3075 6.9075 5.3075 9 P 0 ;1
L 6.9075 5.3575 6.9075 5.3575 9 P 0 ;1
L 6.9075 5.4075 6.9075 5.4075 9 P 0 ;1
L 6.9075 5.4575 6.9075 5.4575 9 P 0 ;1
L 6.9075 5.5075 6.9075 5.5075 9 P 0 ;1
L 6.9075 5.5575 6.9075 5.5575 9 P 0 ;1
L 6.9075 5.6075 6.9075 5.6075 9 P 0 ;1
L 6.9075 5.6575 6.9075 5.6575 9 P 0 ;1
L 6.9075 5.7075 6.9075 5.7075 9 P 0 ;1
L 6.9075 5.7575 6.9075 5.7575 9 P 0 ;1
L 6.9075 5.8075 6.9075 5.8075 9 P 0 ;1
L 6.9075 5.8575 6.9075 5.8575 9 P 0 ;1
L 6.9075 5.9075 6.9075 5.9075 9 P 0 ;1
L 6.9575 0.1575 6.9575 0.1575 9 P 0 ;1
L 6.9575 0.3075 6.9575 0.3075 9 P 0 ;1
L 6.9575 0.3575 6.9575 0.3575 9 P 0 ;1
L 6.9575 0.4075 6.9575 0.4075 9 P 0 ;1
L 6.9575 0.4575 6.9575 0.4575 9 P 0 ;1
L 6.9575 0.5075 6.9575 0.5075 9 P 0 ;1
L 6.9575 0.5575 6.9575 0.5575 9 P 0 ;1
L 6.9575 0.6075 6.9575 0.6075 9 P 0 ;1
L 6.9575 0.6575 6.9575 0.6575 9 P 0 ;1
L 6.9575 0.7075 6.9575 0.7075 9 P 0 ;1
L 6.9575 0.7575 6.9575 0.7575 9 P 0 ;1
L 6.9575 0.8075 6.9575 0.8075 9 P 0 ;1
L 6.9575 0.8575 6.9575 0.8575 9 P 0 ;1
L 6.9575 1.0575 6.9575 1.0575 9 P 0 ;1
L 6.9575 1.1075 6.9575 1.1075 9 P 0 ;1
L 6.9575 1.1575 6.9575 1.1575 9 P 0 ;1
L 6.9575 1.2075 6.9575 1.2075 9 P 0 ;1
L 6.9575 1.2575 6.9575 1.2575 9 P 0 ;1
L 6.9575 1.3075 6.9575 1.3075 9 P 0 ;1
L 6.9575 1.9075 6.9575 1.9075 9 P 0 ;1
L 6.9575 1.9575 6.9575 1.9575 9 P 0 ;1
L 6.9575 2.0075 6.9575 2.0075 9 P 0 ;1
L 6.9575 2.0575 6.9575 2.0575 9 P 0 ;1
L 6.9575 2.1075 6.9575 2.1075 9 P 0 ;1
L 6.9575 2.1575 6.9575 2.1575 9 P 0 ;1
L 6.9575 2.2075 6.9575 2.2075 9 P 0 ;1
L 6.9575 2.2575 6.9575 2.2575 9 P 0 ;1
L 6.9575 2.3075 6.9575 2.3075 9 P 0 ;1
L 6.9575 2.3575 6.9575 2.3575 9 P 0 ;1
L 6.9575 2.4075 6.9575 2.4075 9 P 0 ;1
L 6.9575 2.4575 6.9575 2.4575 9 P 0 ;1
L 6.9575 2.7075 6.9575 2.7075 9 P 0 ;1
L 6.9575 2.7575 6.9575 2.7575 9 P 0 ;1
L 6.9575 2.8075 6.9575 2.8075 9 P 0 ;1
L 6.9575 2.8575 6.9575 2.8575 9 P 0 ;1
L 6.9575 2.9075 6.9575 2.9075 9 P 0 ;1
L 6.9575 2.9575 6.9575 2.9575 9 P 0 ;1
L 6.9575 3.0075 6.9575 3.0075 9 P 0 ;1
L 6.9575 3.0575 6.9575 3.0575 9 P 0 ;1
L 6.9575 3.1075 6.9575 3.1075 9 P 0 ;1
L 6.9575 3.1575 6.9575 3.1575 9 P 0 ;1
L 6.9575 3.2075 6.9575 3.2075 9 P 0 ;1
L 6.9575 3.2575 6.9575 3.2575 9 P 0 ;1
L 6.9575 3.3075 6.9575 3.3075 9 P 0 ;1
L 6.9575 3.3575 6.9575 3.3575 9 P 0 ;1
L 6.9575 3.4075 6.9575 3.4075 9 P 0 ;1
L 6.9575 3.4575 6.9575 3.4575 9 P 0 ;1
L 6.9575 3.5075 6.9575 3.5075 9 P 0 ;1
L 6.9575 3.5575 6.9575 3.5575 9 P 0 ;1
L 6.9575 3.6075 6.9575 3.6075 9 P 0 ;1
L 6.9575 3.6575 6.9575 3.6575 9 P 0 ;1
L 6.9575 3.7075 6.9575 3.7075 9 P 0 ;1
L 6.9575 3.7575 6.9575 3.7575 9 P 0 ;1
L 6.9575 3.8075 6.9575 3.8075 9 P 0 ;1
L 6.9575 3.8575 6.9575 3.8575 9 P 0 ;1
L 6.9575 3.9075 6.9575 3.9075 9 P 0 ;1
L 6.9575 3.9575 6.9575 3.9575 9 P 0 ;1
L 6.9575 4.4575 6.9575 4.4575 9 P 0 ;1
L 6.9575 5.0575 6.9575 5.0575 9 P 0 ;1
L 6.9575 5.1075 6.9575 5.1075 9 P 0 ;1
L 6.9575 5.1575 6.9575 5.1575 9 P 0 ;1
L 6.9575 5.2075 6.9575 5.2075 9 P 0 ;1
L 6.9575 5.2575 6.9575 5.2575 9 P 0 ;1
L 6.9575 5.3075 6.9575 5.3075 9 P 0 ;1
L 6.9575 5.3575 6.9575 5.3575 9 P 0 ;1
L 6.9575 5.4075 6.9575 5.4075 9 P 0 ;1
L 6.9575 5.4575 6.9575 5.4575 9 P 0 ;1
L 6.9575 5.5075 6.9575 5.5075 9 P 0 ;1
L 6.9575 5.5575 6.9575 5.5575 9 P 0 ;1
L 6.9575 5.6075 6.9575 5.6075 9 P 0 ;1
L 6.9575 5.6575 6.9575 5.6575 9 P 0 ;1
L 6.9575 5.7075 6.9575 5.7075 9 P 0 ;1
L 6.9575 5.7575 6.9575 5.7575 9 P 0 ;1
L 6.9575 5.8575 6.9575 5.8575 9 P 0 ;1
L 6.9575 5.9075 6.9575 5.9075 9 P 0 ;1
L 7.0075 0.4075 7.0075 0.4075 9 P 0 ;1
L 7.0075 0.4575 7.0075 0.4575 9 P 0 ;1
L 7.0075 0.5075 7.0075 0.5075 9 P 0 ;1
L 7.0075 0.5575 7.0075 0.5575 9 P 0 ;1
L 7.0075 0.6075 7.0075 0.6075 9 P 0 ;1
L 7.0075 0.6575 7.0075 0.6575 9 P 0 ;1
L 7.0075 0.7075 7.0075 0.7075 9 P 0 ;1
L 7.0075 0.7575 7.0075 0.7575 9 P 0 ;1
L 7.0075 0.8075 7.0075 0.8075 9 P 0 ;1
L 7.0075 0.8575 7.0075 0.8575 9 P 0 ;1
L 7.0075 1.0575 7.0075 1.0575 9 P 0 ;1
L 7.0075 1.1075 7.0075 1.1075 9 P 0 ;1
L 7.0075 1.1575 7.0075 1.1575 9 P 0 ;1
L 7.0075 1.2075 7.0075 1.2075 9 P 0 ;1
L 7.0075 1.2575 7.0075 1.2575 9 P 0 ;1
L 7.0075 1.3075 7.0075 1.3075 9 P 0 ;1
L 7.0075 1.9075 7.0075 1.9075 9 P 0 ;1
L 7.0075 1.9575 7.0075 1.9575 9 P 0 ;1
L 7.0075 2.0075 7.0075 2.0075 9 P 0 ;1
L 7.0075 2.0575 7.0075 2.0575 9 P 0 ;1
L 7.0075 2.1075 7.0075 2.1075 9 P 0 ;1
L 7.0075 2.1575 7.0075 2.1575 9 P 0 ;1
L 7.0075 2.2075 7.0075 2.2075 9 P 0 ;1
L 7.0075 2.2575 7.0075 2.2575 9 P 0 ;1
L 7.0075 2.3075 7.0075 2.3075 9 P 0 ;1
L 7.0075 2.3575 7.0075 2.3575 9 P 0 ;1
L 7.0075 2.4075 7.0075 2.4075 9 P 0 ;1
L 7.0075 2.7575 7.0075 2.7575 9 P 0 ;1
L 7.0075 2.8075 7.0075 2.8075 9 P 0 ;1
L 7.0075 2.8575 7.0075 2.8575 9 P 0 ;1
L 7.0075 2.9075 7.0075 2.9075 9 P 0 ;1
L 7.0075 2.9575 7.0075 2.9575 9 P 0 ;1
L 7.0075 3.0075 7.0075 3.0075 9 P 0 ;1
L 7.0075 3.0575 7.0075 3.0575 9 P 0 ;1
L 7.0075 3.1075 7.0075 3.1075 9 P 0 ;1
L 7.0075 3.1575 7.0075 3.1575 9 P 0 ;1
L 7.0075 3.2075 7.0075 3.2075 9 P 0 ;1
L 7.0075 3.2575 7.0075 3.2575 9 P 0 ;1
L 7.0075 3.3075 7.0075 3.3075 9 P 0 ;1
L 7.0075 3.3575 7.0075 3.3575 9 P 0 ;1
L 7.0075 3.4075 7.0075 3.4075 9 P 0 ;1
L 7.0075 3.4575 7.0075 3.4575 9 P 0 ;1
L 7.0075 3.5075 7.0075 3.5075 9 P 0 ;1
L 7.0075 3.5575 7.0075 3.5575 9 P 0 ;1
L 7.0075 3.6075 7.0075 3.6075 9 P 0 ;1
L 7.0075 3.6575 7.0075 3.6575 9 P 0 ;1
L 7.0075 3.7075 7.0075 3.7075 9 P 0 ;1
L 7.0075 3.7575 7.0075 3.7575 9 P 0 ;1
L 7.0075 3.8075 7.0075 3.8075 9 P 0 ;1
L 7.0075 3.8575 7.0075 3.8575 9 P 0 ;1
L 7.0075 3.9075 7.0075 3.9075 9 P 0 ;1
L 7.0075 3.9575 7.0075 3.9575 9 P 0 ;1
L 7.0075 4.4075 7.0075 4.4075 9 P 0 ;1
L 7.0075 4.4575 7.0075 4.4575 9 P 0 ;1
L 7.0075 4.5075 7.0075 4.5075 9 P 0 ;1
L 7.0075 4.5575 7.0075 4.5575 9 P 0 ;1
L 7.0075 4.6075 7.0075 4.6075 9 P 0 ;1
L 7.0075 4.6575 7.0075 4.6575 9 P 0 ;1
L 7.0075 4.9075 7.0075 4.9075 9 P 0 ;1
L 7.0075 4.9575 7.0075 4.9575 9 P 0 ;1
L 7.0075 5.0075 7.0075 5.0075 9 P 0 ;1
L 7.0075 5.0575 7.0075 5.0575 9 P 0 ;1
L 7.0075 5.1075 7.0075 5.1075 9 P 0 ;1
L 7.0075 5.1575 7.0075 5.1575 9 P 0 ;1
L 7.0075 5.2075 7.0075 5.2075 9 P 0 ;1
L 7.0075 5.2575 7.0075 5.2575 9 P 0 ;1
L 7.0075 5.3075 7.0075 5.3075 9 P 0 ;1
L 7.0075 5.3575 7.0075 5.3575 9 P 0 ;1
L 7.0075 5.4075 7.0075 5.4075 9 P 0 ;1
L 7.0075 5.4575 7.0075 5.4575 9 P 0 ;1
L 7.0075 5.5075 7.0075 5.5075 9 P 0 ;1
L 7.0075 5.5575 7.0075 5.5575 9 P 0 ;1
L 7.0075 5.6075 7.0075 5.6075 9 P 0 ;1
L 7.0575 0.4575 7.0575 0.4575 9 P 0 ;1
L 7.0575 0.5075 7.0575 0.5075 9 P 0 ;1
L 7.0575 0.5575 7.0575 0.5575 9 P 0 ;1
L 7.0575 0.6075 7.0575 0.6075 9 P 0 ;1
L 7.0575 0.6575 7.0575 0.6575 9 P 0 ;1
L 7.0575 0.7075 7.0575 0.7075 9 P 0 ;1
L 7.0575 0.7575 7.0575 0.7575 9 P 0 ;1
L 7.0575 0.8075 7.0575 0.8075 9 P 0 ;1
L 7.0575 0.8575 7.0575 0.8575 9 P 0 ;1
L 7.0575 1.0575 7.0575 1.0575 9 P 0 ;1
L 7.0575 1.1075 7.0575 1.1075 9 P 0 ;1
L 7.0575 1.1575 7.0575 1.1575 9 P 0 ;1
L 7.0575 1.2075 7.0575 1.2075 9 P 0 ;1
L 7.0575 1.2575 7.0575 1.2575 9 P 0 ;1
L 7.0575 1.3075 7.0575 1.3075 9 P 0 ;1
L 7.0575 1.3575 7.0575 1.3575 9 P 0 ;1
L 7.0575 1.9075 7.0575 1.9075 9 P 0 ;1
L 7.0575 1.9575 7.0575 1.9575 9 P 0 ;1
L 7.0575 2.0075 7.0575 2.0075 9 P 0 ;1
L 7.0575 2.0575 7.0575 2.0575 9 P 0 ;1
L 7.0575 2.1075 7.0575 2.1075 9 P 0 ;1
L 7.0575 2.1575 7.0575 2.1575 9 P 0 ;1
L 7.0575 2.2075 7.0575 2.2075 9 P 0 ;1
L 7.0575 2.2575 7.0575 2.2575 9 P 0 ;1
L 7.0575 2.3075 7.0575 2.3075 9 P 0 ;1
L 7.0575 2.3575 7.0575 2.3575 9 P 0 ;1
L 7.0575 2.4075 7.0575 2.4075 9 P 0 ;1
L 7.0575 2.7575 7.0575 2.7575 9 P 0 ;1
L 7.0575 2.8075 7.0575 2.8075 9 P 0 ;1
L 7.0575 2.8575 7.0575 2.8575 9 P 0 ;1
L 7.0575 2.9075 7.0575 2.9075 9 P 0 ;1
L 7.0575 2.9575 7.0575 2.9575 9 P 0 ;1
L 7.0575 3.0075 7.0575 3.0075 9 P 0 ;1
L 7.0575 3.0575 7.0575 3.0575 9 P 0 ;1
L 7.0575 3.1075 7.0575 3.1075 9 P 0 ;1
L 7.0575 3.1575 7.0575 3.1575 9 P 0 ;1
L 7.0575 3.2075 7.0575 3.2075 9 P 0 ;1
L 7.0575 3.2575 7.0575 3.2575 9 P 0 ;1
L 7.0575 3.3075 7.0575 3.3075 9 P 0 ;1
L 7.0575 3.3575 7.0575 3.3575 9 P 0 ;1
L 7.0575 3.4075 7.0575 3.4075 9 P 0 ;1
L 7.0575 3.4575 7.0575 3.4575 9 P 0 ;1
L 7.0575 3.5075 7.0575 3.5075 9 P 0 ;1
L 7.0575 3.5575 7.0575 3.5575 9 P 0 ;1
L 7.0575 3.6075 7.0575 3.6075 9 P 0 ;1
L 7.0575 3.6575 7.0575 3.6575 9 P 0 ;1
L 7.0575 3.7075 7.0575 3.7075 9 P 0 ;1
L 7.0575 3.7575 7.0575 3.7575 9 P 0 ;1
L 7.0575 3.8075 7.0575 3.8075 9 P 0 ;1
L 7.0575 3.8575 7.0575 3.8575 9 P 0 ;1
L 7.0575 3.9075 7.0575 3.9075 9 P 0 ;1
L 7.0575 3.9575 7.0575 3.9575 9 P 0 ;1
L 7.0575 4.0075 7.0575 4.0075 9 P 0 ;1
L 7.0575 4.4075 7.0575 4.4075 9 P 0 ;1
L 7.0575 4.4575 7.0575 4.4575 9 P 0 ;1
L 7.0575 4.5075 7.0575 4.5075 9 P 0 ;1
L 7.0575 4.5575 7.0575 4.5575 9 P 0 ;1
L 7.0575 4.6075 7.0575 4.6075 9 P 0 ;1
L 7.0575 4.6575 7.0575 4.6575 9 P 0 ;1
L 7.0575 4.7075 7.0575 4.7075 9 P 0 ;1
L 7.0575 4.7575 7.0575 4.7575 9 P 0 ;1
L 7.0575 4.8075 7.0575 4.8075 9 P 0 ;1
L 7.0575 4.8575 7.0575 4.8575 9 P 0 ;1
L 7.0575 4.9075 7.0575 4.9075 9 P 0 ;1
L 7.0575 4.9575 7.0575 4.9575 9 P 0 ;1
L 7.0575 5.0075 7.0575 5.0075 9 P 0 ;1
L 7.0575 5.0575 7.0575 5.0575 9 P 0 ;1
L 7.0575 5.1075 7.0575 5.1075 9 P 0 ;1
L 7.0575 5.1575 7.0575 5.1575 9 P 0 ;1
L 7.0575 5.2075 7.0575 5.2075 9 P 0 ;1
L 7.0575 5.2575 7.0575 5.2575 9 P 0 ;1
L 7.0575 5.3075 7.0575 5.3075 9 P 0 ;1
L 7.0575 5.3575 7.0575 5.3575 9 P 0 ;1
L 7.0575 5.4075 7.0575 5.4075 9 P 0 ;1
L 7.0575 5.4575 7.0575 5.4575 9 P 0 ;1
L 7.0575 5.5075 7.0575 5.5075 9 P 0 ;1
L 7.0575 5.5575 7.0575 5.5575 9 P 0 ;1
L 7.0575 5.6075 7.0575 5.6075 9 P 0 ;1
L 7.1075 0.4575 7.1075 0.4575 9 P 0 ;1
L 7.1075 0.5075 7.1075 0.5075 9 P 0 ;1
L 7.1075 0.5575 7.1075 0.5575 9 P 0 ;1
L 7.1075 0.6075 7.1075 0.6075 9 P 0 ;1
L 7.1075 0.6575 7.1075 0.6575 9 P 0 ;1
L 7.1075 0.7075 7.1075 0.7075 9 P 0 ;1
L 7.1075 0.7575 7.1075 0.7575 9 P 0 ;1
L 7.1075 0.8075 7.1075 0.8075 9 P 0 ;1
L 7.1075 0.8575 7.1075 0.8575 9 P 0 ;1
L 7.1075 1.0575 7.1075 1.0575 9 P 0 ;1
L 7.1075 1.1075 7.1075 1.1075 9 P 0 ;1
L 7.1075 1.1575 7.1075 1.1575 9 P 0 ;1
L 7.1075 1.2075 7.1075 1.2075 9 P 0 ;1
L 7.1075 1.2575 7.1075 1.2575 9 P 0 ;1
L 7.1075 1.3075 7.1075 1.3075 9 P 0 ;1
L 7.1075 1.3575 7.1075 1.3575 9 P 0 ;1
L 7.1075 1.9075 7.1075 1.9075 9 P 0 ;1
L 7.1075 1.9575 7.1075 1.9575 9 P 0 ;1
L 7.1075 2.0075 7.1075 2.0075 9 P 0 ;1
L 7.1075 2.0575 7.1075 2.0575 9 P 0 ;1
L 7.1075 2.1075 7.1075 2.1075 9 P 0 ;1
L 7.1075 2.1575 7.1075 2.1575 9 P 0 ;1
L 7.1075 2.2075 7.1075 2.2075 9 P 0 ;1
L 7.1075 2.2575 7.1075 2.2575 9 P 0 ;1
L 7.1075 2.3075 7.1075 2.3075 9 P 0 ;1
L 7.1075 2.3575 7.1075 2.3575 9 P 0 ;1
L 7.1075 2.4075 7.1075 2.4075 9 P 0 ;1
L 7.1075 2.7575 7.1075 2.7575 9 P 0 ;1
L 7.1075 2.8075 7.1075 2.8075 9 P 0 ;1
L 7.1075 2.8575 7.1075 2.8575 9 P 0 ;1
L 7.1075 2.9075 7.1075 2.9075 9 P 0 ;1
L 7.1075 2.9575 7.1075 2.9575 9 P 0 ;1
L 7.1075 3.0075 7.1075 3.0075 9 P 0 ;1
L 7.1075 3.0575 7.1075 3.0575 9 P 0 ;1
L 7.1075 3.1075 7.1075 3.1075 9 P 0 ;1
L 7.1075 3.1575 7.1075 3.1575 9 P 0 ;1
L 7.1075 3.2075 7.1075 3.2075 9 P 0 ;1
L 7.1075 3.2575 7.1075 3.2575 9 P 0 ;1
L 7.1075 3.3075 7.1075 3.3075 9 P 0 ;1
L 7.1075 3.3575 7.1075 3.3575 9 P 0 ;1
L 7.1075 3.4075 7.1075 3.4075 9 P 0 ;1
L 7.1075 3.4575 7.1075 3.4575 9 P 0 ;1
L 7.1075 3.5075 7.1075 3.5075 9 P 0 ;1
L 7.1075 3.5575 7.1075 3.5575 9 P 0 ;1
L 7.1075 3.6075 7.1075 3.6075 9 P 0 ;1
L 7.1075 3.6575 7.1075 3.6575 9 P 0 ;1
L 7.1075 3.7075 7.1075 3.7075 9 P 0 ;1
L 7.1075 3.7575 7.1075 3.7575 9 P 0 ;1
L 7.1075 3.8075 7.1075 3.8075 9 P 0 ;1
L 7.1075 3.8575 7.1075 3.8575 9 P 0 ;1
L 7.1075 3.9075 7.1075 3.9075 9 P 0 ;1
L 7.1075 3.9575 7.1075 3.9575 9 P 0 ;1
L 7.1075 4.0075 7.1075 4.0075 9 P 0 ;1
L 7.1075 4.4075 7.1075 4.4075 9 P 0 ;1
L 7.1075 4.4575 7.1075 4.4575 9 P 0 ;1
L 7.1075 4.5075 7.1075 4.5075 9 P 0 ;1
L 7.1075 4.5575 7.1075 4.5575 9 P 0 ;1
L 7.1075 4.6075 7.1075 4.6075 9 P 0 ;1
L 7.1075 4.6575 7.1075 4.6575 9 P 0 ;1
L 7.1075 4.7075 7.1075 4.7075 9 P 0 ;1
L 7.1075 4.7575 7.1075 4.7575 9 P 0 ;1
L 7.1075 4.8075 7.1075 4.8075 9 P 0 ;1
L 7.1075 4.8575 7.1075 4.8575 9 P 0 ;1
L 7.1075 4.9075 7.1075 4.9075 9 P 0 ;1
L 7.1075 4.9575 7.1075 4.9575 9 P 0 ;1
L 7.1075 5.0075 7.1075 5.0075 9 P 0 ;1
L 7.1075 5.0575 7.1075 5.0575 9 P 0 ;1
L 7.1075 5.1075 7.1075 5.1075 9 P 0 ;1
L 7.1075 5.1575 7.1075 5.1575 9 P 0 ;1
L 7.1075 5.2075 7.1075 5.2075 9 P 0 ;1
L 7.1075 5.2575 7.1075 5.2575 9 P 0 ;1
L 7.1075 5.3075 7.1075 5.3075 9 P 0 ;1
L 7.1075 5.3575 7.1075 5.3575 9 P 0 ;1
L 7.1075 5.4075 7.1075 5.4075 9 P 0 ;1
L 7.1075 5.4575 7.1075 5.4575 9 P 0 ;1
L 7.1075 5.5075 7.1075 5.5075 9 P 0 ;1
L 7.1075 5.5575 7.1075 5.5575 9 P 0 ;1
L 7.1575 0.5075 7.1575 0.5075 9 P 0 ;1
L 7.1575 0.5575 7.1575 0.5575 9 P 0 ;1
L 7.1575 0.6075 7.1575 0.6075 9 P 0 ;1
L 7.1575 0.6575 7.1575 0.6575 9 P 0 ;1
L 7.1575 0.7075 7.1575 0.7075 9 P 0 ;1
L 7.1575 0.7575 7.1575 0.7575 9 P 0 ;1
L 7.1575 0.8075 7.1575 0.8075 9 P 0 ;1
L 7.1575 0.8575 7.1575 0.8575 9 P 0 ;1
L 7.1575 1.0575 7.1575 1.0575 9 P 0 ;1
L 7.1575 1.1075 7.1575 1.1075 9 P 0 ;1
L 7.1575 1.1575 7.1575 1.1575 9 P 0 ;1
L 7.1575 1.2075 7.1575 1.2075 9 P 0 ;1
L 7.1575 1.2575 7.1575 1.2575 9 P 0 ;1
L 7.1575 1.3075 7.1575 1.3075 9 P 0 ;1
L 7.1575 1.3575 7.1575 1.3575 9 P 0 ;1
L 7.1575 1.4075 7.1575 1.4075 9 P 0 ;1
L 7.1575 1.4575 7.1575 1.4575 9 P 0 ;1
L 7.1575 1.6075 7.1575 1.6075 9 P 0 ;1
L 7.1575 1.6575 7.1575 1.6575 9 P 0 ;1
L 7.1575 1.9075 7.1575 1.9075 9 P 0 ;1
L 7.1575 1.9575 7.1575 1.9575 9 P 0 ;1
L 7.1575 2.0075 7.1575 2.0075 9 P 0 ;1
L 7.1575 2.0575 7.1575 2.0575 9 P 0 ;1
L 7.1575 2.1075 7.1575 2.1075 9 P 0 ;1
L 7.1575 2.1575 7.1575 2.1575 9 P 0 ;1
L 7.1575 2.2075 7.1575 2.2075 9 P 0 ;1
L 7.1575 2.2575 7.1575 2.2575 9 P 0 ;1
L 7.1575 2.3075 7.1575 2.3075 9 P 0 ;1
L 7.1575 2.3575 7.1575 2.3575 9 P 0 ;1
L 7.1575 2.4075 7.1575 2.4075 9 P 0 ;1
L 7.1575 2.7575 7.1575 2.7575 9 P 0 ;1
L 7.1575 2.8075 7.1575 2.8075 9 P 0 ;1
L 7.1575 2.8575 7.1575 2.8575 9 P 0 ;1
L 7.1575 2.9075 7.1575 2.9075 9 P 0 ;1
L 7.1575 2.9575 7.1575 2.9575 9 P 0 ;1
L 7.1575 3.0075 7.1575 3.0075 9 P 0 ;1
L 7.1575 3.0575 7.1575 3.0575 9 P 0 ;1
L 7.1575 3.1075 7.1575 3.1075 9 P 0 ;1
L 7.1575 3.1575 7.1575 3.1575 9 P 0 ;1
L 7.1575 3.2075 7.1575 3.2075 9 P 0 ;1
L 7.1575 3.2575 7.1575 3.2575 9 P 0 ;1
L 7.1575 3.3075 7.1575 3.3075 9 P 0 ;1
L 7.1575 3.3575 7.1575 3.3575 9 P 0 ;1
L 7.1575 3.4075 7.1575 3.4075 9 P 0 ;1
L 7.1575 3.4575 7.1575 3.4575 9 P 0 ;1
L 7.1575 3.5075 7.1575 3.5075 9 P 0 ;1
L 7.1575 3.5575 7.1575 3.5575 9 P 0 ;1
L 7.1575 3.6075 7.1575 3.6075 9 P 0 ;1
L 7.1575 3.6575 7.1575 3.6575 9 P 0 ;1
L 7.1575 3.7075 7.1575 3.7075 9 P 0 ;1
L 7.1575 3.7575 7.1575 3.7575 9 P 0 ;1
L 7.1575 3.8075 7.1575 3.8075 9 P 0 ;1
L 7.1575 3.8575 7.1575 3.8575 9 P 0 ;1
L 7.1575 3.9075 7.1575 3.9075 9 P 0 ;1
L 7.1575 3.9575 7.1575 3.9575 9 P 0 ;1
L 7.1575 4.0075 7.1575 4.0075 9 P 0 ;1
L 7.1575 4.0575 7.1575 4.0575 9 P 0 ;1
L 7.1575 4.1075 7.1575 4.1075 9 P 0 ;1
L 7.1575 4.2575 7.1575 4.2575 9 P 0 ;1
L 7.1575 4.3075 7.1575 4.3075 9 P 0 ;1
L 7.1575 4.3575 7.1575 4.3575 9 P 0 ;1
L 7.1575 4.4075 7.1575 4.4075 9 P 0 ;1
L 7.1575 4.4575 7.1575 4.4575 9 P 0 ;1
L 7.1575 4.5075 7.1575 4.5075 9 P 0 ;1
L 7.1575 4.5575 7.1575 4.5575 9 P 0 ;1
L 7.1575 4.6075 7.1575 4.6075 9 P 0 ;1
L 7.1575 4.6575 7.1575 4.6575 9 P 0 ;1
L 7.1575 4.7075 7.1575 4.7075 9 P 0 ;1
L 7.1575 4.7575 7.1575 4.7575 9 P 0 ;1
L 7.1575 4.8075 7.1575 4.8075 9 P 0 ;1
L 7.1575 4.8575 7.1575 4.8575 9 P 0 ;1
L 7.1575 5.2575 7.1575 5.2575 9 P 0 ;1
L 7.1575 5.3075 7.1575 5.3075 9 P 0 ;1
L 7.1575 5.3575 7.1575 5.3575 9 P 0 ;1
L 7.1575 5.4075 7.1575 5.4075 9 P 0 ;1
L 7.1575 5.4575 7.1575 5.4575 9 P 0 ;1
L 7.1575 5.5075 7.1575 5.5075 9 P 0 ;1
L 7.1575 5.5575 7.1575 5.5575 9 P 0 ;1
L 7.2075 0.4575 7.2075 0.4575 9 P 0 ;1
L 7.2075 0.5075 7.2075 0.5075 9 P 0 ;1
L 7.2075 0.5575 7.2075 0.5575 9 P 0 ;1
L 7.2075 0.6075 7.2075 0.6075 9 P 0 ;1
L 7.2075 0.6575 7.2075 0.6575 9 P 0 ;1
L 7.2075 0.7075 7.2075 0.7075 9 P 0 ;1
L 7.2075 0.7575 7.2075 0.7575 9 P 0 ;1
L 7.2075 0.8075 7.2075 0.8075 9 P 0 ;1
L 7.2075 0.8575 7.2075 0.8575 9 P 0 ;1
L 7.2075 1.0575 7.2075 1.0575 9 P 0 ;1
L 7.2075 1.1075 7.2075 1.1075 9 P 0 ;1
L 7.2075 1.1575 7.2075 1.1575 9 P 0 ;1
L 7.2075 1.2075 7.2075 1.2075 9 P 0 ;1
L 7.2075 1.2575 7.2075 1.2575 9 P 0 ;1
L 7.2075 1.3075 7.2075 1.3075 9 P 0 ;1
L 7.2075 1.3575 7.2075 1.3575 9 P 0 ;1
L 7.2075 1.4075 7.2075 1.4075 9 P 0 ;1
L 7.2075 1.4575 7.2075 1.4575 9 P 0 ;1
L 7.2075 1.5075 7.2075 1.5075 9 P 0 ;1
L 7.2075 1.5575 7.2075 1.5575 9 P 0 ;1
L 7.2075 1.6075 7.2075 1.6075 9 P 0 ;1
L 7.2075 1.6575 7.2075 1.6575 9 P 0 ;1
L 7.2075 1.9075 7.2075 1.9075 9 P 0 ;1
L 7.2075 1.9575 7.2075 1.9575 9 P 0 ;1
L 7.2075 2.0075 7.2075 2.0075 9 P 0 ;1
L 7.2075 2.0575 7.2075 2.0575 9 P 0 ;1
L 7.2075 2.1075 7.2075 2.1075 9 P 0 ;1
L 7.2075 2.1575 7.2075 2.1575 9 P 0 ;1
L 7.2075 2.2075 7.2075 2.2075 9 P 0 ;1
L 7.2075 2.2575 7.2075 2.2575 9 P 0 ;1
L 7.2075 2.3075 7.2075 2.3075 9 P 0 ;1
L 7.2075 2.3575 7.2075 2.3575 9 P 0 ;1
L 7.2075 2.4075 7.2075 2.4075 9 P 0 ;1
L 7.2075 2.4575 7.2075 2.4575 9 P 0 ;1
L 7.2075 2.7075 7.2075 2.7075 9 P 0 ;1
L 7.2075 2.7575 7.2075 2.7575 9 P 0 ;1
L 7.2075 2.8075 7.2075 2.8075 9 P 0 ;1
L 7.2075 2.8575 7.2075 2.8575 9 P 0 ;1
L 7.2075 2.9075 7.2075 2.9075 9 P 0 ;1
L 7.2075 2.9575 7.2075 2.9575 9 P 0 ;1
L 7.2075 3.0075 7.2075 3.0075 9 P 0 ;1
L 7.2075 3.0575 7.2075 3.0575 9 P 0 ;1
L 7.2075 3.1075 7.2075 3.1075 9 P 0 ;1
L 7.2075 3.1575 7.2075 3.1575 9 P 0 ;1
L 7.2075 3.2075 7.2075 3.2075 9 P 0 ;1
L 7.2075 3.2575 7.2075 3.2575 9 P 0 ;1
L 7.2075 3.3075 7.2075 3.3075 9 P 0 ;1
L 7.2075 3.3575 7.2075 3.3575 9 P 0 ;1
L 7.2075 3.4075 7.2075 3.4075 9 P 0 ;1
L 7.2075 3.4575 7.2075 3.4575 9 P 0 ;1
L 7.2075 3.5075 7.2075 3.5075 9 P 0 ;1
L 7.2075 3.5575 7.2075 3.5575 9 P 0 ;1
L 7.2075 3.6075 7.2075 3.6075 9 P 0 ;1
L 7.2075 3.6575 7.2075 3.6575 9 P 0 ;1
L 7.2075 3.7075 7.2075 3.7075 9 P 0 ;1
L 7.2075 3.7575 7.2075 3.7575 9 P 0 ;1
L 7.2075 3.8075 7.2075 3.8075 9 P 0 ;1
L 7.2075 3.8575 7.2075 3.8575 9 P 0 ;1
L 7.2075 3.9075 7.2075 3.9075 9 P 0 ;1
L 7.2075 3.9575 7.2075 3.9575 9 P 0 ;1
L 7.2075 4.0075 7.2075 4.0075 9 P 0 ;1
L 7.2075 4.0575 7.2075 4.0575 9 P 0 ;1
L 7.2075 4.1075 7.2075 4.1075 9 P 0 ;1
L 7.2075 4.1575 7.2075 4.1575 9 P 0 ;1
L 7.2075 4.2075 7.2075 4.2075 9 P 0 ;1
L 7.2075 4.2575 7.2075 4.2575 9 P 0 ;1
L 7.2075 4.3075 7.2075 4.3075 9 P 0 ;1
L 7.2075 4.3575 7.2075 4.3575 9 P 0 ;1
L 7.2075 4.4075 7.2075 4.4075 9 P 0 ;1
L 7.2075 4.4575 7.2075 4.4575 9 P 0 ;1
L 7.2075 4.5075 7.2075 4.5075 9 P 0 ;1
L 7.2075 4.8075 7.2075 4.8075 9 P 0 ;1
L 7.2075 4.8575 7.2075 4.8575 9 P 0 ;1
L 7.2075 5.2575 7.2075 5.2575 9 P 0 ;1
L 7.2075 5.3075 7.2075 5.3075 9 P 0 ;1
L 7.2075 5.3575 7.2075 5.3575 9 P 0 ;1
L 7.2075 5.4075 7.2075 5.4075 9 P 0 ;1
L 7.2075 5.4575 7.2075 5.4575 9 P 0 ;1
L 7.2075 5.5075 7.2075 5.5075 9 P 0 ;1
L 7.2075 5.5575 7.2075 5.5575 9 P 0 ;1
L 7.2575 0.4575 7.2575 0.4575 9 P 0 ;1
L 7.2575 0.5075 7.2575 0.5075 9 P 0 ;1
L 7.2575 0.5575 7.2575 0.5575 9 P 0 ;1
L 7.2575 0.6075 7.2575 0.6075 9 P 0 ;1
L 7.2575 0.6575 7.2575 0.6575 9 P 0 ;1
L 7.2575 0.7075 7.2575 0.7075 9 P 0 ;1
L 7.2575 0.7575 7.2575 0.7575 9 P 0 ;1
L 7.2575 0.8075 7.2575 0.8075 9 P 0 ;1
L 7.2575 0.8575 7.2575 0.8575 9 P 0 ;1
L 7.2575 1.0575 7.2575 1.0575 9 P 0 ;1
L 7.2575 1.1075 7.2575 1.1075 9 P 0 ;1
L 7.2575 1.1575 7.2575 1.1575 9 P 0 ;1
L 7.2575 1.2075 7.2575 1.2075 9 P 0 ;1
L 7.2575 1.2575 7.2575 1.2575 9 P 0 ;1
L 7.2575 1.3075 7.2575 1.3075 9 P 0 ;1
L 7.2575 1.3575 7.2575 1.3575 9 P 0 ;1
L 7.2575 1.4075 7.2575 1.4075 9 P 0 ;1
L 7.2575 1.4575 7.2575 1.4575 9 P 0 ;1
L 7.2575 1.5075 7.2575 1.5075 9 P 0 ;1
L 7.2575 1.5575 7.2575 1.5575 9 P 0 ;1
L 7.2575 1.6075 7.2575 1.6075 9 P 0 ;1
L 7.2575 1.6575 7.2575 1.6575 9 P 0 ;1
L 7.2575 1.9075 7.2575 1.9075 9 P 0 ;1
L 7.2575 1.9575 7.2575 1.9575 9 P 0 ;1
L 7.2575 2.0075 7.2575 2.0075 9 P 0 ;1
L 7.2575 2.0575 7.2575 2.0575 9 P 0 ;1
L 7.2575 2.1075 7.2575 2.1075 9 P 0 ;1
L 7.2575 2.1575 7.2575 2.1575 9 P 0 ;1
L 7.2575 2.2075 7.2575 2.2075 9 P 0 ;1
L 7.2575 2.2575 7.2575 2.2575 9 P 0 ;1
L 7.2575 2.3075 7.2575 2.3075 9 P 0 ;1
L 7.2575 2.3575 7.2575 2.3575 9 P 0 ;1
L 7.2575 2.4075 7.2575 2.4075 9 P 0 ;1
L 7.2575 2.4575 7.2575 2.4575 9 P 0 ;1
L 7.2575 2.5075 7.2575 2.5075 9 P 0 ;1
L 7.2575 2.5575 7.2575 2.5575 9 P 0 ;1
L 7.2575 2.6075 7.2575 2.6075 9 P 0 ;1
L 7.2575 2.6575 7.2575 2.6575 9 P 0 ;1
L 7.2575 2.7075 7.2575 2.7075 9 P 0 ;1
L 7.2575 2.7575 7.2575 2.7575 9 P 0 ;1
L 7.2575 2.8075 7.2575 2.8075 9 P 0 ;1
L 7.2575 2.8575 7.2575 2.8575 9 P 0 ;1
L 7.2575 2.9075 7.2575 2.9075 9 P 0 ;1
L 7.2575 2.9575 7.2575 2.9575 9 P 0 ;1
L 7.2575 3.0075 7.2575 3.0075 9 P 0 ;1
L 7.2575 3.0575 7.2575 3.0575 9 P 0 ;1
L 7.2575 3.1075 7.2575 3.1075 9 P 0 ;1
L 7.2575 3.1575 7.2575 3.1575 9 P 0 ;1
L 7.2575 3.2075 7.2575 3.2075 9 P 0 ;1
L 7.2575 3.2575 7.2575 3.2575 9 P 0 ;1
L 7.2575 3.3075 7.2575 3.3075 9 P 0 ;1
L 7.2575 3.3575 7.2575 3.3575 9 P 0 ;1
L 7.2575 3.4075 7.2575 3.4075 9 P 0 ;1
L 7.2575 3.4575 7.2575 3.4575 9 P 0 ;1
L 7.2575 3.5075 7.2575 3.5075 9 P 0 ;1
L 7.2575 3.5575 7.2575 3.5575 9 P 0 ;1
L 7.2575 3.6075 7.2575 3.6075 9 P 0 ;1
L 7.2575 3.6575 7.2575 3.6575 9 P 0 ;1
L 7.2575 3.7075 7.2575 3.7075 9 P 0 ;1
L 7.2575 3.7575 7.2575 3.7575 9 P 0 ;1
L 7.2575 3.8075 7.2575 3.8075 9 P 0 ;1
L 7.2575 3.8575 7.2575 3.8575 9 P 0 ;1
L 7.2575 3.9075 7.2575 3.9075 9 P 0 ;1
L 7.2575 3.9575 7.2575 3.9575 9 P 0 ;1
L 7.2575 4.0075 7.2575 4.0075 9 P 0 ;1
L 7.2575 4.0575 7.2575 4.0575 9 P 0 ;1
L 7.2575 4.1075 7.2575 4.1075 9 P 0 ;1
L 7.2575 4.1575 7.2575 4.1575 9 P 0 ;1
L 7.2575 4.2075 7.2575 4.2075 9 P 0 ;1
L 7.2575 4.2575 7.2575 4.2575 9 P 0 ;1
L 7.2575 4.3075 7.2575 4.3075 9 P 0 ;1
L 7.2575 4.3575 7.2575 4.3575 9 P 0 ;1
L 7.2575 4.4075 7.2575 4.4075 9 P 0 ;1
L 7.2575 4.4575 7.2575 4.4575 9 P 0 ;1
L 7.2575 4.5075 7.2575 4.5075 9 P 0 ;1
L 7.2575 4.8075 7.2575 4.8075 9 P 0 ;1
L 7.2575 4.8575 7.2575 4.8575 9 P 0 ;1
L 7.2575 5.2575 7.2575 5.2575 9 P 0 ;1
L 7.2575 5.3075 7.2575 5.3075 9 P 0 ;1
L 7.2575 5.3575 7.2575 5.3575 9 P 0 ;1
L 7.2575 5.4075 7.2575 5.4075 9 P 0 ;1
L 7.2575 5.4575 7.2575 5.4575 9 P 0 ;1
L 7.2575 5.5075 7.2575 5.5075 9 P 0 ;1
L 7.2575 5.5575 7.2575 5.5575 9 P 0 ;1
L 7.2575 5.6075 7.2575 5.6075 9 P 0 ;1
L 7.3075 0.4575 7.3075 0.4575 9 P 0 ;1
L 7.3075 0.5075 7.3075 0.5075 9 P 0 ;1
L 7.3075 0.5575 7.3075 0.5575 9 P 0 ;1
L 7.3075 0.6075 7.3075 0.6075 9 P 0 ;1
L 7.3075 0.6575 7.3075 0.6575 9 P 0 ;1
L 7.3075 0.7075 7.3075 0.7075 9 P 0 ;1
L 7.3075 0.7575 7.3075 0.7575 9 P 0 ;1
L 7.3075 0.8075 7.3075 0.8075 9 P 0 ;1
L 7.3075 0.8575 7.3075 0.8575 9 P 0 ;1
L 7.3075 1.0575 7.3075 1.0575 9 P 0 ;1
L 7.3075 1.1075 7.3075 1.1075 9 P 0 ;1
L 7.3075 1.1575 7.3075 1.1575 9 P 0 ;1
L 7.3075 1.2075 7.3075 1.2075 9 P 0 ;1
L 7.3075 1.2575 7.3075 1.2575 9 P 0 ;1
L 7.3075 1.3075 7.3075 1.3075 9 P 0 ;1
L 7.3075 1.3575 7.3075 1.3575 9 P 0 ;1
L 7.3075 1.4075 7.3075 1.4075 9 P 0 ;1
L 7.3075 1.4575 7.3075 1.4575 9 P 0 ;1
L 7.3075 1.5075 7.3075 1.5075 9 P 0 ;1
L 7.3075 1.5575 7.3075 1.5575 9 P 0 ;1
L 7.3075 1.6075 7.3075 1.6075 9 P 0 ;1
L 7.3075 1.6575 7.3075 1.6575 9 P 0 ;1
L 7.3075 1.9075 7.3075 1.9075 9 P 0 ;1
L 7.3075 1.9575 7.3075 1.9575 9 P 0 ;1
L 7.3075 2.0075 7.3075 2.0075 9 P 0 ;1
L 7.3075 2.0575 7.3075 2.0575 9 P 0 ;1
L 7.3075 2.1075 7.3075 2.1075 9 P 0 ;1
L 7.3075 2.1575 7.3075 2.1575 9 P 0 ;1
L 7.3075 2.2075 7.3075 2.2075 9 P 0 ;1
L 7.3075 2.2575 7.3075 2.2575 9 P 0 ;1
L 7.3075 2.3075 7.3075 2.3075 9 P 0 ;1
L 7.3075 2.3575 7.3075 2.3575 9 P 0 ;1
L 7.3075 2.4075 7.3075 2.4075 9 P 0 ;1
L 7.3075 2.4575 7.3075 2.4575 9 P 0 ;1
L 7.3075 2.5075 7.3075 2.5075 9 P 0 ;1
L 7.3075 2.5575 7.3075 2.5575 9 P 0 ;1
L 7.3075 2.6075 7.3075 2.6075 9 P 0 ;1
L 7.3075 2.6575 7.3075 2.6575 9 P 0 ;1
L 7.3075 2.7075 7.3075 2.7075 9 P 0 ;1
L 7.3075 2.7575 7.3075 2.7575 9 P 0 ;1
L 7.3075 2.8075 7.3075 2.8075 9 P 0 ;1
L 7.3075 2.8575 7.3075 2.8575 9 P 0 ;1
L 7.3075 2.9075 7.3075 2.9075 9 P 0 ;1
L 7.3075 2.9575 7.3075 2.9575 9 P 0 ;1
L 7.3075 3.0075 7.3075 3.0075 9 P 0 ;1
L 7.3075 3.0575 7.3075 3.0575 9 P 0 ;1
L 7.3075 3.1075 7.3075 3.1075 9 P 0 ;1
L 7.3075 3.1575 7.3075 3.1575 9 P 0 ;1
L 7.3075 3.2075 7.3075 3.2075 9 P 0 ;1
L 7.3075 3.2575 7.3075 3.2575 9 P 0 ;1
L 7.3075 3.3075 7.3075 3.3075 9 P 0 ;1
L 7.3075 3.3575 7.3075 3.3575 9 P 0 ;1
L 7.3075 3.4075 7.3075 3.4075 9 P 0 ;1
L 7.3075 3.4575 7.3075 3.4575 9 P 0 ;1
L 7.3075 3.5075 7.3075 3.5075 9 P 0 ;1
L 7.3075 3.5575 7.3075 3.5575 9 P 0 ;1
L 7.3075 3.6075 7.3075 3.6075 9 P 0 ;1
L 7.3075 3.6575 7.3075 3.6575 9 P 0 ;1
L 7.3075 3.7075 7.3075 3.7075 9 P 0 ;1
L 7.3075 3.7575 7.3075 3.7575 9 P 0 ;1
L 7.3075 3.8075 7.3075 3.8075 9 P 0 ;1
L 7.3075 3.8575 7.3075 3.8575 9 P 0 ;1
L 7.3075 3.9075 7.3075 3.9075 9 P 0 ;1
L 7.3075 3.9575 7.3075 3.9575 9 P 0 ;1
L 7.3075 4.0075 7.3075 4.0075 9 P 0 ;1
L 7.3075 4.0575 7.3075 4.0575 9 P 0 ;1
L 7.3075 4.1075 7.3075 4.1075 9 P 0 ;1
L 7.3075 4.1575 7.3075 4.1575 9 P 0 ;1
L 7.3075 4.2075 7.3075 4.2075 9 P 0 ;1
L 7.3075 4.2575 7.3075 4.2575 9 P 0 ;1
L 7.3075 4.3075 7.3075 4.3075 9 P 0 ;1
L 7.3075 4.3575 7.3075 4.3575 9 P 0 ;1
L 7.3075 4.4075 7.3075 4.4075 9 P 0 ;1
L 7.3075 4.4575 7.3075 4.4575 9 P 0 ;1
L 7.3075 4.5075 7.3075 4.5075 9 P 0 ;1
L 7.3075 4.9575 7.3075 4.9575 9 P 0 ;1
L 7.3075 5.2575 7.3075 5.2575 9 P 0 ;1
L 7.3075 5.3075 7.3075 5.3075 9 P 0 ;1
L 7.3075 5.3575 7.3075 5.3575 9 P 0 ;1
L 7.3075 5.4075 7.3075 5.4075 9 P 0 ;1
L 7.3075 5.4575 7.3075 5.4575 9 P 0 ;1
L 7.3075 5.5075 7.3075 5.5075 9 P 0 ;1
L 7.3075 5.5575 7.3075 5.5575 9 P 0 ;1
L 7.3075 5.6075 7.3075 5.6075 9 P 0 ;1
L 7.3575 0.1575 7.3575 0.1575 9 P 0 ;1
L 7.3575 0.3575 7.3575 0.3575 9 P 0 ;1
L 7.3575 0.4075 7.3575 0.4075 9 P 0 ;1
L 7.3575 0.4575 7.3575 0.4575 9 P 0 ;1
L 7.3575 0.5075 7.3575 0.5075 9 P 0 ;1
L 7.3575 0.5575 7.3575 0.5575 9 P 0 ;1
L 7.3575 0.6075 7.3575 0.6075 9 P 0 ;1
L 7.3575 0.6575 7.3575 0.6575 9 P 0 ;1
L 7.3575 0.7075 7.3575 0.7075 9 P 0 ;1
L 7.3575 0.7575 7.3575 0.7575 9 P 0 ;1
L 7.3575 0.8075 7.3575 0.8075 9 P 0 ;1
L 7.3575 0.8575 7.3575 0.8575 9 P 0 ;1
L 7.3575 1.0575 7.3575 1.0575 9 P 0 ;1
L 7.3575 1.1075 7.3575 1.1075 9 P 0 ;1
L 7.3575 1.1575 7.3575 1.1575 9 P 0 ;1
L 7.3575 1.2075 7.3575 1.2075 9 P 0 ;1
L 7.3575 1.2575 7.3575 1.2575 9 P 0 ;1
L 7.3575 1.3075 7.3575 1.3075 9 P 0 ;1
L 7.3575 1.3575 7.3575 1.3575 9 P 0 ;1
L 7.3575 1.4075 7.3575 1.4075 9 P 0 ;1
L 7.3575 1.4575 7.3575 1.4575 9 P 0 ;1
L 7.3575 1.5075 7.3575 1.5075 9 P 0 ;1
L 7.3575 1.5575 7.3575 1.5575 9 P 0 ;1
L 7.3575 1.6075 7.3575 1.6075 9 P 0 ;1
L 7.3575 1.6575 7.3575 1.6575 9 P 0 ;1
L 7.3575 1.9075 7.3575 1.9075 9 P 0 ;1
L 7.3575 1.9575 7.3575 1.9575 9 P 0 ;1
L 7.3575 2.0075 7.3575 2.0075 9 P 0 ;1
L 7.3575 2.0575 7.3575 2.0575 9 P 0 ;1
L 7.3575 2.1075 7.3575 2.1075 9 P 0 ;1
L 7.3575 2.1575 7.3575 2.1575 9 P 0 ;1
L 7.3575 2.2075 7.3575 2.2075 9 P 0 ;1
L 7.3575 2.2575 7.3575 2.2575 9 P 0 ;1
L 7.3575 2.3075 7.3575 2.3075 9 P 0 ;1
L 7.3575 2.3575 7.3575 2.3575 9 P 0 ;1
L 7.3575 2.4075 7.3575 2.4075 9 P 0 ;1
L 7.3575 2.4575 7.3575 2.4575 9 P 0 ;1
L 7.3575 2.5075 7.3575 2.5075 9 P 0 ;1
L 7.3575 2.5575 7.3575 2.5575 9 P 0 ;1
L 7.3575 2.6075 7.3575 2.6075 9 P 0 ;1
L 7.3575 2.6575 7.3575 2.6575 9 P 0 ;1
L 7.3575 2.7075 7.3575 2.7075 9 P 0 ;1
L 7.3575 2.7575 7.3575 2.7575 9 P 0 ;1
L 7.3575 2.8075 7.3575 2.8075 9 P 0 ;1
L 7.3575 2.8575 7.3575 2.8575 9 P 0 ;1
L 7.3575 2.9075 7.3575 2.9075 9 P 0 ;1
L 7.3575 2.9575 7.3575 2.9575 9 P 0 ;1
L 7.3575 3.0075 7.3575 3.0075 9 P 0 ;1
L 7.3575 3.0575 7.3575 3.0575 9 P 0 ;1
L 7.3575 3.1075 7.3575 3.1075 9 P 0 ;1
L 7.3575 3.1575 7.3575 3.1575 9 P 0 ;1
L 7.3575 3.2075 7.3575 3.2075 9 P 0 ;1
L 7.3575 3.2575 7.3575 3.2575 9 P 0 ;1
L 7.3575 3.3075 7.3575 3.3075 9 P 0 ;1
L 7.3575 3.3575 7.3575 3.3575 9 P 0 ;1
L 7.3575 3.5075 7.3575 3.5075 9 P 0 ;1
L 7.3575 3.5575 7.3575 3.5575 9 P 0 ;1
L 7.3575 3.6075 7.3575 3.6075 9 P 0 ;1
L 7.3575 3.6575 7.3575 3.6575 9 P 0 ;1
L 7.3575 3.7075 7.3575 3.7075 9 P 0 ;1
L 7.3575 3.7575 7.3575 3.7575 9 P 0 ;1
L 7.3575 3.8075 7.3575 3.8075 9 P 0 ;1
L 7.3575 3.8575 7.3575 3.8575 9 P 0 ;1
L 7.3575 3.9075 7.3575 3.9075 9 P 0 ;1
L 7.3575 3.9575 7.3575 3.9575 9 P 0 ;1
L 7.3575 4.0075 7.3575 4.0075 9 P 0 ;1
L 7.3575 4.0575 7.3575 4.0575 9 P 0 ;1
L 7.3575 4.1075 7.3575 4.1075 9 P 0 ;1
L 7.3575 4.1575 7.3575 4.1575 9 P 0 ;1
L 7.3575 4.2075 7.3575 4.2075 9 P 0 ;1
L 7.3575 4.2575 7.3575 4.2575 9 P 0 ;1
L 7.3575 4.3075 7.3575 4.3075 9 P 0 ;1
L 7.3575 4.3575 7.3575 4.3575 9 P 0 ;1
L 7.3575 4.4075 7.3575 4.4075 9 P 0 ;1
L 7.3575 4.4575 7.3575 4.4575 9 P 0 ;1
L 7.3575 4.5075 7.3575 4.5075 9 P 0 ;1
L 7.3575 4.9575 7.3575 4.9575 9 P 0 ;1
L 7.3575 5.2575 7.3575 5.2575 9 P 0 ;1
L 7.3575 5.3075 7.3575 5.3075 9 P 0 ;1
L 7.3575 5.3575 7.3575 5.3575 9 P 0 ;1
L 7.3575 5.4075 7.3575 5.4075 9 P 0 ;1
L 7.3575 5.4575 7.3575 5.4575 9 P 0 ;1
L 7.3575 5.5075 7.3575 5.5075 9 P 0 ;1
L 7.3575 5.5575 7.3575 5.5575 9 P 0 ;1
L 7.3575 5.6075 7.3575 5.6075 9 P 0 ;1
L 7.3575 5.6575 7.3575 5.6575 9 P 0 ;1
L 7.3575 5.7075 7.3575 5.7075 9 P 0 ;1
L 7.3575 5.9075 7.3575 5.9075 9 P 0 ;1
L 7.4075 0.1575 7.4075 0.1575 9 P 0 ;1
L 7.4075 0.2075 7.4075 0.2075 9 P 0 ;1
L 7.4075 0.2575 7.4075 0.2575 9 P 0 ;1
L 7.4075 0.3075 7.4075 0.3075 9 P 0 ;1
L 7.4075 0.3575 7.4075 0.3575 9 P 0 ;1
L 7.4075 0.4075 7.4075 0.4075 9 P 0 ;1
L 7.4075 0.4575 7.4075 0.4575 9 P 0 ;1
L 7.4075 0.5075 7.4075 0.5075 9 P 0 ;1
L 7.4075 0.5575 7.4075 0.5575 9 P 0 ;1
L 7.4075 0.6075 7.4075 0.6075 9 P 0 ;1
L 7.4075 0.6575 7.4075 0.6575 9 P 0 ;1
L 7.4075 0.7075 7.4075 0.7075 9 P 0 ;1
L 7.4075 0.7575 7.4075 0.7575 9 P 0 ;1
L 7.4075 0.8075 7.4075 0.8075 9 P 0 ;1
L 7.4075 0.8575 7.4075 0.8575 9 P 0 ;1
L 7.4075 1.0575 7.4075 1.0575 9 P 0 ;1
L 7.4075 1.1075 7.4075 1.1075 9 P 0 ;1
L 7.4075 1.1575 7.4075 1.1575 9 P 0 ;1
L 7.4075 1.2075 7.4075 1.2075 9 P 0 ;1
L 7.4075 1.2575 7.4075 1.2575 9 P 0 ;1
L 7.4075 1.3075 7.4075 1.3075 9 P 0 ;1
L 7.4075 1.3575 7.4075 1.3575 9 P 0 ;1
L 7.4075 1.4075 7.4075 1.4075 9 P 0 ;1
L 7.4075 1.4575 7.4075 1.4575 9 P 0 ;1
L 7.4075 1.5075 7.4075 1.5075 9 P 0 ;1
L 7.4075 1.5575 7.4075 1.5575 9 P 0 ;1
L 7.4075 1.6075 7.4075 1.6075 9 P 0 ;1
L 7.4075 1.9075 7.4075 1.9075 9 P 0 ;1
L 7.4075 1.9575 7.4075 1.9575 9 P 0 ;1
L 7.4075 2.0075 7.4075 2.0075 9 P 0 ;1
L 7.4075 2.0575 7.4075 2.0575 9 P 0 ;1
L 7.4075 2.1075 7.4075 2.1075 9 P 0 ;1
L 7.4075 2.1575 7.4075 2.1575 9 P 0 ;1
L 7.4075 2.2075 7.4075 2.2075 9 P 0 ;1
L 7.4075 2.2575 7.4075 2.2575 9 P 0 ;1
L 7.4075 2.3075 7.4075 2.3075 9 P 0 ;1
L 7.4075 2.3575 7.4075 2.3575 9 P 0 ;1
L 7.4075 2.4075 7.4075 2.4075 9 P 0 ;1
L 7.4075 2.4575 7.4075 2.4575 9 P 0 ;1
L 7.4075 2.5075 7.4075 2.5075 9 P 0 ;1
L 7.4075 2.5575 7.4075 2.5575 9 P 0 ;1
L 7.4075 2.6075 7.4075 2.6075 9 P 0 ;1
L 7.4075 2.6575 7.4075 2.6575 9 P 0 ;1
L 7.4075 2.7075 7.4075 2.7075 9 P 0 ;1
L 7.4075 2.7575 7.4075 2.7575 9 P 0 ;1
L 7.4075 2.8075 7.4075 2.8075 9 P 0 ;1
L 7.4075 2.8575 7.4075 2.8575 9 P 0 ;1
L 7.4075 2.9075 7.4075 2.9075 9 P 0 ;1
L 7.4075 2.9575 7.4075 2.9575 9 P 0 ;1
L 7.4075 3.0075 7.4075 3.0075 9 P 0 ;1
L 7.4075 3.0575 7.4075 3.0575 9 P 0 ;1
L 7.4075 3.1075 7.4075 3.1075 9 P 0 ;1
L 7.4075 3.1575 7.4075 3.1575 9 P 0 ;1
L 7.4075 3.2075 7.4075 3.2075 9 P 0 ;1
L 7.4075 3.2575 7.4075 3.2575 9 P 0 ;1
L 7.4075 3.3075 7.4075 3.3075 9 P 0 ;1
L 7.4075 3.5075 7.4075 3.5075 9 P 0 ;1
L 7.4075 3.5575 7.4075 3.5575 9 P 0 ;1
L 7.4075 3.6075 7.4075 3.6075 9 P 0 ;1
L 7.4075 3.6575 7.4075 3.6575 9 P 0 ;1
L 7.4075 3.7075 7.4075 3.7075 9 P 0 ;1
L 7.4075 3.7575 7.4075 3.7575 9 P 0 ;1
L 7.4075 3.8075 7.4075 3.8075 9 P 0 ;1
L 7.4075 3.8575 7.4075 3.8575 9 P 0 ;1
L 7.4075 3.9075 7.4075 3.9075 9 P 0 ;1
L 7.4075 3.9575 7.4075 3.9575 9 P 0 ;1
L 7.4075 4.0075 7.4075 4.0075 9 P 0 ;1
L 7.4075 4.0575 7.4075 4.0575 9 P 0 ;1
L 7.4075 4.1075 7.4075 4.1075 9 P 0 ;1
L 7.4075 4.1575 7.4075 4.1575 9 P 0 ;1
L 7.4075 4.2075 7.4075 4.2075 9 P 0 ;1
L 7.4075 4.2575 7.4075 4.2575 9 P 0 ;1
L 7.4075 4.3075 7.4075 4.3075 9 P 0 ;1
L 7.4075 4.3575 7.4075 4.3575 9 P 0 ;1
L 7.4075 4.4075 7.4075 4.4075 9 P 0 ;1
L 7.4075 4.4575 7.4075 4.4575 9 P 0 ;1
L 7.4075 4.5075 7.4075 4.5075 9 P 0 ;1
L 7.4075 4.5575 7.4075 4.5575 9 P 0 ;1
L 7.4075 4.6075 7.4075 4.6075 9 P 0 ;1
L 7.4075 4.7575 7.4075 4.7575 9 P 0 ;1
L 7.4075 4.8075 7.4075 4.8075 9 P 0 ;1
L 7.4075 4.9075 7.4075 4.9075 9 P 0 ;1
L 7.4075 4.9575 7.4075 4.9575 9 P 0 ;1
L 7.4075 5.0075 7.4075 5.0075 9 P 0 ;1
L 7.4075 5.0575 7.4075 5.0575 9 P 0 ;1
L 7.4075 5.2575 7.4075 5.2575 9 P 0 ;1
L 7.4075 5.3075 7.4075 5.3075 9 P 0 ;1
L 7.4075 5.3575 7.4075 5.3575 9 P 0 ;1
L 7.4075 5.4075 7.4075 5.4075 9 P 0 ;1
L 7.4075 5.4575 7.4075 5.4575 9 P 0 ;1
L 7.4075 5.5075 7.4075 5.5075 9 P 0 ;1
L 7.4075 5.5575 7.4075 5.5575 9 P 0 ;1
L 7.4075 5.6075 7.4075 5.6075 9 P 0 ;1
L 7.4075 5.6575 7.4075 5.6575 9 P 0 ;1
L 7.4075 5.7075 7.4075 5.7075 9 P 0 ;1
L 7.4075 5.7575 7.4075 5.7575 9 P 0 ;1
L 7.4075 5.8075 7.4075 5.8075 9 P 0 ;1
L 7.4075 5.8575 7.4075 5.8575 9 P 0 ;1
L 7.4075 5.9075 7.4075 5.9075 9 P 0 ;1
L 7.4575 0.1575 7.4575 0.1575 9 P 0 ;1
L 7.4575 0.2075 7.4575 0.2075 9 P 0 ;1
L 7.4575 0.2575 7.4575 0.2575 9 P 0 ;1
L 7.4575 0.3075 7.4575 0.3075 9 P 0 ;1
L 7.4575 0.3575 7.4575 0.3575 9 P 0 ;1
L 7.4575 0.4075 7.4575 0.4075 9 P 0 ;1
L 7.4575 0.4575 7.4575 0.4575 9 P 0 ;1
L 7.4575 0.5075 7.4575 0.5075 9 P 0 ;1
L 7.4575 0.5575 7.4575 0.5575 9 P 0 ;1
L 7.4575 0.6075 7.4575 0.6075 9 P 0 ;1
L 7.4575 0.6575 7.4575 0.6575 9 P 0 ;1
L 7.4575 0.7075 7.4575 0.7075 9 P 0 ;1
L 7.4575 0.7575 7.4575 0.7575 9 P 0 ;1
L 7.4575 0.8075 7.4575 0.8075 9 P 0 ;1
L 7.4575 0.8575 7.4575 0.8575 9 P 0 ;1
L 7.4575 1.0575 7.4575 1.0575 9 P 0 ;1
L 7.4575 1.1075 7.4575 1.1075 9 P 0 ;1
L 7.4575 1.1575 7.4575 1.1575 9 P 0 ;1
L 7.4575 1.2075 7.4575 1.2075 9 P 0 ;1
L 7.4575 1.2575 7.4575 1.2575 9 P 0 ;1
L 7.4575 1.3075 7.4575 1.3075 9 P 0 ;1
L 7.4575 1.3575 7.4575 1.3575 9 P 0 ;1
L 7.4575 1.4075 7.4575 1.4075 9 P 0 ;1
L 7.4575 1.4575 7.4575 1.4575 9 P 0 ;1
L 7.4575 1.5075 7.4575 1.5075 9 P 0 ;1
L 7.4575 1.5575 7.4575 1.5575 9 P 0 ;1
L 7.4575 1.6075 7.4575 1.6075 9 P 0 ;1
L 7.4575 1.9075 7.4575 1.9075 9 P 0 ;1
L 7.4575 1.9575 7.4575 1.9575 9 P 0 ;1
L 7.4575 2.0075 7.4575 2.0075 9 P 0 ;1
L 7.4575 2.0575 7.4575 2.0575 9 P 0 ;1
L 7.4575 2.1075 7.4575 2.1075 9 P 0 ;1
L 7.4575 2.1575 7.4575 2.1575 9 P 0 ;1
L 7.4575 2.2075 7.4575 2.2075 9 P 0 ;1
L 7.4575 2.2575 7.4575 2.2575 9 P 0 ;1
L 7.4575 2.3075 7.4575 2.3075 9 P 0 ;1
L 7.4575 2.3575 7.4575 2.3575 9 P 0 ;1
L 7.4575 2.4075 7.4575 2.4075 9 P 0 ;1
L 7.4575 2.4575 7.4575 2.4575 9 P 0 ;1
L 7.4575 2.5075 7.4575 2.5075 9 P 0 ;1
L 7.4575 2.5575 7.4575 2.5575 9 P 0 ;1
L 7.4575 2.6075 7.4575 2.6075 9 P 0 ;1
L 7.4575 2.6575 7.4575 2.6575 9 P 0 ;1
L 7.4575 2.7075 7.4575 2.7075 9 P 0 ;1
L 7.4575 2.7575 7.4575 2.7575 9 P 0 ;1
L 7.4575 2.8075 7.4575 2.8075 9 P 0 ;1
L 7.4575 2.8575 7.4575 2.8575 9 P 0 ;1
L 7.4575 2.9075 7.4575 2.9075 9 P 0 ;1
L 7.4575 2.9575 7.4575 2.9575 9 P 0 ;1
L 7.4575 3.0075 7.4575 3.0075 9 P 0 ;1
L 7.4575 3.0575 7.4575 3.0575 9 P 0 ;1
L 7.4575 3.1075 7.4575 3.1075 9 P 0 ;1
L 7.4575 3.1575 7.4575 3.1575 9 P 0 ;1
L 7.4575 3.2075 7.4575 3.2075 9 P 0 ;1
L 7.4575 3.2575 7.4575 3.2575 9 P 0 ;1
L 7.4575 3.3075 7.4575 3.3075 9 P 0 ;1
L 7.4575 3.5075 7.4575 3.5075 9 P 0 ;1
L 7.4575 3.5575 7.4575 3.5575 9 P 0 ;1
L 7.4575 3.6075 7.4575 3.6075 9 P 0 ;1
L 7.4575 3.6575 7.4575 3.6575 9 P 0 ;1
L 7.4575 3.7075 7.4575 3.7075 9 P 0 ;1
L 7.4575 3.7575 7.4575 3.7575 9 P 0 ;1
L 7.4575 3.8075 7.4575 3.8075 9 P 0 ;1
L 7.4575 3.8575 7.4575 3.8575 9 P 0 ;1
L 7.4575 3.9075 7.4575 3.9075 9 P 0 ;1
L 7.4575 3.9575 7.4575 3.9575 9 P 0 ;1
L 7.4575 4.0075 7.4575 4.0075 9 P 0 ;1
L 7.4575 4.0575 7.4575 4.0575 9 P 0 ;1
L 7.4575 4.1075 7.4575 4.1075 9 P 0 ;1
L 7.4575 4.1575 7.4575 4.1575 9 P 0 ;1
L 7.4575 4.2075 7.4575 4.2075 9 P 0 ;1
L 7.4575 4.2575 7.4575 4.2575 9 P 0 ;1
L 7.4575 4.3075 7.4575 4.3075 9 P 0 ;1
L 7.4575 4.3575 7.4575 4.3575 9 P 0 ;1
L 7.4575 4.4075 7.4575 4.4075 9 P 0 ;1
L 7.4575 4.4575 7.4575 4.4575 9 P 0 ;1
L 7.4575 4.5075 7.4575 4.5075 9 P 0 ;1
L 7.4575 4.5575 7.4575 4.5575 9 P 0 ;1
L 7.4575 4.6075 7.4575 4.6075 9 P 0 ;1
L 7.4575 4.6575 7.4575 4.6575 9 P 0 ;1
L 7.4575 4.7075 7.4575 4.7075 9 P 0 ;1
L 7.4575 4.8575 7.4575 4.8575 9 P 0 ;1
L 7.4575 4.9075 7.4575 4.9075 9 P 0 ;1
L 7.4575 4.9575 7.4575 4.9575 9 P 0 ;1
L 7.4575 5.0075 7.4575 5.0075 9 P 0 ;1
L 7.4575 5.2575 7.4575 5.2575 9 P 0 ;1
L 7.4575 5.3075 7.4575 5.3075 9 P 0 ;1
L 7.4575 5.3575 7.4575 5.3575 9 P 0 ;1
L 7.4575 5.4075 7.4575 5.4075 9 P 0 ;1
L 7.4575 5.4575 7.4575 5.4575 9 P 0 ;1
L 7.4575 5.5075 7.4575 5.5075 9 P 0 ;1
L 7.4575 5.5575 7.4575 5.5575 9 P 0 ;1
L 7.4575 5.6075 7.4575 5.6075 9 P 0 ;1
L 7.4575 5.6575 7.4575 5.6575 9 P 0 ;1
L 7.4575 5.7075 7.4575 5.7075 9 P 0 ;1
L 7.4575 5.7575 7.4575 5.7575 9 P 0 ;1
L 7.4575 5.8075 7.4575 5.8075 9 P 0 ;1
L 7.4575 5.8575 7.4575 5.8575 9 P 0 ;1
L 7.4575 5.9075 7.4575 5.9075 9 P 0 ;1
L 7.5075 0.1575 7.5075 0.1575 9 P 0 ;1
L 7.5075 0.2075 7.5075 0.2075 9 P 0 ;1
L 7.5075 0.2575 7.5075 0.2575 9 P 0 ;1
L 7.5075 0.3075 7.5075 0.3075 9 P 0 ;1
L 7.5075 0.3575 7.5075 0.3575 9 P 0 ;1
L 7.5075 0.4075 7.5075 0.4075 9 P 0 ;1
L 7.5075 0.4575 7.5075 0.4575 9 P 0 ;1
L 7.5075 0.5075 7.5075 0.5075 9 P 0 ;1
L 7.5075 0.5575 7.5075 0.5575 9 P 0 ;1
L 7.5075 0.6075 7.5075 0.6075 9 P 0 ;1
L 7.5075 0.6575 7.5075 0.6575 9 P 0 ;1
L 7.5075 0.7075 7.5075 0.7075 9 P 0 ;1
L 7.5075 0.7575 7.5075 0.7575 9 P 0 ;1
L 7.5075 0.8075 7.5075 0.8075 9 P 0 ;1
L 7.5075 0.8575 7.5075 0.8575 9 P 0 ;1
L 7.5075 1.0575 7.5075 1.0575 9 P 0 ;1
L 7.5075 1.1075 7.5075 1.1075 9 P 0 ;1
L 7.5075 1.1575 7.5075 1.1575 9 P 0 ;1
L 7.5075 1.2075 7.5075 1.2075 9 P 0 ;1
L 7.5075 1.2575 7.5075 1.2575 9 P 0 ;1
L 7.5075 1.3075 7.5075 1.3075 9 P 0 ;1
L 7.5075 1.3575 7.5075 1.3575 9 P 0 ;1
L 7.5075 1.4075 7.5075 1.4075 9 P 0 ;1
L 7.5075 1.4575 7.5075 1.4575 9 P 0 ;1
L 7.5075 1.5075 7.5075 1.5075 9 P 0 ;1
L 7.5075 1.5575 7.5075 1.5575 9 P 0 ;1
L 7.5075 1.6075 7.5075 1.6075 9 P 0 ;1
L 7.5075 1.9075 7.5075 1.9075 9 P 0 ;1
L 7.5075 1.9575 7.5075 1.9575 9 P 0 ;1
L 7.5075 2.0075 7.5075 2.0075 9 P 0 ;1
L 7.5075 2.0575 7.5075 2.0575 9 P 0 ;1
L 7.5075 2.1075 7.5075 2.1075 9 P 0 ;1
L 7.5075 2.1575 7.5075 2.1575 9 P 0 ;1
L 7.5075 2.2075 7.5075 2.2075 9 P 0 ;1
L 7.5075 2.2575 7.5075 2.2575 9 P 0 ;1
L 7.5075 2.3075 7.5075 2.3075 9 P 0 ;1
L 7.5075 2.3575 7.5075 2.3575 9 P 0 ;1
L 7.5075 2.4075 7.5075 2.4075 9 P 0 ;1
L 7.5075 2.4575 7.5075 2.4575 9 P 0 ;1
L 7.5075 2.5075 7.5075 2.5075 9 P 0 ;1
L 7.5075 2.5575 7.5075 2.5575 9 P 0 ;1
L 7.5075 2.6075 7.5075 2.6075 9 P 0 ;1
L 7.5075 2.6575 7.5075 2.6575 9 P 0 ;1
L 7.5075 2.7075 7.5075 2.7075 9 P 0 ;1
L 7.5075 2.7575 7.5075 2.7575 9 P 0 ;1
L 7.5075 2.8075 7.5075 2.8075 9 P 0 ;1
L 7.5075 2.8575 7.5075 2.8575 9 P 0 ;1
L 7.5075 2.9075 7.5075 2.9075 9 P 0 ;1
L 7.5075 2.9575 7.5075 2.9575 9 P 0 ;1
L 7.5075 3.0075 7.5075 3.0075 9 P 0 ;1
L 7.5075 3.0575 7.5075 3.0575 9 P 0 ;1
L 7.5075 3.1075 7.5075 3.1075 9 P 0 ;1
L 7.5075 3.1575 7.5075 3.1575 9 P 0 ;1
L 7.5075 3.2075 7.5075 3.2075 9 P 0 ;1
L 7.5075 3.2575 7.5075 3.2575 9 P 0 ;1
L 7.5075 3.3075 7.5075 3.3075 9 P 0 ;1
L 7.5075 3.3575 7.5075 3.3575 9 P 0 ;1
L 7.5075 3.4075 7.5075 3.4075 9 P 0 ;1
L 7.5075 3.4575 7.5075 3.4575 9 P 0 ;1
L 7.5075 3.5075 7.5075 3.5075 9 P 0 ;1
L 7.5075 3.5575 7.5075 3.5575 9 P 0 ;1
L 7.5075 3.6075 7.5075 3.6075 9 P 0 ;1
L 7.5075 3.6575 7.5075 3.6575 9 P 0 ;1
L 7.5075 3.7075 7.5075 3.7075 9 P 0 ;1
L 7.5075 3.7575 7.5075 3.7575 9 P 0 ;1
L 7.5075 3.8075 7.5075 3.8075 9 P 0 ;1
L 7.5075 3.8575 7.5075 3.8575 9 P 0 ;1
L 7.5075 3.9075 7.5075 3.9075 9 P 0 ;1
L 7.5075 3.9575 7.5075 3.9575 9 P 0 ;1
L 7.5075 4.0075 7.5075 4.0075 9 P 0 ;1
L 7.5075 4.0575 7.5075 4.0575 9 P 0 ;1
L 7.5075 4.1075 7.5075 4.1075 9 P 0 ;1
L 7.5075 4.1575 7.5075 4.1575 9 P 0 ;1
L 7.5075 4.2075 7.5075 4.2075 9 P 0 ;1
L 7.5075 4.2575 7.5075 4.2575 9 P 0 ;1
L 7.5075 4.3075 7.5075 4.3075 9 P 0 ;1
L 7.5075 4.3575 7.5075 4.3575 9 P 0 ;1
L 7.5075 4.4075 7.5075 4.4075 9 P 0 ;1
L 7.5075 4.4575 7.5075 4.4575 9 P 0 ;1
L 7.5075 4.5075 7.5075 4.5075 9 P 0 ;1
L 7.5075 4.5575 7.5075 4.5575 9 P 0 ;1
L 7.5075 4.6075 7.5075 4.6075 9 P 0 ;1
L 7.5075 5.2075 7.5075 5.2075 9 P 0 ;1
L 7.5075 5.2575 7.5075 5.2575 9 P 0 ;1
L 7.5075 5.3075 7.5075 5.3075 9 P 0 ;1
L 7.5075 5.3575 7.5075 5.3575 9 P 0 ;1
L 7.5075 5.4075 7.5075 5.4075 9 P 0 ;1
L 7.5075 5.4575 7.5075 5.4575 9 P 0 ;1
L 7.5075 5.5075 7.5075 5.5075 9 P 0 ;1
L 7.5075 5.5575 7.5075 5.5575 9 P 0 ;1
L 7.5075 5.6075 7.5075 5.6075 9 P 0 ;1
L 7.5075 5.6575 7.5075 5.6575 9 P 0 ;1
L 7.5075 5.7075 7.5075 5.7075 9 P 0 ;1
L 7.5075 5.7575 7.5075 5.7575 9 P 0 ;1
L 7.5075 5.8075 7.5075 5.8075 9 P 0 ;1
L 7.5075 5.8575 7.5075 5.8575 9 P 0 ;1
L 7.5075 5.9075 7.5075 5.9075 9 P 0 ;1
L 7.5575 0.1575 7.5575 0.1575 9 P 0 ;1
L 7.5575 0.2075 7.5575 0.2075 9 P 0 ;1
L 7.5575 0.2575 7.5575 0.2575 9 P 0 ;1
L 7.5575 0.3075 7.5575 0.3075 9 P 0 ;1
L 7.5575 0.3575 7.5575 0.3575 9 P 0 ;1
L 7.5575 0.4075 7.5575 0.4075 9 P 0 ;1
L 7.5575 0.4575 7.5575 0.4575 9 P 0 ;1
L 7.5575 0.5075 7.5575 0.5075 9 P 0 ;1
L 7.5575 0.5575 7.5575 0.5575 9 P 0 ;1
L 7.5575 0.6075 7.5575 0.6075 9 P 0 ;1
L 7.5575 0.6575 7.5575 0.6575 9 P 0 ;1
L 7.5575 0.7075 7.5575 0.7075 9 P 0 ;1
L 7.5575 0.7575 7.5575 0.7575 9 P 0 ;1
L 7.5575 0.8075 7.5575 0.8075 9 P 0 ;1
L 7.5575 0.8575 7.5575 0.8575 9 P 0 ;1
L 7.5575 1.0575 7.5575 1.0575 9 P 0 ;1
L 7.5575 1.1075 7.5575 1.1075 9 P 0 ;1
L 7.5575 1.1575 7.5575 1.1575 9 P 0 ;1
L 7.5575 1.2075 7.5575 1.2075 9 P 0 ;1
L 7.5575 1.2575 7.5575 1.2575 9 P 0 ;1
L 7.5575 1.3075 7.5575 1.3075 9 P 0 ;1
L 7.5575 1.3575 7.5575 1.3575 9 P 0 ;1
L 7.5575 1.4075 7.5575 1.4075 9 P 0 ;1
L 7.5575 1.4575 7.5575 1.4575 9 P 0 ;1
L 7.5575 1.5075 7.5575 1.5075 9 P 0 ;1
L 7.5575 1.5575 7.5575 1.5575 9 P 0 ;1
L 7.5575 1.6075 7.5575 1.6075 9 P 0 ;1
L 7.5575 1.9075 7.5575 1.9075 9 P 0 ;1
L 7.5575 1.9575 7.5575 1.9575 9 P 0 ;1
L 7.5575 2.0075 7.5575 2.0075 9 P 0 ;1
L 7.5575 2.0575 7.5575 2.0575 9 P 0 ;1
L 7.5575 2.1075 7.5575 2.1075 9 P 0 ;1
L 7.5575 2.1575 7.5575 2.1575 9 P 0 ;1
L 7.5575 2.2075 7.5575 2.2075 9 P 0 ;1
L 7.5575 2.2575 7.5575 2.2575 9 P 0 ;1
L 7.5575 2.3075 7.5575 2.3075 9 P 0 ;1
L 7.5575 2.3575 7.5575 2.3575 9 P 0 ;1
L 7.5575 2.4075 7.5575 2.4075 9 P 0 ;1
L 7.5575 2.4575 7.5575 2.4575 9 P 0 ;1
L 7.5575 2.5075 7.5575 2.5075 9 P 0 ;1
L 7.5575 2.5575 7.5575 2.5575 9 P 0 ;1
L 7.5575 2.6075 7.5575 2.6075 9 P 0 ;1
L 7.5575 2.6575 7.5575 2.6575 9 P 0 ;1
L 7.5575 2.7075 7.5575 2.7075 9 P 0 ;1
L 7.5575 2.7575 7.5575 2.7575 9 P 0 ;1
L 7.5575 2.8075 7.5575 2.8075 9 P 0 ;1
L 7.5575 2.8575 7.5575 2.8575 9 P 0 ;1
L 7.5575 2.9075 7.5575 2.9075 9 P 0 ;1
L 7.5575 2.9575 7.5575 2.9575 9 P 0 ;1
L 7.5575 3.0075 7.5575 3.0075 9 P 0 ;1
L 7.5575 3.0575 7.5575 3.0575 9 P 0 ;1
L 7.5575 3.1075 7.5575 3.1075 9 P 0 ;1
L 7.5575 3.1575 7.5575 3.1575 9 P 0 ;1
L 7.5575 3.2075 7.5575 3.2075 9 P 0 ;1
L 7.5575 3.2575 7.5575 3.2575 9 P 0 ;1
L 7.5575 3.3075 7.5575 3.3075 9 P 0 ;1
L 7.5575 3.3575 7.5575 3.3575 9 P 0 ;1
L 7.5575 3.4075 7.5575 3.4075 9 P 0 ;1
L 7.5575 3.4575 7.5575 3.4575 9 P 0 ;1
L 7.5575 3.5075 7.5575 3.5075 9 P 0 ;1
L 7.5575 3.5575 7.5575 3.5575 9 P 0 ;1
L 7.5575 3.6075 7.5575 3.6075 9 P 0 ;1
L 7.5575 3.6575 7.5575 3.6575 9 P 0 ;1
L 7.5575 3.7075 7.5575 3.7075 9 P 0 ;1
L 7.5575 3.7575 7.5575 3.7575 9 P 0 ;1
L 7.5575 3.8075 7.5575 3.8075 9 P 0 ;1
L 7.5575 3.8575 7.5575 3.8575 9 P 0 ;1
L 7.5575 3.9075 7.5575 3.9075 9 P 0 ;1
L 7.5575 3.9575 7.5575 3.9575 9 P 0 ;1
L 7.5575 4.0075 7.5575 4.0075 9 P 0 ;1
L 7.5575 4.0575 7.5575 4.0575 9 P 0 ;1
L 7.5575 4.1075 7.5575 4.1075 9 P 0 ;1
L 7.5575 4.1575 7.5575 4.1575 9 P 0 ;1
L 7.5575 4.2075 7.5575 4.2075 9 P 0 ;1
L 7.5575 4.2575 7.5575 4.2575 9 P 0 ;1
L 7.5575 4.3075 7.5575 4.3075 9 P 0 ;1
L 7.5575 4.3575 7.5575 4.3575 9 P 0 ;1
L 7.5575 4.4075 7.5575 4.4075 9 P 0 ;1
L 7.5575 4.4575 7.5575 4.4575 9 P 0 ;1
L 7.5575 4.5075 7.5575 4.5075 9 P 0 ;1
L 7.5575 4.5575 7.5575 4.5575 9 P 0 ;1
L 7.5575 5.2575 7.5575 5.2575 9 P 0 ;1
L 7.5575 5.3075 7.5575 5.3075 9 P 0 ;1
L 7.5575 5.3575 7.5575 5.3575 9 P 0 ;1
L 7.5575 5.4075 7.5575 5.4075 9 P 0 ;1
L 7.5575 5.4575 7.5575 5.4575 9 P 0 ;1
L 7.5575 5.5075 7.5575 5.5075 9 P 0 ;1
L 7.5575 5.5575 7.5575 5.5575 9 P 0 ;1
L 7.5575 5.6075 7.5575 5.6075 9 P 0 ;1
L 7.5575 5.6575 7.5575 5.6575 9 P 0 ;1
L 7.5575 5.7075 7.5575 5.7075 9 P 0 ;1
L 7.5575 5.7575 7.5575 5.7575 9 P 0 ;1
L 7.5575 5.8075 7.5575 5.8075 9 P 0 ;1
L 7.5575 5.8575 7.5575 5.8575 9 P 0 ;1
L 7.5575 5.9075 7.5575 5.9075 9 P 0 ;1
L 7.6075 0.1575 7.6075 0.1575 9 P 0 ;1
L 7.6075 0.2075 7.6075 0.2075 9 P 0 ;1
L 7.6075 0.2575 7.6075 0.2575 9 P 0 ;1
L 7.6075 0.3075 7.6075 0.3075 9 P 0 ;1
L 7.6075 0.3575 7.6075 0.3575 9 P 0 ;1
L 7.6075 0.4075 7.6075 0.4075 9 P 0 ;1
L 7.6075 0.4575 7.6075 0.4575 9 P 0 ;1
L 7.6075 0.5075 7.6075 0.5075 9 P 0 ;1
L 7.6075 0.5575 7.6075 0.5575 9 P 0 ;1
L 7.6075 0.6075 7.6075 0.6075 9 P 0 ;1
L 7.6075 0.6575 7.6075 0.6575 9 P 0 ;1
L 7.6075 0.7075 7.6075 0.7075 9 P 0 ;1
L 7.6075 0.7575 7.6075 0.7575 9 P 0 ;1
L 7.6075 0.8075 7.6075 0.8075 9 P 0 ;1
L 7.6075 0.8575 7.6075 0.8575 9 P 0 ;1
L 7.6075 1.0575 7.6075 1.0575 9 P 0 ;1
L 7.6075 1.1075 7.6075 1.1075 9 P 0 ;1
L 7.6075 1.1575 7.6075 1.1575 9 P 0 ;1
L 7.6075 1.2075 7.6075 1.2075 9 P 0 ;1
L 7.6075 1.2575 7.6075 1.2575 9 P 0 ;1
L 7.6075 1.3075 7.6075 1.3075 9 P 0 ;1
L 7.6075 1.3575 7.6075 1.3575 9 P 0 ;1
L 7.6075 1.4075 7.6075 1.4075 9 P 0 ;1
L 7.6075 1.4575 7.6075 1.4575 9 P 0 ;1
L 7.6075 1.5075 7.6075 1.5075 9 P 0 ;1
L 7.6075 1.5575 7.6075 1.5575 9 P 0 ;1
L 7.6075 1.6075 7.6075 1.6075 9 P 0 ;1
L 7.6075 1.9075 7.6075 1.9075 9 P 0 ;1
L 7.6075 1.9575 7.6075 1.9575 9 P 0 ;1
L 7.6075 2.0075 7.6075 2.0075 9 P 0 ;1
L 7.6075 2.0575 7.6075 2.0575 9 P 0 ;1
L 7.6075 2.1075 7.6075 2.1075 9 P 0 ;1
L 7.6075 2.1575 7.6075 2.1575 9 P 0 ;1
L 7.6075 2.2075 7.6075 2.2075 9 P 0 ;1
L 7.6075 2.2575 7.6075 2.2575 9 P 0 ;1
L 7.6075 2.3075 7.6075 2.3075 9 P 0 ;1
L 7.6075 2.3575 7.6075 2.3575 9 P 0 ;1
L 7.6075 2.4075 7.6075 2.4075 9 P 0 ;1
L 7.6075 2.4575 7.6075 2.4575 9 P 0 ;1
L 7.6075 2.5075 7.6075 2.5075 9 P 0 ;1
L 7.6075 2.5575 7.6075 2.5575 9 P 0 ;1
L 7.6075 2.6075 7.6075 2.6075 9 P 0 ;1
L 7.6075 2.6575 7.6075 2.6575 9 P 0 ;1
L 7.6075 2.7075 7.6075 2.7075 9 P 0 ;1
L 7.6075 2.7575 7.6075 2.7575 9 P 0 ;1
L 7.6075 2.8075 7.6075 2.8075 9 P 0 ;1
L 7.6075 2.8575 7.6075 2.8575 9 P 0 ;1
L 7.6075 2.9075 7.6075 2.9075 9 P 0 ;1
L 7.6075 2.9575 7.6075 2.9575 9 P 0 ;1
L 7.6075 3.0075 7.6075 3.0075 9 P 0 ;1
L 7.6075 3.0575 7.6075 3.0575 9 P 0 ;1
L 7.6075 3.1075 7.6075 3.1075 9 P 0 ;1
L 7.6075 3.1575 7.6075 3.1575 9 P 0 ;1
L 7.6075 3.2075 7.6075 3.2075 9 P 0 ;1
L 7.6075 3.2575 7.6075 3.2575 9 P 0 ;1
L 7.6075 3.3075 7.6075 3.3075 9 P 0 ;1
L 7.6075 3.3575 7.6075 3.3575 9 P 0 ;1
L 7.6075 3.4075 7.6075 3.4075 9 P 0 ;1
L 7.6075 3.4575 7.6075 3.4575 9 P 0 ;1
L 7.6075 3.5075 7.6075 3.5075 9 P 0 ;1
L 7.6075 3.5575 7.6075 3.5575 9 P 0 ;1
L 7.6075 3.6075 7.6075 3.6075 9 P 0 ;1
L 7.6075 3.6575 7.6075 3.6575 9 P 0 ;1
L 7.6075 3.7075 7.6075 3.7075 9 P 0 ;1
L 7.6075 3.7575 7.6075 3.7575 9 P 0 ;1
L 7.6075 3.8075 7.6075 3.8075 9 P 0 ;1
L 7.6075 3.8575 7.6075 3.8575 9 P 0 ;1
L 7.6075 3.9075 7.6075 3.9075 9 P 0 ;1
L 7.6075 3.9575 7.6075 3.9575 9 P 0 ;1
L 7.6075 4.0075 7.6075 4.0075 9 P 0 ;1
L 7.6075 4.0575 7.6075 4.0575 9 P 0 ;1
L 7.6075 4.1075 7.6075 4.1075 9 P 0 ;1
L 7.6075 4.1575 7.6075 4.1575 9 P 0 ;1
L 7.6075 4.2075 7.6075 4.2075 9 P 0 ;1
L 7.6075 4.2575 7.6075 4.2575 9 P 0 ;1
L 7.6075 4.3075 7.6075 4.3075 9 P 0 ;1
L 7.6075 4.3575 7.6075 4.3575 9 P 0 ;1
L 7.6075 4.4075 7.6075 4.4075 9 P 0 ;1
L 7.6075 4.4575 7.6075 4.4575 9 P 0 ;1
L 7.6075 4.5075 7.6075 4.5075 9 P 0 ;1
L 7.6075 4.5575 7.6075 4.5575 9 P 0 ;1
L 7.6075 5.2575 7.6075 5.2575 9 P 0 ;1
L 7.6075 5.3075 7.6075 5.3075 9 P 0 ;1
L 7.6075 5.3575 7.6075 5.3575 9 P 0 ;1
L 7.6075 5.4075 7.6075 5.4075 9 P 0 ;1
L 7.6075 5.4575 7.6075 5.4575 9 P 0 ;1
L 7.6075 5.5075 7.6075 5.5075 9 P 0 ;1
L 7.6075 5.5575 7.6075 5.5575 9 P 0 ;1
L 7.6075 5.6075 7.6075 5.6075 9 P 0 ;1
L 7.6075 5.6575 7.6075 5.6575 9 P 0 ;1
L 7.6075 5.7075 7.6075 5.7075 9 P 0 ;1
L 7.6075 5.7575 7.6075 5.7575 9 P 0 ;1
L 7.6075 5.8075 7.6075 5.8075 9 P 0 ;1
L 7.6075 5.8575 7.6075 5.8575 9 P 0 ;1
L 7.6075 5.9075 7.6075 5.9075 9 P 0 ;1
L 7.6575 0.1575 7.6575 0.1575 9 P 0 ;1
L 7.6575 0.2075 7.6575 0.2075 9 P 0 ;1
L 7.6575 0.2575 7.6575 0.2575 9 P 0 ;1
L 7.6575 0.3075 7.6575 0.3075 9 P 0 ;1
L 7.6575 0.3575 7.6575 0.3575 9 P 0 ;1
L 7.6575 0.4075 7.6575 0.4075 9 P 0 ;1
L 7.6575 0.4575 7.6575 0.4575 9 P 0 ;1
L 7.6575 0.5075 7.6575 0.5075 9 P 0 ;1
L 7.6575 0.5575 7.6575 0.5575 9 P 0 ;1
L 7.6575 0.6075 7.6575 0.6075 9 P 0 ;1
L 7.6575 0.6575 7.6575 0.6575 9 P 0 ;1
L 7.6575 0.7075 7.6575 0.7075 9 P 0 ;1
L 7.6575 0.7575 7.6575 0.7575 9 P 0 ;1
L 7.6575 0.8075 7.6575 0.8075 9 P 0 ;1
L 7.6575 0.8575 7.6575 0.8575 9 P 0 ;1
L 7.6575 1.0575 7.6575 1.0575 9 P 0 ;1
L 7.6575 1.1075 7.6575 1.1075 9 P 0 ;1
L 7.6575 1.1575 7.6575 1.1575 9 P 0 ;1
L 7.6575 1.2075 7.6575 1.2075 9 P 0 ;1
L 7.6575 1.2575 7.6575 1.2575 9 P 0 ;1
L 7.6575 1.3075 7.6575 1.3075 9 P 0 ;1
L 7.6575 1.3575 7.6575 1.3575 9 P 0 ;1
L 7.6575 1.4075 7.6575 1.4075 9 P 0 ;1
L 7.6575 1.4575 7.6575 1.4575 9 P 0 ;1
L 7.6575 1.5075 7.6575 1.5075 9 P 0 ;1
L 7.6575 1.5575 7.6575 1.5575 9 P 0 ;1
L 7.6575 1.6075 7.6575 1.6075 9 P 0 ;1
L 7.6575 1.9075 7.6575 1.9075 9 P 0 ;1
L 7.6575 1.9575 7.6575 1.9575 9 P 0 ;1
L 7.6575 2.0075 7.6575 2.0075 9 P 0 ;1
L 7.6575 2.0575 7.6575 2.0575 9 P 0 ;1
L 7.6575 2.1075 7.6575 2.1075 9 P 0 ;1
L 7.6575 2.1575 7.6575 2.1575 9 P 0 ;1
L 7.6575 2.2075 7.6575 2.2075 9 P 0 ;1
L 7.6575 2.2575 7.6575 2.2575 9 P 0 ;1
L 7.6575 2.3075 7.6575 2.3075 9 P 0 ;1
L 7.6575 2.3575 7.6575 2.3575 9 P 0 ;1
L 7.6575 2.4075 7.6575 2.4075 9 P 0 ;1
L 7.6575 2.4575 7.6575 2.4575 9 P 0 ;1
L 7.6575 2.5075 7.6575 2.5075 9 P 0 ;1
L 7.6575 2.5575 7.6575 2.5575 9 P 0 ;1
L 7.6575 2.6075 7.6575 2.6075 9 P 0 ;1
L 7.6575 2.6575 7.6575 2.6575 9 P 0 ;1
L 7.6575 2.7075 7.6575 2.7075 9 P 0 ;1
L 7.6575 2.7575 7.6575 2.7575 9 P 0 ;1
L 7.6575 2.8075 7.6575 2.8075 9 P 0 ;1
L 7.6575 2.8575 7.6575 2.8575 9 P 0 ;1
L 7.6575 2.9075 7.6575 2.9075 9 P 0 ;1
L 7.6575 2.9575 7.6575 2.9575 9 P 0 ;1
L 7.6575 3.0075 7.6575 3.0075 9 P 0 ;1
L 7.6575 3.0575 7.6575 3.0575 9 P 0 ;1
L 7.6575 3.1075 7.6575 3.1075 9 P 0 ;1
L 7.6575 3.1575 7.6575 3.1575 9 P 0 ;1
L 7.6575 3.2075 7.6575 3.2075 9 P 0 ;1
L 7.6575 3.2575 7.6575 3.2575 9 P 0 ;1
L 7.6575 3.3075 7.6575 3.3075 9 P 0 ;1
L 7.6575 3.3575 7.6575 3.3575 9 P 0 ;1
L 7.6575 3.4075 7.6575 3.4075 9 P 0 ;1
L 7.6575 3.4575 7.6575 3.4575 9 P 0 ;1
L 7.6575 3.5075 7.6575 3.5075 9 P 0 ;1
L 7.6575 3.5575 7.6575 3.5575 9 P 0 ;1
L 7.6575 3.6075 7.6575 3.6075 9 P 0 ;1
L 7.6575 3.6575 7.6575 3.6575 9 P 0 ;1
L 7.6575 3.7075 7.6575 3.7075 9 P 0 ;1
L 7.6575 3.7575 7.6575 3.7575 9 P 0 ;1
L 7.6575 3.8075 7.6575 3.8075 9 P 0 ;1
L 7.6575 3.8575 7.6575 3.8575 9 P 0 ;1
L 7.6575 3.9075 7.6575 3.9075 9 P 0 ;1
L 7.6575 3.9575 7.6575 3.9575 9 P 0 ;1
L 7.6575 4.0075 7.6575 4.0075 9 P 0 ;1
L 7.6575 4.0575 7.6575 4.0575 9 P 0 ;1
L 7.6575 4.1075 7.6575 4.1075 9 P 0 ;1
L 7.6575 4.1575 7.6575 4.1575 9 P 0 ;1
L 7.6575 4.2075 7.6575 4.2075 9 P 0 ;1
L 7.6575 4.2575 7.6575 4.2575 9 P 0 ;1
L 7.6575 4.3075 7.6575 4.3075 9 P 0 ;1
L 7.6575 4.3575 7.6575 4.3575 9 P 0 ;1
L 7.6575 4.4075 7.6575 4.4075 9 P 0 ;1
L 7.6575 4.4575 7.6575 4.4575 9 P 0 ;1
L 7.6575 4.5075 7.6575 4.5075 9 P 0 ;1
L 7.6575 4.5575 7.6575 4.5575 9 P 0 ;1
L 7.6575 5.2575 7.6575 5.2575 9 P 0 ;1
L 7.6575 5.3075 7.6575 5.3075 9 P 0 ;1
L 7.6575 5.3575 7.6575 5.3575 9 P 0 ;1
L 7.6575 5.4075 7.6575 5.4075 9 P 0 ;1
L 7.6575 5.4575 7.6575 5.4575 9 P 0 ;1
L 7.6575 5.5075 7.6575 5.5075 9 P 0 ;1
L 7.6575 5.5575 7.6575 5.5575 9 P 0 ;1
L 7.6575 5.6075 7.6575 5.6075 9 P 0 ;1
L 7.6575 5.6575 7.6575 5.6575 9 P 0 ;1
L 7.6575 5.7075 7.6575 5.7075 9 P 0 ;1
L 7.6575 5.7575 7.6575 5.7575 9 P 0 ;1
L 7.6575 5.8075 7.6575 5.8075 9 P 0 ;1
L 7.6575 5.8575 7.6575 5.8575 9 P 0 ;1
L 7.6575 5.9075 7.6575 5.9075 9 P 0 ;1
L 7.7075 0.1575 7.7075 0.1575 9 P 0 ;1
L 7.7075 0.2075 7.7075 0.2075 9 P 0 ;1
L 7.7075 0.2575 7.7075 0.2575 9 P 0 ;1
L 7.7075 0.3075 7.7075 0.3075 9 P 0 ;1
L 7.7075 0.3575 7.7075 0.3575 9 P 0 ;1
L 7.7075 0.4075 7.7075 0.4075 9 P 0 ;1
L 7.7075 0.4575 7.7075 0.4575 9 P 0 ;1
L 7.7075 0.5075 7.7075 0.5075 9 P 0 ;1
L 7.7075 0.5575 7.7075 0.5575 9 P 0 ;1
L 7.7075 0.6075 7.7075 0.6075 9 P 0 ;1
L 7.7075 0.6575 7.7075 0.6575 9 P 0 ;1
L 7.7075 0.7075 7.7075 0.7075 9 P 0 ;1
L 7.7075 0.7575 7.7075 0.7575 9 P 0 ;1
L 7.7075 0.8075 7.7075 0.8075 9 P 0 ;1
L 7.7075 0.8575 7.7075 0.8575 9 P 0 ;1
L 7.7075 1.0575 7.7075 1.0575 9 P 0 ;1
L 7.7075 1.1075 7.7075 1.1075 9 P 0 ;1
L 7.7075 1.1575 7.7075 1.1575 9 P 0 ;1
L 7.7075 1.2075 7.7075 1.2075 9 P 0 ;1
L 7.7075 1.2575 7.7075 1.2575 9 P 0 ;1
L 7.7075 1.3075 7.7075 1.3075 9 P 0 ;1
L 7.7075 1.3575 7.7075 1.3575 9 P 0 ;1
L 7.7075 1.4075 7.7075 1.4075 9 P 0 ;1
L 7.7075 1.4575 7.7075 1.4575 9 P 0 ;1
L 7.7075 1.5075 7.7075 1.5075 9 P 0 ;1
L 7.7075 1.5575 7.7075 1.5575 9 P 0 ;1
L 7.7075 1.6075 7.7075 1.6075 9 P 0 ;1
L 7.7075 1.9075 7.7075 1.9075 9 P 0 ;1
L 7.7075 1.9575 7.7075 1.9575 9 P 0 ;1
L 7.7075 2.0075 7.7075 2.0075 9 P 0 ;1
L 7.7075 2.0575 7.7075 2.0575 9 P 0 ;1
L 7.7075 2.1075 7.7075 2.1075 9 P 0 ;1
L 7.7075 2.1575 7.7075 2.1575 9 P 0 ;1
L 7.7075 2.2075 7.7075 2.2075 9 P 0 ;1
L 7.7075 2.2575 7.7075 2.2575 9 P 0 ;1
L 7.7075 2.3075 7.7075 2.3075 9 P 0 ;1
L 7.7075 2.3575 7.7075 2.3575 9 P 0 ;1
L 7.7075 2.4075 7.7075 2.4075 9 P 0 ;1
L 7.7075 2.5575 7.7075 2.5575 9 P 0 ;1
L 7.7075 2.6075 7.7075 2.6075 9 P 0 ;1
L 7.7075 2.6575 7.7075 2.6575 9 P 0 ;1
L 7.7075 2.7075 7.7075 2.7075 9 P 0 ;1
L 7.7075 2.7575 7.7075 2.7575 9 P 0 ;1
L 7.7075 2.8075 7.7075 2.8075 9 P 0 ;1
L 7.7075 2.8575 7.7075 2.8575 9 P 0 ;1
L 7.7075 2.9075 7.7075 2.9075 9 P 0 ;1
L 7.7075 2.9575 7.7075 2.9575 9 P 0 ;1
L 7.7075 3.0075 7.7075 3.0075 9 P 0 ;1
L 7.7075 3.0575 7.7075 3.0575 9 P 0 ;1
L 7.7075 3.1075 7.7075 3.1075 9 P 0 ;1
L 7.7075 3.1575 7.7075 3.1575 9 P 0 ;1
L 7.7075 3.2075 7.7075 3.2075 9 P 0 ;1
L 7.7075 3.2575 7.7075 3.2575 9 P 0 ;1
L 7.7075 3.3075 7.7075 3.3075 9 P 0 ;1
L 7.7075 3.3575 7.7075 3.3575 9 P 0 ;1
L 7.7075 3.4075 7.7075 3.4075 9 P 0 ;1
L 7.7075 3.4575 7.7075 3.4575 9 P 0 ;1
L 7.7075 3.5075 7.7075 3.5075 9 P 0 ;1
L 7.7075 3.5575 7.7075 3.5575 9 P 0 ;1
L 7.7075 3.6075 7.7075 3.6075 9 P 0 ;1
L 7.7075 3.6575 7.7075 3.6575 9 P 0 ;1
L 7.7075 3.7075 7.7075 3.7075 9 P 0 ;1
L 7.7075 3.7575 7.7075 3.7575 9 P 0 ;1
L 7.7075 3.8075 7.7075 3.8075 9 P 0 ;1
L 7.7075 3.8575 7.7075 3.8575 9 P 0 ;1
L 7.7075 3.9075 7.7075 3.9075 9 P 0 ;1
L 7.7075 3.9575 7.7075 3.9575 9 P 0 ;1
L 7.7075 4.0075 7.7075 4.0075 9 P 0 ;1
L 7.7075 4.0575 7.7075 4.0575 9 P 0 ;1
L 7.7075 4.1075 7.7075 4.1075 9 P 0 ;1
L 7.7075 4.1575 7.7075 4.1575 9 P 0 ;1
L 7.7075 4.2075 7.7075 4.2075 9 P 0 ;1
L 7.7075 4.2575 7.7075 4.2575 9 P 0 ;1
L 7.7075 4.3075 7.7075 4.3075 9 P 0 ;1
L 7.7075 4.3575 7.7075 4.3575 9 P 0 ;1
L 7.7075 4.4075 7.7075 4.4075 9 P 0 ;1
L 7.7075 4.5075 7.7075 4.5075 9 P 0 ;1
L 7.7075 4.5575 7.7075 4.5575 9 P 0 ;1
L 7.7075 4.6075 7.7075 4.6075 9 P 0 ;1
L 7.7075 5.2075 7.7075 5.2075 9 P 0 ;1
L 7.7075 5.2575 7.7075 5.2575 9 P 0 ;1
L 7.7075 5.3075 7.7075 5.3075 9 P 0 ;1
L 7.7075 5.3575 7.7075 5.3575 9 P 0 ;1
L 7.7075 5.4075 7.7075 5.4075 9 P 0 ;1
L 7.7075 5.4575 7.7075 5.4575 9 P 0 ;1
L 7.7075 5.5075 7.7075 5.5075 9 P 0 ;1
L 7.7075 5.5575 7.7075 5.5575 9 P 0 ;1
L 7.7075 5.6075 7.7075 5.6075 9 P 0 ;1
L 7.7075 5.6575 7.7075 5.6575 9 P 0 ;1
L 7.7075 5.7075 7.7075 5.7075 9 P 0 ;1
L 7.7075 5.7575 7.7075 5.7575 9 P 0 ;1
L 7.7075 5.8075 7.7075 5.8075 9 P 0 ;1
L 7.7075 5.8575 7.7075 5.8575 9 P 0 ;1
L 7.7075 5.9075 7.7075 5.9075 9 P 0 ;1
L 7.7575 0.1575 7.7575 0.1575 9 P 0 ;1
L 7.7575 0.2075 7.7575 0.2075 9 P 0 ;1
L 7.7575 0.2575 7.7575 0.2575 9 P 0 ;1
L 7.7575 0.3075 7.7575 0.3075 9 P 0 ;1
L 7.7575 0.3575 7.7575 0.3575 9 P 0 ;1
L 7.7575 0.4075 7.7575 0.4075 9 P 0 ;1
L 7.7575 0.4575 7.7575 0.4575 9 P 0 ;1
L 7.7575 0.5075 7.7575 0.5075 9 P 0 ;1
L 7.7575 0.5575 7.7575 0.5575 9 P 0 ;1
L 7.7575 0.6075 7.7575 0.6075 9 P 0 ;1
L 7.7575 0.6575 7.7575 0.6575 9 P 0 ;1
L 7.7575 0.7075 7.7575 0.7075 9 P 0 ;1
L 7.7575 0.7575 7.7575 0.7575 9 P 0 ;1
L 7.7575 0.8075 7.7575 0.8075 9 P 0 ;1
L 7.7575 0.8575 7.7575 0.8575 9 P 0 ;1
L 7.7575 1.0575 7.7575 1.0575 9 P 0 ;1
L 7.7575 1.1075 7.7575 1.1075 9 P 0 ;1
L 7.7575 1.1575 7.7575 1.1575 9 P 0 ;1
L 7.7575 1.2075 7.7575 1.2075 9 P 0 ;1
L 7.7575 1.2575 7.7575 1.2575 9 P 0 ;1
L 7.7575 1.3075 7.7575 1.3075 9 P 0 ;1
L 7.7575 1.3575 7.7575 1.3575 9 P 0 ;1
L 7.7575 1.4075 7.7575 1.4075 9 P 0 ;1
L 7.7575 1.4575 7.7575 1.4575 9 P 0 ;1
L 7.7575 1.5075 7.7575 1.5075 9 P 0 ;1
L 7.7575 1.5575 7.7575 1.5575 9 P 0 ;1
L 7.7575 1.6075 7.7575 1.6075 9 P 0 ;1
L 7.7575 1.9075 7.7575 1.9075 9 P 0 ;1
L 7.7575 1.9575 7.7575 1.9575 9 P 0 ;1
L 7.7575 2.0075 7.7575 2.0075 9 P 0 ;1
L 7.7575 2.0575 7.7575 2.0575 9 P 0 ;1
L 7.7575 2.1075 7.7575 2.1075 9 P 0 ;1
L 7.7575 2.1575 7.7575 2.1575 9 P 0 ;1
L 7.7575 2.2075 7.7575 2.2075 9 P 0 ;1
L 7.7575 2.2575 7.7575 2.2575 9 P 0 ;1
L 7.7575 2.3075 7.7575 2.3075 9 P 0 ;1
L 7.7575 2.3575 7.7575 2.3575 9 P 0 ;1
L 7.7575 2.5575 7.7575 2.5575 9 P 0 ;1
L 7.7575 2.6075 7.7575 2.6075 9 P 0 ;1
L 7.7575 2.6575 7.7575 2.6575 9 P 0 ;1
L 7.7575 2.7075 7.7575 2.7075 9 P 0 ;1
L 7.7575 2.7575 7.7575 2.7575 9 P 0 ;1
L 7.7575 2.8075 7.7575 2.8075 9 P 0 ;1
L 7.7575 2.8575 7.7575 2.8575 9 P 0 ;1
L 7.7575 2.9075 7.7575 2.9075 9 P 0 ;1
L 7.7575 2.9575 7.7575 2.9575 9 P 0 ;1
L 7.7575 3.0075 7.7575 3.0075 9 P 0 ;1
L 7.7575 3.0575 7.7575 3.0575 9 P 0 ;1
L 7.7575 3.1075 7.7575 3.1075 9 P 0 ;1
L 7.7575 3.1575 7.7575 3.1575 9 P 0 ;1
L 7.7575 3.2075 7.7575 3.2075 9 P 0 ;1
L 7.7575 3.2575 7.7575 3.2575 9 P 0 ;1
L 7.7575 3.3075 7.7575 3.3075 9 P 0 ;1
L 7.7575 3.3575 7.7575 3.3575 9 P 0 ;1
L 7.7575 3.4075 7.7575 3.4075 9 P 0 ;1
L 7.7575 3.4575 7.7575 3.4575 9 P 0 ;1
L 7.7575 3.5075 7.7575 3.5075 9 P 0 ;1
L 7.7575 3.5575 7.7575 3.5575 9 P 0 ;1
L 7.7575 3.6075 7.7575 3.6075 9 P 0 ;1
L 7.7575 3.6575 7.7575 3.6575 9 P 0 ;1
L 7.7575 3.7075 7.7575 3.7075 9 P 0 ;1
L 7.7575 3.7575 7.7575 3.7575 9 P 0 ;1
L 7.7575 3.8075 7.7575 3.8075 9 P 0 ;1
L 7.7575 3.8575 7.7575 3.8575 9 P 0 ;1
L 7.7575 3.9075 7.7575 3.9075 9 P 0 ;1
L 7.7575 3.9575 7.7575 3.9575 9 P 0 ;1
L 7.7575 4.0075 7.7575 4.0075 9 P 0 ;1
L 7.7575 4.0575 7.7575 4.0575 9 P 0 ;1
L 7.7575 4.1075 7.7575 4.1075 9 P 0 ;1
L 7.7575 4.1575 7.7575 4.1575 9 P 0 ;1
L 7.7575 4.2075 7.7575 4.2075 9 P 0 ;1
L 7.7575 4.2575 7.7575 4.2575 9 P 0 ;1
L 7.7575 4.3075 7.7575 4.3075 9 P 0 ;1
L 7.7575 4.3575 7.7575 4.3575 9 P 0 ;1
L 7.7575 4.5575 7.7575 4.5575 9 P 0 ;1
L 7.7575 4.6075 7.7575 4.6075 9 P 0 ;1
L 7.7575 4.6575 7.7575 4.6575 9 P 0 ;1
L 7.7575 5.1575 7.7575 5.1575 9 P 0 ;1
L 7.7575 5.2075 7.7575 5.2075 9 P 0 ;1
L 7.7575 5.2575 7.7575 5.2575 9 P 0 ;1
L 7.7575 5.3075 7.7575 5.3075 9 P 0 ;1
L 7.7575 5.3575 7.7575 5.3575 9 P 0 ;1
L 7.7575 5.4075 7.7575 5.4075 9 P 0 ;1
L 7.7575 5.4575 7.7575 5.4575 9 P 0 ;1
L 7.7575 5.5075 7.7575 5.5075 9 P 0 ;1
L 7.7575 5.5575 7.7575 5.5575 9 P 0 ;1
L 7.7575 5.6075 7.7575 5.6075 9 P 0 ;1
L 7.7575 5.6575 7.7575 5.6575 9 P 0 ;1
L 7.7575 5.7075 7.7575 5.7075 9 P 0 ;1
L 7.7575 5.7575 7.7575 5.7575 9 P 0 ;1
L 7.7575 5.8075 7.7575 5.8075 9 P 0 ;1
L 7.7575 5.8575 7.7575 5.8575 9 P 0 ;1
L 7.7575 5.9075 7.7575 5.9075 9 P 0 ;1
L 7.8075 0.1575 7.8075 0.1575 9 P 0 ;1
L 7.8075 0.2075 7.8075 0.2075 9 P 0 ;1
L 7.8075 0.2575 7.8075 0.2575 9 P 0 ;1
L 7.8075 0.3075 7.8075 0.3075 9 P 0 ;1
L 7.8075 0.3575 7.8075 0.3575 9 P 0 ;1
L 7.8075 0.4075 7.8075 0.4075 9 P 0 ;1
L 7.8075 0.4575 7.8075 0.4575 9 P 0 ;1
L 7.8075 0.5075 7.8075 0.5075 9 P 0 ;1
L 7.8075 0.5575 7.8075 0.5575 9 P 0 ;1
L 7.8075 0.6075 7.8075 0.6075 9 P 0 ;1
L 7.8075 0.6575 7.8075 0.6575 9 P 0 ;1
L 7.8075 0.7075 7.8075 0.7075 9 P 0 ;1
L 7.8075 0.7575 7.8075 0.7575 9 P 0 ;1
L 7.8075 0.8075 7.8075 0.8075 9 P 0 ;1
L 7.8075 0.8575 7.8075 0.8575 9 P 0 ;1
L 7.8075 1.0575 7.8075 1.0575 9 P 0 ;1
L 7.8075 1.1075 7.8075 1.1075 9 P 0 ;1
L 7.8075 1.1575 7.8075 1.1575 9 P 0 ;1
L 7.8075 1.2075 7.8075 1.2075 9 P 0 ;1
L 7.8075 1.2575 7.8075 1.2575 9 P 0 ;1
L 7.8075 1.3075 7.8075 1.3075 9 P 0 ;1
L 7.8075 1.3575 7.8075 1.3575 9 P 0 ;1
L 7.8075 1.4075 7.8075 1.4075 9 P 0 ;1
L 7.8075 1.4575 7.8075 1.4575 9 P 0 ;1
L 7.8075 1.5075 7.8075 1.5075 9 P 0 ;1
L 7.8075 1.5575 7.8075 1.5575 9 P 0 ;1
L 7.8075 1.6075 7.8075 1.6075 9 P 0 ;1
L 7.8075 1.9075 7.8075 1.9075 9 P 0 ;1
L 7.8075 1.9575 7.8075 1.9575 9 P 0 ;1
L 7.8075 2.0075 7.8075 2.0075 9 P 0 ;1
L 7.8075 2.0575 7.8075 2.0575 9 P 0 ;1
L 7.8075 2.1075 7.8075 2.1075 9 P 0 ;1
L 7.8075 2.1575 7.8075 2.1575 9 P 0 ;1
L 7.8075 2.2075 7.8075 2.2075 9 P 0 ;1
L 7.8075 2.2575 7.8075 2.2575 9 P 0 ;1
L 7.8075 2.3075 7.8075 2.3075 9 P 0 ;1
L 7.8075 2.3575 7.8075 2.3575 9 P 0 ;1
L 7.8075 2.5575 7.8075 2.5575 9 P 0 ;1
L 7.8075 2.6075 7.8075 2.6075 9 P 0 ;1
L 7.8075 2.6575 7.8075 2.6575 9 P 0 ;1
L 7.8075 2.7075 7.8075 2.7075 9 P 0 ;1
L 7.8075 2.7575 7.8075 2.7575 9 P 0 ;1
L 7.8075 2.8075 7.8075 2.8075 9 P 0 ;1
L 7.8075 2.8575 7.8075 2.8575 9 P 0 ;1
L 7.8075 2.9075 7.8075 2.9075 9 P 0 ;1
L 7.8075 2.9575 7.8075 2.9575 9 P 0 ;1
L 7.8075 3.0075 7.8075 3.0075 9 P 0 ;1
L 7.8075 3.0575 7.8075 3.0575 9 P 0 ;1
L 7.8075 3.1075 7.8075 3.1075 9 P 0 ;1
L 7.8075 3.1575 7.8075 3.1575 9 P 0 ;1
L 7.8075 3.2075 7.8075 3.2075 9 P 0 ;1
L 7.8075 3.2575 7.8075 3.2575 9 P 0 ;1
L 7.8075 3.3075 7.8075 3.3075 9 P 0 ;1
L 7.8075 3.3575 7.8075 3.3575 9 P 0 ;1
L 7.8075 3.4075 7.8075 3.4075 9 P 0 ;1
L 7.8075 3.4575 7.8075 3.4575 9 P 0 ;1
L 7.8075 3.5075 7.8075 3.5075 9 P 0 ;1
L 7.8075 3.5575 7.8075 3.5575 9 P 0 ;1
L 7.8075 3.6075 7.8075 3.6075 9 P 0 ;1
L 7.8075 4.1575 7.8075 4.1575 9 P 0 ;1
L 7.8075 4.2075 7.8075 4.2075 9 P 0 ;1
L 7.8075 4.2575 7.8075 4.2575 9 P 0 ;1
L 7.8075 4.3075 7.8075 4.3075 9 P 0 ;1
L 7.8075 4.3575 7.8075 4.3575 9 P 0 ;1
L 7.8075 5.2575 7.8075 5.2575 9 P 0 ;1
L 7.8075 5.3075 7.8075 5.3075 9 P 0 ;1
L 7.8075 5.3575 7.8075 5.3575 9 P 0 ;1
L 7.8075 5.4075 7.8075 5.4075 9 P 0 ;1
L 7.8075 5.4575 7.8075 5.4575 9 P 0 ;1
L 7.8075 5.5075 7.8075 5.5075 9 P 0 ;1
L 7.8075 5.5575 7.8075 5.5575 9 P 0 ;1
L 7.8075 5.6075 7.8075 5.6075 9 P 0 ;1
L 7.8075 5.6575 7.8075 5.6575 9 P 0 ;1
L 7.8075 5.7075 7.8075 5.7075 9 P 0 ;1
L 7.8075 5.7575 7.8075 5.7575 9 P 0 ;1
L 7.8075 5.8075 7.8075 5.8075 9 P 0 ;1
L 7.8075 5.8575 7.8075 5.8575 9 P 0 ;1
L 7.8075 5.9075 7.8075 5.9075 9 P 0 ;1
L 7.8575 0.1575 7.8575 0.1575 9 P 0 ;1
L 7.8575 0.2075 7.8575 0.2075 9 P 0 ;1
L 7.8575 0.2575 7.8575 0.2575 9 P 0 ;1
L 7.8575 0.3075 7.8575 0.3075 9 P 0 ;1
L 7.8575 0.3575 7.8575 0.3575 9 P 0 ;1
L 7.8575 0.4075 7.8575 0.4075 9 P 0 ;1
L 7.8575 0.4575 7.8575 0.4575 9 P 0 ;1
L 7.8575 0.5075 7.8575 0.5075 9 P 0 ;1
L 7.8575 0.5575 7.8575 0.5575 9 P 0 ;1
L 7.8575 0.6075 7.8575 0.6075 9 P 0 ;1
L 7.8575 0.6575 7.8575 0.6575 9 P 0 ;1
L 7.8575 0.7075 7.8575 0.7075 9 P 0 ;1
L 7.8575 0.7575 7.8575 0.7575 9 P 0 ;1
L 7.8575 0.8075 7.8575 0.8075 9 P 0 ;1
L 7.8575 0.8575 7.8575 0.8575 9 P 0 ;1
L 7.8575 1.0575 7.8575 1.0575 9 P 0 ;1
L 7.8575 1.1075 7.8575 1.1075 9 P 0 ;1
L 7.8575 1.1575 7.8575 1.1575 9 P 0 ;1
L 7.8575 1.2075 7.8575 1.2075 9 P 0 ;1
L 7.8575 1.2575 7.8575 1.2575 9 P 0 ;1
L 7.8575 1.3075 7.8575 1.3075 9 P 0 ;1
L 7.8575 1.3575 7.8575 1.3575 9 P 0 ;1
L 7.8575 1.4075 7.8575 1.4075 9 P 0 ;1
L 7.8575 1.4575 7.8575 1.4575 9 P 0 ;1
L 7.8575 1.5075 7.8575 1.5075 9 P 0 ;1
L 7.8575 1.5575 7.8575 1.5575 9 P 0 ;1
L 7.8575 1.6075 7.8575 1.6075 9 P 0 ;1
L 7.8575 1.9075 7.8575 1.9075 9 P 0 ;1
L 7.8575 1.9575 7.8575 1.9575 9 P 0 ;1
L 7.8575 2.0075 7.8575 2.0075 9 P 0 ;1
L 7.8575 2.0575 7.8575 2.0575 9 P 0 ;1
L 7.8575 2.1075 7.8575 2.1075 9 P 0 ;1
L 7.8575 2.1575 7.8575 2.1575 9 P 0 ;1
L 7.8575 2.2075 7.8575 2.2075 9 P 0 ;1
L 7.8575 2.2575 7.8575 2.2575 9 P 0 ;1
L 7.8575 2.3075 7.8575 2.3075 9 P 0 ;1
L 7.8575 2.3575 7.8575 2.3575 9 P 0 ;1
L 7.8575 2.4075 7.8575 2.4075 9 P 0 ;1
L 7.8575 2.4575 7.8575 2.4575 9 P 0 ;1
L 7.8575 2.5075 7.8575 2.5075 9 P 0 ;1
L 7.8575 2.5575 7.8575 2.5575 9 P 0 ;1
L 7.8575 2.6075 7.8575 2.6075 9 P 0 ;1
L 7.8575 2.6575 7.8575 2.6575 9 P 0 ;1
L 7.8575 2.7075 7.8575 2.7075 9 P 0 ;1
L 7.8575 2.7575 7.8575 2.7575 9 P 0 ;1
L 7.8575 2.8075 7.8575 2.8075 9 P 0 ;1
L 7.8575 2.8575 7.8575 2.8575 9 P 0 ;1
L 7.8575 2.9075 7.8575 2.9075 9 P 0 ;1
L 7.8575 2.9575 7.8575 2.9575 9 P 0 ;1
L 7.8575 3.0075 7.8575 3.0075 9 P 0 ;1
L 7.8575 3.0575 7.8575 3.0575 9 P 0 ;1
L 7.8575 3.1075 7.8575 3.1075 9 P 0 ;1
L 7.8575 3.1575 7.8575 3.1575 9 P 0 ;1
L 7.8575 3.2075 7.8575 3.2075 9 P 0 ;1
L 7.8575 3.2575 7.8575 3.2575 9 P 0 ;1
L 7.8575 3.3075 7.8575 3.3075 9 P 0 ;1
L 7.8575 3.3575 7.8575 3.3575 9 P 0 ;1
L 7.8575 3.4075 7.8575 3.4075 9 P 0 ;1
L 7.8575 3.4575 7.8575 3.4575 9 P 0 ;1
L 7.8575 3.5075 7.8575 3.5075 9 P 0 ;1
L 7.8575 3.5575 7.8575 3.5575 9 P 0 ;1
L 7.8575 4.3575 7.8575 4.3575 9 P 0 ;1
L 7.8575 5.2575 7.8575 5.2575 9 P 0 ;1
L 7.8575 5.3075 7.8575 5.3075 9 P 0 ;1
L 7.8575 5.4575 7.8575 5.4575 9 P 0 ;1
L 7.8575 5.5075 7.8575 5.5075 9 P 0 ;1
L 7.8575 5.5575 7.8575 5.5575 9 P 0 ;1
L 7.8575 5.6075 7.8575 5.6075 9 P 0 ;1
L 7.8575 5.6575 7.8575 5.6575 9 P 0 ;1
L 7.8575 5.7075 7.8575 5.7075 9 P 0 ;1
L 7.8575 5.7575 7.8575 5.7575 9 P 0 ;1
L 7.8575 5.8075 7.8575 5.8075 9 P 0 ;1
L 7.8575 5.8575 7.8575 5.8575 9 P 0 ;1
L 7.8575 5.9075 7.8575 5.9075 9 P 0 ;1
L 7.9075 0.1575 7.9075 0.1575 9 P 0 ;1
L 7.9075 0.2075 7.9075 0.2075 9 P 0 ;1
L 7.9075 0.2575 7.9075 0.2575 9 P 0 ;1
L 7.9075 0.3075 7.9075 0.3075 9 P 0 ;1
L 7.9075 0.3575 7.9075 0.3575 9 P 0 ;1
L 7.9075 0.4075 7.9075 0.4075 9 P 0 ;1
L 7.9075 0.4575 7.9075 0.4575 9 P 0 ;1
L 7.9075 0.5075 7.9075 0.5075 9 P 0 ;1
L 7.9075 0.5575 7.9075 0.5575 9 P 0 ;1
L 7.9075 0.6075 7.9075 0.6075 9 P 0 ;1
L 7.9075 0.6575 7.9075 0.6575 9 P 0 ;1
L 7.9075 0.7075 7.9075 0.7075 9 P 0 ;1
L 7.9075 0.7575 7.9075 0.7575 9 P 0 ;1
L 7.9075 0.8075 7.9075 0.8075 9 P 0 ;1
L 7.9075 0.8575 7.9075 0.8575 9 P 0 ;1
L 7.9075 1.0575 7.9075 1.0575 9 P 0 ;1
L 7.9075 1.1075 7.9075 1.1075 9 P 0 ;1
L 7.9075 1.1575 7.9075 1.1575 9 P 0 ;1
L 7.9075 1.2075 7.9075 1.2075 9 P 0 ;1
L 7.9075 1.2575 7.9075 1.2575 9 P 0 ;1
L 7.9075 1.3075 7.9075 1.3075 9 P 0 ;1
L 7.9075 1.3575 7.9075 1.3575 9 P 0 ;1
L 7.9075 1.4075 7.9075 1.4075 9 P 0 ;1
L 7.9075 1.4575 7.9075 1.4575 9 P 0 ;1
L 7.9075 1.5075 7.9075 1.5075 9 P 0 ;1
L 7.9075 1.5575 7.9075 1.5575 9 P 0 ;1
L 7.9075 1.6075 7.9075 1.6075 9 P 0 ;1
L 7.9075 1.9075 7.9075 1.9075 9 P 0 ;1
L 7.9075 1.9575 7.9075 1.9575 9 P 0 ;1
L 7.9075 2.0075 7.9075 2.0075 9 P 0 ;1
L 7.9075 2.0575 7.9075 2.0575 9 P 0 ;1
L 7.9075 2.1075 7.9075 2.1075 9 P 0 ;1
L 7.9075 2.1575 7.9075 2.1575 9 P 0 ;1
L 7.9075 2.2075 7.9075 2.2075 9 P 0 ;1
L 7.9075 2.2575 7.9075 2.2575 9 P 0 ;1
L 7.9075 2.3075 7.9075 2.3075 9 P 0 ;1
L 7.9075 2.3575 7.9075 2.3575 9 P 0 ;1
L 7.9075 2.4075 7.9075 2.4075 9 P 0 ;1
L 7.9075 2.4575 7.9075 2.4575 9 P 0 ;1
L 7.9075 2.5075 7.9075 2.5075 9 P 0 ;1
L 7.9075 2.5575 7.9075 2.5575 9 P 0 ;1
L 7.9075 2.6075 7.9075 2.6075 9 P 0 ;1
L 7.9075 2.6575 7.9075 2.6575 9 P 0 ;1
L 7.9075 2.7075 7.9075 2.7075 9 P 0 ;1
L 7.9075 2.7575 7.9075 2.7575 9 P 0 ;1
L 7.9075 2.8075 7.9075 2.8075 9 P 0 ;1
L 7.9075 2.8575 7.9075 2.8575 9 P 0 ;1
L 7.9075 2.9075 7.9075 2.9075 9 P 0 ;1
L 7.9075 2.9575 7.9075 2.9575 9 P 0 ;1
L 7.9075 3.0075 7.9075 3.0075 9 P 0 ;1
L 7.9075 3.0575 7.9075 3.0575 9 P 0 ;1
L 7.9075 3.1075 7.9075 3.1075 9 P 0 ;1
L 7.9075 3.1575 7.9075 3.1575 9 P 0 ;1
L 7.9075 3.2075 7.9075 3.2075 9 P 0 ;1
L 7.9075 3.2575 7.9075 3.2575 9 P 0 ;1
L 7.9075 3.3075 7.9075 3.3075 9 P 0 ;1
L 7.9075 3.3575 7.9075 3.3575 9 P 0 ;1
L 7.9075 3.4075 7.9075 3.4075 9 P 0 ;1
L 7.9075 3.4575 7.9075 3.4575 9 P 0 ;1
L 7.9075 3.5075 7.9075 3.5075 9 P 0 ;1
L 7.9075 4.5075 7.9075 4.5075 9 P 0 ;1
L 7.9075 5.2575 7.9075 5.2575 9 P 0 ;1
L 7.9075 5.4575 7.9075 5.4575 9 P 0 ;1
L 7.9075 5.5075 7.9075 5.5075 9 P 0 ;1
L 7.9075 5.5575 7.9075 5.5575 9 P 0 ;1
L 7.9075 5.6075 7.9075 5.6075 9 P 0 ;1
L 7.9075 5.6575 7.9075 5.6575 9 P 0 ;1
L 7.9075 5.7075 7.9075 5.7075 9 P 0 ;1
L 7.9075 5.7575 7.9075 5.7575 9 P 0 ;1
L 7.9075 5.8075 7.9075 5.8075 9 P 0 ;1
L 7.9075 5.8575 7.9075 5.8575 9 P 0 ;1
L 7.9075 5.9075 7.9075 5.9075 9 P 0 ;1
L 7.9575 0.1575 7.9575 0.1575 9 P 0 ;1
L 7.9575 0.2075 7.9575 0.2075 9 P 0 ;1
L 7.9575 0.2575 7.9575 0.2575 9 P 0 ;1
L 7.9575 0.3075 7.9575 0.3075 9 P 0 ;1
L 7.9575 0.3575 7.9575 0.3575 9 P 0 ;1
L 7.9575 0.4075 7.9575 0.4075 9 P 0 ;1
L 7.9575 0.4575 7.9575 0.4575 9 P 0 ;1
L 7.9575 0.5075 7.9575 0.5075 9 P 0 ;1
L 7.9575 0.5575 7.9575 0.5575 9 P 0 ;1
L 7.9575 0.6075 7.9575 0.6075 9 P 0 ;1
L 7.9575 0.6575 7.9575 0.6575 9 P 0 ;1
L 7.9575 0.7075 7.9575 0.7075 9 P 0 ;1
L 7.9575 0.7575 7.9575 0.7575 9 P 0 ;1
L 7.9575 0.8075 7.9575 0.8075 9 P 0 ;1
L 7.9575 0.8575 7.9575 0.8575 9 P 0 ;1
L 7.9575 1.0575 7.9575 1.0575 9 P 0 ;1
L 7.9575 1.1075 7.9575 1.1075 9 P 0 ;1
L 7.9575 1.1575 7.9575 1.1575 9 P 0 ;1
L 7.9575 1.2075 7.9575 1.2075 9 P 0 ;1
L 7.9575 1.2575 7.9575 1.2575 9 P 0 ;1
L 7.9575 1.3075 7.9575 1.3075 9 P 0 ;1
L 7.9575 1.3575 7.9575 1.3575 9 P 0 ;1
L 7.9575 1.4075 7.9575 1.4075 9 P 0 ;1
L 7.9575 1.4575 7.9575 1.4575 9 P 0 ;1
L 7.9575 1.5075 7.9575 1.5075 9 P 0 ;1
L 7.9575 1.5575 7.9575 1.5575 9 P 0 ;1
L 7.9575 1.6075 7.9575 1.6075 9 P 0 ;1
L 7.9575 1.9075 7.9575 1.9075 9 P 0 ;1
L 7.9575 1.9575 7.9575 1.9575 9 P 0 ;1
L 7.9575 2.0075 7.9575 2.0075 9 P 0 ;1
L 7.9575 2.0575 7.9575 2.0575 9 P 0 ;1
L 7.9575 2.1075 7.9575 2.1075 9 P 0 ;1
L 7.9575 2.1575 7.9575 2.1575 9 P 0 ;1
L 7.9575 2.2075 7.9575 2.2075 9 P 0 ;1
L 7.9575 2.2575 7.9575 2.2575 9 P 0 ;1
L 7.9575 2.3075 7.9575 2.3075 9 P 0 ;1
L 7.9575 2.3575 7.9575 2.3575 9 P 0 ;1
L 7.9575 2.4075 7.9575 2.4075 9 P 0 ;1
L 7.9575 2.4575 7.9575 2.4575 9 P 0 ;1
L 7.9575 2.5075 7.9575 2.5075 9 P 0 ;1
L 7.9575 2.5575 7.9575 2.5575 9 P 0 ;1
L 7.9575 2.6075 7.9575 2.6075 9 P 0 ;1
L 7.9575 2.9575 7.9575 2.9575 9 P 0 ;1
L 7.9575 3.0075 7.9575 3.0075 9 P 0 ;1
L 7.9575 3.0575 7.9575 3.0575 9 P 0 ;1
L 7.9575 3.1075 7.9575 3.1075 9 P 0 ;1
L 7.9575 3.1575 7.9575 3.1575 9 P 0 ;1
L 7.9575 3.2075 7.9575 3.2075 9 P 0 ;1
L 7.9575 3.2575 7.9575 3.2575 9 P 0 ;1
L 7.9575 3.3075 7.9575 3.3075 9 P 0 ;1
L 7.9575 4.5075 7.9575 4.5075 9 P 0 ;1
L 7.9575 5.4575 7.9575 5.4575 9 P 0 ;1
L 7.9575 5.5075 7.9575 5.5075 9 P 0 ;1
L 7.9575 5.5575 7.9575 5.5575 9 P 0 ;1
L 7.9575 5.6075 7.9575 5.6075 9 P 0 ;1
L 7.9575 5.6575 7.9575 5.6575 9 P 0 ;1
L 7.9575 5.7075 7.9575 5.7075 9 P 0 ;1
L 7.9575 5.7575 7.9575 5.7575 9 P 0 ;1
L 7.9575 5.8075 7.9575 5.8075 9 P 0 ;1
L 7.9575 5.8575 7.9575 5.8575 9 P 0 ;1
L 7.9575 5.9075 7.9575 5.9075 9 P 0 ;1
L 8.0075 0.1575 8.0075 0.1575 9 P 0 ;1
L 8.0075 0.2075 8.0075 0.2075 9 P 0 ;1
L 8.0075 0.2575 8.0075 0.2575 9 P 0 ;1
L 8.0075 0.3075 8.0075 0.3075 9 P 0 ;1
L 8.0075 0.3575 8.0075 0.3575 9 P 0 ;1
L 8.0075 0.4075 8.0075 0.4075 9 P 0 ;1
L 8.0075 0.4575 8.0075 0.4575 9 P 0 ;1
L 8.0075 0.5075 8.0075 0.5075 9 P 0 ;1
L 8.0075 0.5575 8.0075 0.5575 9 P 0 ;1
L 8.0075 0.6075 8.0075 0.6075 9 P 0 ;1
L 8.0075 0.6575 8.0075 0.6575 9 P 0 ;1
L 8.0075 0.7075 8.0075 0.7075 9 P 0 ;1
L 8.0075 0.7575 8.0075 0.7575 9 P 0 ;1
L 8.0075 0.8075 8.0075 0.8075 9 P 0 ;1
L 8.0075 0.8575 8.0075 0.8575 9 P 0 ;1
L 8.0075 1.0575 8.0075 1.0575 9 P 0 ;1
L 8.0075 1.1075 8.0075 1.1075 9 P 0 ;1
L 8.0075 1.1575 8.0075 1.1575 9 P 0 ;1
L 8.0075 1.2075 8.0075 1.2075 9 P 0 ;1
L 8.0075 1.2575 8.0075 1.2575 9 P 0 ;1
L 8.0075 1.3075 8.0075 1.3075 9 P 0 ;1
L 8.0075 1.3575 8.0075 1.3575 9 P 0 ;1
L 8.0075 1.4075 8.0075 1.4075 9 P 0 ;1
L 8.0075 1.4575 8.0075 1.4575 9 P 0 ;1
L 8.0075 1.5075 8.0075 1.5075 9 P 0 ;1
L 8.0075 1.5575 8.0075 1.5575 9 P 0 ;1
L 8.0075 1.6075 8.0075 1.6075 9 P 0 ;1
L 8.0075 5.2075 8.0075 5.2075 9 P 0 ;1
L 8.0075 5.4075 8.0075 5.4075 9 P 0 ;1
L 8.0075 5.4575 8.0075 5.4575 9 P 0 ;1
L 8.0075 5.5075 8.0075 5.5075 9 P 0 ;1
L 8.0075 5.5575 8.0075 5.5575 9 P 0 ;1
L 8.0075 5.6075 8.0075 5.6075 9 P 0 ;1
L 8.0075 5.6575 8.0075 5.6575 9 P 0 ;1
L 8.0075 5.7075 8.0075 5.7075 9 P 0 ;1
L 8.0075 5.7575 8.0075 5.7575 9 P 0 ;1
L 8.0075 5.8075 8.0075 5.8075 9 P 0 ;1
L 8.0075 5.8575 8.0075 5.8575 9 P 0 ;1
L 8.0075 5.9075 8.0075 5.9075 9 P 0 ;1
L 8.0575 0.1575 8.0575 0.1575 9 P 0 ;1
L 8.0575 0.2075 8.0575 0.2075 9 P 0 ;1
L 8.0575 0.2575 8.0575 0.2575 9 P 0 ;1
L 8.0575 0.3075 8.0575 0.3075 9 P 0 ;1
L 8.0575 0.3575 8.0575 0.3575 9 P 0 ;1
L 8.0575 0.4075 8.0575 0.4075 9 P 0 ;1
L 8.0575 0.4575 8.0575 0.4575 9 P 0 ;1
L 8.0575 0.5075 8.0575 0.5075 9 P 0 ;1
L 8.0575 0.5575 8.0575 0.5575 9 P 0 ;1
L 8.0575 0.6075 8.0575 0.6075 9 P 0 ;1
L 8.0575 0.6575 8.0575 0.6575 9 P 0 ;1
L 8.0575 0.7075 8.0575 0.7075 9 P 0 ;1
L 8.0575 0.7575 8.0575 0.7575 9 P 0 ;1
L 8.0575 0.8075 8.0575 0.8075 9 P 0 ;1
L 8.0575 0.8575 8.0575 0.8575 9 P 0 ;1
L 8.0575 1.0575 8.0575 1.0575 9 P 0 ;1
L 8.0575 1.1075 8.0575 1.1075 9 P 0 ;1
L 8.0575 1.1575 8.0575 1.1575 9 P 0 ;1
L 8.0575 1.2075 8.0575 1.2075 9 P 0 ;1
L 8.0575 1.2575 8.0575 1.2575 9 P 0 ;1
L 8.0575 1.3075 8.0575 1.3075 9 P 0 ;1
L 8.0575 1.3575 8.0575 1.3575 9 P 0 ;1
L 8.0575 1.4075 8.0575 1.4075 9 P 0 ;1
L 8.0575 1.6075 8.0575 1.6075 9 P 0 ;1
L 8.0575 5.4075 8.0575 5.4075 9 P 0 ;1
L 8.0575 5.4575 8.0575 5.4575 9 P 0 ;1
L 8.0575 5.5075 8.0575 5.5075 9 P 0 ;1
L 8.0575 5.5575 8.0575 5.5575 9 P 0 ;1
L 8.0575 5.6075 8.0575 5.6075 9 P 0 ;1
L 8.0575 5.6575 8.0575 5.6575 9 P 0 ;1
L 8.0575 5.7075 8.0575 5.7075 9 P 0 ;1
L 8.0575 5.7575 8.0575 5.7575 9 P 0 ;1
L 8.0575 5.8075 8.0575 5.8075 9 P 0 ;1
L 8.0575 5.8575 8.0575 5.8575 9 P 0 ;1
L 8.0575 5.9075 8.0575 5.9075 9 P 0 ;1
L 8.1075 0.1575 8.1075 0.1575 9 P 0 ;1
L 8.1075 0.2075 8.1075 0.2075 9 P 0 ;1
L 8.1075 0.2575 8.1075 0.2575 9 P 0 ;1
L 8.1075 0.3075 8.1075 0.3075 9 P 0 ;1
L 8.1075 0.3575 8.1075 0.3575 9 P 0 ;1
L 8.1075 0.4075 8.1075 0.4075 9 P 0 ;1
L 8.1075 0.4575 8.1075 0.4575 9 P 0 ;1
L 8.1075 0.5075 8.1075 0.5075 9 P 0 ;1
L 8.1075 0.5575 8.1075 0.5575 9 P 0 ;1
L 8.1075 0.6075 8.1075 0.6075 9 P 0 ;1
L 8.1075 0.6575 8.1075 0.6575 9 P 0 ;1
L 8.1075 0.7075 8.1075 0.7075 9 P 0 ;1
L 8.1075 0.7575 8.1075 0.7575 9 P 0 ;1
L 8.1075 0.8075 8.1075 0.8075 9 P 0 ;1
L 8.1075 0.8575 8.1075 0.8575 9 P 0 ;1
L 8.1075 1.0575 8.1075 1.0575 9 P 0 ;1
L 8.1075 1.1075 8.1075 1.1075 9 P 0 ;1
L 8.1075 1.1575 8.1075 1.1575 9 P 0 ;1
L 8.1075 1.2075 8.1075 1.2075 9 P 0 ;1
L 8.1075 1.2575 8.1075 1.2575 9 P 0 ;1
L 8.1075 1.3075 8.1075 1.3075 9 P 0 ;1
L 8.1075 5.4575 8.1075 5.4575 9 P 0 ;1
L 8.1075 5.5075 8.1075 5.5075 9 P 0 ;1
L 8.1075 5.5575 8.1075 5.5575 9 P 0 ;1
L 8.1075 5.6075 8.1075 5.6075 9 P 0 ;1
L 8.1075 5.6575 8.1075 5.6575 9 P 0 ;1
L 8.1075 5.7075 8.1075 5.7075 9 P 0 ;1
L 8.1075 5.7575 8.1075 5.7575 9 P 0 ;1
L 8.1075 5.8075 8.1075 5.8075 9 P 0 ;1
L 8.1075 5.8575 8.1075 5.8575 9 P 0 ;1
L 8.1075 5.9075 8.1075 5.9075 9 P 0 ;1
L 8.1575 0.1575 8.1575 0.1575 9 P 0 ;1
L 8.1575 0.2075 8.1575 0.2075 9 P 0 ;1
L 8.1575 0.2575 8.1575 0.2575 9 P 0 ;1
L 8.1575 0.3075 8.1575 0.3075 9 P 0 ;1
L 8.1575 0.3575 8.1575 0.3575 9 P 0 ;1
L 8.1575 0.4075 8.1575 0.4075 9 P 0 ;1
L 8.1575 0.4575 8.1575 0.4575 9 P 0 ;1
L 8.1575 0.5075 8.1575 0.5075 9 P 0 ;1
L 8.1575 0.5575 8.1575 0.5575 9 P 0 ;1
L 8.1575 0.6075 8.1575 0.6075 9 P 0 ;1
L 8.1575 0.6575 8.1575 0.6575 9 P 0 ;1
L 8.1575 0.7075 8.1575 0.7075 9 P 0 ;1
L 8.1575 0.7575 8.1575 0.7575 9 P 0 ;1
L 8.1575 0.8075 8.1575 0.8075 9 P 0 ;1
L 8.1575 0.8575 8.1575 0.8575 9 P 0 ;1
L 8.1575 1.0575 8.1575 1.0575 9 P 0 ;1
L 8.1575 1.1075 8.1575 1.1075 9 P 0 ;1
L 8.1575 1.1575 8.1575 1.1575 9 P 0 ;1
L 8.1575 1.2075 8.1575 1.2075 9 P 0 ;1
L 8.1575 1.2575 8.1575 1.2575 9 P 0 ;1
L 8.1575 1.3075 8.1575 1.3075 9 P 0 ;1
L 8.1575 5.2575 8.1575 5.2575 9 P 0 ;1
L 8.1575 5.4575 8.1575 5.4575 9 P 0 ;1
L 8.1575 5.5075 8.1575 5.5075 9 P 0 ;1
L 8.1575 5.5575 8.1575 5.5575 9 P 0 ;1
L 8.1575 5.6075 8.1575 5.6075 9 P 0 ;1
L 8.1575 5.6575 8.1575 5.6575 9 P 0 ;1
L 8.1575 5.7075 8.1575 5.7075 9 P 0 ;1
L 8.1575 5.7575 8.1575 5.7575 9 P 0 ;1
L 8.1575 5.8075 8.1575 5.8075 9 P 0 ;1
L 8.1575 5.8575 8.1575 5.8575 9 P 0 ;1
L 8.1575 5.9075 8.1575 5.9075 9 P 0 ;1
L 8.2075 0.1575 8.2075 0.1575 9 P 0 ;1
L 8.2075 0.2075 8.2075 0.2075 9 P 0 ;1
L 8.2075 0.2575 8.2075 0.2575 9 P 0 ;1
L 8.2075 0.3075 8.2075 0.3075 9 P 0 ;1
L 8.2075 0.3575 8.2075 0.3575 9 P 0 ;1
L 8.2075 0.4075 8.2075 0.4075 9 P 0 ;1
L 8.2075 0.4575 8.2075 0.4575 9 P 0 ;1
L 8.2075 0.5075 8.2075 0.5075 9 P 0 ;1
L 8.2075 0.5575 8.2075 0.5575 9 P 0 ;1
L 8.2075 0.6075 8.2075 0.6075 9 P 0 ;1
L 8.2075 0.6575 8.2075 0.6575 9 P 0 ;1
L 8.2075 0.7075 8.2075 0.7075 9 P 0 ;1
L 8.2075 0.7575 8.2075 0.7575 9 P 0 ;1
L 8.2075 0.8075 8.2075 0.8075 9 P 0 ;1
L 8.2075 0.8575 8.2075 0.8575 9 P 0 ;1
L 8.2075 1.0575 8.2075 1.0575 9 P 0 ;1
L 8.2075 1.1075 8.2075 1.1075 9 P 0 ;1
L 8.2075 1.1575 8.2075 1.1575 9 P 0 ;1
L 8.2075 1.2075 8.2075 1.2075 9 P 0 ;1
L 8.2075 1.2575 8.2075 1.2575 9 P 0 ;1
L 8.2075 1.3075 8.2075 1.3075 9 P 0 ;1
L 8.2075 5.2075 8.2075 5.2075 9 P 0 ;1
L 8.2075 5.2575 8.2075 5.2575 9 P 0 ;1
L 8.2075 5.3075 8.2075 5.3075 9 P 0 ;1
L 8.2075 5.4575 8.2075 5.4575 9 P 0 ;1
L 8.2075 5.5075 8.2075 5.5075 9 P 0 ;1
L 8.2075 5.5575 8.2075 5.5575 9 P 0 ;1
L 8.2075 5.6075 8.2075 5.6075 9 P 0 ;1
L 8.2075 5.6575 8.2075 5.6575 9 P 0 ;1
L 8.2075 5.7075 8.2075 5.7075 9 P 0 ;1
L 8.2075 5.7575 8.2075 5.7575 9 P 0 ;1
L 8.2075 5.8075 8.2075 5.8075 9 P 0 ;1
L 8.2075 5.8575 8.2075 5.8575 9 P 0 ;1
L 8.2075 5.9075 8.2075 5.9075 9 P 0 ;1
L 8.2575 0.1575 8.2575 0.1575 9 P 0 ;1
L 8.2575 0.2075 8.2575 0.2075 9 P 0 ;1
L 8.2575 0.2575 8.2575 0.2575 9 P 0 ;1
L 8.2575 0.3075 8.2575 0.3075 9 P 0 ;1
L 8.2575 0.3575 8.2575 0.3575 9 P 0 ;1
L 8.2575 0.4075 8.2575 0.4075 9 P 0 ;1
L 8.2575 0.4575 8.2575 0.4575 9 P 0 ;1
L 8.2575 0.5075 8.2575 0.5075 9 P 0 ;1
L 8.2575 0.5575 8.2575 0.5575 9 P 0 ;1
L 8.2575 0.6075 8.2575 0.6075 9 P 0 ;1
L 8.2575 0.6575 8.2575 0.6575 9 P 0 ;1
L 8.2575 0.7075 8.2575 0.7075 9 P 0 ;1
L 8.2575 0.7575 8.2575 0.7575 9 P 0 ;1
L 8.2575 0.8075 8.2575 0.8075 9 P 0 ;1
L 8.2575 0.8575 8.2575 0.8575 9 P 0 ;1
L 8.2575 1.0575 8.2575 1.0575 9 P 0 ;1
L 8.2575 1.1075 8.2575 1.1075 9 P 0 ;1
L 8.2575 1.1575 8.2575 1.1575 9 P 0 ;1
L 8.2575 1.2075 8.2575 1.2075 9 P 0 ;1
L 8.2575 1.2575 8.2575 1.2575 9 P 0 ;1
L 8.2575 5.1575 8.2575 5.1575 9 P 0 ;1
L 8.2575 5.2075 8.2575 5.2075 9 P 0 ;1
L 8.2575 5.2575 8.2575 5.2575 9 P 0 ;1
L 8.2575 5.3075 8.2575 5.3075 9 P 0 ;1
L 8.2575 5.3575 8.2575 5.3575 9 P 0 ;1
L 8.2575 5.4075 8.2575 5.4075 9 P 0 ;1
L 8.2575 5.4575 8.2575 5.4575 9 P 0 ;1
L 8.2575 5.5075 8.2575 5.5075 9 P 0 ;1
L 8.2575 5.5575 8.2575 5.5575 9 P 0 ;1
L 8.2575 5.6075 8.2575 5.6075 9 P 0 ;1
L 8.2575 5.6575 8.2575 5.6575 9 P 0 ;1
L 8.2575 5.7075 8.2575 5.7075 9 P 0 ;1
L 8.2575 5.7575 8.2575 5.7575 9 P 0 ;1
L 8.2575 5.8075 8.2575 5.8075 9 P 0 ;1
L 8.2575 5.8575 8.2575 5.8575 9 P 0 ;1
L 8.2575 5.9075 8.2575 5.9075 9 P 0 ;1
L 8.3075 0.1575 8.3075 0.1575 9 P 0 ;1
L 8.3075 0.2075 8.3075 0.2075 9 P 0 ;1
L 8.3075 0.2575 8.3075 0.2575 9 P 0 ;1
L 8.3075 0.3075 8.3075 0.3075 9 P 0 ;1
L 8.3075 0.3575 8.3075 0.3575 9 P 0 ;1
L 8.3075 0.4075 8.3075 0.4075 9 P 0 ;1
L 8.3075 0.4575 8.3075 0.4575 9 P 0 ;1
L 8.3075 0.5075 8.3075 0.5075 9 P 0 ;1
L 8.3075 0.5575 8.3075 0.5575 9 P 0 ;1
L 8.3075 0.6075 8.3075 0.6075 9 P 0 ;1
L 8.3075 0.6575 8.3075 0.6575 9 P 0 ;1
L 8.3075 0.7075 8.3075 0.7075 9 P 0 ;1
L 8.3075 0.7575 8.3075 0.7575 9 P 0 ;1
L 8.3075 0.8075 8.3075 0.8075 9 P 0 ;1
L 8.3075 0.8575 8.3075 0.8575 9 P 0 ;1
L 8.3075 1.0575 8.3075 1.0575 9 P 0 ;1
L 8.3075 1.1075 8.3075 1.1075 9 P 0 ;1
L 8.3075 1.1575 8.3075 1.1575 9 P 0 ;1
L 8.3075 1.2075 8.3075 1.2075 9 P 0 ;1
L 8.3075 1.2575 8.3075 1.2575 9 P 0 ;1
L 8.3075 1.3075 8.3075 1.3075 9 P 0 ;1
L 8.3075 5.2575 8.3075 5.2575 9 P 0 ;1
L 8.3075 5.3075 8.3075 5.3075 9 P 0 ;1
L 8.3075 5.3575 8.3075 5.3575 9 P 0 ;1
L 8.3075 5.4075 8.3075 5.4075 9 P 0 ;1
L 8.3075 5.4575 8.3075 5.4575 9 P 0 ;1
L 8.3075 5.5075 8.3075 5.5075 9 P 0 ;1
L 8.3075 5.5575 8.3075 5.5575 9 P 0 ;1
L 8.3075 5.6075 8.3075 5.6075 9 P 0 ;1
L 8.3075 5.6575 8.3075 5.6575 9 P 0 ;1
L 8.3075 5.7075 8.3075 5.7075 9 P 0 ;1
L 8.3075 5.7575 8.3075 5.7575 9 P 0 ;1
L 8.3075 5.8075 8.3075 5.8075 9 P 0 ;1
L 8.3075 5.8575 8.3075 5.8575 9 P 0 ;1
L 8.3075 5.9075 8.3075 5.9075 9 P 0 ;1
L 8.3575 0.1575 8.3575 0.1575 9 P 0 ;1
L 8.3575 0.2075 8.3575 0.2075 9 P 0 ;1
L 8.3575 0.2575 8.3575 0.2575 9 P 0 ;1
L 8.3575 0.3075 8.3575 0.3075 9 P 0 ;1
L 8.3575 0.3575 8.3575 0.3575 9 P 0 ;1
L 8.3575 0.4075 8.3575 0.4075 9 P 0 ;1
L 8.3575 0.4575 8.3575 0.4575 9 P 0 ;1
L 8.3575 0.5075 8.3575 0.5075 9 P 0 ;1
L 8.3575 0.5575 8.3575 0.5575 9 P 0 ;1
L 8.3575 0.6075 8.3575 0.6075 9 P 0 ;1
L 8.3575 0.6575 8.3575 0.6575 9 P 0 ;1
L 8.3575 0.7075 8.3575 0.7075 9 P 0 ;1
L 8.3575 0.7575 8.3575 0.7575 9 P 0 ;1
L 8.3575 0.8075 8.3575 0.8075 9 P 0 ;1
L 8.3575 0.8575 8.3575 0.8575 9 P 0 ;1
L 8.3575 1.0575 8.3575 1.0575 9 P 0 ;1
L 8.3575 1.1075 8.3575 1.1075 9 P 0 ;1
L 8.3575 1.1575 8.3575 1.1575 9 P 0 ;1
L 8.3575 1.2075 8.3575 1.2075 9 P 0 ;1
L 8.3575 1.2575 8.3575 1.2575 9 P 0 ;1
L 8.3575 1.3075 8.3575 1.3075 9 P 0 ;1
L 8.3575 5.2575 8.3575 5.2575 9 P 0 ;1
L 8.3575 5.3075 8.3575 5.3075 9 P 0 ;1
L 8.3575 5.3575 8.3575 5.3575 9 P 0 ;1
L 8.3575 5.4075 8.3575 5.4075 9 P 0 ;1
L 8.3575 5.4575 8.3575 5.4575 9 P 0 ;1
L 8.3575 5.5075 8.3575 5.5075 9 P 0 ;1
L 8.3575 5.5575 8.3575 5.5575 9 P 0 ;1
L 8.3575 5.6075 8.3575 5.6075 9 P 0 ;1
L 8.3575 5.6575 8.3575 5.6575 9 P 0 ;1
L 8.3575 5.7075 8.3575 5.7075 9 P 0 ;1
L 8.3575 5.7575 8.3575 5.7575 9 P 0 ;1
L 8.3575 5.8075 8.3575 5.8075 9 P 0 ;1
L 8.3575 5.8575 8.3575 5.8575 9 P 0 ;1
L 8.3575 5.9075 8.3575 5.9075 9 P 0 ;1
L 8.4075 0.1575 8.4075 0.1575 9 P 0 ;1
L 8.4075 0.2075 8.4075 0.2075 9 P 0 ;1
L 8.4075 0.2575 8.4075 0.2575 9 P 0 ;1
L 8.4075 0.3075 8.4075 0.3075 9 P 0 ;1
L 8.4075 0.3575 8.4075 0.3575 9 P 0 ;1
L 8.4075 0.4075 8.4075 0.4075 9 P 0 ;1
L 8.4075 0.4575 8.4075 0.4575 9 P 0 ;1
L 8.4075 0.5075 8.4075 0.5075 9 P 0 ;1
L 8.4075 0.5575 8.4075 0.5575 9 P 0 ;1
L 8.4075 0.6075 8.4075 0.6075 9 P 0 ;1
L 8.4075 0.6575 8.4075 0.6575 9 P 0 ;1
L 8.4075 0.7075 8.4075 0.7075 9 P 0 ;1
L 8.4075 0.7575 8.4075 0.7575 9 P 0 ;1
L 8.4075 0.8075 8.4075 0.8075 9 P 0 ;1
L 8.4075 0.8575 8.4075 0.8575 9 P 0 ;1
L 8.4075 1.0575 8.4075 1.0575 9 P 0 ;1
L 8.4075 1.1075 8.4075 1.1075 9 P 0 ;1
L 8.4075 1.1575 8.4075 1.1575 9 P 0 ;1
L 8.4075 1.2075 8.4075 1.2075 9 P 0 ;1
L 8.4075 1.2575 8.4075 1.2575 9 P 0 ;1
L 8.4075 1.3075 8.4075 1.3075 9 P 0 ;1
L 8.4075 1.3575 8.4075 1.3575 9 P 0 ;1
L 8.4075 5.2575 8.4075 5.2575 9 P 0 ;1
L 8.4075 5.3075 8.4075 5.3075 9 P 0 ;1
L 8.4075 5.3575 8.4075 5.3575 9 P 0 ;1
L 8.4075 5.4075 8.4075 5.4075 9 P 0 ;1
L 8.4075 5.4575 8.4075 5.4575 9 P 0 ;1
L 8.4075 5.5075 8.4075 5.5075 9 P 0 ;1
L 8.4075 5.5575 8.4075 5.5575 9 P 0 ;1
L 8.4075 5.6075 8.4075 5.6075 9 P 0 ;1
L 8.4075 5.6575 8.4075 5.6575 9 P 0 ;1
L 8.4075 5.7075 8.4075 5.7075 9 P 0 ;1
L 8.4075 5.7575 8.4075 5.7575 9 P 0 ;1
L 8.4075 5.8075 8.4075 5.8075 9 P 0 ;1
L 8.4075 5.8575 8.4075 5.8575 9 P 0 ;1
L 8.4075 5.9075 8.4075 5.9075 9 P 0 ;1
L 8.4575 0.1575 8.4575 0.1575 9 P 0 ;1
L 8.4575 0.2075 8.4575 0.2075 9 P 0 ;1
L 8.4575 0.2575 8.4575 0.2575 9 P 0 ;1
L 8.4575 0.3075 8.4575 0.3075 9 P 0 ;1
L 8.4575 0.3575 8.4575 0.3575 9 P 0 ;1
L 8.4575 0.4075 8.4575 0.4075 9 P 0 ;1
L 8.4575 0.4575 8.4575 0.4575 9 P 0 ;1
L 8.4575 0.5075 8.4575 0.5075 9 P 0 ;1
L 8.4575 0.5575 8.4575 0.5575 9 P 0 ;1
L 8.4575 0.6075 8.4575 0.6075 9 P 0 ;1
L 8.4575 0.6575 8.4575 0.6575 9 P 0 ;1
L 8.4575 0.7075 8.4575 0.7075 9 P 0 ;1
L 8.4575 0.7575 8.4575 0.7575 9 P 0 ;1
L 8.4575 0.8075 8.4575 0.8075 9 P 0 ;1
L 8.4575 0.8575 8.4575 0.8575 9 P 0 ;1
L 8.4575 1.0575 8.4575 1.0575 9 P 0 ;1
L 8.4575 1.1075 8.4575 1.1075 9 P 0 ;1
L 8.4575 1.1575 8.4575 1.1575 9 P 0 ;1
L 8.4575 1.2075 8.4575 1.2075 9 P 0 ;1
L 8.4575 1.2575 8.4575 1.2575 9 P 0 ;1
L 8.4575 1.3075 8.4575 1.3075 9 P 0 ;1
L 8.4575 1.3575 8.4575 1.3575 9 P 0 ;1
L 8.4575 1.4075 8.4575 1.4075 9 P 0 ;1
L 8.4575 1.4575 8.4575 1.4575 9 P 0 ;1
L 8.4575 1.5075 8.4575 1.5075 9 P 0 ;1
L 8.4575 1.5575 8.4575 1.5575 9 P 0 ;1
L 8.4575 1.6075 8.4575 1.6075 9 P 0 ;1
L 8.4575 5.2575 8.4575 5.2575 9 P 0 ;1
L 8.4575 5.3075 8.4575 5.3075 9 P 0 ;1
L 8.4575 5.3575 8.4575 5.3575 9 P 0 ;1
L 8.4575 5.4075 8.4575 5.4075 9 P 0 ;1
L 8.4575 5.4575 8.4575 5.4575 9 P 0 ;1
L 8.4575 5.5075 8.4575 5.5075 9 P 0 ;1
L 8.4575 5.5575 8.4575 5.5575 9 P 0 ;1
L 8.4575 5.6075 8.4575 5.6075 9 P 0 ;1
L 8.4575 5.6575 8.4575 5.6575 9 P 0 ;1
L 8.4575 5.7075 8.4575 5.7075 9 P 0 ;1
L 8.4575 5.7575 8.4575 5.7575 9 P 0 ;1
L 8.4575 5.8075 8.4575 5.8075 9 P 0 ;1
L 8.4575 5.8575 8.4575 5.8575 9 P 0 ;1
L 8.4575 5.9075 8.4575 5.9075 9 P 0 ;1
L 8.5075 0.1575 8.5075 0.1575 9 P 0 ;1
L 8.5075 0.2075 8.5075 0.2075 9 P 0 ;1
L 8.5075 0.2575 8.5075 0.2575 9 P 0 ;1
L 8.5075 0.3075 8.5075 0.3075 9 P 0 ;1
L 8.5075 0.3575 8.5075 0.3575 9 P 0 ;1
L 8.5075 0.4075 8.5075 0.4075 9 P 0 ;1
L 8.5075 0.4575 8.5075 0.4575 9 P 0 ;1
L 8.5075 0.5075 8.5075 0.5075 9 P 0 ;1
L 8.5075 0.5575 8.5075 0.5575 9 P 0 ;1
L 8.5075 0.6075 8.5075 0.6075 9 P 0 ;1
L 8.5075 0.6575 8.5075 0.6575 9 P 0 ;1
L 8.5075 0.7075 8.5075 0.7075 9 P 0 ;1
L 8.5075 0.7575 8.5075 0.7575 9 P 0 ;1
L 8.5075 0.8075 8.5075 0.8075 9 P 0 ;1
L 8.5075 0.8575 8.5075 0.8575 9 P 0 ;1
L 8.5075 1.0575 8.5075 1.0575 9 P 0 ;1
L 8.5075 1.1075 8.5075 1.1075 9 P 0 ;1
L 8.5075 1.1575 8.5075 1.1575 9 P 0 ;1
L 8.5075 1.2075 8.5075 1.2075 9 P 0 ;1
L 8.5075 1.2575 8.5075 1.2575 9 P 0 ;1
L 8.5075 1.3075 8.5075 1.3075 9 P 0 ;1
L 8.5075 1.3575 8.5075 1.3575 9 P 0 ;1
L 8.5075 1.4075 8.5075 1.4075 9 P 0 ;1
L 8.5075 1.4575 8.5075 1.4575 9 P 0 ;1
L 8.5075 1.5075 8.5075 1.5075 9 P 0 ;1
L 8.5075 1.5575 8.5075 1.5575 9 P 0 ;1
L 8.5075 1.6075 8.5075 1.6075 9 P 0 ;1
L 8.5075 5.1575 8.5075 5.1575 9 P 0 ;1
L 8.5075 5.2075 8.5075 5.2075 9 P 0 ;1
L 8.5075 5.2575 8.5075 5.2575 9 P 0 ;1
L 8.5075 5.3075 8.5075 5.3075 9 P 0 ;1
L 8.5075 5.3575 8.5075 5.3575 9 P 0 ;1
L 8.5075 5.4075 8.5075 5.4075 9 P 0 ;1
L 8.5075 5.4575 8.5075 5.4575 9 P 0 ;1
L 8.5075 5.5075 8.5075 5.5075 9 P 0 ;1
L 8.5075 5.5575 8.5075 5.5575 9 P 0 ;1
L 8.5075 5.6075 8.5075 5.6075 9 P 0 ;1
L 8.5075 5.6575 8.5075 5.6575 9 P 0 ;1
L 8.5075 5.7075 8.5075 5.7075 9 P 0 ;1
L 8.5075 5.7575 8.5075 5.7575 9 P 0 ;1
L 8.5075 5.8075 8.5075 5.8075 9 P 0 ;1
L 8.5075 5.8575 8.5075 5.8575 9 P 0 ;1
L 8.5075 5.9075 8.5075 5.9075 9 P 0 ;1
L 8.5575 0.1575 8.5575 0.1575 9 P 0 ;1
L 8.5575 0.2075 8.5575 0.2075 9 P 0 ;1
L 8.5575 0.2575 8.5575 0.2575 9 P 0 ;1
L 8.5575 0.3075 8.5575 0.3075 9 P 0 ;1
L 8.5575 0.3575 8.5575 0.3575 9 P 0 ;1
L 8.5575 0.4075 8.5575 0.4075 9 P 0 ;1
L 8.5575 0.4575 8.5575 0.4575 9 P 0 ;1
L 8.5575 0.5075 8.5575 0.5075 9 P 0 ;1
L 8.5575 0.5575 8.5575 0.5575 9 P 0 ;1
L 8.5575 0.6075 8.5575 0.6075 9 P 0 ;1
L 8.5575 0.6575 8.5575 0.6575 9 P 0 ;1
L 8.5575 0.7075 8.5575 0.7075 9 P 0 ;1
L 8.5575 0.7575 8.5575 0.7575 9 P 0 ;1
L 8.5575 0.8075 8.5575 0.8075 9 P 0 ;1
L 8.5575 0.8575 8.5575 0.8575 9 P 0 ;1
L 8.5575 1.0575 8.5575 1.0575 9 P 0 ;1
L 8.5575 1.1075 8.5575 1.1075 9 P 0 ;1
L 8.5575 1.1575 8.5575 1.1575 9 P 0 ;1
L 8.5575 1.2075 8.5575 1.2075 9 P 0 ;1
L 8.5575 1.2575 8.5575 1.2575 9 P 0 ;1
L 8.5575 1.3075 8.5575 1.3075 9 P 0 ;1
L 8.5575 1.3575 8.5575 1.3575 9 P 0 ;1
L 8.5575 1.4075 8.5575 1.4075 9 P 0 ;1
L 8.5575 1.4575 8.5575 1.4575 9 P 0 ;1
L 8.5575 1.5075 8.5575 1.5075 9 P 0 ;1
L 8.5575 1.5575 8.5575 1.5575 9 P 0 ;1
L 8.5575 1.6075 8.5575 1.6075 9 P 0 ;1
L 8.5575 5.2075 8.5575 5.2075 9 P 0 ;1
L 8.5575 5.2575 8.5575 5.2575 9 P 0 ;1
L 8.5575 5.3075 8.5575 5.3075 9 P 0 ;1
L 8.5575 5.3575 8.5575 5.3575 9 P 0 ;1
L 8.5575 5.4075 8.5575 5.4075 9 P 0 ;1
L 8.5575 5.4575 8.5575 5.4575 9 P 0 ;1
L 8.5575 5.5075 8.5575 5.5075 9 P 0 ;1
L 8.5575 5.5575 8.5575 5.5575 9 P 0 ;1
L 8.5575 5.6075 8.5575 5.6075 9 P 0 ;1
L 8.5575 5.6575 8.5575 5.6575 9 P 0 ;1
L 8.5575 5.7075 8.5575 5.7075 9 P 0 ;1
L 8.5575 5.7575 8.5575 5.7575 9 P 0 ;1
L 8.5575 5.8075 8.5575 5.8075 9 P 0 ;1
L 8.5575 5.8575 8.5575 5.8575 9 P 0 ;1
L 8.5575 5.9075 8.5575 5.9075 9 P 0 ;1
L 8.6075 0.1575 8.6075 0.1575 9 P 0 ;1
L 8.6075 0.2075 8.6075 0.2075 9 P 0 ;1
L 8.6075 0.2575 8.6075 0.2575 9 P 0 ;1
L 8.6075 0.3075 8.6075 0.3075 9 P 0 ;1
L 8.6075 0.3575 8.6075 0.3575 9 P 0 ;1
L 8.6075 0.4075 8.6075 0.4075 9 P 0 ;1
L 8.6075 0.4575 8.6075 0.4575 9 P 0 ;1
L 8.6075 0.5075 8.6075 0.5075 9 P 0 ;1
L 8.6075 0.5575 8.6075 0.5575 9 P 0 ;1
L 8.6075 0.6075 8.6075 0.6075 9 P 0 ;1
L 8.6075 0.6575 8.6075 0.6575 9 P 0 ;1
L 8.6075 0.7075 8.6075 0.7075 9 P 0 ;1
L 8.6075 0.7575 8.6075 0.7575 9 P 0 ;1
L 8.6075 0.8075 8.6075 0.8075 9 P 0 ;1
L 8.6075 0.8575 8.6075 0.8575 9 P 0 ;1
L 8.6075 1.0575 8.6075 1.0575 9 P 0 ;1
L 8.6075 1.1075 8.6075 1.1075 9 P 0 ;1
L 8.6075 1.1575 8.6075 1.1575 9 P 0 ;1
L 8.6075 1.2075 8.6075 1.2075 9 P 0 ;1
L 8.6075 1.2575 8.6075 1.2575 9 P 0 ;1
L 8.6075 1.3075 8.6075 1.3075 9 P 0 ;1
L 8.6075 1.3575 8.6075 1.3575 9 P 0 ;1
L 8.6075 1.4075 8.6075 1.4075 9 P 0 ;1
L 8.6075 1.4575 8.6075 1.4575 9 P 0 ;1
L 8.6075 1.5075 8.6075 1.5075 9 P 0 ;1
L 8.6075 1.5575 8.6075 1.5575 9 P 0 ;1
L 8.6075 1.6075 8.6075 1.6075 9 P 0 ;1
L 8.6075 1.9075 8.6075 1.9075 9 P 0 ;1
L 8.6075 1.9575 8.6075 1.9575 9 P 0 ;1
L 8.6075 2.0075 8.6075 2.0075 9 P 0 ;1
L 8.6075 2.0575 8.6075 2.0575 9 P 0 ;1
L 8.6075 2.1075 8.6075 2.1075 9 P 0 ;1
L 8.6075 2.1575 8.6075 2.1575 9 P 0 ;1
L 8.6075 2.2075 8.6075 2.2075 9 P 0 ;1
L 8.6075 2.2575 8.6075 2.2575 9 P 0 ;1
L 8.6075 2.3075 8.6075 2.3075 9 P 0 ;1
L 8.6075 2.3575 8.6075 2.3575 9 P 0 ;1
L 8.6075 2.4075 8.6075 2.4075 9 P 0 ;1
L 8.6075 2.4575 8.6075 2.4575 9 P 0 ;1
L 8.6075 2.5075 8.6075 2.5075 9 P 0 ;1
L 8.6075 2.5575 8.6075 2.5575 9 P 0 ;1
L 8.6075 2.6075 8.6075 2.6075 9 P 0 ;1
L 8.6075 2.6575 8.6075 2.6575 9 P 0 ;1
L 8.6075 2.7075 8.6075 2.7075 9 P 0 ;1
L 8.6075 2.7575 8.6075 2.7575 9 P 0 ;1
L 8.6075 2.8075 8.6075 2.8075 9 P 0 ;1
L 8.6075 2.8575 8.6075 2.8575 9 P 0 ;1
L 8.6075 2.9075 8.6075 2.9075 9 P 0 ;1
L 8.6075 2.9575 8.6075 2.9575 9 P 0 ;1
L 8.6075 3.0075 8.6075 3.0075 9 P 0 ;1
L 8.6075 3.0575 8.6075 3.0575 9 P 0 ;1
L 8.6075 3.1075 8.6075 3.1075 9 P 0 ;1
L 8.6075 3.1575 8.6075 3.1575 9 P 0 ;1
L 8.6075 3.2075 8.6075 3.2075 9 P 0 ;1
L 8.6075 3.2575 8.6075 3.2575 9 P 0 ;1
L 8.6075 3.3075 8.6075 3.3075 9 P 0 ;1
L 8.6075 3.3575 8.6075 3.3575 9 P 0 ;1
L 8.6075 3.4075 8.6075 3.4075 9 P 0 ;1
L 8.6075 4.0575 8.6075 4.0575 9 P 0 ;1
L 8.6075 5.2575 8.6075 5.2575 9 P 0 ;1
L 8.6075 5.3075 8.6075 5.3075 9 P 0 ;1
L 8.6075 5.3575 8.6075 5.3575 9 P 0 ;1
L 8.6075 5.4075 8.6075 5.4075 9 P 0 ;1
L 8.6075 5.4575 8.6075 5.4575 9 P 0 ;1
L 8.6075 5.5075 8.6075 5.5075 9 P 0 ;1
L 8.6075 5.5575 8.6075 5.5575 9 P 0 ;1
L 8.6075 5.6075 8.6075 5.6075 9 P 0 ;1
L 8.6075 5.6575 8.6075 5.6575 9 P 0 ;1
L 8.6075 5.7075 8.6075 5.7075 9 P 0 ;1
L 8.6075 5.7575 8.6075 5.7575 9 P 0 ;1
L 8.6075 5.8075 8.6075 5.8075 9 P 0 ;1
L 8.6075 5.8575 8.6075 5.8575 9 P 0 ;1
L 8.6075 5.9075 8.6075 5.9075 9 P 0 ;1
L 8.6575 0.1575 8.6575 0.1575 9 P 0 ;1
L 8.6575 0.2075 8.6575 0.2075 9 P 0 ;1
L 8.6575 0.2575 8.6575 0.2575 9 P 0 ;1
L 8.6575 0.3075 8.6575 0.3075 9 P 0 ;1
L 8.6575 0.3575 8.6575 0.3575 9 P 0 ;1
L 8.6575 0.4075 8.6575 0.4075 9 P 0 ;1
L 8.6575 0.4575 8.6575 0.4575 9 P 0 ;1
L 8.6575 0.5075 8.6575 0.5075 9 P 0 ;1
L 8.6575 0.5575 8.6575 0.5575 9 P 0 ;1
L 8.6575 0.6075 8.6575 0.6075 9 P 0 ;1
L 8.6575 0.6575 8.6575 0.6575 9 P 0 ;1
L 8.6575 0.7075 8.6575 0.7075 9 P 0 ;1
L 8.6575 0.7575 8.6575 0.7575 9 P 0 ;1
L 8.6575 0.8075 8.6575 0.8075 9 P 0 ;1
L 8.6575 0.8575 8.6575 0.8575 9 P 0 ;1
L 8.6575 1.0575 8.6575 1.0575 9 P 0 ;1
L 8.6575 1.1075 8.6575 1.1075 9 P 0 ;1
L 8.6575 1.1575 8.6575 1.1575 9 P 0 ;1
L 8.6575 1.2075 8.6575 1.2075 9 P 0 ;1
L 8.6575 1.2575 8.6575 1.2575 9 P 0 ;1
L 8.6575 1.3075 8.6575 1.3075 9 P 0 ;1
L 8.6575 1.3575 8.6575 1.3575 9 P 0 ;1
L 8.6575 1.4075 8.6575 1.4075 9 P 0 ;1
L 8.6575 1.4575 8.6575 1.4575 9 P 0 ;1
L 8.6575 1.5075 8.6575 1.5075 9 P 0 ;1
L 8.6575 1.5575 8.6575 1.5575 9 P 0 ;1
L 8.6575 1.6075 8.6575 1.6075 9 P 0 ;1
L 8.6575 1.9075 8.6575 1.9075 9 P 0 ;1
L 8.6575 1.9575 8.6575 1.9575 9 P 0 ;1
L 8.6575 2.0075 8.6575 2.0075 9 P 0 ;1
L 8.6575 2.0575 8.6575 2.0575 9 P 0 ;1
L 8.6575 2.1075 8.6575 2.1075 9 P 0 ;1
L 8.6575 2.1575 8.6575 2.1575 9 P 0 ;1
L 8.6575 2.2075 8.6575 2.2075 9 P 0 ;1
L 8.6575 2.2575 8.6575 2.2575 9 P 0 ;1
L 8.6575 2.3075 8.6575 2.3075 9 P 0 ;1
L 8.6575 2.3575 8.6575 2.3575 9 P 0 ;1
L 8.6575 2.4075 8.6575 2.4075 9 P 0 ;1
L 8.6575 2.4575 8.6575 2.4575 9 P 0 ;1
L 8.6575 2.5075 8.6575 2.5075 9 P 0 ;1
L 8.6575 2.5575 8.6575 2.5575 9 P 0 ;1
L 8.6575 2.6075 8.6575 2.6075 9 P 0 ;1
L 8.6575 2.6575 8.6575 2.6575 9 P 0 ;1
L 8.6575 2.7075 8.6575 2.7075 9 P 0 ;1
L 8.6575 2.7575 8.6575 2.7575 9 P 0 ;1
L 8.6575 2.8075 8.6575 2.8075 9 P 0 ;1
L 8.6575 2.8575 8.6575 2.8575 9 P 0 ;1
L 8.6575 2.9075 8.6575 2.9075 9 P 0 ;1
L 8.6575 2.9575 8.6575 2.9575 9 P 0 ;1
L 8.6575 3.0075 8.6575 3.0075 9 P 0 ;1
L 8.6575 3.0575 8.6575 3.0575 9 P 0 ;1
L 8.6575 3.1075 8.6575 3.1075 9 P 0 ;1
L 8.6575 3.1575 8.6575 3.1575 9 P 0 ;1
L 8.6575 3.2075 8.6575 3.2075 9 P 0 ;1
L 8.6575 3.2575 8.6575 3.2575 9 P 0 ;1
L 8.6575 3.3075 8.6575 3.3075 9 P 0 ;1
L 8.6575 3.3575 8.6575 3.3575 9 P 0 ;1
L 8.6575 3.4075 8.6575 3.4075 9 P 0 ;1
L 8.6575 4.0075 8.6575 4.0075 9 P 0 ;1
L 8.6575 4.0575 8.6575 4.0575 9 P 0 ;1
L 8.6575 5.3075 8.6575 5.3075 9 P 0 ;1
L 8.6575 5.3575 8.6575 5.3575 9 P 0 ;1
L 8.6575 5.4075 8.6575 5.4075 9 P 0 ;1
L 8.6575 5.4575 8.6575 5.4575 9 P 0 ;1
L 8.6575 5.5075 8.6575 5.5075 9 P 0 ;1
L 8.6575 5.5575 8.6575 5.5575 9 P 0 ;1
L 8.6575 5.6075 8.6575 5.6075 9 P 0 ;1
L 8.6575 5.6575 8.6575 5.6575 9 P 0 ;1
L 8.6575 5.7075 8.6575 5.7075 9 P 0 ;1
L 8.6575 5.7575 8.6575 5.7575 9 P 0 ;1
L 8.6575 5.8075 8.6575 5.8075 9 P 0 ;1
L 8.6575 5.8575 8.6575 5.8575 9 P 0 ;1
L 8.6575 5.9075 8.6575 5.9075 9 P 0 ;1
L 8.7075 0.1575 8.7075 0.1575 9 P 0 ;1
L 8.7075 0.2075 8.7075 0.2075 9 P 0 ;1
L 8.7075 0.2575 8.7075 0.2575 9 P 0 ;1
L 8.7075 0.3075 8.7075 0.3075 9 P 0 ;1
L 8.7075 0.3575 8.7075 0.3575 9 P 0 ;1
L 8.7075 0.4075 8.7075 0.4075 9 P 0 ;1
L 8.7075 0.4575 8.7075 0.4575 9 P 0 ;1
L 8.7075 0.5075 8.7075 0.5075 9 P 0 ;1
L 8.7075 0.5575 8.7075 0.5575 9 P 0 ;1
L 8.7075 0.6075 8.7075 0.6075 9 P 0 ;1
L 8.7075 0.6575 8.7075 0.6575 9 P 0 ;1
L 8.7075 0.7075 8.7075 0.7075 9 P 0 ;1
L 8.7075 0.7575 8.7075 0.7575 9 P 0 ;1
L 8.7075 0.8075 8.7075 0.8075 9 P 0 ;1
L 8.7075 0.8575 8.7075 0.8575 9 P 0 ;1
L 8.7075 1.0575 8.7075 1.0575 9 P 0 ;1
L 8.7075 1.1075 8.7075 1.1075 9 P 0 ;1
L 8.7075 1.1575 8.7075 1.1575 9 P 0 ;1
L 8.7075 1.2075 8.7075 1.2075 9 P 0 ;1
L 8.7075 1.2575 8.7075 1.2575 9 P 0 ;1
L 8.7075 1.3075 8.7075 1.3075 9 P 0 ;1
L 8.7075 1.3575 8.7075 1.3575 9 P 0 ;1
L 8.7075 1.4075 8.7075 1.4075 9 P 0 ;1
L 8.7075 1.4575 8.7075 1.4575 9 P 0 ;1
L 8.7075 1.5075 8.7075 1.5075 9 P 0 ;1
L 8.7075 1.5575 8.7075 1.5575 9 P 0 ;1
L 8.7075 1.6075 8.7075 1.6075 9 P 0 ;1
L 8.7075 1.9075 8.7075 1.9075 9 P 0 ;1
L 8.7075 1.9575 8.7075 1.9575 9 P 0 ;1
L 8.7075 2.0075 8.7075 2.0075 9 P 0 ;1
L 8.7075 2.0575 8.7075 2.0575 9 P 0 ;1
L 8.7075 2.1075 8.7075 2.1075 9 P 0 ;1
L 8.7075 2.1575 8.7075 2.1575 9 P 0 ;1
L 8.7075 2.2075 8.7075 2.2075 9 P 0 ;1
L 8.7075 2.2575 8.7075 2.2575 9 P 0 ;1
L 8.7075 2.3075 8.7075 2.3075 9 P 0 ;1
L 8.7075 2.3575 8.7075 2.3575 9 P 0 ;1
L 8.7075 2.4075 8.7075 2.4075 9 P 0 ;1
L 8.7075 2.4575 8.7075 2.4575 9 P 0 ;1
L 8.7075 2.5075 8.7075 2.5075 9 P 0 ;1
L 8.7075 2.5575 8.7075 2.5575 9 P 0 ;1
L 8.7075 2.6075 8.7075 2.6075 9 P 0 ;1
L 8.7075 2.6575 8.7075 2.6575 9 P 0 ;1
L 8.7075 2.7075 8.7075 2.7075 9 P 0 ;1
L 8.7075 2.7575 8.7075 2.7575 9 P 0 ;1
L 8.7075 2.8075 8.7075 2.8075 9 P 0 ;1
L 8.7075 2.8575 8.7075 2.8575 9 P 0 ;1
L 8.7075 2.9075 8.7075 2.9075 9 P 0 ;1
L 8.7075 2.9575 8.7075 2.9575 9 P 0 ;1
L 8.7075 3.0075 8.7075 3.0075 9 P 0 ;1
L 8.7075 3.0575 8.7075 3.0575 9 P 0 ;1
L 8.7075 3.1075 8.7075 3.1075 9 P 0 ;1
L 8.7075 3.1575 8.7075 3.1575 9 P 0 ;1
L 8.7075 3.2075 8.7075 3.2075 9 P 0 ;1
L 8.7075 3.2575 8.7075 3.2575 9 P 0 ;1
L 8.7075 3.3075 8.7075 3.3075 9 P 0 ;1
L 8.7075 3.3575 8.7075 3.3575 9 P 0 ;1
L 8.7075 3.4075 8.7075 3.4075 9 P 0 ;1
L 8.7075 4.0075 8.7075 4.0075 9 P 0 ;1
L 8.7075 4.0575 8.7075 4.0575 9 P 0 ;1
L 8.7075 5.3075 8.7075 5.3075 9 P 0 ;1
L 8.7075 5.3575 8.7075 5.3575 9 P 0 ;1
L 8.7075 5.4075 8.7075 5.4075 9 P 0 ;1
L 8.7075 5.4575 8.7075 5.4575 9 P 0 ;1
L 8.7075 5.5075 8.7075 5.5075 9 P 0 ;1
L 8.7075 5.5575 8.7075 5.5575 9 P 0 ;1
L 8.7075 5.6075 8.7075 5.6075 9 P 0 ;1
L 8.7075 5.6575 8.7075 5.6575 9 P 0 ;1
L 8.7075 5.7075 8.7075 5.7075 9 P 0 ;1
L 8.7075 5.7575 8.7075 5.7575 9 P 0 ;1
L 8.7075 5.8075 8.7075 5.8075 9 P 0 ;1
L 8.7075 5.8575 8.7075 5.8575 9 P 0 ;1
L 8.7075 5.9075 8.7075 5.9075 9 P 0 ;1
L 8.7575 0.1575 8.7575 0.1575 9 P 0 ;1
L 8.7575 0.2075 8.7575 0.2075 9 P 0 ;1
L 8.7575 0.2575 8.7575 0.2575 9 P 0 ;1
L 8.7575 0.3075 8.7575 0.3075 9 P 0 ;1
L 8.7575 0.3575 8.7575 0.3575 9 P 0 ;1
L 8.7575 0.4075 8.7575 0.4075 9 P 0 ;1
L 8.7575 0.4575 8.7575 0.4575 9 P 0 ;1
L 8.7575 0.5075 8.7575 0.5075 9 P 0 ;1
L 8.7575 0.5575 8.7575 0.5575 9 P 0 ;1
L 8.7575 0.6075 8.7575 0.6075 9 P 0 ;1
L 8.7575 0.6575 8.7575 0.6575 9 P 0 ;1
L 8.7575 0.7075 8.7575 0.7075 9 P 0 ;1
L 8.7575 0.7575 8.7575 0.7575 9 P 0 ;1
L 8.7575 0.8075 8.7575 0.8075 9 P 0 ;1
L 8.7575 0.8575 8.7575 0.8575 9 P 0 ;1
L 8.7575 1.0575 8.7575 1.0575 9 P 0 ;1
L 8.7575 1.1075 8.7575 1.1075 9 P 0 ;1
L 8.7575 1.1575 8.7575 1.1575 9 P 0 ;1
L 8.7575 1.2075 8.7575 1.2075 9 P 0 ;1
L 8.7575 1.2575 8.7575 1.2575 9 P 0 ;1
L 8.7575 1.3075 8.7575 1.3075 9 P 0 ;1
L 8.7575 1.3575 8.7575 1.3575 9 P 0 ;1
L 8.7575 1.4075 8.7575 1.4075 9 P 0 ;1
L 8.7575 1.4575 8.7575 1.4575 9 P 0 ;1
L 8.7575 1.5075 8.7575 1.5075 9 P 0 ;1
L 8.7575 1.5575 8.7575 1.5575 9 P 0 ;1
L 8.7575 1.6075 8.7575 1.6075 9 P 0 ;1
L 8.7575 1.9075 8.7575 1.9075 9 P 0 ;1
L 8.7575 1.9575 8.7575 1.9575 9 P 0 ;1
L 8.7575 2.0075 8.7575 2.0075 9 P 0 ;1
L 8.7575 2.0575 8.7575 2.0575 9 P 0 ;1
L 8.7575 2.1075 8.7575 2.1075 9 P 0 ;1
L 8.7575 2.1575 8.7575 2.1575 9 P 0 ;1
L 8.7575 2.2075 8.7575 2.2075 9 P 0 ;1
L 8.7575 2.2575 8.7575 2.2575 9 P 0 ;1
L 8.7575 2.3075 8.7575 2.3075 9 P 0 ;1
L 8.7575 2.3575 8.7575 2.3575 9 P 0 ;1
L 8.7575 2.4075 8.7575 2.4075 9 P 0 ;1
L 8.7575 2.4575 8.7575 2.4575 9 P 0 ;1
L 8.7575 2.5075 8.7575 2.5075 9 P 0 ;1
L 8.7575 2.5575 8.7575 2.5575 9 P 0 ;1
L 8.7575 2.6075 8.7575 2.6075 9 P 0 ;1
L 8.7575 2.6575 8.7575 2.6575 9 P 0 ;1
L 8.7575 2.7075 8.7575 2.7075 9 P 0 ;1
L 8.7575 2.7575 8.7575 2.7575 9 P 0 ;1
L 8.7575 2.8075 8.7575 2.8075 9 P 0 ;1
L 8.7575 2.8575 8.7575 2.8575 9 P 0 ;1
L 8.7575 2.9075 8.7575 2.9075 9 P 0 ;1
L 8.7575 2.9575 8.7575 2.9575 9 P 0 ;1
L 8.7575 3.0075 8.7575 3.0075 9 P 0 ;1
L 8.7575 3.0575 8.7575 3.0575 9 P 0 ;1
L 8.7575 3.1075 8.7575 3.1075 9 P 0 ;1
L 8.7575 3.1575 8.7575 3.1575 9 P 0 ;1
L 8.7575 3.2075 8.7575 3.2075 9 P 0 ;1
L 8.7575 3.2575 8.7575 3.2575 9 P 0 ;1
L 8.7575 3.3075 8.7575 3.3075 9 P 0 ;1
L 8.7575 3.3575 8.7575 3.3575 9 P 0 ;1
L 8.7575 3.4075 8.7575 3.4075 9 P 0 ;1
L 8.7575 3.9575 8.7575 3.9575 9 P 0 ;1
L 8.7575 4.0075 8.7575 4.0075 9 P 0 ;1
L 8.7575 5.3075 8.7575 5.3075 9 P 0 ;1
L 8.7575 5.3575 8.7575 5.3575 9 P 0 ;1
L 8.7575 5.4075 8.7575 5.4075 9 P 0 ;1
L 8.7575 5.4575 8.7575 5.4575 9 P 0 ;1
L 8.7575 5.5075 8.7575 5.5075 9 P 0 ;1
L 8.7575 5.5575 8.7575 5.5575 9 P 0 ;1
L 8.7575 5.6075 8.7575 5.6075 9 P 0 ;1
L 8.7575 5.6575 8.7575 5.6575 9 P 0 ;1
L 8.7575 5.7075 8.7575 5.7075 9 P 0 ;1
L 8.7575 5.7575 8.7575 5.7575 9 P 0 ;1
L 8.7575 5.8075 8.7575 5.8075 9 P 0 ;1
L 8.7575 5.8575 8.7575 5.8575 9 P 0 ;1
L 8.7575 5.9075 8.7575 5.9075 9 P 0 ;1
L 8.8075 0.1575 8.8075 0.1575 9 P 0 ;1
L 8.8075 0.2075 8.8075 0.2075 9 P 0 ;1
L 8.8075 0.2575 8.8075 0.2575 9 P 0 ;1
L 8.8075 0.3075 8.8075 0.3075 9 P 0 ;1
L 8.8075 0.3575 8.8075 0.3575 9 P 0 ;1
L 8.8075 0.4075 8.8075 0.4075 9 P 0 ;1
L 8.8075 0.4575 8.8075 0.4575 9 P 0 ;1
L 8.8075 0.5075 8.8075 0.5075 9 P 0 ;1
L 8.8075 0.5575 8.8075 0.5575 9 P 0 ;1
L 8.8075 0.6075 8.8075 0.6075 9 P 0 ;1
L 8.8075 0.6575 8.8075 0.6575 9 P 0 ;1
L 8.8075 0.7075 8.8075 0.7075 9 P 0 ;1
L 8.8075 0.7575 8.8075 0.7575 9 P 0 ;1
L 8.8075 0.8075 8.8075 0.8075 9 P 0 ;1
L 8.8075 0.8575 8.8075 0.8575 9 P 0 ;1
L 8.8075 1.0575 8.8075 1.0575 9 P 0 ;1
L 8.8075 1.1075 8.8075 1.1075 9 P 0 ;1
L 8.8075 1.1575 8.8075 1.1575 9 P 0 ;1
L 8.8075 1.2075 8.8075 1.2075 9 P 0 ;1
L 8.8075 1.2575 8.8075 1.2575 9 P 0 ;1
L 8.8075 1.3075 8.8075 1.3075 9 P 0 ;1
L 8.8075 1.3575 8.8075 1.3575 9 P 0 ;1
L 8.8075 1.4075 8.8075 1.4075 9 P 0 ;1
L 8.8075 1.4575 8.8075 1.4575 9 P 0 ;1
L 8.8075 1.5075 8.8075 1.5075 9 P 0 ;1
L 8.8075 1.5575 8.8075 1.5575 9 P 0 ;1
L 8.8075 1.6075 8.8075 1.6075 9 P 0 ;1
L 8.8075 1.9075 8.8075 1.9075 9 P 0 ;1
L 8.8075 1.9575 8.8075 1.9575 9 P 0 ;1
L 8.8075 2.0075 8.8075 2.0075 9 P 0 ;1
L 8.8075 2.0575 8.8075 2.0575 9 P 0 ;1
L 8.8075 2.1075 8.8075 2.1075 9 P 0 ;1
L 8.8075 2.1575 8.8075 2.1575 9 P 0 ;1
L 8.8075 2.2075 8.8075 2.2075 9 P 0 ;1
L 8.8075 2.2575 8.8075 2.2575 9 P 0 ;1
L 8.8075 2.3075 8.8075 2.3075 9 P 0 ;1
L 8.8075 2.3575 8.8075 2.3575 9 P 0 ;1
L 8.8075 2.4075 8.8075 2.4075 9 P 0 ;1
L 8.8075 2.4575 8.8075 2.4575 9 P 0 ;1
L 8.8075 2.5075 8.8075 2.5075 9 P 0 ;1
L 8.8075 2.5575 8.8075 2.5575 9 P 0 ;1
L 8.8075 2.6075 8.8075 2.6075 9 P 0 ;1
L 8.8075 2.6575 8.8075 2.6575 9 P 0 ;1
L 8.8075 2.7075 8.8075 2.7075 9 P 0 ;1
L 8.8075 2.7575 8.8075 2.7575 9 P 0 ;1
L 8.8075 2.8075 8.8075 2.8075 9 P 0 ;1
L 8.8075 2.8575 8.8075 2.8575 9 P 0 ;1
L 8.8075 2.9075 8.8075 2.9075 9 P 0 ;1
L 8.8075 2.9575 8.8075 2.9575 9 P 0 ;1
L 8.8075 3.0075 8.8075 3.0075 9 P 0 ;1
L 8.8075 3.0575 8.8075 3.0575 9 P 0 ;1
L 8.8075 3.1075 8.8075 3.1075 9 P 0 ;1
L 8.8075 3.1575 8.8075 3.1575 9 P 0 ;1
L 8.8075 3.2075 8.8075 3.2075 9 P 0 ;1
L 8.8075 3.2575 8.8075 3.2575 9 P 0 ;1
L 8.8075 3.3075 8.8075 3.3075 9 P 0 ;1
L 8.8075 3.3575 8.8075 3.3575 9 P 0 ;1
L 8.8075 3.4075 8.8075 3.4075 9 P 0 ;1
L 8.8075 4.0075 8.8075 4.0075 9 P 0 ;1
L 8.8075 5.3075 8.8075 5.3075 9 P 0 ;1
L 8.8075 5.3575 8.8075 5.3575 9 P 0 ;1
L 8.8075 5.4075 8.8075 5.4075 9 P 0 ;1
L 8.8075 5.4575 8.8075 5.4575 9 P 0 ;1
L 8.8075 5.5075 8.8075 5.5075 9 P 0 ;1
L 8.8075 5.5575 8.8075 5.5575 9 P 0 ;1
L 8.8075 5.6075 8.8075 5.6075 9 P 0 ;1
L 8.8075 5.6575 8.8075 5.6575 9 P 0 ;1
L 8.8075 5.7075 8.8075 5.7075 9 P 0 ;1
L 8.8075 5.7575 8.8075 5.7575 9 P 0 ;1
L 8.8075 5.8075 8.8075 5.8075 9 P 0 ;1
L 8.8075 5.8575 8.8075 5.8575 9 P 0 ;1
L 8.8075 5.9075 8.8075 5.9075 9 P 0 ;1
L 8.8575 0.1575 8.8575 0.1575 9 P 0 ;1
L 8.8575 0.2075 8.8575 0.2075 9 P 0 ;1
L 8.8575 0.2575 8.8575 0.2575 9 P 0 ;1
L 8.8575 0.3075 8.8575 0.3075 9 P 0 ;1
L 8.8575 0.3575 8.8575 0.3575 9 P 0 ;1
L 8.8575 0.4075 8.8575 0.4075 9 P 0 ;1
L 8.8575 0.4575 8.8575 0.4575 9 P 0 ;1
L 8.8575 0.5075 8.8575 0.5075 9 P 0 ;1
L 8.8575 0.5575 8.8575 0.5575 9 P 0 ;1
L 8.8575 0.6075 8.8575 0.6075 9 P 0 ;1
L 8.8575 0.6575 8.8575 0.6575 9 P 0 ;1
L 8.8575 0.7075 8.8575 0.7075 9 P 0 ;1
L 8.8575 0.7575 8.8575 0.7575 9 P 0 ;1
L 8.8575 0.8075 8.8575 0.8075 9 P 0 ;1
L 8.8575 0.8575 8.8575 0.8575 9 P 0 ;1
L 8.8575 1.0575 8.8575 1.0575 9 P 0 ;1
L 8.8575 1.1075 8.8575 1.1075 9 P 0 ;1
L 8.8575 1.1575 8.8575 1.1575 9 P 0 ;1
L 8.8575 1.2075 8.8575 1.2075 9 P 0 ;1
L 8.8575 1.2575 8.8575 1.2575 9 P 0 ;1
L 8.8575 1.3075 8.8575 1.3075 9 P 0 ;1
L 8.8575 1.3575 8.8575 1.3575 9 P 0 ;1
L 8.8575 1.4075 8.8575 1.4075 9 P 0 ;1
L 8.8575 1.4575 8.8575 1.4575 9 P 0 ;1
L 8.8575 1.5075 8.8575 1.5075 9 P 0 ;1
L 8.8575 1.5575 8.8575 1.5575 9 P 0 ;1
L 8.8575 1.6075 8.8575 1.6075 9 P 0 ;1
L 8.8575 1.9075 8.8575 1.9075 9 P 0 ;1
L 8.8575 1.9575 8.8575 1.9575 9 P 0 ;1
L 8.8575 2.0075 8.8575 2.0075 9 P 0 ;1
L 8.8575 2.0575 8.8575 2.0575 9 P 0 ;1
L 8.8575 2.1075 8.8575 2.1075 9 P 0 ;1
L 8.8575 2.1575 8.8575 2.1575 9 P 0 ;1
L 8.8575 2.2075 8.8575 2.2075 9 P 0 ;1
L 8.8575 2.2575 8.8575 2.2575 9 P 0 ;1
L 8.8575 2.3075 8.8575 2.3075 9 P 0 ;1
L 8.8575 2.3575 8.8575 2.3575 9 P 0 ;1
L 8.8575 2.4075 8.8575 2.4075 9 P 0 ;1
L 8.8575 2.4575 8.8575 2.4575 9 P 0 ;1
L 8.8575 2.5075 8.8575 2.5075 9 P 0 ;1
L 8.8575 2.5575 8.8575 2.5575 9 P 0 ;1
L 8.8575 2.6075 8.8575 2.6075 9 P 0 ;1
L 8.8575 2.6575 8.8575 2.6575 9 P 0 ;1
L 8.8575 2.7075 8.8575 2.7075 9 P 0 ;1
L 8.8575 2.7575 8.8575 2.7575 9 P 0 ;1
L 8.8575 2.8075 8.8575 2.8075 9 P 0 ;1
L 8.8575 2.8575 8.8575 2.8575 9 P 0 ;1
L 8.8575 2.9075 8.8575 2.9075 9 P 0 ;1
L 8.8575 2.9575 8.8575 2.9575 9 P 0 ;1
L 8.8575 3.0075 8.8575 3.0075 9 P 0 ;1
L 8.8575 3.0575 8.8575 3.0575 9 P 0 ;1
L 8.8575 3.1075 8.8575 3.1075 9 P 0 ;1
L 8.8575 3.1575 8.8575 3.1575 9 P 0 ;1
L 8.8575 3.2075 8.8575 3.2075 9 P 0 ;1
L 8.8575 3.2575 8.8575 3.2575 9 P 0 ;1
L 8.8575 3.3075 8.8575 3.3075 9 P 0 ;1
L 8.8575 3.3575 8.8575 3.3575 9 P 0 ;1
L 8.8575 3.4075 8.8575 3.4075 9 P 0 ;1
L 8.8575 4.0075 8.8575 4.0075 9 P 0 ;1
L 8.8575 5.3075 8.8575 5.3075 9 P 0 ;1
L 8.8575 5.3575 8.8575 5.3575 9 P 0 ;1
L 8.8575 5.4075 8.8575 5.4075 9 P 0 ;1
L 8.8575 5.4575 8.8575 5.4575 9 P 0 ;1
L 8.8575 5.5075 8.8575 5.5075 9 P 0 ;1
L 8.8575 5.5575 8.8575 5.5575 9 P 0 ;1
L 8.8575 5.6075 8.8575 5.6075 9 P 0 ;1
L 8.8575 5.6575 8.8575 5.6575 9 P 0 ;1
L 8.8575 5.7075 8.8575 5.7075 9 P 0 ;1
L 8.8575 5.7575 8.8575 5.7575 9 P 0 ;1
L 8.8575 5.8075 8.8575 5.8075 9 P 0 ;1
L 8.8575 5.8575 8.8575 5.8575 9 P 0 ;1
L 8.8575 5.9075 8.8575 5.9075 9 P 0 ;1
L 8.9075 0.1575 8.9075 0.1575 9 P 0 ;1
L 8.9075 0.2075 8.9075 0.2075 9 P 0 ;1
L 8.9075 0.2575 8.9075 0.2575 9 P 0 ;1
L 8.9075 0.3075 8.9075 0.3075 9 P 0 ;1
L 8.9075 0.3575 8.9075 0.3575 9 P 0 ;1
L 8.9075 0.4075 8.9075 0.4075 9 P 0 ;1
L 8.9075 0.4575 8.9075 0.4575 9 P 0 ;1
L 8.9075 0.5075 8.9075 0.5075 9 P 0 ;1
L 8.9075 0.5575 8.9075 0.5575 9 P 0 ;1
L 8.9075 0.6075 8.9075 0.6075 9 P 0 ;1
L 8.9075 0.6575 8.9075 0.6575 9 P 0 ;1
L 8.9075 0.7075 8.9075 0.7075 9 P 0 ;1
L 8.9075 0.7575 8.9075 0.7575 9 P 0 ;1
L 8.9075 0.8075 8.9075 0.8075 9 P 0 ;1
L 8.9075 0.8575 8.9075 0.8575 9 P 0 ;1
L 8.9075 1.0575 8.9075 1.0575 9 P 0 ;1
L 8.9075 1.1075 8.9075 1.1075 9 P 0 ;1
L 8.9075 1.1575 8.9075 1.1575 9 P 0 ;1
L 8.9075 1.2075 8.9075 1.2075 9 P 0 ;1
L 8.9075 1.2575 8.9075 1.2575 9 P 0 ;1
L 8.9075 1.3075 8.9075 1.3075 9 P 0 ;1
L 8.9075 1.3575 8.9075 1.3575 9 P 0 ;1
L 8.9075 1.4075 8.9075 1.4075 9 P 0 ;1
L 8.9075 1.4575 8.9075 1.4575 9 P 0 ;1
L 8.9075 1.5075 8.9075 1.5075 9 P 0 ;1
L 8.9075 1.5575 8.9075 1.5575 9 P 0 ;1
L 8.9075 1.6075 8.9075 1.6075 9 P 0 ;1
L 8.9075 1.9075 8.9075 1.9075 9 P 0 ;1
L 8.9075 1.9575 8.9075 1.9575 9 P 0 ;1
L 8.9075 2.0075 8.9075 2.0075 9 P 0 ;1
L 8.9075 2.0575 8.9075 2.0575 9 P 0 ;1
L 8.9075 2.1075 8.9075 2.1075 9 P 0 ;1
L 8.9075 2.1575 8.9075 2.1575 9 P 0 ;1
L 8.9075 2.2075 8.9075 2.2075 9 P 0 ;1
L 8.9075 2.2575 8.9075 2.2575 9 P 0 ;1
L 8.9075 2.3075 8.9075 2.3075 9 P 0 ;1
L 8.9075 2.3575 8.9075 2.3575 9 P 0 ;1
L 8.9075 2.4075 8.9075 2.4075 9 P 0 ;1
L 8.9075 2.4575 8.9075 2.4575 9 P 0 ;1
L 8.9075 2.5075 8.9075 2.5075 9 P 0 ;1
L 8.9075 2.5575 8.9075 2.5575 9 P 0 ;1
L 8.9075 2.6075 8.9075 2.6075 9 P 0 ;1
L 8.9075 2.6575 8.9075 2.6575 9 P 0 ;1
L 8.9075 2.7075 8.9075 2.7075 9 P 0 ;1
L 8.9075 3.0075 8.9075 3.0075 9 P 0 ;1
L 8.9075 3.0575 8.9075 3.0575 9 P 0 ;1
L 8.9075 3.1075 8.9075 3.1075 9 P 0 ;1
L 8.9075 3.1575 8.9075 3.1575 9 P 0 ;1
L 8.9075 3.2075 8.9075 3.2075 9 P 0 ;1
L 8.9075 3.2575 8.9075 3.2575 9 P 0 ;1
L 8.9075 3.3075 8.9075 3.3075 9 P 0 ;1
L 8.9075 3.3575 8.9075 3.3575 9 P 0 ;1
L 8.9075 3.4075 8.9075 3.4075 9 P 0 ;1
L 8.9075 5.3075 8.9075 5.3075 9 P 0 ;1
L 8.9075 5.3575 8.9075 5.3575 9 P 0 ;1
L 8.9075 5.4075 8.9075 5.4075 9 P 0 ;1
L 8.9075 5.4575 8.9075 5.4575 9 P 0 ;1
L 8.9075 5.5075 8.9075 5.5075 9 P 0 ;1
L 8.9075 5.5575 8.9075 5.5575 9 P 0 ;1
L 8.9075 5.6075 8.9075 5.6075 9 P 0 ;1
L 8.9075 5.6575 8.9075 5.6575 9 P 0 ;1
L 8.9075 5.7075 8.9075 5.7075 9 P 0 ;1
L 8.9075 5.7575 8.9075 5.7575 9 P 0 ;1
L 8.9075 5.8075 8.9075 5.8075 9 P 0 ;1
L 8.9075 5.8575 8.9075 5.8575 9 P 0 ;1
L 8.9075 5.9075 8.9075 5.9075 9 P 0 ;1
L 8.9575 0.1575 8.9575 0.1575 9 P 0 ;1
L 8.9575 0.2075 8.9575 0.2075 9 P 0 ;1
L 8.9575 0.2575 8.9575 0.2575 9 P 0 ;1
L 8.9575 0.3075 8.9575 0.3075 9 P 0 ;1
L 8.9575 0.3575 8.9575 0.3575 9 P 0 ;1
L 8.9575 0.4075 8.9575 0.4075 9 P 0 ;1
L 8.9575 0.4575 8.9575 0.4575 9 P 0 ;1
L 8.9575 0.5075 8.9575 0.5075 9 P 0 ;1
L 8.9575 0.5575 8.9575 0.5575 9 P 0 ;1
L 8.9575 0.6075 8.9575 0.6075 9 P 0 ;1
L 8.9575 0.6575 8.9575 0.6575 9 P 0 ;1
L 8.9575 0.7075 8.9575 0.7075 9 P 0 ;1
L 8.9575 0.7575 8.9575 0.7575 9 P 0 ;1
L 8.9575 0.8075 8.9575 0.8075 9 P 0 ;1
L 8.9575 0.8575 8.9575 0.8575 9 P 0 ;1
L 8.9575 1.0575 8.9575 1.0575 9 P 0 ;1
L 8.9575 1.1075 8.9575 1.1075 9 P 0 ;1
L 8.9575 1.1575 8.9575 1.1575 9 P 0 ;1
L 8.9575 1.2075 8.9575 1.2075 9 P 0 ;1
L 8.9575 1.2575 8.9575 1.2575 9 P 0 ;1
L 8.9575 1.3075 8.9575 1.3075 9 P 0 ;1
L 8.9575 1.3575 8.9575 1.3575 9 P 0 ;1
L 8.9575 1.4075 8.9575 1.4075 9 P 0 ;1
L 8.9575 1.4575 8.9575 1.4575 9 P 0 ;1
L 8.9575 1.5075 8.9575 1.5075 9 P 0 ;1
L 8.9575 1.5575 8.9575 1.5575 9 P 0 ;1
L 8.9575 1.6075 8.9575 1.6075 9 P 0 ;1
L 8.9575 1.9075 8.9575 1.9075 9 P 0 ;1
L 8.9575 1.9575 8.9575 1.9575 9 P 0 ;1
L 8.9575 2.0075 8.9575 2.0075 9 P 0 ;1
L 8.9575 2.0575 8.9575 2.0575 9 P 0 ;1
L 8.9575 2.1075 8.9575 2.1075 9 P 0 ;1
L 8.9575 2.1575 8.9575 2.1575 9 P 0 ;1
L 8.9575 2.2075 8.9575 2.2075 9 P 0 ;1
L 8.9575 2.2575 8.9575 2.2575 9 P 0 ;1
L 8.9575 2.3075 8.9575 2.3075 9 P 0 ;1
L 8.9575 2.3575 8.9575 2.3575 9 P 0 ;1
L 8.9575 2.4075 8.9575 2.4075 9 P 0 ;1
L 8.9575 2.4575 8.9575 2.4575 9 P 0 ;1
L 8.9575 2.5075 8.9575 2.5075 9 P 0 ;1
L 8.9575 2.5575 8.9575 2.5575 9 P 0 ;1
L 8.9575 2.6075 8.9575 2.6075 9 P 0 ;1
L 8.9575 2.6575 8.9575 2.6575 9 P 0 ;1
L 8.9575 2.7075 8.9575 2.7075 9 P 0 ;1
L 8.9575 3.0075 8.9575 3.0075 9 P 0 ;1
L 8.9575 3.0575 8.9575 3.0575 9 P 0 ;1
L 8.9575 3.1075 8.9575 3.1075 9 P 0 ;1
L 8.9575 3.1575 8.9575 3.1575 9 P 0 ;1
L 8.9575 3.2075 8.9575 3.2075 9 P 0 ;1
L 8.9575 3.2575 8.9575 3.2575 9 P 0 ;1
L 8.9575 3.3075 8.9575 3.3075 9 P 0 ;1
L 8.9575 3.3575 8.9575 3.3575 9 P 0 ;1
L 8.9575 3.4075 8.9575 3.4075 9 P 0 ;1
L 8.9575 4.0575 8.9575 4.0575 9 P 0 ;1
L 8.9575 5.3075 8.9575 5.3075 9 P 0 ;1
L 8.9575 5.3575 8.9575 5.3575 9 P 0 ;1
L 8.9575 5.4075 8.9575 5.4075 9 P 0 ;1
L 8.9575 5.4575 8.9575 5.4575 9 P 0 ;1
L 8.9575 5.5075 8.9575 5.5075 9 P 0 ;1
L 8.9575 5.5575 8.9575 5.5575 9 P 0 ;1
L 8.9575 5.6075 8.9575 5.6075 9 P 0 ;1
L 8.9575 5.6575 8.9575 5.6575 9 P 0 ;1
L 8.9575 5.7075 8.9575 5.7075 9 P 0 ;1
L 8.9575 5.7575 8.9575 5.7575 9 P 0 ;1
L 8.9575 5.8075 8.9575 5.8075 9 P 0 ;1
L 8.9575 5.8575 8.9575 5.8575 9 P 0 ;1
L 8.9575 5.9075 8.9575 5.9075 9 P 0 ;1
L 9.0075 0.1575 9.0075 0.1575 9 P 0 ;1
L 9.0075 0.2075 9.0075 0.2075 9 P 0 ;1
L 9.0075 0.2575 9.0075 0.2575 9 P 0 ;1
L 9.0075 0.3075 9.0075 0.3075 9 P 0 ;1
L 9.0075 0.3575 9.0075 0.3575 9 P 0 ;1
L 9.0075 0.4075 9.0075 0.4075 9 P 0 ;1
L 9.0075 0.4575 9.0075 0.4575 9 P 0 ;1
L 9.0075 0.5075 9.0075 0.5075 9 P 0 ;1
L 9.0075 0.5575 9.0075 0.5575 9 P 0 ;1
L 9.0075 0.6075 9.0075 0.6075 9 P 0 ;1
L 9.0075 0.6575 9.0075 0.6575 9 P 0 ;1
L 9.0075 0.7075 9.0075 0.7075 9 P 0 ;1
L 9.0075 0.7575 9.0075 0.7575 9 P 0 ;1
L 9.0075 0.8075 9.0075 0.8075 9 P 0 ;1
L 9.0075 0.8575 9.0075 0.8575 9 P 0 ;1
L 9.0075 1.0575 9.0075 1.0575 9 P 0 ;1
L 9.0075 1.1075 9.0075 1.1075 9 P 0 ;1
L 9.0075 1.1575 9.0075 1.1575 9 P 0 ;1
L 9.0075 1.2075 9.0075 1.2075 9 P 0 ;1
L 9.0075 1.2575 9.0075 1.2575 9 P 0 ;1
L 9.0075 1.3075 9.0075 1.3075 9 P 0 ;1
L 9.0075 1.3575 9.0075 1.3575 9 P 0 ;1
L 9.0075 1.4075 9.0075 1.4075 9 P 0 ;1
L 9.0075 1.4575 9.0075 1.4575 9 P 0 ;1
L 9.0075 1.5075 9.0075 1.5075 9 P 0 ;1
L 9.0075 1.5575 9.0075 1.5575 9 P 0 ;1
L 9.0075 1.6075 9.0075 1.6075 9 P 0 ;1
L 9.0075 1.9075 9.0075 1.9075 9 P 0 ;1
L 9.0075 1.9575 9.0075 1.9575 9 P 0 ;1
L 9.0075 2.0075 9.0075 2.0075 9 P 0 ;1
L 9.0075 2.0575 9.0075 2.0575 9 P 0 ;1
L 9.0075 2.1075 9.0075 2.1075 9 P 0 ;1
L 9.0075 2.1575 9.0075 2.1575 9 P 0 ;1
L 9.0075 2.2075 9.0075 2.2075 9 P 0 ;1
L 9.0075 2.2575 9.0075 2.2575 9 P 0 ;1
L 9.0075 2.3075 9.0075 2.3075 9 P 0 ;1
L 9.0075 2.3575 9.0075 2.3575 9 P 0 ;1
L 9.0075 2.4075 9.0075 2.4075 9 P 0 ;1
L 9.0075 2.4575 9.0075 2.4575 9 P 0 ;1
L 9.0075 2.5075 9.0075 2.5075 9 P 0 ;1
L 9.0075 2.5575 9.0075 2.5575 9 P 0 ;1
L 9.0075 2.6075 9.0075 2.6075 9 P 0 ;1
L 9.0075 2.6575 9.0075 2.6575 9 P 0 ;1
L 9.0075 2.7075 9.0075 2.7075 9 P 0 ;1
L 9.0075 3.0075 9.0075 3.0075 9 P 0 ;1
L 9.0075 3.0575 9.0075 3.0575 9 P 0 ;1
L 9.0075 3.1075 9.0075 3.1075 9 P 0 ;1
L 9.0075 3.1575 9.0075 3.1575 9 P 0 ;1
L 9.0075 3.2075 9.0075 3.2075 9 P 0 ;1
L 9.0075 3.2575 9.0075 3.2575 9 P 0 ;1
L 9.0075 3.3075 9.0075 3.3075 9 P 0 ;1
L 9.0075 3.3575 9.0075 3.3575 9 P 0 ;1
L 9.0075 3.4075 9.0075 3.4075 9 P 0 ;1
L 9.0075 3.4575 9.0075 3.4575 9 P 0 ;1
L 9.0075 4.0575 9.0075 4.0575 9 P 0 ;1
L 9.0075 4.1075 9.0075 4.1075 9 P 0 ;1
L 9.0075 4.1575 9.0075 4.1575 9 P 0 ;1
L 9.0075 5.4075 9.0075 5.4075 9 P 0 ;1
L 9.0075 5.4575 9.0075 5.4575 9 P 0 ;1
L 9.0075 5.5075 9.0075 5.5075 9 P 0 ;1
L 9.0075 5.5575 9.0075 5.5575 9 P 0 ;1
L 9.0075 5.6075 9.0075 5.6075 9 P 0 ;1
L 9.0075 5.6575 9.0075 5.6575 9 P 0 ;1
L 9.0075 5.7075 9.0075 5.7075 9 P 0 ;1
L 9.0075 5.7575 9.0075 5.7575 9 P 0 ;1
L 9.0075 5.8075 9.0075 5.8075 9 P 0 ;1
L 9.0075 5.8575 9.0075 5.8575 9 P 0 ;1
L 9.0075 5.9075 9.0075 5.9075 9 P 0 ;1
L 9.0575 0.1575 9.0575 0.1575 9 P 0 ;1
L 9.0575 0.2075 9.0575 0.2075 9 P 0 ;1
L 9.0575 0.2575 9.0575 0.2575 9 P 0 ;1
L 9.0575 0.3075 9.0575 0.3075 9 P 0 ;1
L 9.0575 0.3575 9.0575 0.3575 9 P 0 ;1
L 9.0575 0.4075 9.0575 0.4075 9 P 0 ;1
L 9.0575 0.4575 9.0575 0.4575 9 P 0 ;1
L 9.0575 0.5075 9.0575 0.5075 9 P 0 ;1
L 9.0575 0.5575 9.0575 0.5575 9 P 0 ;1
L 9.0575 0.6075 9.0575 0.6075 9 P 0 ;1
L 9.0575 0.6575 9.0575 0.6575 9 P 0 ;1
L 9.0575 0.7075 9.0575 0.7075 9 P 0 ;1
L 9.0575 0.7575 9.0575 0.7575 9 P 0 ;1
L 9.0575 0.8075 9.0575 0.8075 9 P 0 ;1
L 9.0575 0.8575 9.0575 0.8575 9 P 0 ;1
L 9.0575 1.0575 9.0575 1.0575 9 P 0 ;1
L 9.0575 1.1075 9.0575 1.1075 9 P 0 ;1
L 9.0575 1.1575 9.0575 1.1575 9 P 0 ;1
L 9.0575 1.2075 9.0575 1.2075 9 P 0 ;1
L 9.0575 1.2575 9.0575 1.2575 9 P 0 ;1
L 9.0575 1.3075 9.0575 1.3075 9 P 0 ;1
L 9.0575 1.3575 9.0575 1.3575 9 P 0 ;1
L 9.0575 1.4075 9.0575 1.4075 9 P 0 ;1
L 9.0575 1.4575 9.0575 1.4575 9 P 0 ;1
L 9.0575 1.5075 9.0575 1.5075 9 P 0 ;1
L 9.0575 1.5575 9.0575 1.5575 9 P 0 ;1
L 9.0575 1.6075 9.0575 1.6075 9 P 0 ;1
L 9.0575 1.9075 9.0575 1.9075 9 P 0 ;1
L 9.0575 1.9575 9.0575 1.9575 9 P 0 ;1
L 9.0575 2.0075 9.0575 2.0075 9 P 0 ;1
L 9.0575 2.0575 9.0575 2.0575 9 P 0 ;1
L 9.0575 2.1075 9.0575 2.1075 9 P 0 ;1
L 9.0575 2.1575 9.0575 2.1575 9 P 0 ;1
L 9.0575 2.2075 9.0575 2.2075 9 P 0 ;1
L 9.0575 2.2575 9.0575 2.2575 9 P 0 ;1
L 9.0575 2.3075 9.0575 2.3075 9 P 0 ;1
L 9.0575 2.3575 9.0575 2.3575 9 P 0 ;1
L 9.0575 2.4075 9.0575 2.4075 9 P 0 ;1
L 9.0575 2.4575 9.0575 2.4575 9 P 0 ;1
L 9.0575 2.5075 9.0575 2.5075 9 P 0 ;1
L 9.0575 2.5575 9.0575 2.5575 9 P 0 ;1
L 9.0575 2.6075 9.0575 2.6075 9 P 0 ;1
L 9.0575 2.6575 9.0575 2.6575 9 P 0 ;1
L 9.0575 2.7075 9.0575 2.7075 9 P 0 ;1
L 9.0575 2.7575 9.0575 2.7575 9 P 0 ;1
L 9.0575 2.8075 9.0575 2.8075 9 P 0 ;1
L 9.0575 2.9575 9.0575 2.9575 9 P 0 ;1
L 9.0575 3.0075 9.0575 3.0075 9 P 0 ;1
L 9.0575 3.0575 9.0575 3.0575 9 P 0 ;1
L 9.0575 3.1075 9.0575 3.1075 9 P 0 ;1
L 9.0575 3.1575 9.0575 3.1575 9 P 0 ;1
L 9.0575 3.2075 9.0575 3.2075 9 P 0 ;1
L 9.0575 3.2575 9.0575 3.2575 9 P 0 ;1
L 9.0575 3.3075 9.0575 3.3075 9 P 0 ;1
L 9.0575 3.3575 9.0575 3.3575 9 P 0 ;1
L 9.0575 3.4075 9.0575 3.4075 9 P 0 ;1
L 9.0575 3.4575 9.0575 3.4575 9 P 0 ;1
L 9.0575 4.0575 9.0575 4.0575 9 P 0 ;1
L 9.0575 4.1075 9.0575 4.1075 9 P 0 ;1
L 9.0575 4.1575 9.0575 4.1575 9 P 0 ;1
L 9.0575 5.4575 9.0575 5.4575 9 P 0 ;1
L 9.0575 5.5075 9.0575 5.5075 9 P 0 ;1
L 9.0575 5.5575 9.0575 5.5575 9 P 0 ;1
L 9.0575 5.6075 9.0575 5.6075 9 P 0 ;1
L 9.0575 5.6575 9.0575 5.6575 9 P 0 ;1
L 9.0575 5.7075 9.0575 5.7075 9 P 0 ;1
L 9.0575 5.7575 9.0575 5.7575 9 P 0 ;1
L 9.0575 5.8075 9.0575 5.8075 9 P 0 ;1
L 9.0575 5.8575 9.0575 5.8575 9 P 0 ;1
L 9.0575 5.9075 9.0575 5.9075 9 P 0 ;1
L 9.1075 0.1575 9.1075 0.1575 9 P 0 ;1
L 9.1075 0.2075 9.1075 0.2075 9 P 0 ;1
L 9.1075 0.2575 9.1075 0.2575 9 P 0 ;1
L 9.1075 0.3075 9.1075 0.3075 9 P 0 ;1
L 9.1075 0.3575 9.1075 0.3575 9 P 0 ;1
L 9.1075 0.4075 9.1075 0.4075 9 P 0 ;1
L 9.1075 0.4575 9.1075 0.4575 9 P 0 ;1
L 9.1075 0.5075 9.1075 0.5075 9 P 0 ;1
L 9.1075 0.5575 9.1075 0.5575 9 P 0 ;1
L 9.1075 0.6075 9.1075 0.6075 9 P 0 ;1
L 9.1075 0.6575 9.1075 0.6575 9 P 0 ;1
L 9.1075 0.7075 9.1075 0.7075 9 P 0 ;1
L 9.1075 0.7575 9.1075 0.7575 9 P 0 ;1
L 9.1075 0.8075 9.1075 0.8075 9 P 0 ;1
L 9.1075 0.8575 9.1075 0.8575 9 P 0 ;1
L 9.1075 1.0575 9.1075 1.0575 9 P 0 ;1
L 9.1075 1.1075 9.1075 1.1075 9 P 0 ;1
L 9.1075 1.1575 9.1075 1.1575 9 P 0 ;1
L 9.1075 1.2075 9.1075 1.2075 9 P 0 ;1
L 9.1075 1.2575 9.1075 1.2575 9 P 0 ;1
L 9.1075 1.3075 9.1075 1.3075 9 P 0 ;1
L 9.1075 1.3575 9.1075 1.3575 9 P 0 ;1
L 9.1075 1.4075 9.1075 1.4075 9 P 0 ;1
L 9.1075 1.4575 9.1075 1.4575 9 P 0 ;1
L 9.1075 1.5075 9.1075 1.5075 9 P 0 ;1
L 9.1075 1.5575 9.1075 1.5575 9 P 0 ;1
L 9.1075 1.6075 9.1075 1.6075 9 P 0 ;1
L 9.1075 1.9075 9.1075 1.9075 9 P 0 ;1
L 9.1075 1.9575 9.1075 1.9575 9 P 0 ;1
L 9.1075 2.0075 9.1075 2.0075 9 P 0 ;1
L 9.1075 2.0575 9.1075 2.0575 9 P 0 ;1
L 9.1075 2.1075 9.1075 2.1075 9 P 0 ;1
L 9.1075 2.1575 9.1075 2.1575 9 P 0 ;1
L 9.1075 2.2075 9.1075 2.2075 9 P 0 ;1
L 9.1075 2.2575 9.1075 2.2575 9 P 0 ;1
L 9.1075 2.3075 9.1075 2.3075 9 P 0 ;1
L 9.1075 2.3575 9.1075 2.3575 9 P 0 ;1
L 9.1075 2.4075 9.1075 2.4075 9 P 0 ;1
L 9.1075 2.4575 9.1075 2.4575 9 P 0 ;1
L 9.1075 2.5075 9.1075 2.5075 9 P 0 ;1
L 9.1075 2.5575 9.1075 2.5575 9 P 0 ;1
L 9.1075 2.6075 9.1075 2.6075 9 P 0 ;1
L 9.1075 2.6575 9.1075 2.6575 9 P 0 ;1
L 9.1075 2.7075 9.1075 2.7075 9 P 0 ;1
L 9.1075 2.7575 9.1075 2.7575 9 P 0 ;1
L 9.1075 2.8075 9.1075 2.8075 9 P 0 ;1
L 9.1075 2.8575 9.1075 2.8575 9 P 0 ;1
L 9.1075 2.9075 9.1075 2.9075 9 P 0 ;1
L 9.1075 2.9575 9.1075 2.9575 9 P 0 ;1
L 9.1075 3.0075 9.1075 3.0075 9 P 0 ;1
L 9.1075 3.0575 9.1075 3.0575 9 P 0 ;1
L 9.1075 3.1075 9.1075 3.1075 9 P 0 ;1
L 9.1075 3.1575 9.1075 3.1575 9 P 0 ;1
L 9.1075 3.2075 9.1075 3.2075 9 P 0 ;1
L 9.1075 3.2575 9.1075 3.2575 9 P 0 ;1
L 9.1075 3.3075 9.1075 3.3075 9 P 0 ;1
L 9.1075 3.3575 9.1075 3.3575 9 P 0 ;1
L 9.1075 3.4075 9.1075 3.4075 9 P 0 ;1
L 9.1075 3.4575 9.1075 3.4575 9 P 0 ;1
L 9.1075 3.5075 9.1075 3.5075 9 P 0 ;1
L 9.1075 4.1075 9.1075 4.1075 9 P 0 ;1
L 9.1075 4.1575 9.1075 4.1575 9 P 0 ;1
L 9.1075 4.2075 9.1075 4.2075 9 P 0 ;1
L 9.1075 4.2575 9.1075 4.2575 9 P 0 ;1
L 9.1075 4.3075 9.1075 4.3075 9 P 0 ;1
L 9.1075 5.4075 9.1075 5.4075 9 P 0 ;1
L 9.1075 5.4575 9.1075 5.4575 9 P 0 ;1
L 9.1075 5.5075 9.1075 5.5075 9 P 0 ;1
L 9.1075 5.5575 9.1075 5.5575 9 P 0 ;1
L 9.1075 5.6075 9.1075 5.6075 9 P 0 ;1
L 9.1075 5.6575 9.1075 5.6575 9 P 0 ;1
L 9.1075 5.7075 9.1075 5.7075 9 P 0 ;1
L 9.1075 5.7575 9.1075 5.7575 9 P 0 ;1
L 9.1075 5.8075 9.1075 5.8075 9 P 0 ;1
L 9.1075 5.8575 9.1075 5.8575 9 P 0 ;1
L 9.1075 5.9075 9.1075 5.9075 9 P 0 ;1
L 9.1575 0.1575 9.1575 0.1575 9 P 0 ;1
L 9.1575 0.2075 9.1575 0.2075 9 P 0 ;1
L 9.1575 0.2575 9.1575 0.2575 9 P 0 ;1
L 9.1575 0.3075 9.1575 0.3075 9 P 0 ;1
L 9.1575 0.3575 9.1575 0.3575 9 P 0 ;1
L 9.1575 0.4075 9.1575 0.4075 9 P 0 ;1
L 9.1575 0.4575 9.1575 0.4575 9 P 0 ;1
L 9.1575 0.5075 9.1575 0.5075 9 P 0 ;1
L 9.1575 0.5575 9.1575 0.5575 9 P 0 ;1
L 9.1575 0.6075 9.1575 0.6075 9 P 0 ;1
L 9.1575 0.6575 9.1575 0.6575 9 P 0 ;1
L 9.1575 0.7075 9.1575 0.7075 9 P 0 ;1
L 9.1575 0.7575 9.1575 0.7575 9 P 0 ;1
L 9.1575 0.8075 9.1575 0.8075 9 P 0 ;1
L 9.1575 0.8575 9.1575 0.8575 9 P 0 ;1
L 9.1575 1.0575 9.1575 1.0575 9 P 0 ;1
L 9.1575 1.1075 9.1575 1.1075 9 P 0 ;1
L 9.1575 1.1575 9.1575 1.1575 9 P 0 ;1
L 9.1575 1.2075 9.1575 1.2075 9 P 0 ;1
L 9.1575 1.2575 9.1575 1.2575 9 P 0 ;1
L 9.1575 1.3075 9.1575 1.3075 9 P 0 ;1
L 9.1575 1.3575 9.1575 1.3575 9 P 0 ;1
L 9.1575 1.4075 9.1575 1.4075 9 P 0 ;1
L 9.1575 1.4575 9.1575 1.4575 9 P 0 ;1
L 9.1575 1.5075 9.1575 1.5075 9 P 0 ;1
L 9.1575 1.5575 9.1575 1.5575 9 P 0 ;1
L 9.1575 1.6075 9.1575 1.6075 9 P 0 ;1
L 9.1575 1.9075 9.1575 1.9075 9 P 0 ;1
L 9.1575 1.9575 9.1575 1.9575 9 P 0 ;1
L 9.1575 2.0075 9.1575 2.0075 9 P 0 ;1
L 9.1575 2.0575 9.1575 2.0575 9 P 0 ;1
L 9.1575 2.1075 9.1575 2.1075 9 P 0 ;1
L 9.1575 2.1575 9.1575 2.1575 9 P 0 ;1
L 9.1575 2.2075 9.1575 2.2075 9 P 0 ;1
L 9.1575 2.2575 9.1575 2.2575 9 P 0 ;1
L 9.1575 2.3075 9.1575 2.3075 9 P 0 ;1
L 9.1575 2.3575 9.1575 2.3575 9 P 0 ;1
L 9.1575 2.4075 9.1575 2.4075 9 P 0 ;1
L 9.1575 2.4575 9.1575 2.4575 9 P 0 ;1
L 9.1575 2.5075 9.1575 2.5075 9 P 0 ;1
L 9.1575 2.5575 9.1575 2.5575 9 P 0 ;1
L 9.1575 2.6075 9.1575 2.6075 9 P 0 ;1
L 9.1575 2.6575 9.1575 2.6575 9 P 0 ;1
L 9.1575 2.7075 9.1575 2.7075 9 P 0 ;1
L 9.1575 2.7575 9.1575 2.7575 9 P 0 ;1
L 9.1575 2.8075 9.1575 2.8075 9 P 0 ;1
L 9.1575 2.8575 9.1575 2.8575 9 P 0 ;1
L 9.1575 2.9075 9.1575 2.9075 9 P 0 ;1
L 9.1575 2.9575 9.1575 2.9575 9 P 0 ;1
L 9.1575 3.0075 9.1575 3.0075 9 P 0 ;1
L 9.1575 3.0575 9.1575 3.0575 9 P 0 ;1
L 9.1575 3.1075 9.1575 3.1075 9 P 0 ;1
L 9.1575 3.1575 9.1575 3.1575 9 P 0 ;1
L 9.1575 3.2075 9.1575 3.2075 9 P 0 ;1
L 9.1575 3.2575 9.1575 3.2575 9 P 0 ;1
L 9.1575 3.3075 9.1575 3.3075 9 P 0 ;1
L 9.1575 3.3575 9.1575 3.3575 9 P 0 ;1
L 9.1575 3.4075 9.1575 3.4075 9 P 0 ;1
L 9.1575 3.4575 9.1575 3.4575 9 P 0 ;1
L 9.1575 3.5075 9.1575 3.5075 9 P 0 ;1
L 9.1575 3.5575 9.1575 3.5575 9 P 0 ;1
L 9.1575 5.3575 9.1575 5.3575 9 P 0 ;1
L 9.1575 5.4075 9.1575 5.4075 9 P 0 ;1
L 9.1575 5.4575 9.1575 5.4575 9 P 0 ;1
L 9.1575 5.5075 9.1575 5.5075 9 P 0 ;1
L 9.1575 5.5575 9.1575 5.5575 9 P 0 ;1
L 9.1575 5.6075 9.1575 5.6075 9 P 0 ;1
L 9.1575 5.6575 9.1575 5.6575 9 P 0 ;1
L 9.1575 5.7075 9.1575 5.7075 9 P 0 ;1
L 9.1575 5.7575 9.1575 5.7575 9 P 0 ;1
L 9.1575 5.8075 9.1575 5.8075 9 P 0 ;1
L 9.1575 5.8575 9.1575 5.8575 9 P 0 ;1
L 9.1575 5.9075 9.1575 5.9075 9 P 0 ;1
L 9.2075 0.1575 9.2075 0.1575 9 P 0 ;1
L 9.2075 0.2075 9.2075 0.2075 9 P 0 ;1
L 9.2075 0.2575 9.2075 0.2575 9 P 0 ;1
L 9.2075 0.3075 9.2075 0.3075 9 P 0 ;1
L 9.2075 0.3575 9.2075 0.3575 9 P 0 ;1
L 9.2075 0.4075 9.2075 0.4075 9 P 0 ;1
L 9.2075 0.4575 9.2075 0.4575 9 P 0 ;1
L 9.2075 0.5075 9.2075 0.5075 9 P 0 ;1
L 9.2075 0.5575 9.2075 0.5575 9 P 0 ;1
L 9.2075 0.6075 9.2075 0.6075 9 P 0 ;1
L 9.2075 0.6575 9.2075 0.6575 9 P 0 ;1
L 9.2075 0.7075 9.2075 0.7075 9 P 0 ;1
L 9.2075 0.7575 9.2075 0.7575 9 P 0 ;1
L 9.2075 0.8075 9.2075 0.8075 9 P 0 ;1
L 9.2075 0.8575 9.2075 0.8575 9 P 0 ;1
L 9.2075 1.0575 9.2075 1.0575 9 P 0 ;1
L 9.2075 1.1075 9.2075 1.1075 9 P 0 ;1
L 9.2075 1.1575 9.2075 1.1575 9 P 0 ;1
L 9.2075 1.2075 9.2075 1.2075 9 P 0 ;1
L 9.2075 1.2575 9.2075 1.2575 9 P 0 ;1
L 9.2075 1.3075 9.2075 1.3075 9 P 0 ;1
L 9.2075 1.3575 9.2075 1.3575 9 P 0 ;1
L 9.2075 1.4075 9.2075 1.4075 9 P 0 ;1
L 9.2075 1.4575 9.2075 1.4575 9 P 0 ;1
L 9.2075 1.5075 9.2075 1.5075 9 P 0 ;1
L 9.2075 1.5575 9.2075 1.5575 9 P 0 ;1
L 9.2075 1.6075 9.2075 1.6075 9 P 0 ;1
L 9.2075 1.9075 9.2075 1.9075 9 P 0 ;1
L 9.2075 1.9575 9.2075 1.9575 9 P 0 ;1
L 9.2075 2.0075 9.2075 2.0075 9 P 0 ;1
L 9.2075 2.0575 9.2075 2.0575 9 P 0 ;1
L 9.2075 2.1075 9.2075 2.1075 9 P 0 ;1
L 9.2075 2.1575 9.2075 2.1575 9 P 0 ;1
L 9.2075 2.2075 9.2075 2.2075 9 P 0 ;1
L 9.2075 2.2575 9.2075 2.2575 9 P 0 ;1
L 9.2075 2.3075 9.2075 2.3075 9 P 0 ;1
L 9.2075 2.3575 9.2075 2.3575 9 P 0 ;1
L 9.2075 2.4075 9.2075 2.4075 9 P 0 ;1
L 9.2075 2.4575 9.2075 2.4575 9 P 0 ;1
L 9.2075 2.5075 9.2075 2.5075 9 P 0 ;1
L 9.2075 2.5575 9.2075 2.5575 9 P 0 ;1
L 9.2075 2.6075 9.2075 2.6075 9 P 0 ;1
L 9.2075 2.6575 9.2075 2.6575 9 P 0 ;1
L 9.2075 2.7075 9.2075 2.7075 9 P 0 ;1
L 9.2075 2.7575 9.2075 2.7575 9 P 0 ;1
L 9.2075 2.8075 9.2075 2.8075 9 P 0 ;1
L 9.2075 2.8575 9.2075 2.8575 9 P 0 ;1
L 9.2075 2.9075 9.2075 2.9075 9 P 0 ;1
L 9.2075 2.9575 9.2075 2.9575 9 P 0 ;1
L 9.2075 3.0075 9.2075 3.0075 9 P 0 ;1
L 9.2075 3.0575 9.2075 3.0575 9 P 0 ;1
L 9.2075 3.1075 9.2075 3.1075 9 P 0 ;1
L 9.2075 3.1575 9.2075 3.1575 9 P 0 ;1
L 9.2075 3.2075 9.2075 3.2075 9 P 0 ;1
L 9.2075 3.2575 9.2075 3.2575 9 P 0 ;1
L 9.2075 3.3075 9.2075 3.3075 9 P 0 ;1
L 9.2075 3.3575 9.2075 3.3575 9 P 0 ;1
L 9.2075 3.4075 9.2075 3.4075 9 P 0 ;1
L 9.2075 3.4575 9.2075 3.4575 9 P 0 ;1
L 9.2075 3.5075 9.2075 3.5075 9 P 0 ;1
L 9.2075 3.5575 9.2075 3.5575 9 P 0 ;1
L 9.2075 3.6075 9.2075 3.6075 9 P 0 ;1
L 9.2075 5.4075 9.2075 5.4075 9 P 0 ;1
L 9.2075 5.4575 9.2075 5.4575 9 P 0 ;1
L 9.2075 5.5075 9.2075 5.5075 9 P 0 ;1
L 9.2075 5.5575 9.2075 5.5575 9 P 0 ;1
L 9.2075 5.6075 9.2075 5.6075 9 P 0 ;1
L 9.2075 5.6575 9.2075 5.6575 9 P 0 ;1
L 9.2075 5.7075 9.2075 5.7075 9 P 0 ;1
L 9.2075 5.7575 9.2075 5.7575 9 P 0 ;1
L 9.2075 5.8075 9.2075 5.8075 9 P 0 ;1
L 9.2075 5.8575 9.2075 5.8575 9 P 0 ;1
L 9.2075 5.9075 9.2075 5.9075 9 P 0 ;1
L 9.2575 0.1575 9.2575 0.1575 9 P 0 ;1
L 9.2575 0.2075 9.2575 0.2075 9 P 0 ;1
L 9.2575 0.2575 9.2575 0.2575 9 P 0 ;1
L 9.2575 0.3075 9.2575 0.3075 9 P 0 ;1
L 9.2575 0.3575 9.2575 0.3575 9 P 0 ;1
L 9.2575 0.4075 9.2575 0.4075 9 P 0 ;1
L 9.2575 0.4575 9.2575 0.4575 9 P 0 ;1
L 9.2575 0.5075 9.2575 0.5075 9 P 0 ;1
L 9.2575 0.5575 9.2575 0.5575 9 P 0 ;1
L 9.2575 0.6075 9.2575 0.6075 9 P 0 ;1
L 9.2575 0.6575 9.2575 0.6575 9 P 0 ;1
L 9.2575 0.7075 9.2575 0.7075 9 P 0 ;1
L 9.2575 0.7575 9.2575 0.7575 9 P 0 ;1
L 9.2575 0.8075 9.2575 0.8075 9 P 0 ;1
L 9.2575 0.8575 9.2575 0.8575 9 P 0 ;1
L 9.2575 1.0575 9.2575 1.0575 9 P 0 ;1
L 9.2575 1.1075 9.2575 1.1075 9 P 0 ;1
L 9.2575 1.1575 9.2575 1.1575 9 P 0 ;1
L 9.2575 1.2075 9.2575 1.2075 9 P 0 ;1
L 9.2575 1.2575 9.2575 1.2575 9 P 0 ;1
L 9.2575 1.3075 9.2575 1.3075 9 P 0 ;1
L 9.2575 1.3575 9.2575 1.3575 9 P 0 ;1
L 9.2575 1.4075 9.2575 1.4075 9 P 0 ;1
L 9.2575 1.4575 9.2575 1.4575 9 P 0 ;1
L 9.2575 1.5075 9.2575 1.5075 9 P 0 ;1
L 9.2575 1.5575 9.2575 1.5575 9 P 0 ;1
L 9.2575 1.6075 9.2575 1.6075 9 P 0 ;1
L 9.2575 1.9075 9.2575 1.9075 9 P 0 ;1
L 9.2575 1.9575 9.2575 1.9575 9 P 0 ;1
L 9.2575 2.0075 9.2575 2.0075 9 P 0 ;1
L 9.2575 2.0575 9.2575 2.0575 9 P 0 ;1
L 9.2575 2.1075 9.2575 2.1075 9 P 0 ;1
L 9.2575 2.1575 9.2575 2.1575 9 P 0 ;1
L 9.2575 2.2075 9.2575 2.2075 9 P 0 ;1
L 9.2575 2.2575 9.2575 2.2575 9 P 0 ;1
L 9.2575 2.3075 9.2575 2.3075 9 P 0 ;1
L 9.2575 2.3575 9.2575 2.3575 9 P 0 ;1
L 9.2575 2.4075 9.2575 2.4075 9 P 0 ;1
L 9.2575 2.4575 9.2575 2.4575 9 P 0 ;1
L 9.2575 2.5075 9.2575 2.5075 9 P 0 ;1
L 9.2575 2.5575 9.2575 2.5575 9 P 0 ;1
L 9.2575 2.6075 9.2575 2.6075 9 P 0 ;1
L 9.2575 2.6575 9.2575 2.6575 9 P 0 ;1
L 9.2575 2.7075 9.2575 2.7075 9 P 0 ;1
L 9.2575 2.7575 9.2575 2.7575 9 P 0 ;1
L 9.2575 2.8075 9.2575 2.8075 9 P 0 ;1
L 9.2575 2.8575 9.2575 2.8575 9 P 0 ;1
L 9.2575 2.9075 9.2575 2.9075 9 P 0 ;1
L 9.2575 2.9575 9.2575 2.9575 9 P 0 ;1
L 9.2575 3.0075 9.2575 3.0075 9 P 0 ;1
L 9.2575 3.0575 9.2575 3.0575 9 P 0 ;1
L 9.2575 3.1075 9.2575 3.1075 9 P 0 ;1
L 9.2575 3.1575 9.2575 3.1575 9 P 0 ;1
L 9.2575 3.2075 9.2575 3.2075 9 P 0 ;1
L 9.2575 3.2575 9.2575 3.2575 9 P 0 ;1
L 9.2575 3.3075 9.2575 3.3075 9 P 0 ;1
L 9.2575 3.3575 9.2575 3.3575 9 P 0 ;1
L 9.2575 3.4075 9.2575 3.4075 9 P 0 ;1
L 9.2575 3.4575 9.2575 3.4575 9 P 0 ;1
L 9.2575 3.5075 9.2575 3.5075 9 P 0 ;1
L 9.2575 3.5575 9.2575 3.5575 9 P 0 ;1
L 9.2575 3.6075 9.2575 3.6075 9 P 0 ;1
L 9.2575 5.4575 9.2575 5.4575 9 P 0 ;1
L 9.2575 5.5075 9.2575 5.5075 9 P 0 ;1
L 9.2575 5.5575 9.2575 5.5575 9 P 0 ;1
L 9.2575 5.6075 9.2575 5.6075 9 P 0 ;1
L 9.2575 5.6575 9.2575 5.6575 9 P 0 ;1
L 9.2575 5.7075 9.2575 5.7075 9 P 0 ;1
L 9.2575 5.7575 9.2575 5.7575 9 P 0 ;1
L 9.2575 5.8075 9.2575 5.8075 9 P 0 ;1
L 9.2575 5.8575 9.2575 5.8575 9 P 0 ;1
L 9.2575 5.9075 9.2575 5.9075 9 P 0 ;1
L 9.3075 0.1575 9.3075 0.1575 9 P 0 ;1
L 9.3075 0.2075 9.3075 0.2075 9 P 0 ;1
L 9.3075 0.2575 9.3075 0.2575 9 P 0 ;1
L 9.3075 0.3075 9.3075 0.3075 9 P 0 ;1
L 9.3075 0.3575 9.3075 0.3575 9 P 0 ;1
L 9.3075 0.4075 9.3075 0.4075 9 P 0 ;1
L 9.3075 0.5575 9.3075 0.5575 9 P 0 ;1
L 9.3075 0.6075 9.3075 0.6075 9 P 0 ;1
L 9.3075 0.6575 9.3075 0.6575 9 P 0 ;1
L 9.3075 0.7075 9.3075 0.7075 9 P 0 ;1
L 9.3075 0.7575 9.3075 0.7575 9 P 0 ;1
L 9.3075 0.8075 9.3075 0.8075 9 P 0 ;1
L 9.3075 0.8575 9.3075 0.8575 9 P 0 ;1
L 9.3075 1.0575 9.3075 1.0575 9 P 0 ;1
L 9.3075 1.1075 9.3075 1.1075 9 P 0 ;1
L 9.3075 1.1575 9.3075 1.1575 9 P 0 ;1
L 9.3075 1.2075 9.3075 1.2075 9 P 0 ;1
L 9.3075 1.2575 9.3075 1.2575 9 P 0 ;1
L 9.3075 1.3075 9.3075 1.3075 9 P 0 ;1
L 9.3075 1.3575 9.3075 1.3575 9 P 0 ;1
L 9.3075 1.4075 9.3075 1.4075 9 P 0 ;1
L 9.3075 1.4575 9.3075 1.4575 9 P 0 ;1
L 9.3075 1.5075 9.3075 1.5075 9 P 0 ;1
L 9.3075 1.5575 9.3075 1.5575 9 P 0 ;1
L 9.3075 1.6075 9.3075 1.6075 9 P 0 ;1
L 9.3075 1.9075 9.3075 1.9075 9 P 0 ;1
L 9.3075 1.9575 9.3075 1.9575 9 P 0 ;1
L 9.3075 2.0075 9.3075 2.0075 9 P 0 ;1
L 9.3075 2.0575 9.3075 2.0575 9 P 0 ;1
L 9.3075 2.1075 9.3075 2.1075 9 P 0 ;1
L 9.3075 2.1575 9.3075 2.1575 9 P 0 ;1
L 9.3075 2.2075 9.3075 2.2075 9 P 0 ;1
L 9.3075 2.2575 9.3075 2.2575 9 P 0 ;1
L 9.3075 2.3075 9.3075 2.3075 9 P 0 ;1
L 9.3075 2.3575 9.3075 2.3575 9 P 0 ;1
L 9.3075 2.4075 9.3075 2.4075 9 P 0 ;1
L 9.3075 2.4575 9.3075 2.4575 9 P 0 ;1
L 9.3075 2.5075 9.3075 2.5075 9 P 0 ;1
L 9.3075 2.5575 9.3075 2.5575 9 P 0 ;1
L 9.3075 2.6075 9.3075 2.6075 9 P 0 ;1
L 9.3075 2.6575 9.3075 2.6575 9 P 0 ;1
L 9.3075 2.7075 9.3075 2.7075 9 P 0 ;1
L 9.3075 2.7575 9.3075 2.7575 9 P 0 ;1
L 9.3075 2.8075 9.3075 2.8075 9 P 0 ;1
L 9.3075 2.8575 9.3075 2.8575 9 P 0 ;1
L 9.3075 2.9075 9.3075 2.9075 9 P 0 ;1
L 9.3075 2.9575 9.3075 2.9575 9 P 0 ;1
L 9.3075 3.0075 9.3075 3.0075 9 P 0 ;1
L 9.3075 3.0575 9.3075 3.0575 9 P 0 ;1
L 9.3075 3.1075 9.3075 3.1075 9 P 0 ;1
L 9.3075 3.1575 9.3075 3.1575 9 P 0 ;1
L 9.3075 3.2075 9.3075 3.2075 9 P 0 ;1
L 9.3075 3.2575 9.3075 3.2575 9 P 0 ;1
L 9.3075 3.3075 9.3075 3.3075 9 P 0 ;1
L 9.3075 3.3575 9.3075 3.3575 9 P 0 ;1
L 9.3075 3.4075 9.3075 3.4075 9 P 0 ;1
L 9.3075 3.4575 9.3075 3.4575 9 P 0 ;1
L 9.3075 3.5075 9.3075 3.5075 9 P 0 ;1
L 9.3075 3.5575 9.3075 3.5575 9 P 0 ;1
L 9.3075 3.6075 9.3075 3.6075 9 P 0 ;1
L 9.3075 3.6575 9.3075 3.6575 9 P 0 ;1
L 9.3075 5.4075 9.3075 5.4075 9 P 0 ;1
L 9.3075 5.4575 9.3075 5.4575 9 P 0 ;1
L 9.3075 5.5075 9.3075 5.5075 9 P 0 ;1
L 9.3075 5.5575 9.3075 5.5575 9 P 0 ;1
L 9.3075 5.6075 9.3075 5.6075 9 P 0 ;1
L 9.3075 5.6575 9.3075 5.6575 9 P 0 ;1
L 9.3075 5.7075 9.3075 5.7075 9 P 0 ;1
L 9.3075 5.7575 9.3075 5.7575 9 P 0 ;1
L 9.3075 5.8075 9.3075 5.8075 9 P 0 ;1
L 9.3075 5.8575 9.3075 5.8575 9 P 0 ;1
L 9.3075 5.9075 9.3075 5.9075 9 P 0 ;1
L 9.3575 0.1575 9.3575 0.1575 9 P 0 ;1
L 9.3575 0.3575 9.3575 0.3575 9 P 0 ;1
L 9.3575 0.4075 9.3575 0.4075 9 P 0 ;1
L 9.3575 0.6075 9.3575 0.6075 9 P 0 ;1
L 9.3575 0.6575 9.3575 0.6575 9 P 0 ;1
L 9.3575 0.7075 9.3575 0.7075 9 P 0 ;1
L 9.3575 0.8075 9.3575 0.8075 9 P 0 ;1
L 9.3575 0.8575 9.3575 0.8575 9 P 0 ;1
L 9.3575 1.0575 9.3575 1.0575 9 P 0 ;1
L 9.3575 1.1075 9.3575 1.1075 9 P 0 ;1
L 9.3575 1.1575 9.3575 1.1575 9 P 0 ;1
L 9.3575 1.2075 9.3575 1.2075 9 P 0 ;1
L 9.3575 1.2575 9.3575 1.2575 9 P 0 ;1
L 9.3575 1.3075 9.3575 1.3075 9 P 0 ;1
L 9.3575 1.3575 9.3575 1.3575 9 P 0 ;1
L 9.3575 1.4075 9.3575 1.4075 9 P 0 ;1
L 9.3575 1.4575 9.3575 1.4575 9 P 0 ;1
L 9.3575 1.5075 9.3575 1.5075 9 P 0 ;1
L 9.3575 1.5575 9.3575 1.5575 9 P 0 ;1
L 9.3575 1.6075 9.3575 1.6075 9 P 0 ;1
L 9.3575 1.9075 9.3575 1.9075 9 P 0 ;1
L 9.3575 1.9575 9.3575 1.9575 9 P 0 ;1
L 9.3575 2.0075 9.3575 2.0075 9 P 0 ;1
L 9.3575 2.0575 9.3575 2.0575 9 P 0 ;1
L 9.3575 2.1075 9.3575 2.1075 9 P 0 ;1
L 9.3575 2.1575 9.3575 2.1575 9 P 0 ;1
L 9.3575 2.2075 9.3575 2.2075 9 P 0 ;1
L 9.3575 2.2575 9.3575 2.2575 9 P 0 ;1
L 9.3575 2.3075 9.3575 2.3075 9 P 0 ;1
L 9.3575 2.3575 9.3575 2.3575 9 P 0 ;1
L 9.3575 2.4075 9.3575 2.4075 9 P 0 ;1
L 9.3575 2.4575 9.3575 2.4575 9 P 0 ;1
L 9.3575 2.5075 9.3575 2.5075 9 P 0 ;1
L 9.3575 2.5575 9.3575 2.5575 9 P 0 ;1
L 9.3575 2.6075 9.3575 2.6075 9 P 0 ;1
L 9.3575 2.6575 9.3575 2.6575 9 P 0 ;1
L 9.3575 2.7075 9.3575 2.7075 9 P 0 ;1
L 9.3575 2.7575 9.3575 2.7575 9 P 0 ;1
L 9.3575 2.8075 9.3575 2.8075 9 P 0 ;1
L 9.3575 2.8575 9.3575 2.8575 9 P 0 ;1
L 9.3575 2.9075 9.3575 2.9075 9 P 0 ;1
L 9.3575 2.9575 9.3575 2.9575 9 P 0 ;1
L 9.3575 3.0075 9.3575 3.0075 9 P 0 ;1
L 9.3575 3.0575 9.3575 3.0575 9 P 0 ;1
L 9.3575 3.1075 9.3575 3.1075 9 P 0 ;1
L 9.3575 3.1575 9.3575 3.1575 9 P 0 ;1
L 9.3575 3.2075 9.3575 3.2075 9 P 0 ;1
L 9.3575 3.2575 9.3575 3.2575 9 P 0 ;1
L 9.3575 3.3075 9.3575 3.3075 9 P 0 ;1
L 9.3575 3.3575 9.3575 3.3575 9 P 0 ;1
L 9.3575 3.4075 9.3575 3.4075 9 P 0 ;1
L 9.3575 3.4575 9.3575 3.4575 9 P 0 ;1
L 9.3575 3.5075 9.3575 3.5075 9 P 0 ;1
L 9.3575 3.5575 9.3575 3.5575 9 P 0 ;1
L 9.3575 3.6075 9.3575 3.6075 9 P 0 ;1
L 9.3575 3.6575 9.3575 3.6575 9 P 0 ;1
L 9.3575 3.7075 9.3575 3.7075 9 P 0 ;1
L 9.3575 5.4075 9.3575 5.4075 9 P 0 ;1
L 9.3575 5.4575 9.3575 5.4575 9 P 0 ;1
L 9.3575 5.5075 9.3575 5.5075 9 P 0 ;1
L 9.3575 5.5575 9.3575 5.5575 9 P 0 ;1
L 9.3575 5.6075 9.3575 5.6075 9 P 0 ;1
L 9.3575 5.6575 9.3575 5.6575 9 P 0 ;1
L 9.3575 5.7075 9.3575 5.7075 9 P 0 ;1
L 9.3575 5.7575 9.3575 5.7575 9 P 0 ;1
L 9.3575 5.8075 9.3575 5.8075 9 P 0 ;1
L 9.3575 5.8575 9.3575 5.8575 9 P 0 ;1
L 9.3575 5.9075 9.3575 5.9075 9 P 0 ;1
L 9.4075 0.1575 9.4075 0.1575 9 P 0 ;1
L 9.4075 0.6075 9.4075 0.6075 9 P 0 ;1
L 9.4075 0.6575 9.4075 0.6575 9 P 0 ;1
L 9.4075 1.0575 9.4075 1.0575 9 P 0 ;1
L 9.4075 1.1075 9.4075 1.1075 9 P 0 ;1
L 9.4075 1.1575 9.4075 1.1575 9 P 0 ;1
L 9.4075 1.2075 9.4075 1.2075 9 P 0 ;1
L 9.4075 1.2575 9.4075 1.2575 9 P 0 ;1
L 9.4075 1.3075 9.4075 1.3075 9 P 0 ;1
L 9.4075 1.3575 9.4075 1.3575 9 P 0 ;1
L 9.4075 1.4075 9.4075 1.4075 9 P 0 ;1
L 9.4075 1.4575 9.4075 1.4575 9 P 0 ;1
L 9.4075 1.5075 9.4075 1.5075 9 P 0 ;1
L 9.4075 1.5575 9.4075 1.5575 9 P 0 ;1
L 9.4075 1.6075 9.4075 1.6075 9 P 0 ;1
L 9.4075 1.9075 9.4075 1.9075 9 P 0 ;1
L 9.4075 1.9575 9.4075 1.9575 9 P 0 ;1
L 9.4075 2.0075 9.4075 2.0075 9 P 0 ;1
L 9.4075 2.0575 9.4075 2.0575 9 P 0 ;1
L 9.4075 2.1075 9.4075 2.1075 9 P 0 ;1
L 9.4075 2.1575 9.4075 2.1575 9 P 0 ;1
L 9.4075 2.2075 9.4075 2.2075 9 P 0 ;1
L 9.4075 2.2575 9.4075 2.2575 9 P 0 ;1
L 9.4075 2.3075 9.4075 2.3075 9 P 0 ;1
L 9.4075 2.3575 9.4075 2.3575 9 P 0 ;1
L 9.4075 2.4075 9.4075 2.4075 9 P 0 ;1
L 9.4075 2.4575 9.4075 2.4575 9 P 0 ;1
L 9.4075 2.5075 9.4075 2.5075 9 P 0 ;1
L 9.4075 2.5575 9.4075 2.5575 9 P 0 ;1
L 9.4075 2.6075 9.4075 2.6075 9 P 0 ;1
L 9.4075 2.6575 9.4075 2.6575 9 P 0 ;1
L 9.4075 2.7075 9.4075 2.7075 9 P 0 ;1
L 9.4075 2.7575 9.4075 2.7575 9 P 0 ;1
L 9.4075 2.8075 9.4075 2.8075 9 P 0 ;1
L 9.4075 2.8575 9.4075 2.8575 9 P 0 ;1
L 9.4075 2.9075 9.4075 2.9075 9 P 0 ;1
L 9.4075 2.9575 9.4075 2.9575 9 P 0 ;1
L 9.4075 3.0075 9.4075 3.0075 9 P 0 ;1
L 9.4075 3.0575 9.4075 3.0575 9 P 0 ;1
L 9.4075 3.1075 9.4075 3.1075 9 P 0 ;1
L 9.4075 3.1575 9.4075 3.1575 9 P 0 ;1
L 9.4075 3.2075 9.4075 3.2075 9 P 0 ;1
L 9.4075 3.2575 9.4075 3.2575 9 P 0 ;1
L 9.4075 3.3075 9.4075 3.3075 9 P 0 ;1
L 9.4075 3.3575 9.4075 3.3575 9 P 0 ;1
L 9.4075 3.4075 9.4075 3.4075 9 P 0 ;1
L 9.4075 3.4575 9.4075 3.4575 9 P 0 ;1
L 9.4075 3.5075 9.4075 3.5075 9 P 0 ;1
L 9.4075 3.5575 9.4075 3.5575 9 P 0 ;1
L 9.4075 3.6075 9.4075 3.6075 9 P 0 ;1
L 9.4075 3.6575 9.4075 3.6575 9 P 0 ;1
L 9.4075 3.7075 9.4075 3.7075 9 P 0 ;1
L 9.4075 5.4575 9.4075 5.4575 9 P 0 ;1
L 9.4075 5.5075 9.4075 5.5075 9 P 0 ;1
L 9.4075 5.5575 9.4075 5.5575 9 P 0 ;1
L 9.4075 5.6075 9.4075 5.6075 9 P 0 ;1
L 9.4075 5.6575 9.4075 5.6575 9 P 0 ;1
L 9.4075 5.7075 9.4075 5.7075 9 P 0 ;1
L 9.4075 5.7575 9.4075 5.7575 9 P 0 ;1
L 9.4075 5.8075 9.4075 5.8075 9 P 0 ;1
L 9.4075 5.8575 9.4075 5.8575 9 P 0 ;1
L 9.4075 5.9075 9.4075 5.9075 9 P 0 ;1
L 9.4575 0.1575 9.4575 0.1575 9 P 0 ;1
L 9.4575 0.6075 9.4575 0.6075 9 P 0 ;1
L 9.4575 0.6575 9.4575 0.6575 9 P 0 ;1
L 9.4575 1.0575 9.4575 1.0575 9 P 0 ;1
L 9.4575 1.1075 9.4575 1.1075 9 P 0 ;1
L 9.4575 1.1575 9.4575 1.1575 9 P 0 ;1
L 9.4575 1.2075 9.4575 1.2075 9 P 0 ;1
L 9.4575 1.2575 9.4575 1.2575 9 P 0 ;1
L 9.4575 1.3075 9.4575 1.3075 9 P 0 ;1
L 9.4575 1.3575 9.4575 1.3575 9 P 0 ;1
L 9.4575 1.4075 9.4575 1.4075 9 P 0 ;1
L 9.4575 1.4575 9.4575 1.4575 9 P 0 ;1
L 9.4575 1.5075 9.4575 1.5075 9 P 0 ;1
L 9.4575 1.5575 9.4575 1.5575 9 P 0 ;1
L 9.4575 1.6075 9.4575 1.6075 9 P 0 ;1
L 9.4575 1.9075 9.4575 1.9075 9 P 0 ;1
L 9.4575 1.9575 9.4575 1.9575 9 P 0 ;1
L 9.4575 2.0075 9.4575 2.0075 9 P 0 ;1
L 9.4575 2.0575 9.4575 2.0575 9 P 0 ;1
L 9.4575 2.1075 9.4575 2.1075 9 P 0 ;1
L 9.4575 2.1575 9.4575 2.1575 9 P 0 ;1
L 9.4575 2.2075 9.4575 2.2075 9 P 0 ;1
L 9.4575 2.2575 9.4575 2.2575 9 P 0 ;1
L 9.4575 2.3075 9.4575 2.3075 9 P 0 ;1
L 9.4575 2.3575 9.4575 2.3575 9 P 0 ;1
L 9.4575 2.4075 9.4575 2.4075 9 P 0 ;1
L 9.4575 2.4575 9.4575 2.4575 9 P 0 ;1
L 9.4575 2.5075 9.4575 2.5075 9 P 0 ;1
L 9.4575 2.5575 9.4575 2.5575 9 P 0 ;1
L 9.4575 2.6075 9.4575 2.6075 9 P 0 ;1
L 9.4575 2.6575 9.4575 2.6575 9 P 0 ;1
L 9.4575 2.7075 9.4575 2.7075 9 P 0 ;1
L 9.4575 2.7575 9.4575 2.7575 9 P 0 ;1
L 9.4575 2.8075 9.4575 2.8075 9 P 0 ;1
L 9.4575 2.8575 9.4575 2.8575 9 P 0 ;1
L 9.4575 2.9075 9.4575 2.9075 9 P 0 ;1
L 9.4575 2.9575 9.4575 2.9575 9 P 0 ;1
L 9.4575 3.0075 9.4575 3.0075 9 P 0 ;1
L 9.4575 3.0575 9.4575 3.0575 9 P 0 ;1
L 9.4575 3.1075 9.4575 3.1075 9 P 0 ;1
L 9.4575 3.1575 9.4575 3.1575 9 P 0 ;1
L 9.4575 3.2075 9.4575 3.2075 9 P 0 ;1
L 9.4575 3.2575 9.4575 3.2575 9 P 0 ;1
L 9.4575 3.3075 9.4575 3.3075 9 P 0 ;1
L 9.4575 3.3575 9.4575 3.3575 9 P 0 ;1
L 9.4575 3.4075 9.4575 3.4075 9 P 0 ;1
L 9.4575 3.4575 9.4575 3.4575 9 P 0 ;1
L 9.4575 3.5075 9.4575 3.5075 9 P 0 ;1
L 9.4575 3.5575 9.4575 3.5575 9 P 0 ;1
L 9.4575 3.6075 9.4575 3.6075 9 P 0 ;1
L 9.4575 3.6575 9.4575 3.6575 9 P 0 ;1
L 9.4575 3.7075 9.4575 3.7075 9 P 0 ;1
L 9.4575 3.7575 9.4575 3.7575 9 P 0 ;1
L 9.4575 5.4075 9.4575 5.4075 9 P 0 ;1
L 9.4575 5.4575 9.4575 5.4575 9 P 0 ;1
L 9.4575 5.5075 9.4575 5.5075 9 P 0 ;1
L 9.4575 5.5575 9.4575 5.5575 9 P 0 ;1
L 9.4575 5.6075 9.4575 5.6075 9 P 0 ;1
L 9.4575 5.6575 9.4575 5.6575 9 P 0 ;1
L 9.4575 5.7075 9.4575 5.7075 9 P 0 ;1
L 9.4575 5.7575 9.4575 5.7575 9 P 0 ;1
L 9.4575 5.8075 9.4575 5.8075 9 P 0 ;1
L 9.4575 5.8575 9.4575 5.8575 9 P 0 ;1
L 9.4575 5.9075 9.4575 5.9075 9 P 0 ;1
L 9.5075 0.1575 9.5075 0.1575 9 P 0 ;1
L 9.5075 0.4575 9.5075 0.4575 9 P 0 ;1
L 9.5075 0.5575 9.5075 0.5575 9 P 0 ;1
L 9.5075 0.6075 9.5075 0.6075 9 P 0 ;1
L 9.5075 1.0575 9.5075 1.0575 9 P 0 ;1
L 9.5075 1.1075 9.5075 1.1075 9 P 0 ;1
L 9.5075 1.1575 9.5075 1.1575 9 P 0 ;1
L 9.5075 1.2075 9.5075 1.2075 9 P 0 ;1
L 9.5075 1.2575 9.5075 1.2575 9 P 0 ;1
L 9.5075 1.3075 9.5075 1.3075 9 P 0 ;1
L 9.5075 1.3575 9.5075 1.3575 9 P 0 ;1
L 9.5075 1.4075 9.5075 1.4075 9 P 0 ;1
L 9.5075 1.4575 9.5075 1.4575 9 P 0 ;1
L 9.5075 1.5075 9.5075 1.5075 9 P 0 ;1
L 9.5075 1.5575 9.5075 1.5575 9 P 0 ;1
L 9.5075 1.6075 9.5075 1.6075 9 P 0 ;1
L 9.5075 1.9075 9.5075 1.9075 9 P 0 ;1
L 9.5075 1.9575 9.5075 1.9575 9 P 0 ;1
L 9.5075 2.0075 9.5075 2.0075 9 P 0 ;1
L 9.5075 2.0575 9.5075 2.0575 9 P 0 ;1
L 9.5075 2.1075 9.5075 2.1075 9 P 0 ;1
L 9.5075 2.1575 9.5075 2.1575 9 P 0 ;1
L 9.5075 2.2075 9.5075 2.2075 9 P 0 ;1
L 9.5075 2.2575 9.5075 2.2575 9 P 0 ;1
L 9.5075 2.3075 9.5075 2.3075 9 P 0 ;1
L 9.5075 2.3575 9.5075 2.3575 9 P 0 ;1
L 9.5075 2.4075 9.5075 2.4075 9 P 0 ;1
L 9.5075 2.4575 9.5075 2.4575 9 P 0 ;1
L 9.5075 2.5075 9.5075 2.5075 9 P 0 ;1
L 9.5075 2.5575 9.5075 2.5575 9 P 0 ;1
L 9.5075 2.6075 9.5075 2.6075 9 P 0 ;1
L 9.5075 2.6575 9.5075 2.6575 9 P 0 ;1
L 9.5075 2.7075 9.5075 2.7075 9 P 0 ;1
L 9.5075 2.7575 9.5075 2.7575 9 P 0 ;1
L 9.5075 2.8075 9.5075 2.8075 9 P 0 ;1
L 9.5075 2.8575 9.5075 2.8575 9 P 0 ;1
L 9.5075 2.9075 9.5075 2.9075 9 P 0 ;1
L 9.5075 2.9575 9.5075 2.9575 9 P 0 ;1
L 9.5075 3.0075 9.5075 3.0075 9 P 0 ;1
L 9.5075 3.0575 9.5075 3.0575 9 P 0 ;1
L 9.5075 3.1075 9.5075 3.1075 9 P 0 ;1
L 9.5075 3.1575 9.5075 3.1575 9 P 0 ;1
L 9.5075 3.2075 9.5075 3.2075 9 P 0 ;1
L 9.5075 3.2575 9.5075 3.2575 9 P 0 ;1
L 9.5075 3.3075 9.5075 3.3075 9 P 0 ;1
L 9.5075 3.3575 9.5075 3.3575 9 P 0 ;1
L 9.5075 3.4075 9.5075 3.4075 9 P 0 ;1
L 9.5075 3.4575 9.5075 3.4575 9 P 0 ;1
L 9.5075 3.5075 9.5075 3.5075 9 P 0 ;1
L 9.5075 3.5575 9.5075 3.5575 9 P 0 ;1
L 9.5075 3.6075 9.5075 3.6075 9 P 0 ;1
L 9.5075 3.6575 9.5075 3.6575 9 P 0 ;1
L 9.5075 3.7075 9.5075 3.7075 9 P 0 ;1
L 9.5075 3.7575 9.5075 3.7575 9 P 0 ;1
L 9.5075 3.8075 9.5075 3.8075 9 P 0 ;1
L 9.5075 3.8575 9.5075 3.8575 9 P 0 ;1
L 9.5075 5.4075 9.5075 5.4075 9 P 0 ;1
L 9.5075 5.4575 9.5075 5.4575 9 P 0 ;1
L 9.5075 5.5075 9.5075 5.5075 9 P 0 ;1
L 9.5075 5.5575 9.5075 5.5575 9 P 0 ;1
L 9.5075 5.6075 9.5075 5.6075 9 P 0 ;1
L 9.5075 5.6575 9.5075 5.6575 9 P 0 ;1
L 9.5075 5.7075 9.5075 5.7075 9 P 0 ;1
L 9.5075 5.7575 9.5075 5.7575 9 P 0 ;1
L 9.5075 5.8075 9.5075 5.8075 9 P 0 ;1
L 9.5075 5.8575 9.5075 5.8575 9 P 0 ;1
L 9.5075 5.9075 9.5075 5.9075 9 P 0 ;1
L 9.5575 0.1575 9.5575 0.1575 9 P 0 ;1
L 9.5575 0.4575 9.5575 0.4575 9 P 0 ;1
L 9.5575 0.5075 9.5575 0.5075 9 P 0 ;1
L 9.5575 0.5575 9.5575 0.5575 9 P 0 ;1
L 9.5575 0.6075 9.5575 0.6075 9 P 0 ;1
L 9.5575 0.8075 9.5575 0.8075 9 P 0 ;1
L 9.5575 0.8575 9.5575 0.8575 9 P 0 ;1
L 9.5575 1.0575 9.5575 1.0575 9 P 0 ;1
L 9.5575 1.1075 9.5575 1.1075 9 P 0 ;1
L 9.5575 1.1575 9.5575 1.1575 9 P 0 ;1
L 9.5575 1.2075 9.5575 1.2075 9 P 0 ;1
L 9.5575 1.2575 9.5575 1.2575 9 P 0 ;1
L 9.5575 1.3075 9.5575 1.3075 9 P 0 ;1
L 9.5575 1.3575 9.5575 1.3575 9 P 0 ;1
L 9.5575 1.4075 9.5575 1.4075 9 P 0 ;1
L 9.5575 1.4575 9.5575 1.4575 9 P 0 ;1
L 9.5575 1.5075 9.5575 1.5075 9 P 0 ;1
L 9.5575 1.5575 9.5575 1.5575 9 P 0 ;1
L 9.5575 1.6075 9.5575 1.6075 9 P 0 ;1
L 9.5575 1.9075 9.5575 1.9075 9 P 0 ;1
L 9.5575 1.9575 9.5575 1.9575 9 P 0 ;1
L 9.5575 2.0075 9.5575 2.0075 9 P 0 ;1
L 9.5575 2.0575 9.5575 2.0575 9 P 0 ;1
L 9.5575 2.1075 9.5575 2.1075 9 P 0 ;1
L 9.5575 2.1575 9.5575 2.1575 9 P 0 ;1
L 9.5575 2.2075 9.5575 2.2075 9 P 0 ;1
L 9.5575 2.2575 9.5575 2.2575 9 P 0 ;1
L 9.5575 2.3075 9.5575 2.3075 9 P 0 ;1
L 9.5575 2.3575 9.5575 2.3575 9 P 0 ;1
L 9.5575 2.4075 9.5575 2.4075 9 P 0 ;1
L 9.5575 2.4575 9.5575 2.4575 9 P 0 ;1
L 9.5575 2.5075 9.5575 2.5075 9 P 0 ;1
L 9.5575 2.5575 9.5575 2.5575 9 P 0 ;1
L 9.5575 2.6075 9.5575 2.6075 9 P 0 ;1
L 9.5575 2.6575 9.5575 2.6575 9 P 0 ;1
L 9.5575 2.7075 9.5575 2.7075 9 P 0 ;1
L 9.5575 2.7575 9.5575 2.7575 9 P 0 ;1
L 9.5575 2.8075 9.5575 2.8075 9 P 0 ;1
L 9.5575 2.8575 9.5575 2.8575 9 P 0 ;1
L 9.5575 2.9075 9.5575 2.9075 9 P 0 ;1
L 9.5575 2.9575 9.5575 2.9575 9 P 0 ;1
L 9.5575 3.0075 9.5575 3.0075 9 P 0 ;1
L 9.5575 3.0575 9.5575 3.0575 9 P 0 ;1
L 9.5575 3.1075 9.5575 3.1075 9 P 0 ;1
L 9.5575 3.1575 9.5575 3.1575 9 P 0 ;1
L 9.5575 3.2075 9.5575 3.2075 9 P 0 ;1
L 9.5575 3.2575 9.5575 3.2575 9 P 0 ;1
L 9.5575 3.3075 9.5575 3.3075 9 P 0 ;1
L 9.5575 3.3575 9.5575 3.3575 9 P 0 ;1
L 9.5575 3.4075 9.5575 3.4075 9 P 0 ;1
L 9.5575 3.4575 9.5575 3.4575 9 P 0 ;1
L 9.5575 3.5075 9.5575 3.5075 9 P 0 ;1
L 9.5575 3.5575 9.5575 3.5575 9 P 0 ;1
L 9.5575 3.6075 9.5575 3.6075 9 P 0 ;1
L 9.5575 3.6575 9.5575 3.6575 9 P 0 ;1
L 9.5575 3.7075 9.5575 3.7075 9 P 0 ;1
L 9.5575 3.7575 9.5575 3.7575 9 P 0 ;1
L 9.5575 3.8075 9.5575 3.8075 9 P 0 ;1
L 9.5575 3.8575 9.5575 3.8575 9 P 0 ;1
L 9.5575 3.9075 9.5575 3.9075 9 P 0 ;1
L 9.5575 5.2575 9.5575 5.2575 9 P 0 ;1
L 9.5575 5.3075 9.5575 5.3075 9 P 0 ;1
L 9.5575 5.3575 9.5575 5.3575 9 P 0 ;1
L 9.5575 5.4075 9.5575 5.4075 9 P 0 ;1
L 9.5575 5.4575 9.5575 5.4575 9 P 0 ;1
L 9.5575 5.5075 9.5575 5.5075 9 P 0 ;1
L 9.5575 5.5575 9.5575 5.5575 9 P 0 ;1
L 9.5575 5.6075 9.5575 5.6075 9 P 0 ;1
L 9.5575 5.6575 9.5575 5.6575 9 P 0 ;1
L 9.5575 5.7075 9.5575 5.7075 9 P 0 ;1
L 9.5575 5.7575 9.5575 5.7575 9 P 0 ;1
L 9.5575 5.8075 9.5575 5.8075 9 P 0 ;1
L 9.5575 5.8575 9.5575 5.8575 9 P 0 ;1
L 9.5575 5.9075 9.5575 5.9075 9 P 0 ;1
L 9.6075 0.1575 9.6075 0.1575 9 P 0 ;1
L 9.6075 0.4575 9.6075 0.4575 9 P 0 ;1
L 9.6075 0.5075 9.6075 0.5075 9 P 0 ;1
L 9.6075 0.5575 9.6075 0.5575 9 P 0 ;1
L 9.6075 0.6075 9.6075 0.6075 9 P 0 ;1
L 9.6075 1.0575 9.6075 1.0575 9 P 0 ;1
L 9.6075 1.1075 9.6075 1.1075 9 P 0 ;1
L 9.6075 1.1575 9.6075 1.1575 9 P 0 ;1
L 9.6075 1.2075 9.6075 1.2075 9 P 0 ;1
L 9.6075 1.2575 9.6075 1.2575 9 P 0 ;1
L 9.6075 1.3075 9.6075 1.3075 9 P 0 ;1
L 9.6075 1.3575 9.6075 1.3575 9 P 0 ;1
L 9.6075 1.4075 9.6075 1.4075 9 P 0 ;1
L 9.6075 1.4575 9.6075 1.4575 9 P 0 ;1
L 9.6075 1.5075 9.6075 1.5075 9 P 0 ;1
L 9.6075 1.5575 9.6075 1.5575 9 P 0 ;1
L 9.6075 1.6075 9.6075 1.6075 9 P 0 ;1
L 9.6075 1.9075 9.6075 1.9075 9 P 0 ;1
L 9.6075 1.9575 9.6075 1.9575 9 P 0 ;1
L 9.6075 2.0075 9.6075 2.0075 9 P 0 ;1
L 9.6075 2.0575 9.6075 2.0575 9 P 0 ;1
L 9.6075 2.1075 9.6075 2.1075 9 P 0 ;1
L 9.6075 2.1575 9.6075 2.1575 9 P 0 ;1
L 9.6075 2.2075 9.6075 2.2075 9 P 0 ;1
L 9.6075 2.2575 9.6075 2.2575 9 P 0 ;1
L 9.6075 2.3075 9.6075 2.3075 9 P 0 ;1
L 9.6075 2.3575 9.6075 2.3575 9 P 0 ;1
L 9.6075 2.4075 9.6075 2.4075 9 P 0 ;1
L 9.6075 2.4575 9.6075 2.4575 9 P 0 ;1
L 9.6075 2.5075 9.6075 2.5075 9 P 0 ;1
L 9.6075 2.5575 9.6075 2.5575 9 P 0 ;1
L 9.6075 2.6075 9.6075 2.6075 9 P 0 ;1
L 9.6075 2.6575 9.6075 2.6575 9 P 0 ;1
L 9.6075 2.7075 9.6075 2.7075 9 P 0 ;1
L 9.6075 2.7575 9.6075 2.7575 9 P 0 ;1
L 9.6075 2.8075 9.6075 2.8075 9 P 0 ;1
L 9.6075 2.8575 9.6075 2.8575 9 P 0 ;1
L 9.6075 2.9075 9.6075 2.9075 9 P 0 ;1
L 9.6075 2.9575 9.6075 2.9575 9 P 0 ;1
L 9.6075 3.0075 9.6075 3.0075 9 P 0 ;1
L 9.6075 3.0575 9.6075 3.0575 9 P 0 ;1
L 9.6075 3.1075 9.6075 3.1075 9 P 0 ;1
L 9.6075 3.1575 9.6075 3.1575 9 P 0 ;1
L 9.6075 3.2075 9.6075 3.2075 9 P 0 ;1
L 9.6075 3.2575 9.6075 3.2575 9 P 0 ;1
L 9.6075 3.3075 9.6075 3.3075 9 P 0 ;1
L 9.6075 3.3575 9.6075 3.3575 9 P 0 ;1
L 9.6075 3.4075 9.6075 3.4075 9 P 0 ;1
L 9.6075 3.4575 9.6075 3.4575 9 P 0 ;1
L 9.6075 3.5075 9.6075 3.5075 9 P 0 ;1
L 9.6075 3.5575 9.6075 3.5575 9 P 0 ;1
L 9.6075 3.6075 9.6075 3.6075 9 P 0 ;1
L 9.6075 3.6575 9.6075 3.6575 9 P 0 ;1
L 9.6075 3.7075 9.6075 3.7075 9 P 0 ;1
L 9.6075 3.7575 9.6075 3.7575 9 P 0 ;1
L 9.6075 3.8075 9.6075 3.8075 9 P 0 ;1
L 9.6075 3.8575 9.6075 3.8575 9 P 0 ;1
L 9.6075 3.9075 9.6075 3.9075 9 P 0 ;1
L 9.6075 3.9575 9.6075 3.9575 9 P 0 ;1
L 9.6075 5.2575 9.6075 5.2575 9 P 0 ;1
L 9.6075 5.3075 9.6075 5.3075 9 P 0 ;1
L 9.6075 5.3575 9.6075 5.3575 9 P 0 ;1
L 9.6075 5.4075 9.6075 5.4075 9 P 0 ;1
L 9.6075 5.4575 9.6075 5.4575 9 P 0 ;1
L 9.6075 5.5075 9.6075 5.5075 9 P 0 ;1
L 9.6075 5.5575 9.6075 5.5575 9 P 0 ;1
L 9.6075 5.6075 9.6075 5.6075 9 P 0 ;1
L 9.6075 5.6575 9.6075 5.6575 9 P 0 ;1
L 9.6075 5.7075 9.6075 5.7075 9 P 0 ;1
L 9.6075 5.7575 9.6075 5.7575 9 P 0 ;1
L 9.6075 5.8075 9.6075 5.8075 9 P 0 ;1
L 9.6075 5.8575 9.6075 5.8575 9 P 0 ;1
L 9.6075 5.9075 9.6075 5.9075 9 P 0 ;1
L 9.6575 0.1575 9.6575 0.1575 9 P 0 ;1
L 9.6575 0.2075 9.6575 0.2075 9 P 0 ;1
L 9.6575 0.2575 9.6575 0.2575 9 P 0 ;1
L 9.6575 0.3075 9.6575 0.3075 9 P 0 ;1
L 9.6575 0.3575 9.6575 0.3575 9 P 0 ;1
L 9.6575 0.4075 9.6575 0.4075 9 P 0 ;1
L 9.6575 0.4575 9.6575 0.4575 9 P 0 ;1
L 9.6575 0.5075 9.6575 0.5075 9 P 0 ;1
L 9.6575 0.5575 9.6575 0.5575 9 P 0 ;1
L 9.6575 0.6075 9.6575 0.6075 9 P 0 ;1
L 9.6575 1.0575 9.6575 1.0575 9 P 0 ;1
L 9.6575 1.1075 9.6575 1.1075 9 P 0 ;1
L 9.6575 1.1575 9.6575 1.1575 9 P 0 ;1
L 9.6575 1.2075 9.6575 1.2075 9 P 0 ;1
L 9.6575 1.2575 9.6575 1.2575 9 P 0 ;1
L 9.6575 1.3075 9.6575 1.3075 9 P 0 ;1
L 9.6575 1.3575 9.6575 1.3575 9 P 0 ;1
L 9.6575 1.4075 9.6575 1.4075 9 P 0 ;1
L 9.6575 1.4575 9.6575 1.4575 9 P 0 ;1
L 9.6575 1.5075 9.6575 1.5075 9 P 0 ;1
L 9.6575 1.5575 9.6575 1.5575 9 P 0 ;1
L 9.6575 1.6075 9.6575 1.6075 9 P 0 ;1
L 9.6575 1.9075 9.6575 1.9075 9 P 0 ;1
L 9.6575 1.9575 9.6575 1.9575 9 P 0 ;1
L 9.6575 2.0075 9.6575 2.0075 9 P 0 ;1
L 9.6575 2.0575 9.6575 2.0575 9 P 0 ;1
L 9.6575 2.1075 9.6575 2.1075 9 P 0 ;1
L 9.6575 2.1575 9.6575 2.1575 9 P 0 ;1
L 9.6575 2.2075 9.6575 2.2075 9 P 0 ;1
L 9.6575 2.2575 9.6575 2.2575 9 P 0 ;1
L 9.6575 2.3075 9.6575 2.3075 9 P 0 ;1
L 9.6575 2.3575 9.6575 2.3575 9 P 0 ;1
L 9.6575 2.4075 9.6575 2.4075 9 P 0 ;1
L 9.6575 2.4575 9.6575 2.4575 9 P 0 ;1
L 9.6575 2.5075 9.6575 2.5075 9 P 0 ;1
L 9.6575 2.5575 9.6575 2.5575 9 P 0 ;1
L 9.6575 2.6075 9.6575 2.6075 9 P 0 ;1
L 9.6575 2.6575 9.6575 2.6575 9 P 0 ;1
L 9.6575 2.7075 9.6575 2.7075 9 P 0 ;1
L 9.6575 2.7575 9.6575 2.7575 9 P 0 ;1
L 9.6575 2.8075 9.6575 2.8075 9 P 0 ;1
L 9.6575 2.8575 9.6575 2.8575 9 P 0 ;1
L 9.6575 2.9075 9.6575 2.9075 9 P 0 ;1
L 9.6575 2.9575 9.6575 2.9575 9 P 0 ;1
L 9.6575 3.0075 9.6575 3.0075 9 P 0 ;1
L 9.6575 3.0575 9.6575 3.0575 9 P 0 ;1
L 9.6575 3.1075 9.6575 3.1075 9 P 0 ;1
L 9.6575 3.1575 9.6575 3.1575 9 P 0 ;1
L 9.6575 3.2075 9.6575 3.2075 9 P 0 ;1
L 9.6575 3.2575 9.6575 3.2575 9 P 0 ;1
L 9.6575 3.3075 9.6575 3.3075 9 P 0 ;1
L 9.6575 3.3575 9.6575 3.3575 9 P 0 ;1
L 9.6575 3.4075 9.6575 3.4075 9 P 0 ;1
L 9.6575 3.4575 9.6575 3.4575 9 P 0 ;1
L 9.6575 3.5075 9.6575 3.5075 9 P 0 ;1
L 9.6575 3.5575 9.6575 3.5575 9 P 0 ;1
L 9.6575 3.6075 9.6575 3.6075 9 P 0 ;1
L 9.6575 3.6575 9.6575 3.6575 9 P 0 ;1
L 9.6575 3.7075 9.6575 3.7075 9 P 0 ;1
L 9.6575 3.7575 9.6575 3.7575 9 P 0 ;1
L 9.6575 3.8075 9.6575 3.8075 9 P 0 ;1
L 9.6575 3.8575 9.6575 3.8575 9 P 0 ;1
L 9.6575 3.9075 9.6575 3.9075 9 P 0 ;1
L 9.6575 3.9575 9.6575 3.9575 9 P 0 ;1
L 9.6575 4.0075 9.6575 4.0075 9 P 0 ;1
L 9.6575 4.0575 9.6575 4.0575 9 P 0 ;1
L 9.6575 4.1075 9.6575 4.1075 9 P 0 ;1
L 9.6575 4.1575 9.6575 4.1575 9 P 0 ;1
L 9.6575 4.6575 9.6575 4.6575 9 P 0 ;1
L 9.6575 5.2075 9.6575 5.2075 9 P 0 ;1
L 9.6575 5.2575 9.6575 5.2575 9 P 0 ;1
L 9.6575 5.3075 9.6575 5.3075 9 P 0 ;1
L 9.6575 5.3575 9.6575 5.3575 9 P 0 ;1
L 9.6575 5.4075 9.6575 5.4075 9 P 0 ;1
L 9.6575 5.4575 9.6575 5.4575 9 P 0 ;1
L 9.6575 5.5075 9.6575 5.5075 9 P 0 ;1
L 9.6575 5.5575 9.6575 5.5575 9 P 0 ;1
L 9.6575 5.6075 9.6575 5.6075 9 P 0 ;1
L 9.6575 5.6575 9.6575 5.6575 9 P 0 ;1
L 9.6575 5.7075 9.6575 5.7075 9 P 0 ;1
L 9.6575 5.7575 9.6575 5.7575 9 P 0 ;1
L 9.6575 5.8075 9.6575 5.8075 9 P 0 ;1
L 9.6575 5.8575 9.6575 5.8575 9 P 0 ;1
L 9.6575 5.9075 9.6575 5.9075 9 P 0 ;1
L 9.7075 0.1575 9.7075 0.1575 9 P 0 ;1
L 9.7075 0.2075 9.7075 0.2075 9 P 0 ;1
L 9.7075 0.2575 9.7075 0.2575 9 P 0 ;1
L 9.7075 0.3075 9.7075 0.3075 9 P 0 ;1
L 9.7075 0.3575 9.7075 0.3575 9 P 0 ;1
L 9.7075 0.4075 9.7075 0.4075 9 P 0 ;1
L 9.7075 0.4575 9.7075 0.4575 9 P 0 ;1
L 9.7075 0.5075 9.7075 0.5075 9 P 0 ;1
L 9.7075 0.5575 9.7075 0.5575 9 P 0 ;1
L 9.7075 0.6075 9.7075 0.6075 9 P 0 ;1
L 9.7075 0.6575 9.7075 0.6575 9 P 0 ;1
L 9.7075 0.8575 9.7075 0.8575 9 P 0 ;1
L 9.7075 1.1075 9.7075 1.1075 9 P 0 ;1
L 9.7075 1.1575 9.7075 1.1575 9 P 0 ;1
L 9.7075 1.2075 9.7075 1.2075 9 P 0 ;1
L 9.7075 1.2575 9.7075 1.2575 9 P 0 ;1
L 9.7075 1.3075 9.7075 1.3075 9 P 0 ;1
L 9.7075 1.3575 9.7075 1.3575 9 P 0 ;1
L 9.7075 1.4075 9.7075 1.4075 9 P 0 ;1
L 9.7075 1.4575 9.7075 1.4575 9 P 0 ;1
L 9.7075 1.5075 9.7075 1.5075 9 P 0 ;1
L 9.7075 1.5575 9.7075 1.5575 9 P 0 ;1
L 9.7075 1.6075 9.7075 1.6075 9 P 0 ;1
L 9.7075 1.9075 9.7075 1.9075 9 P 0 ;1
L 9.7075 1.9575 9.7075 1.9575 9 P 0 ;1
L 9.7075 2.0075 9.7075 2.0075 9 P 0 ;1
L 9.7075 2.0575 9.7075 2.0575 9 P 0 ;1
L 9.7075 2.1075 9.7075 2.1075 9 P 0 ;1
L 9.7075 2.1575 9.7075 2.1575 9 P 0 ;1
L 9.7075 2.2075 9.7075 2.2075 9 P 0 ;1
L 9.7075 2.2575 9.7075 2.2575 9 P 0 ;1
L 9.7075 2.3075 9.7075 2.3075 9 P 0 ;1
L 9.7075 2.3575 9.7075 2.3575 9 P 0 ;1
L 9.7075 2.4075 9.7075 2.4075 9 P 0 ;1
L 9.7075 2.4575 9.7075 2.4575 9 P 0 ;1
L 9.7075 2.5075 9.7075 2.5075 9 P 0 ;1
L 9.7075 2.5575 9.7075 2.5575 9 P 0 ;1
L 9.7075 2.6075 9.7075 2.6075 9 P 0 ;1
L 9.7075 2.6575 9.7075 2.6575 9 P 0 ;1
L 9.7075 2.7075 9.7075 2.7075 9 P 0 ;1
L 9.7075 2.7575 9.7075 2.7575 9 P 0 ;1
L 9.7075 2.8075 9.7075 2.8075 9 P 0 ;1
L 9.7075 2.8575 9.7075 2.8575 9 P 0 ;1
L 9.7075 2.9075 9.7075 2.9075 9 P 0 ;1
L 9.7075 2.9575 9.7075 2.9575 9 P 0 ;1
L 9.7075 3.0075 9.7075 3.0075 9 P 0 ;1
L 9.7075 3.0575 9.7075 3.0575 9 P 0 ;1
L 9.7075 3.1075 9.7075 3.1075 9 P 0 ;1
L 9.7075 3.1575 9.7075 3.1575 9 P 0 ;1
L 9.7075 3.2075 9.7075 3.2075 9 P 0 ;1
L 9.7075 3.2575 9.7075 3.2575 9 P 0 ;1
L 9.7075 3.3075 9.7075 3.3075 9 P 0 ;1
L 9.7075 3.3575 9.7075 3.3575 9 P 0 ;1
L 9.7075 3.4075 9.7075 3.4075 9 P 0 ;1
L 9.7075 3.4575 9.7075 3.4575 9 P 0 ;1
L 9.7075 3.5075 9.7075 3.5075 9 P 0 ;1
L 9.7075 3.5575 9.7075 3.5575 9 P 0 ;1
L 9.7075 3.6075 9.7075 3.6075 9 P 0 ;1
L 9.7075 3.6575 9.7075 3.6575 9 P 0 ;1
L 9.7075 3.7075 9.7075 3.7075 9 P 0 ;1
L 9.7075 3.7575 9.7075 3.7575 9 P 0 ;1
L 9.7075 3.8075 9.7075 3.8075 9 P 0 ;1
L 9.7075 3.8575 9.7075 3.8575 9 P 0 ;1
L 9.7075 3.9075 9.7075 3.9075 9 P 0 ;1
L 9.7075 3.9575 9.7075 3.9575 9 P 0 ;1
L 9.7075 4.0075 9.7075 4.0075 9 P 0 ;1
L 9.7075 4.0575 9.7075 4.0575 9 P 0 ;1
L 9.7075 4.1075 9.7075 4.1075 9 P 0 ;1
L 9.7075 4.1575 9.7075 4.1575 9 P 0 ;1
L 9.7075 4.2075 9.7075 4.2075 9 P 0 ;1
L 9.7075 4.2575 9.7075 4.2575 9 P 0 ;1
L 9.7075 4.3075 9.7075 4.3075 9 P 0 ;1
L 9.7075 4.3575 9.7075 4.3575 9 P 0 ;1
L 9.7075 4.4075 9.7075 4.4075 9 P 0 ;1
L 9.7075 4.6075 9.7075 4.6075 9 P 0 ;1
L 9.7075 4.6575 9.7075 4.6575 9 P 0 ;1
L 9.7075 5.1575 9.7075 5.1575 9 P 0 ;1
L 9.7075 5.2075 9.7075 5.2075 9 P 0 ;1
L 9.7075 5.2575 9.7075 5.2575 9 P 0 ;1
L 9.7075 5.3075 9.7075 5.3075 9 P 0 ;1
L 9.7075 5.3575 9.7075 5.3575 9 P 0 ;1
L 9.7075 5.4075 9.7075 5.4075 9 P 0 ;1
L 9.7075 5.4575 9.7075 5.4575 9 P 0 ;1
L 9.7075 5.5075 9.7075 5.5075 9 P 0 ;1
L 9.7075 5.5575 9.7075 5.5575 9 P 0 ;1
L 9.7075 5.6075 9.7075 5.6075 9 P 0 ;1
L 9.7075 5.6575 9.7075 5.6575 9 P 0 ;1
L 9.7075 5.7075 9.7075 5.7075 9 P 0 ;1
L 9.7075 5.7575 9.7075 5.7575 9 P 0 ;1
L 9.7075 5.8075 9.7075 5.8075 9 P 0 ;1
L 9.7075 5.8575 9.7075 5.8575 9 P 0 ;1
L 9.7075 5.9075 9.7075 5.9075 9 P 0 ;1
L 9.7575 0.1575 9.7575 0.1575 9 P 0 ;1
L 9.7575 0.2075 9.7575 0.2075 9 P 0 ;1
L 9.7575 0.2575 9.7575 0.2575 9 P 0 ;1
L 9.7575 0.3075 9.7575 0.3075 9 P 0 ;1
L 9.7575 0.3575 9.7575 0.3575 9 P 0 ;1
L 9.7575 0.4075 9.7575 0.4075 9 P 0 ;1
L 9.7575 0.4575 9.7575 0.4575 9 P 0 ;1
L 9.7575 0.5075 9.7575 0.5075 9 P 0 ;1
L 9.7575 0.5575 9.7575 0.5575 9 P 0 ;1
L 9.7575 0.6075 9.7575 0.6075 9 P 0 ;1
L 9.7575 0.6575 9.7575 0.6575 9 P 0 ;1
L 9.7575 0.7075 9.7575 0.7075 9 P 0 ;1
L 9.7575 0.7575 9.7575 0.7575 9 P 0 ;1
L 9.7575 0.8075 9.7575 0.8075 9 P 0 ;1
L 9.7575 0.8575 9.7575 0.8575 9 P 0 ;1
L 9.7575 0.9075 9.7575 0.9075 9 P 0 ;1
L 9.7575 1.1575 9.7575 1.1575 9 P 0 ;1
L 9.7575 1.2075 9.7575 1.2075 9 P 0 ;1
L 9.7575 1.2575 9.7575 1.2575 9 P 0 ;1
L 9.7575 1.3075 9.7575 1.3075 9 P 0 ;1
L 9.7575 1.3575 9.7575 1.3575 9 P 0 ;1
L 9.7575 1.4075 9.7575 1.4075 9 P 0 ;1
L 9.7575 1.4575 9.7575 1.4575 9 P 0 ;1
L 9.7575 1.5075 9.7575 1.5075 9 P 0 ;1
L 9.7575 1.5575 9.7575 1.5575 9 P 0 ;1
L 9.7575 1.6075 9.7575 1.6075 9 P 0 ;1
L 9.7575 1.9575 9.7575 1.9575 9 P 0 ;1
L 9.7575 2.0075 9.7575 2.0075 9 P 0 ;1
L 9.7575 2.0575 9.7575 2.0575 9 P 0 ;1
L 9.7575 2.1075 9.7575 2.1075 9 P 0 ;1
L 9.7575 2.1575 9.7575 2.1575 9 P 0 ;1
L 9.7575 2.2075 9.7575 2.2075 9 P 0 ;1
L 9.7575 2.2575 9.7575 2.2575 9 P 0 ;1
L 9.7575 2.3075 9.7575 2.3075 9 P 0 ;1
L 9.7575 2.3575 9.7575 2.3575 9 P 0 ;1
L 9.7575 2.4075 9.7575 2.4075 9 P 0 ;1
L 9.7575 2.4575 9.7575 2.4575 9 P 0 ;1
L 9.7575 2.5075 9.7575 2.5075 9 P 0 ;1
L 9.7575 2.5575 9.7575 2.5575 9 P 0 ;1
L 9.7575 2.6075 9.7575 2.6075 9 P 0 ;1
L 9.7575 2.6575 9.7575 2.6575 9 P 0 ;1
L 9.7575 2.7075 9.7575 2.7075 9 P 0 ;1
L 9.7575 2.7575 9.7575 2.7575 9 P 0 ;1
L 9.7575 2.8075 9.7575 2.8075 9 P 0 ;1
L 9.7575 2.8575 9.7575 2.8575 9 P 0 ;1
L 9.7575 2.9075 9.7575 2.9075 9 P 0 ;1
L 9.7575 2.9575 9.7575 2.9575 9 P 0 ;1
L 9.7575 3.0075 9.7575 3.0075 9 P 0 ;1
L 9.7575 3.0575 9.7575 3.0575 9 P 0 ;1
L 9.7575 3.1075 9.7575 3.1075 9 P 0 ;1
L 9.7575 3.1575 9.7575 3.1575 9 P 0 ;1
L 9.7575 3.2075 9.7575 3.2075 9 P 0 ;1
L 9.7575 3.2575 9.7575 3.2575 9 P 0 ;1
L 9.7575 3.3075 9.7575 3.3075 9 P 0 ;1
L 9.7575 3.3575 9.7575 3.3575 9 P 0 ;1
L 9.7575 3.4075 9.7575 3.4075 9 P 0 ;1
L 9.7575 3.4575 9.7575 3.4575 9 P 0 ;1
L 9.7575 3.5075 9.7575 3.5075 9 P 0 ;1
L 9.7575 3.5575 9.7575 3.5575 9 P 0 ;1
L 9.7575 3.6075 9.7575 3.6075 9 P 0 ;1
L 9.7575 3.6575 9.7575 3.6575 9 P 0 ;1
L 9.7575 3.7075 9.7575 3.7075 9 P 0 ;1
L 9.7575 3.7575 9.7575 3.7575 9 P 0 ;1
L 9.7575 3.8075 9.7575 3.8075 9 P 0 ;1
L 9.7575 3.8575 9.7575 3.8575 9 P 0 ;1
L 9.7575 3.9075 9.7575 3.9075 9 P 0 ;1
L 9.7575 3.9575 9.7575 3.9575 9 P 0 ;1
L 9.7575 4.0075 9.7575 4.0075 9 P 0 ;1
L 9.7575 4.0575 9.7575 4.0575 9 P 0 ;1
L 9.7575 4.1075 9.7575 4.1075 9 P 0 ;1
L 9.7575 4.1575 9.7575 4.1575 9 P 0 ;1
L 9.7575 4.2075 9.7575 4.2075 9 P 0 ;1
L 9.7575 4.2575 9.7575 4.2575 9 P 0 ;1
L 9.7575 4.3075 9.7575 4.3075 9 P 0 ;1
L 9.7575 4.3575 9.7575 4.3575 9 P 0 ;1
L 9.7575 4.4075 9.7575 4.4075 9 P 0 ;1
L 9.7575 4.4575 9.7575 4.4575 9 P 0 ;1
L 9.7575 4.5075 9.7575 4.5075 9 P 0 ;1
L 9.7575 4.5575 9.7575 4.5575 9 P 0 ;1
L 9.7575 4.6075 9.7575 4.6075 9 P 0 ;1
L 9.7575 4.6575 9.7575 4.6575 9 P 0 ;1
L 9.7575 4.7075 9.7575 4.7075 9 P 0 ;1
L 9.7575 4.7575 9.7575 4.7575 9 P 0 ;1
L 9.7575 4.8075 9.7575 4.8075 9 P 0 ;1
L 9.7575 4.8575 9.7575 4.8575 9 P 0 ;1
L 9.7575 4.9075 9.7575 4.9075 9 P 0 ;1
L 9.7575 4.9575 9.7575 4.9575 9 P 0 ;1
L 9.7575 5.0075 9.7575 5.0075 9 P 0 ;1
L 9.7575 5.0575 9.7575 5.0575 9 P 0 ;1
L 9.7575 5.1075 9.7575 5.1075 9 P 0 ;1
L 9.7575 5.1575 9.7575 5.1575 9 P 0 ;1
L 9.7575 5.2075 9.7575 5.2075 9 P 0 ;1
L 9.7575 5.2575 9.7575 5.2575 9 P 0 ;1
L 9.7575 5.3075 9.7575 5.3075 9 P 0 ;1
L 9.7575 5.3575 9.7575 5.3575 9 P 0 ;1
L 9.7575 5.4075 9.7575 5.4075 9 P 0 ;1
L 9.7575 5.4575 9.7575 5.4575 9 P 0 ;1
L 9.7575 5.5075 9.7575 5.5075 9 P 0 ;1
L 9.7575 5.5575 9.7575 5.5575 9 P 0 ;1
L 9.7575 5.6075 9.7575 5.6075 9 P 0 ;1
L 9.7575 5.6575 9.7575 5.6575 9 P 0 ;1
L 9.7575 5.7075 9.7575 5.7075 9 P 0 ;1
L 9.7575 5.7575 9.7575 5.7575 9 P 0 ;1
L 9.7575 5.8075 9.7575 5.8075 9 P 0 ;1
L 9.7575 5.8575 9.7575 5.8575 9 P 0 ;1
L 9.7575 5.9075 9.7575 5.9075 9 P 0 ;1
L 9.8075 0.1575 9.8075 0.1575 9 P 0 ;1
L 9.8075 0.2075 9.8075 0.2075 9 P 0 ;1
L 9.8075 0.2575 9.8075 0.2575 9 P 0 ;1
L 9.8075 0.3075 9.8075 0.3075 9 P 0 ;1
L 9.8075 0.3575 9.8075 0.3575 9 P 0 ;1
L 9.8075 0.4075 9.8075 0.4075 9 P 0 ;1
L 9.8075 0.4575 9.8075 0.4575 9 P 0 ;1
L 9.8075 0.5075 9.8075 0.5075 9 P 0 ;1
L 9.8075 0.5575 9.8075 0.5575 9 P 0 ;1
L 9.8075 0.6075 9.8075 0.6075 9 P 0 ;1
L 9.8075 0.6575 9.8075 0.6575 9 P 0 ;1
L 9.8075 0.7075 9.8075 0.7075 9 P 0 ;1
L 9.8075 0.7575 9.8075 0.7575 9 P 0 ;1
L 9.8075 0.8075 9.8075 0.8075 9 P 0 ;1
L 9.8075 0.8575 9.8075 0.8575 9 P 0 ;1
L 9.8075 0.9075 9.8075 0.9075 9 P 0 ;1
L 9.8075 0.9575 9.8075 0.9575 9 P 0 ;1
L 9.8075 1.2075 9.8075 1.2075 9 P 0 ;1
L 9.8075 1.2575 9.8075 1.2575 9 P 0 ;1
L 9.8075 1.3075 9.8075 1.3075 9 P 0 ;1
L 9.8075 1.3575 9.8075 1.3575 9 P 0 ;1
L 9.8075 1.4075 9.8075 1.4075 9 P 0 ;1
L 9.8075 1.4575 9.8075 1.4575 9 P 0 ;1
L 9.8075 1.5075 9.8075 1.5075 9 P 0 ;1
L 9.8075 1.5575 9.8075 1.5575 9 P 0 ;1
L 9.8075 1.6075 9.8075 1.6075 9 P 0 ;1
L 9.8075 1.6575 9.8075 1.6575 9 P 0 ;1
L 9.8075 2.7575 9.8075 2.7575 9 P 0 ;1
L 9.8075 2.8075 9.8075 2.8075 9 P 0 ;1
L 9.8075 2.8575 9.8075 2.8575 9 P 0 ;1
L 9.8075 2.9075 9.8075 2.9075 9 P 0 ;1
L 9.8075 2.9575 9.8075 2.9575 9 P 0 ;1
L 9.8075 3.0075 9.8075 3.0075 9 P 0 ;1
L 9.8075 3.0575 9.8075 3.0575 9 P 0 ;1
L 9.8075 3.1075 9.8075 3.1075 9 P 0 ;1
L 9.8075 3.1575 9.8075 3.1575 9 P 0 ;1
L 9.8075 3.2075 9.8075 3.2075 9 P 0 ;1
L 9.8075 3.2575 9.8075 3.2575 9 P 0 ;1
L 9.8075 3.3075 9.8075 3.3075 9 P 0 ;1
L 9.8075 3.3575 9.8075 3.3575 9 P 0 ;1
L 9.8075 3.4075 9.8075 3.4075 9 P 0 ;1
L 9.8075 3.4575 9.8075 3.4575 9 P 0 ;1
L 9.8075 3.5075 9.8075 3.5075 9 P 0 ;1
L 9.8075 3.5575 9.8075 3.5575 9 P 0 ;1
L 9.8075 3.6075 9.8075 3.6075 9 P 0 ;1
L 9.8075 3.6575 9.8075 3.6575 9 P 0 ;1
L 9.8075 3.7075 9.8075 3.7075 9 P 0 ;1
L 9.8075 3.7575 9.8075 3.7575 9 P 0 ;1
L 9.8075 3.8075 9.8075 3.8075 9 P 0 ;1
L 9.8075 3.8575 9.8075 3.8575 9 P 0 ;1
L 9.8075 3.9075 9.8075 3.9075 9 P 0 ;1
L 9.8075 3.9575 9.8075 3.9575 9 P 0 ;1
L 9.8075 4.0075 9.8075 4.0075 9 P 0 ;1
L 9.8075 4.0575 9.8075 4.0575 9 P 0 ;1
L 9.8075 4.1075 9.8075 4.1075 9 P 0 ;1
L 9.8075 4.1575 9.8075 4.1575 9 P 0 ;1
L 9.8075 4.2075 9.8075 4.2075 9 P 0 ;1
L 9.8075 4.2575 9.8075 4.2575 9 P 0 ;1
L 9.8075 4.3075 9.8075 4.3075 9 P 0 ;1
L 9.8075 4.3575 9.8075 4.3575 9 P 0 ;1
L 9.8075 4.4075 9.8075 4.4075 9 P 0 ;1
L 9.8075 4.4575 9.8075 4.4575 9 P 0 ;1
L 9.8075 4.5075 9.8075 4.5075 9 P 0 ;1
L 9.8075 4.5575 9.8075 4.5575 9 P 0 ;1
L 9.8075 4.6075 9.8075 4.6075 9 P 0 ;1
L 9.8075 4.6575 9.8075 4.6575 9 P 0 ;1
L 9.8075 4.7075 9.8075 4.7075 9 P 0 ;1
L 9.8075 4.7575 9.8075 4.7575 9 P 0 ;1
L 9.8075 4.8075 9.8075 4.8075 9 P 0 ;1
L 9.8075 4.8575 9.8075 4.8575 9 P 0 ;1
L 9.8075 4.9075 9.8075 4.9075 9 P 0 ;1
L 9.8075 4.9575 9.8075 4.9575 9 P 0 ;1
L 9.8075 5.0075 9.8075 5.0075 9 P 0 ;1
L 9.8075 5.0575 9.8075 5.0575 9 P 0 ;1
L 9.8075 5.1075 9.8075 5.1075 9 P 0 ;1
L 9.8075 5.1575 9.8075 5.1575 9 P 0 ;1
L 9.8075 5.2075 9.8075 5.2075 9 P 0 ;1
L 9.8075 5.2575 9.8075 5.2575 9 P 0 ;1
L 9.8075 5.3075 9.8075 5.3075 9 P 0 ;1
L 9.8075 5.3575 9.8075 5.3575 9 P 0 ;1
L 9.8075 5.4075 9.8075 5.4075 9 P 0 ;1
L 9.8075 5.4575 9.8075 5.4575 9 P 0 ;1
L 9.8075 5.5075 9.8075 5.5075 9 P 0 ;1
L 9.8075 5.5575 9.8075 5.5575 9 P 0 ;1
L 9.8075 5.6075 9.8075 5.6075 9 P 0 ;1
L 9.8075 5.6575 9.8075 5.6575 9 P 0 ;1
L 9.8075 5.7075 9.8075 5.7075 9 P 0 ;1
L 9.8075 5.7575 9.8075 5.7575 9 P 0 ;1
L 9.8075 5.8075 9.8075 5.8075 9 P 0 ;1
L 9.8075 5.8575 9.8075 5.8575 9 P 0 ;1
L 9.8075 5.9075 9.8075 5.9075 9 P 0 ;1
L 9.8575 0.1575 9.8575 0.1575 9 P 0 ;1
L 9.8575 0.2075 9.8575 0.2075 9 P 0 ;1
L 9.8575 0.2575 9.8575 0.2575 9 P 0 ;1
L 9.8575 0.3075 9.8575 0.3075 9 P 0 ;1
L 9.8575 0.3575 9.8575 0.3575 9 P 0 ;1
L 9.8575 0.4075 9.8575 0.4075 9 P 0 ;1
L 9.8575 0.4575 9.8575 0.4575 9 P 0 ;1
L 9.8575 0.5075 9.8575 0.5075 9 P 0 ;1
L 9.8575 0.5575 9.8575 0.5575 9 P 0 ;1
L 9.8575 0.6075 9.8575 0.6075 9 P 0 ;1
L 9.8575 0.6575 9.8575 0.6575 9 P 0 ;1
L 9.8575 0.7075 9.8575 0.7075 9 P 0 ;1
L 9.8575 0.7575 9.8575 0.7575 9 P 0 ;1
L 9.8575 0.8075 9.8575 0.8075 9 P 0 ;1
L 9.8575 0.8575 9.8575 0.8575 9 P 0 ;1
L 9.8575 0.9075 9.8575 0.9075 9 P 0 ;1
L 9.8575 0.9575 9.8575 0.9575 9 P 0 ;1
L 9.8575 1.0075 9.8575 1.0075 9 P 0 ;1
L 9.8575 1.2575 9.8575 1.2575 9 P 0 ;1
L 9.8575 1.3075 9.8575 1.3075 9 P 0 ;1
L 9.8575 1.3575 9.8575 1.3575 9 P 0 ;1
L 9.8575 1.4075 9.8575 1.4075 9 P 0 ;1
L 9.8575 1.4575 9.8575 1.4575 9 P 0 ;1
L 9.8575 1.5075 9.8575 1.5075 9 P 0 ;1
L 9.8575 1.5575 9.8575 1.5575 9 P 0 ;1
L 9.8575 1.6075 9.8575 1.6075 9 P 0 ;1
L 9.8575 1.6575 9.8575 1.6575 9 P 0 ;1
L 9.8575 2.8575 9.8575 2.8575 9 P 0 ;1
L 9.8575 2.9075 9.8575 2.9075 9 P 0 ;1
L 9.8575 2.9575 9.8575 2.9575 9 P 0 ;1
L 9.8575 3.0075 9.8575 3.0075 9 P 0 ;1
L 9.8575 3.0575 9.8575 3.0575 9 P 0 ;1
L 9.8575 3.1075 9.8575 3.1075 9 P 0 ;1
L 9.8575 3.1575 9.8575 3.1575 9 P 0 ;1
L 9.8575 3.2075 9.8575 3.2075 9 P 0 ;1
L 9.8575 3.2575 9.8575 3.2575 9 P 0 ;1
L 9.8575 3.3075 9.8575 3.3075 9 P 0 ;1
L 9.8575 3.3575 9.8575 3.3575 9 P 0 ;1
L 9.8575 3.4075 9.8575 3.4075 9 P 0 ;1
L 9.8575 3.4575 9.8575 3.4575 9 P 0 ;1
L 9.8575 3.5075 9.8575 3.5075 9 P 0 ;1
L 9.8575 3.5575 9.8575 3.5575 9 P 0 ;1
L 9.8575 3.6075 9.8575 3.6075 9 P 0 ;1
L 9.8575 3.6575 9.8575 3.6575 9 P 0 ;1
L 9.8575 3.7075 9.8575 3.7075 9 P 0 ;1
L 9.8575 3.7575 9.8575 3.7575 9 P 0 ;1
L 9.8575 3.8075 9.8575 3.8075 9 P 0 ;1
L 9.8575 3.8575 9.8575 3.8575 9 P 0 ;1
L 9.8575 3.9075 9.8575 3.9075 9 P 0 ;1
L 9.8575 3.9575 9.8575 3.9575 9 P 0 ;1
L 9.8575 4.0075 9.8575 4.0075 9 P 0 ;1
L 9.8575 4.0575 9.8575 4.0575 9 P 0 ;1
L 9.8575 4.1075 9.8575 4.1075 9 P 0 ;1
L 9.8575 4.1575 9.8575 4.1575 9 P 0 ;1
L 9.8575 4.2075 9.8575 4.2075 9 P 0 ;1
L 9.8575 4.2575 9.8575 4.2575 9 P 0 ;1
L 9.8575 4.3075 9.8575 4.3075 9 P 0 ;1
L 9.8575 4.3575 9.8575 4.3575 9 P 0 ;1
L 9.8575 4.5075 9.8575 4.5075 9 P 0 ;1
L 9.8575 4.5575 9.8575 4.5575 9 P 0 ;1
L 9.8575 4.6075 9.8575 4.6075 9 P 0 ;1
L 9.8575 4.8075 9.8575 4.8075 9 P 0 ;1
L 9.8575 4.8575 9.8575 4.8575 9 P 0 ;1
L 9.8575 4.9075 9.8575 4.9075 9 P 0 ;1
L 9.8575 4.9575 9.8575 4.9575 9 P 0 ;1
L 9.8575 5.0075 9.8575 5.0075 9 P 0 ;1
L 9.8575 5.0575 9.8575 5.0575 9 P 0 ;1
L 9.8575 5.1075 9.8575 5.1075 9 P 0 ;1
L 9.8575 5.1575 9.8575 5.1575 9 P 0 ;1
L 9.8575 5.2075 9.8575 5.2075 9 P 0 ;1
L 9.8575 5.2575 9.8575 5.2575 9 P 0 ;1
L 9.8575 5.3075 9.8575 5.3075 9 P 0 ;1
L 9.8575 5.3575 9.8575 5.3575 9 P 0 ;1
L 9.8575 5.4075 9.8575 5.4075 9 P 0 ;1
L 9.8575 5.4575 9.8575 5.4575 9 P 0 ;1
L 9.8575 5.5075 9.8575 5.5075 9 P 0 ;1
L 9.8575 5.5575 9.8575 5.5575 9 P 0 ;1
L 9.8575 5.6075 9.8575 5.6075 9 P 0 ;1
L 9.8575 5.6575 9.8575 5.6575 9 P 0 ;1
L 9.8575 5.7075 9.8575 5.7075 9 P 0 ;1
L 9.8575 5.7575 9.8575 5.7575 9 P 0 ;1
L 9.8575 5.8075 9.8575 5.8075 9 P 0 ;1
L 9.8575 5.8575 9.8575 5.8575 9 P 0 ;1
L 9.8575 5.9075 9.8575 5.9075 9 P 0 ;1
L 9.9075 0.1575 9.9075 0.1575 9 P 0 ;1
L 9.9075 0.2075 9.9075 0.2075 9 P 0 ;1
L 9.9075 0.2575 9.9075 0.2575 9 P 0 ;1
L 9.9075 0.3075 9.9075 0.3075 9 P 0 ;1
L 9.9075 0.3575 9.9075 0.3575 9 P 0 ;1
L 9.9075 0.4075 9.9075 0.4075 9 P 0 ;1
L 9.9075 0.4575 9.9075 0.4575 9 P 0 ;1
L 9.9075 0.5075 9.9075 0.5075 9 P 0 ;1
L 9.9075 0.5575 9.9075 0.5575 9 P 0 ;1
L 9.9075 0.6075 9.9075 0.6075 9 P 0 ;1
L 9.9075 0.6575 9.9075 0.6575 9 P 0 ;1
L 9.9075 0.7075 9.9075 0.7075 9 P 0 ;1
L 9.9075 0.7575 9.9075 0.7575 9 P 0 ;1
L 9.9075 0.8075 9.9075 0.8075 9 P 0 ;1
L 9.9075 0.8575 9.9075 0.8575 9 P 0 ;1
L 9.9075 0.9075 9.9075 0.9075 9 P 0 ;1
L 9.9075 0.9575 9.9075 0.9575 9 P 0 ;1
L 9.9075 1.0075 9.9075 1.0075 9 P 0 ;1
L 9.9075 1.0575 9.9075 1.0575 9 P 0 ;1
L 9.9075 1.3075 9.9075 1.3075 9 P 0 ;1
L 9.9075 1.3575 9.9075 1.3575 9 P 0 ;1
L 9.9075 1.4075 9.9075 1.4075 9 P 0 ;1
L 9.9075 1.4575 9.9075 1.4575 9 P 0 ;1
L 9.9075 1.5075 9.9075 1.5075 9 P 0 ;1
L 9.9075 1.5575 9.9075 1.5575 9 P 0 ;1
L 9.9075 1.6075 9.9075 1.6075 9 P 0 ;1
L 9.9075 1.6575 9.9075 1.6575 9 P 0 ;1
L 9.9075 2.9075 9.9075 2.9075 9 P 0 ;1
L 9.9075 2.9575 9.9075 2.9575 9 P 0 ;1
L 9.9075 3.0075 9.9075 3.0075 9 P 0 ;1
L 9.9075 3.0575 9.9075 3.0575 9 P 0 ;1
L 9.9075 3.1075 9.9075 3.1075 9 P 0 ;1
L 9.9075 3.1575 9.9075 3.1575 9 P 0 ;1
L 9.9075 3.2075 9.9075 3.2075 9 P 0 ;1
L 9.9075 3.2575 9.9075 3.2575 9 P 0 ;1
L 9.9075 3.3075 9.9075 3.3075 9 P 0 ;1
L 9.9075 3.3575 9.9075 3.3575 9 P 0 ;1
L 9.9075 3.4075 9.9075 3.4075 9 P 0 ;1
L 9.9075 3.4575 9.9075 3.4575 9 P 0 ;1
L 9.9075 3.5075 9.9075 3.5075 9 P 0 ;1
L 9.9075 3.5575 9.9075 3.5575 9 P 0 ;1
L 9.9075 3.6075 9.9075 3.6075 9 P 0 ;1
L 9.9075 3.6575 9.9075 3.6575 9 P 0 ;1
L 9.9075 3.7075 9.9075 3.7075 9 P 0 ;1
L 9.9075 3.7575 9.9075 3.7575 9 P 0 ;1
L 9.9075 3.8075 9.9075 3.8075 9 P 0 ;1
L 9.9075 3.8575 9.9075 3.8575 9 P 0 ;1
L 9.9075 3.9075 9.9075 3.9075 9 P 0 ;1
L 9.9075 3.9575 9.9075 3.9575 9 P 0 ;1
L 9.9075 4.0075 9.9075 4.0075 9 P 0 ;1
L 9.9075 4.0575 9.9075 4.0575 9 P 0 ;1
L 9.9075 4.1075 9.9075 4.1075 9 P 0 ;1
L 9.9075 4.1575 9.9075 4.1575 9 P 0 ;1
L 9.9075 4.2075 9.9075 4.2075 9 P 0 ;1
L 9.9075 4.2575 9.9075 4.2575 9 P 0 ;1
L 9.9075 4.3075 9.9075 4.3075 9 P 0 ;1
L 9.9075 4.5575 9.9075 4.5575 9 P 0 ;1
L 9.9075 4.6075 9.9075 4.6075 9 P 0 ;1
L 9.9075 4.8075 9.9075 4.8075 9 P 0 ;1
L 9.9075 4.8575 9.9075 4.8575 9 P 0 ;1
L 9.9075 4.9075 9.9075 4.9075 9 P 0 ;1
L 9.9075 4.9575 9.9075 4.9575 9 P 0 ;1
L 9.9075 5.0075 9.9075 5.0075 9 P 0 ;1
L 9.9075 5.0575 9.9075 5.0575 9 P 0 ;1
L 9.9075 5.1075 9.9075 5.1075 9 P 0 ;1
L 9.9075 5.1575 9.9075 5.1575 9 P 0 ;1
L 9.9075 5.2075 9.9075 5.2075 9 P 0 ;1
L 9.9075 5.2575 9.9075 5.2575 9 P 0 ;1
L 9.9075 5.3075 9.9075 5.3075 9 P 0 ;1
L 9.9075 5.3575 9.9075 5.3575 9 P 0 ;1
L 9.9075 5.4075 9.9075 5.4075 9 P 0 ;1
L 9.9075 5.4575 9.9075 5.4575 9 P 0 ;1
L 9.9075 5.5075 9.9075 5.5075 9 P 0 ;1
L 9.9075 5.5575 9.9075 5.5575 9 P 0 ;1
L 9.9075 5.6075 9.9075 5.6075 9 P 0 ;1
L 9.9075 5.6575 9.9075 5.6575 9 P 0 ;1
L 9.9075 5.7075 9.9075 5.7075 9 P 0 ;1
L 9.9075 5.7575 9.9075 5.7575 9 P 0 ;1
L 9.9075 5.8075 9.9075 5.8075 9 P 0 ;1
L 9.9075 5.8575 9.9075 5.8575 9 P 0 ;1
L 9.9075 5.9075 9.9075 5.9075 9 P 0 ;1
L 9.9575 0.1575 9.9575 0.1575 9 P 0 ;1
L 9.9575 0.2075 9.9575 0.2075 9 P 0 ;1
L 9.9575 0.2575 9.9575 0.2575 9 P 0 ;1
L 9.9575 0.3075 9.9575 0.3075 9 P 0 ;1
L 9.9575 0.3575 9.9575 0.3575 9 P 0 ;1
L 9.9575 0.4075 9.9575 0.4075 9 P 0 ;1
L 9.9575 0.4575 9.9575 0.4575 9 P 0 ;1
L 9.9575 0.5075 9.9575 0.5075 9 P 0 ;1
L 9.9575 0.5575 9.9575 0.5575 9 P 0 ;1
L 9.9575 0.6075 9.9575 0.6075 9 P 0 ;1
L 9.9575 0.6575 9.9575 0.6575 9 P 0 ;1
L 9.9575 0.7075 9.9575 0.7075 9 P 0 ;1
L 9.9575 0.7575 9.9575 0.7575 9 P 0 ;1
L 9.9575 0.8075 9.9575 0.8075 9 P 0 ;1
L 9.9575 0.8575 9.9575 0.8575 9 P 0 ;1
L 9.9575 0.9075 9.9575 0.9075 9 P 0 ;1
L 9.9575 0.9575 9.9575 0.9575 9 P 0 ;1
L 9.9575 1.0075 9.9575 1.0075 9 P 0 ;1
L 9.9575 1.0575 9.9575 1.0575 9 P 0 ;1
L 9.9575 1.1075 9.9575 1.1075 9 P 0 ;1
L 9.9575 1.3575 9.9575 1.3575 9 P 0 ;1
L 9.9575 1.4075 9.9575 1.4075 9 P 0 ;1
L 9.9575 1.4575 9.9575 1.4575 9 P 0 ;1
L 9.9575 1.5075 9.9575 1.5075 9 P 0 ;1
L 9.9575 1.5575 9.9575 1.5575 9 P 0 ;1
L 9.9575 1.6075 9.9575 1.6075 9 P 0 ;1
L 9.9575 1.6575 9.9575 1.6575 9 P 0 ;1
L 9.9575 1.8575 9.9575 1.8575 9 P 0 ;1
L 9.9575 3.0075 9.9575 3.0075 9 P 0 ;1
L 9.9575 3.0575 9.9575 3.0575 9 P 0 ;1
L 9.9575 3.1075 9.9575 3.1075 9 P 0 ;1
L 9.9575 3.1575 9.9575 3.1575 9 P 0 ;1
L 9.9575 3.2075 9.9575 3.2075 9 P 0 ;1
L 9.9575 3.2575 9.9575 3.2575 9 P 0 ;1
L 9.9575 3.3075 9.9575 3.3075 9 P 0 ;1
L 9.9575 3.3575 9.9575 3.3575 9 P 0 ;1
L 9.9575 3.4075 9.9575 3.4075 9 P 0 ;1
L 9.9575 3.4575 9.9575 3.4575 9 P 0 ;1
L 9.9575 3.5075 9.9575 3.5075 9 P 0 ;1
L 9.9575 3.5575 9.9575 3.5575 9 P 0 ;1
L 9.9575 3.6075 9.9575 3.6075 9 P 0 ;1
L 9.9575 3.6575 9.9575 3.6575 9 P 0 ;1
L 9.9575 3.7075 9.9575 3.7075 9 P 0 ;1
L 9.9575 3.7575 9.9575 3.7575 9 P 0 ;1
L 9.9575 3.8075 9.9575 3.8075 9 P 0 ;1
L 9.9575 3.8575 9.9575 3.8575 9 P 0 ;1
L 9.9575 3.9075 9.9575 3.9075 9 P 0 ;1
L 9.9575 3.9575 9.9575 3.9575 9 P 0 ;1
L 9.9575 4.0075 9.9575 4.0075 9 P 0 ;1
L 9.9575 4.0575 9.9575 4.0575 9 P 0 ;1
L 9.9575 4.1075 9.9575 4.1075 9 P 0 ;1
L 9.9575 4.1575 9.9575 4.1575 9 P 0 ;1
L 9.9575 4.2075 9.9575 4.2075 9 P 0 ;1
L 9.9575 4.2575 9.9575 4.2575 9 P 0 ;1
L 9.9575 4.3075 9.9575 4.3075 9 P 0 ;1
L 9.9575 4.3575 9.9575 4.3575 9 P 0 ;1
L 9.9575 4.8075 9.9575 4.8075 9 P 0 ;1
L 9.9575 4.8575 9.9575 4.8575 9 P 0 ;1
L 9.9575 4.9075 9.9575 4.9075 9 P 0 ;1
L 9.9575 4.9575 9.9575 4.9575 9 P 0 ;1
L 9.9575 5.0075 9.9575 5.0075 9 P 0 ;1
L 9.9575 5.0575 9.9575 5.0575 9 P 0 ;1
L 9.9575 5.1075 9.9575 5.1075 9 P 0 ;1
L 9.9575 5.1575 9.9575 5.1575 9 P 0 ;1
L 9.9575 5.2075 9.9575 5.2075 9 P 0 ;1
L 9.9575 5.2575 9.9575 5.2575 9 P 0 ;1
L 9.9575 5.3075 9.9575 5.3075 9 P 0 ;1
L 9.9575 5.5575 9.9575 5.5575 9 P 0 ;1
L 9.9575 5.6075 9.9575 5.6075 9 P 0 ;1
L 9.9575 5.6575 9.9575 5.6575 9 P 0 ;1
L 9.9575 5.7075 9.9575 5.7075 9 P 0 ;1
L 9.9575 5.7575 9.9575 5.7575 9 P 0 ;1
L 9.9575 5.8075 9.9575 5.8075 9 P 0 ;1
L 9.9575 5.8575 9.9575 5.8575 9 P 0 ;1
L 9.9575 5.9075 9.9575 5.9075 9 P 0 ;1
L 10.0075 0.1575 10.0075 0.1575 9 P 0 ;1
L 10.0075 0.2075 10.0075 0.2075 9 P 0 ;1
L 10.0075 0.2575 10.0075 0.2575 9 P 0 ;1
L 10.0075 0.3075 10.0075 0.3075 9 P 0 ;1
L 10.0075 0.3575 10.0075 0.3575 9 P 0 ;1
L 10.0075 0.4075 10.0075 0.4075 9 P 0 ;1
L 10.0075 0.4575 10.0075 0.4575 9 P 0 ;1
L 10.0075 0.5075 10.0075 0.5075 9 P 0 ;1
L 10.0075 0.5575 10.0075 0.5575 9 P 0 ;1
L 10.0075 0.6075 10.0075 0.6075 9 P 0 ;1
L 10.0075 0.6575 10.0075 0.6575 9 P 0 ;1
L 10.0075 0.7075 10.0075 0.7075 9 P 0 ;1
L 10.0075 0.7575 10.0075 0.7575 9 P 0 ;1
L 10.0075 0.8075 10.0075 0.8075 9 P 0 ;1
L 10.0075 0.8575 10.0075 0.8575 9 P 0 ;1
L 10.0075 0.9075 10.0075 0.9075 9 P 0 ;1
L 10.0075 0.9575 10.0075 0.9575 9 P 0 ;1
L 10.0075 1.0075 10.0075 1.0075 9 P 0 ;1
L 10.0075 1.0575 10.0075 1.0575 9 P 0 ;1
L 10.0075 1.1075 10.0075 1.1075 9 P 0 ;1
L 10.0075 1.1575 10.0075 1.1575 9 P 0 ;1
L 10.0075 1.4075 10.0075 1.4075 9 P 0 ;1
L 10.0075 1.4575 10.0075 1.4575 9 P 0 ;1
L 10.0075 1.5075 10.0075 1.5075 9 P 0 ;1
L 10.0075 1.5575 10.0075 1.5575 9 P 0 ;1
L 10.0075 1.6075 10.0075 1.6075 9 P 0 ;1
L 10.0075 1.6575 10.0075 1.6575 9 P 0 ;1
L 10.0075 1.8575 10.0075 1.8575 9 P 0 ;1
L 10.0075 1.9075 10.0075 1.9075 9 P 0 ;1
L 10.0075 1.9575 10.0075 1.9575 9 P 0 ;1
L 10.0075 2.0075 10.0075 2.0075 9 P 0 ;1
L 10.0075 2.0575 10.0075 2.0575 9 P 0 ;1
L 10.0075 2.1075 10.0075 2.1075 9 P 0 ;1
L 10.0075 3.0575 10.0075 3.0575 9 P 0 ;1
L 10.0075 3.1075 10.0075 3.1075 9 P 0 ;1
L 10.0075 3.1575 10.0075 3.1575 9 P 0 ;1
L 10.0075 3.2075 10.0075 3.2075 9 P 0 ;1
L 10.0075 3.2575 10.0075 3.2575 9 P 0 ;1
L 10.0075 3.3075 10.0075 3.3075 9 P 0 ;1
L 10.0075 3.3575 10.0075 3.3575 9 P 0 ;1
L 10.0075 3.4075 10.0075 3.4075 9 P 0 ;1
L 10.0075 3.4575 10.0075 3.4575 9 P 0 ;1
L 10.0075 3.5075 10.0075 3.5075 9 P 0 ;1
L 10.0075 3.5575 10.0075 3.5575 9 P 0 ;1
L 10.0075 3.6075 10.0075 3.6075 9 P 0 ;1
L 10.0075 3.6575 10.0075 3.6575 9 P 0 ;1
L 10.0075 3.7075 10.0075 3.7075 9 P 0 ;1
L 10.0075 3.7575 10.0075 3.7575 9 P 0 ;1
L 10.0075 3.8075 10.0075 3.8075 9 P 0 ;1
L 10.0075 3.8575 10.0075 3.8575 9 P 0 ;1
L 10.0075 3.9075 10.0075 3.9075 9 P 0 ;1
L 10.0075 3.9575 10.0075 3.9575 9 P 0 ;1
L 10.0075 4.0075 10.0075 4.0075 9 P 0 ;1
L 10.0075 4.0575 10.0075 4.0575 9 P 0 ;1
L 10.0075 4.1075 10.0075 4.1075 9 P 0 ;1
L 10.0075 4.1575 10.0075 4.1575 9 P 0 ;1
L 10.0075 4.2075 10.0075 4.2075 9 P 0 ;1
L 10.0075 4.2575 10.0075 4.2575 9 P 0 ;1
L 10.0075 4.3075 10.0075 4.3075 9 P 0 ;1
L 10.0075 4.3575 10.0075 4.3575 9 P 0 ;1
L 10.0075 4.4075 10.0075 4.4075 9 P 0 ;1
L 10.0075 4.7575 10.0075 4.7575 9 P 0 ;1
L 10.0075 4.8075 10.0075 4.8075 9 P 0 ;1
L 10.0075 4.8575 10.0075 4.8575 9 P 0 ;1
L 10.0075 4.9075 10.0075 4.9075 9 P 0 ;1
L 10.0075 4.9575 10.0075 4.9575 9 P 0 ;1
L 10.0075 5.0075 10.0075 5.0075 9 P 0 ;1
L 10.0075 5.0575 10.0075 5.0575 9 P 0 ;1
L 10.0075 5.1075 10.0075 5.1075 9 P 0 ;1
L 10.0075 5.1575 10.0075 5.1575 9 P 0 ;1
L 10.0075 5.2075 10.0075 5.2075 9 P 0 ;1
L 10.0075 5.2575 10.0075 5.2575 9 P 0 ;1
L 10.0075 5.6575 10.0075 5.6575 9 P 0 ;1
L 10.0075 5.7075 10.0075 5.7075 9 P 0 ;1
L 10.0075 5.7575 10.0075 5.7575 9 P 0 ;1
L 10.0075 5.8075 10.0075 5.8075 9 P 0 ;1
L 10.0075 5.8575 10.0075 5.8575 9 P 0 ;1
L 10.0075 5.9075 10.0075 5.9075 9 P 0 ;1
L 10.0575 0.1575 10.0575 0.1575 9 P 0 ;1
L 10.0575 0.2075 10.0575 0.2075 9 P 0 ;1
L 10.0575 0.2575 10.0575 0.2575 9 P 0 ;1
L 10.0575 0.3075 10.0575 0.3075 9 P 0 ;1
L 10.0575 0.3575 10.0575 0.3575 9 P 0 ;1
L 10.0575 0.4075 10.0575 0.4075 9 P 0 ;1
L 10.0575 0.4575 10.0575 0.4575 9 P 0 ;1
L 10.0575 0.5075 10.0575 0.5075 9 P 0 ;1
L 10.0575 0.5575 10.0575 0.5575 9 P 0 ;1
L 10.0575 0.6075 10.0575 0.6075 9 P 0 ;1
L 10.0575 0.6575 10.0575 0.6575 9 P 0 ;1
L 10.0575 0.7075 10.0575 0.7075 9 P 0 ;1
L 10.0575 0.7575 10.0575 0.7575 9 P 0 ;1
L 10.0575 0.8075 10.0575 0.8075 9 P 0 ;1
L 10.0575 0.8575 10.0575 0.8575 9 P 0 ;1
L 10.0575 0.9075 10.0575 0.9075 9 P 0 ;1
L 10.0575 0.9575 10.0575 0.9575 9 P 0 ;1
L 10.0575 1.0075 10.0575 1.0075 9 P 0 ;1
L 10.0575 1.0575 10.0575 1.0575 9 P 0 ;1
L 10.0575 1.1075 10.0575 1.1075 9 P 0 ;1
L 10.0575 1.1575 10.0575 1.1575 9 P 0 ;1
L 10.0575 1.2075 10.0575 1.2075 9 P 0 ;1
L 10.0575 1.4575 10.0575 1.4575 9 P 0 ;1
L 10.0575 1.5075 10.0575 1.5075 9 P 0 ;1
L 10.0575 1.5575 10.0575 1.5575 9 P 0 ;1
L 10.0575 1.6075 10.0575 1.6075 9 P 0 ;1
L 10.0575 1.6575 10.0575 1.6575 9 P 0 ;1
L 10.0575 1.8575 10.0575 1.8575 9 P 0 ;1
L 10.0575 1.9075 10.0575 1.9075 9 P 0 ;1
L 10.0575 3.0575 10.0575 3.0575 9 P 0 ;1
L 10.0575 3.1075 10.0575 3.1075 9 P 0 ;1
L 10.0575 3.1575 10.0575 3.1575 9 P 0 ;1
L 10.0575 3.2075 10.0575 3.2075 9 P 0 ;1
L 10.0575 3.2575 10.0575 3.2575 9 P 0 ;1
L 10.0575 3.3075 10.0575 3.3075 9 P 0 ;1
L 10.0575 3.3575 10.0575 3.3575 9 P 0 ;1
L 10.0575 3.4075 10.0575 3.4075 9 P 0 ;1
L 10.0575 3.4575 10.0575 3.4575 9 P 0 ;1
L 10.0575 3.5075 10.0575 3.5075 9 P 0 ;1
L 10.0575 3.5575 10.0575 3.5575 9 P 0 ;1
L 10.0575 3.6075 10.0575 3.6075 9 P 0 ;1
L 10.0575 3.6575 10.0575 3.6575 9 P 0 ;1
L 10.0575 3.7075 10.0575 3.7075 9 P 0 ;1
L 10.0575 3.7575 10.0575 3.7575 9 P 0 ;1
L 10.0575 3.8075 10.0575 3.8075 9 P 0 ;1
L 10.0575 3.8575 10.0575 3.8575 9 P 0 ;1
L 10.0575 3.9075 10.0575 3.9075 9 P 0 ;1
L 10.0575 3.9575 10.0575 3.9575 9 P 0 ;1
L 10.0575 4.0075 10.0575 4.0075 9 P 0 ;1
L 10.0575 4.0575 10.0575 4.0575 9 P 0 ;1
L 10.0575 4.1075 10.0575 4.1075 9 P 0 ;1
L 10.0575 4.1575 10.0575 4.1575 9 P 0 ;1
L 10.0575 4.2075 10.0575 4.2075 9 P 0 ;1
L 10.0575 4.2575 10.0575 4.2575 9 P 0 ;1
L 10.0575 4.3075 10.0575 4.3075 9 P 0 ;1
L 10.0575 4.3575 10.0575 4.3575 9 P 0 ;1
L 10.0575 4.4075 10.0575 4.4075 9 P 0 ;1
L 10.0575 4.7075 10.0575 4.7075 9 P 0 ;1
L 10.0575 4.7575 10.0575 4.7575 9 P 0 ;1
L 10.0575 4.8075 10.0575 4.8075 9 P 0 ;1
L 10.0575 4.8575 10.0575 4.8575 9 P 0 ;1
L 10.0575 4.9075 10.0575 4.9075 9 P 0 ;1
L 10.0575 4.9575 10.0575 4.9575 9 P 0 ;1
L 10.0575 5.0075 10.0575 5.0075 9 P 0 ;1
L 10.0575 5.0575 10.0575 5.0575 9 P 0 ;1
L 10.0575 5.1075 10.0575 5.1075 9 P 0 ;1
L 10.0575 5.1575 10.0575 5.1575 9 P 0 ;1
L 10.0575 5.2075 10.0575 5.2075 9 P 0 ;1
L 10.0575 5.7075 10.0575 5.7075 9 P 0 ;1
L 10.0575 5.7575 10.0575 5.7575 9 P 0 ;1
L 10.0575 5.8075 10.0575 5.8075 9 P 0 ;1
L 10.0575 5.8575 10.0575 5.8575 9 P 0 ;1
L 10.0575 5.9075 10.0575 5.9075 9 P 0 ;1
L 10.1075 0.1575 10.1075 0.1575 9 P 0 ;1
L 10.1075 0.2075 10.1075 0.2075 9 P 0 ;1
L 10.1075 0.2575 10.1075 0.2575 9 P 0 ;1
L 10.1075 0.3075 10.1075 0.3075 9 P 0 ;1
L 10.1075 0.3575 10.1075 0.3575 9 P 0 ;1
L 10.1075 0.4075 10.1075 0.4075 9 P 0 ;1
L 10.1075 0.4575 10.1075 0.4575 9 P 0 ;1
L 10.1075 0.5075 10.1075 0.5075 9 P 0 ;1
L 10.1075 0.5575 10.1075 0.5575 9 P 0 ;1
L 10.1075 0.6075 10.1075 0.6075 9 P 0 ;1
L 10.1075 0.6575 10.1075 0.6575 9 P 0 ;1
L 10.1075 0.7075 10.1075 0.7075 9 P 0 ;1
L 10.1075 0.7575 10.1075 0.7575 9 P 0 ;1
L 10.1075 0.8075 10.1075 0.8075 9 P 0 ;1
L 10.1075 0.8575 10.1075 0.8575 9 P 0 ;1
L 10.1075 0.9075 10.1075 0.9075 9 P 0 ;1
L 10.1075 0.9575 10.1075 0.9575 9 P 0 ;1
L 10.1075 1.0075 10.1075 1.0075 9 P 0 ;1
L 10.1075 1.0575 10.1075 1.0575 9 P 0 ;1
L 10.1075 1.1075 10.1075 1.1075 9 P 0 ;1
L 10.1075 1.1575 10.1075 1.1575 9 P 0 ;1
L 10.1075 1.2075 10.1075 1.2075 9 P 0 ;1
L 10.1075 1.2575 10.1075 1.2575 9 P 0 ;1
L 10.1075 1.5075 10.1075 1.5075 9 P 0 ;1
L 10.1075 1.5575 10.1075 1.5575 9 P 0 ;1
L 10.1075 1.6075 10.1075 1.6075 9 P 0 ;1
L 10.1075 1.6575 10.1075 1.6575 9 P 0 ;1
L 10.1075 1.8575 10.1075 1.8575 9 P 0 ;1
L 10.1075 1.9075 10.1075 1.9075 9 P 0 ;1
L 10.1075 3.0075 10.1075 3.0075 9 P 0 ;1
L 10.1075 3.0575 10.1075 3.0575 9 P 0 ;1
L 10.1075 3.1075 10.1075 3.1075 9 P 0 ;1
L 10.1075 3.1575 10.1075 3.1575 9 P 0 ;1
L 10.1075 3.2075 10.1075 3.2075 9 P 0 ;1
L 10.1075 3.2575 10.1075 3.2575 9 P 0 ;1
L 10.1075 3.3075 10.1075 3.3075 9 P 0 ;1
L 10.1075 3.3575 10.1075 3.3575 9 P 0 ;1
L 10.1075 3.4075 10.1075 3.4075 9 P 0 ;1
L 10.1075 3.4575 10.1075 3.4575 9 P 0 ;1
L 10.1075 3.5075 10.1075 3.5075 9 P 0 ;1
L 10.1075 3.5575 10.1075 3.5575 9 P 0 ;1
L 10.1075 3.6075 10.1075 3.6075 9 P 0 ;1
L 10.1075 3.6575 10.1075 3.6575 9 P 0 ;1
L 10.1075 3.7075 10.1075 3.7075 9 P 0 ;1
L 10.1075 3.7575 10.1075 3.7575 9 P 0 ;1
L 10.1075 3.8075 10.1075 3.8075 9 P 0 ;1
L 10.1075 3.8575 10.1075 3.8575 9 P 0 ;1
L 10.1075 3.9075 10.1075 3.9075 9 P 0 ;1
L 10.1075 3.9575 10.1075 3.9575 9 P 0 ;1
L 10.1075 4.0075 10.1075 4.0075 9 P 0 ;1
L 10.1075 4.0575 10.1075 4.0575 9 P 0 ;1
L 10.1075 4.1075 10.1075 4.1075 9 P 0 ;1
L 10.1075 4.1575 10.1075 4.1575 9 P 0 ;1
L 10.1075 4.2075 10.1075 4.2075 9 P 0 ;1
L 10.1075 4.2575 10.1075 4.2575 9 P 0 ;1
L 10.1075 4.3075 10.1075 4.3075 9 P 0 ;1
L 10.1075 4.3575 10.1075 4.3575 9 P 0 ;1
L 10.1075 4.4075 10.1075 4.4075 9 P 0 ;1
L 10.1075 4.4575 10.1075 4.4575 9 P 0 ;1
L 10.1075 4.5575 10.1075 4.5575 9 P 0 ;1
L 10.1075 4.6575 10.1075 4.6575 9 P 0 ;1
L 10.1075 4.7075 10.1075 4.7075 9 P 0 ;1
L 10.1075 4.7575 10.1075 4.7575 9 P 0 ;1
L 10.1075 4.8075 10.1075 4.8075 9 P 0 ;1
L 10.1075 4.8575 10.1075 4.8575 9 P 0 ;1
L 10.1075 4.9075 10.1075 4.9075 9 P 0 ;1
L 10.1075 4.9575 10.1075 4.9575 9 P 0 ;1
L 10.1075 5.0075 10.1075 5.0075 9 P 0 ;1
L 10.1075 5.0575 10.1075 5.0575 9 P 0 ;1
L 10.1075 5.1075 10.1075 5.1075 9 P 0 ;1
L 10.1075 5.1575 10.1075 5.1575 9 P 0 ;1
L 10.1075 5.7075 10.1075 5.7075 9 P 0 ;1
L 10.1075 5.7575 10.1075 5.7575 9 P 0 ;1
L 10.1075 5.8075 10.1075 5.8075 9 P 0 ;1
L 10.1075 5.8575 10.1075 5.8575 9 P 0 ;1
L 10.1075 5.9075 10.1075 5.9075 9 P 0 ;1
L 10.1575 0.1575 10.1575 0.1575 9 P 0 ;1
L 10.1575 0.2075 10.1575 0.2075 9 P 0 ;1
L 10.1575 0.2575 10.1575 0.2575 9 P 0 ;1
L 10.1575 0.3075 10.1575 0.3075 9 P 0 ;1
L 10.1575 0.3575 10.1575 0.3575 9 P 0 ;1
L 10.1575 0.4075 10.1575 0.4075 9 P 0 ;1
L 10.1575 0.4575 10.1575 0.4575 9 P 0 ;1
L 10.1575 0.5075 10.1575 0.5075 9 P 0 ;1
L 10.1575 0.5575 10.1575 0.5575 9 P 0 ;1
L 10.1575 0.6075 10.1575 0.6075 9 P 0 ;1
L 10.1575 0.6575 10.1575 0.6575 9 P 0 ;1
L 10.1575 0.7075 10.1575 0.7075 9 P 0 ;1
L 10.1575 0.7575 10.1575 0.7575 9 P 0 ;1
L 10.1575 0.8075 10.1575 0.8075 9 P 0 ;1
L 10.1575 0.8575 10.1575 0.8575 9 P 0 ;1
L 10.1575 0.9075 10.1575 0.9075 9 P 0 ;1
L 10.1575 0.9575 10.1575 0.9575 9 P 0 ;1
L 10.1575 1.0075 10.1575 1.0075 9 P 0 ;1
L 10.1575 1.0575 10.1575 1.0575 9 P 0 ;1
L 10.1575 1.1075 10.1575 1.1075 9 P 0 ;1
L 10.1575 1.1575 10.1575 1.1575 9 P 0 ;1
L 10.1575 1.2075 10.1575 1.2075 9 P 0 ;1
L 10.1575 1.2575 10.1575 1.2575 9 P 0 ;1
L 10.1575 1.3075 10.1575 1.3075 9 P 0 ;1
L 10.1575 1.5575 10.1575 1.5575 9 P 0 ;1
L 10.1575 1.6075 10.1575 1.6075 9 P 0 ;1
L 10.1575 1.6575 10.1575 1.6575 9 P 0 ;1
L 10.1575 1.8575 10.1575 1.8575 9 P 0 ;1
L 10.1575 2.9575 10.1575 2.9575 9 P 0 ;1
L 10.1575 3.0075 10.1575 3.0075 9 P 0 ;1
L 10.1575 3.0575 10.1575 3.0575 9 P 0 ;1
L 10.1575 3.1075 10.1575 3.1075 9 P 0 ;1
L 10.1575 3.1575 10.1575 3.1575 9 P 0 ;1
L 10.1575 3.2075 10.1575 3.2075 9 P 0 ;1
L 10.1575 3.2575 10.1575 3.2575 9 P 0 ;1
L 10.1575 3.3075 10.1575 3.3075 9 P 0 ;1
L 10.1575 3.3575 10.1575 3.3575 9 P 0 ;1
L 10.1575 3.4075 10.1575 3.4075 9 P 0 ;1
L 10.1575 3.4575 10.1575 3.4575 9 P 0 ;1
L 10.1575 3.5075 10.1575 3.5075 9 P 0 ;1
L 10.1575 3.5575 10.1575 3.5575 9 P 0 ;1
L 10.1575 3.6075 10.1575 3.6075 9 P 0 ;1
L 10.1575 3.6575 10.1575 3.6575 9 P 0 ;1
L 10.1575 3.7075 10.1575 3.7075 9 P 0 ;1
L 10.1575 3.7575 10.1575 3.7575 9 P 0 ;1
L 10.1575 3.8075 10.1575 3.8075 9 P 0 ;1
L 10.1575 3.8575 10.1575 3.8575 9 P 0 ;1
L 10.1575 3.9075 10.1575 3.9075 9 P 0 ;1
L 10.1575 3.9575 10.1575 3.9575 9 P 0 ;1
L 10.1575 4.0075 10.1575 4.0075 9 P 0 ;1
L 10.1575 4.0575 10.1575 4.0575 9 P 0 ;1
L 10.1575 4.1075 10.1575 4.1075 9 P 0 ;1
L 10.1575 4.1575 10.1575 4.1575 9 P 0 ;1
L 10.1575 4.2075 10.1575 4.2075 9 P 0 ;1
L 10.1575 4.2575 10.1575 4.2575 9 P 0 ;1
L 10.1575 4.3075 10.1575 4.3075 9 P 0 ;1
L 10.1575 4.3575 10.1575 4.3575 9 P 0 ;1
L 10.1575 4.4075 10.1575 4.4075 9 P 0 ;1
L 10.1575 4.4575 10.1575 4.4575 9 P 0 ;1
L 10.1575 4.5075 10.1575 4.5075 9 P 0 ;1
L 10.1575 4.5575 10.1575 4.5575 9 P 0 ;1
L 10.1575 4.6075 10.1575 4.6075 9 P 0 ;1
L 10.1575 4.6575 10.1575 4.6575 9 P 0 ;1
L 10.1575 4.7075 10.1575 4.7075 9 P 0 ;1
L 10.1575 4.7575 10.1575 4.7575 9 P 0 ;1
L 10.1575 4.8075 10.1575 4.8075 9 P 0 ;1
L 10.1575 4.8575 10.1575 4.8575 9 P 0 ;1
L 10.1575 4.9075 10.1575 4.9075 9 P 0 ;1
L 10.1575 4.9575 10.1575 4.9575 9 P 0 ;1
L 10.1575 5.0075 10.1575 5.0075 9 P 0 ;1
L 10.1575 5.0575 10.1575 5.0575 9 P 0 ;1
L 10.1575 5.1075 10.1575 5.1075 9 P 0 ;1
L 10.1575 5.1575 10.1575 5.1575 9 P 0 ;1
L 10.1575 5.7575 10.1575 5.7575 9 P 0 ;1
L 10.1575 5.8075 10.1575 5.8075 9 P 0 ;1
L 10.1575 5.8575 10.1575 5.8575 9 P 0 ;1
L 10.1575 5.9075 10.1575 5.9075 9 P 0 ;1
L 10.2075 0.1575 10.2075 0.1575 9 P 0 ;1
L 10.2075 0.2075 10.2075 0.2075 9 P 0 ;1
L 10.2075 0.2575 10.2075 0.2575 9 P 0 ;1
L 10.2075 0.3075 10.2075 0.3075 9 P 0 ;1
L 10.2075 0.3575 10.2075 0.3575 9 P 0 ;1
L 10.2075 0.4075 10.2075 0.4075 9 P 0 ;1
L 10.2075 0.4575 10.2075 0.4575 9 P 0 ;1
L 10.2075 0.5075 10.2075 0.5075 9 P 0 ;1
L 10.2075 0.5575 10.2075 0.5575 9 P 0 ;1
L 10.2075 0.6075 10.2075 0.6075 9 P 0 ;1
L 10.2075 0.6575 10.2075 0.6575 9 P 0 ;1
L 10.2075 0.7075 10.2075 0.7075 9 P 0 ;1
L 10.2075 0.7575 10.2075 0.7575 9 P 0 ;1
L 10.2075 0.8075 10.2075 0.8075 9 P 0 ;1
L 10.2075 0.8575 10.2075 0.8575 9 P 0 ;1
L 10.2075 0.9075 10.2075 0.9075 9 P 0 ;1
L 10.2075 0.9575 10.2075 0.9575 9 P 0 ;1
L 10.2075 1.0075 10.2075 1.0075 9 P 0 ;1
L 10.2075 1.0575 10.2075 1.0575 9 P 0 ;1
L 10.2075 1.1075 10.2075 1.1075 9 P 0 ;1
L 10.2075 1.1575 10.2075 1.1575 9 P 0 ;1
L 10.2075 1.2075 10.2075 1.2075 9 P 0 ;1
L 10.2075 1.2575 10.2075 1.2575 9 P 0 ;1
L 10.2075 1.3075 10.2075 1.3075 9 P 0 ;1
L 10.2075 1.3575 10.2075 1.3575 9 P 0 ;1
L 10.2075 2.0575 10.2075 2.0575 9 P 0 ;1
L 10.2075 2.1075 10.2075 2.1075 9 P 0 ;1
L 10.2075 2.1575 10.2075 2.1575 9 P 0 ;1
L 10.2075 2.2075 10.2075 2.2075 9 P 0 ;1
L 10.2075 2.2575 10.2075 2.2575 9 P 0 ;1
L 10.2075 2.3075 10.2075 2.3075 9 P 0 ;1
L 10.2075 2.3575 10.2075 2.3575 9 P 0 ;1
L 10.2075 2.4075 10.2075 2.4075 9 P 0 ;1
L 10.2075 2.4575 10.2075 2.4575 9 P 0 ;1
L 10.2075 2.5075 10.2075 2.5075 9 P 0 ;1
L 10.2075 2.5575 10.2075 2.5575 9 P 0 ;1
L 10.2075 2.6075 10.2075 2.6075 9 P 0 ;1
L 10.2075 2.6575 10.2075 2.6575 9 P 0 ;1
L 10.2075 2.7075 10.2075 2.7075 9 P 0 ;1
L 10.2075 2.9575 10.2075 2.9575 9 P 0 ;1
L 10.2075 3.0075 10.2075 3.0075 9 P 0 ;1
L 10.2075 3.0575 10.2075 3.0575 9 P 0 ;1
L 10.2075 3.1075 10.2075 3.1075 9 P 0 ;1
L 10.2075 3.1575 10.2075 3.1575 9 P 0 ;1
L 10.2075 3.2075 10.2075 3.2075 9 P 0 ;1
L 10.2075 5.7575 10.2075 5.7575 9 P 0 ;1
L 10.2075 5.8075 10.2075 5.8075 9 P 0 ;1
L 10.2075 5.8575 10.2075 5.8575 9 P 0 ;1
L 10.2075 5.9075 10.2075 5.9075 9 P 0 ;1
L 10.2575 0.1575 10.2575 0.1575 9 P 0 ;1
L 10.2575 0.2075 10.2575 0.2075 9 P 0 ;1
L 10.2575 0.2575 10.2575 0.2575 9 P 0 ;1
L 10.2575 0.3075 10.2575 0.3075 9 P 0 ;1
L 10.2575 0.3575 10.2575 0.3575 9 P 0 ;1
L 10.2575 0.4075 10.2575 0.4075 9 P 0 ;1
L 10.2575 0.4575 10.2575 0.4575 9 P 0 ;1
L 10.2575 0.5075 10.2575 0.5075 9 P 0 ;1
L 10.2575 0.5575 10.2575 0.5575 9 P 0 ;1
L 10.2575 0.6075 10.2575 0.6075 9 P 0 ;1
L 10.2575 0.6575 10.2575 0.6575 9 P 0 ;1
L 10.2575 0.7075 10.2575 0.7075 9 P 0 ;1
L 10.2575 0.7575 10.2575 0.7575 9 P 0 ;1
L 10.2575 0.8075 10.2575 0.8075 9 P 0 ;1
L 10.2575 0.8575 10.2575 0.8575 9 P 0 ;1
L 10.2575 0.9075 10.2575 0.9075 9 P 0 ;1
L 10.2575 0.9575 10.2575 0.9575 9 P 0 ;1
L 10.2575 1.0075 10.2575 1.0075 9 P 0 ;1
L 10.2575 1.0575 10.2575 1.0575 9 P 0 ;1
L 10.2575 1.1075 10.2575 1.1075 9 P 0 ;1
L 10.2575 1.1575 10.2575 1.1575 9 P 0 ;1
L 10.2575 1.2075 10.2575 1.2075 9 P 0 ;1
L 10.2575 1.2575 10.2575 1.2575 9 P 0 ;1
L 10.2575 1.3075 10.2575 1.3075 9 P 0 ;1
L 10.2575 1.3575 10.2575 1.3575 9 P 0 ;1
L 10.2575 1.4075 10.2575 1.4075 9 P 0 ;1
L 10.2575 2.0575 10.2575 2.0575 9 P 0 ;1
L 10.2575 2.1075 10.2575 2.1075 9 P 0 ;1
L 10.2575 2.1575 10.2575 2.1575 9 P 0 ;1
L 10.2575 2.2075 10.2575 2.2075 9 P 0 ;1
L 10.2575 2.2575 10.2575 2.2575 9 P 0 ;1
L 10.2575 2.3075 10.2575 2.3075 9 P 0 ;1
L 10.2575 2.3575 10.2575 2.3575 9 P 0 ;1
L 10.2575 2.4075 10.2575 2.4075 9 P 0 ;1
L 10.2575 2.4575 10.2575 2.4575 9 P 0 ;1
L 10.2575 2.5075 10.2575 2.5075 9 P 0 ;1
L 10.2575 2.5575 10.2575 2.5575 9 P 0 ;1
L 10.2575 2.6075 10.2575 2.6075 9 P 0 ;1
L 10.2575 2.6575 10.2575 2.6575 9 P 0 ;1
L 10.2575 2.7075 10.2575 2.7075 9 P 0 ;1
L 10.2575 2.9575 10.2575 2.9575 9 P 0 ;1
L 10.2575 3.0075 10.2575 3.0075 9 P 0 ;1
L 10.2575 3.0575 10.2575 3.0575 9 P 0 ;1
L 10.2575 3.1075 10.2575 3.1075 9 P 0 ;1
L 10.2575 3.1575 10.2575 3.1575 9 P 0 ;1
L 10.2575 5.7575 10.2575 5.7575 9 P 0 ;1
L 10.2575 5.8075 10.2575 5.8075 9 P 0 ;1
L 10.2575 5.8575 10.2575 5.8575 9 P 0 ;1
L 10.2575 5.9075 10.2575 5.9075 9 P 0 ;1
L 10.3075 0.1575 10.3075 0.1575 9 P 0 ;1
L 10.3075 0.2075 10.3075 0.2075 9 P 0 ;1
L 10.3075 0.2575 10.3075 0.2575 9 P 0 ;1
L 10.3075 0.3075 10.3075 0.3075 9 P 0 ;1
L 10.3075 0.3575 10.3075 0.3575 9 P 0 ;1
L 10.3075 0.4075 10.3075 0.4075 9 P 0 ;1
L 10.3075 0.4575 10.3075 0.4575 9 P 0 ;1
L 10.3075 0.5075 10.3075 0.5075 9 P 0 ;1
L 10.3075 0.5575 10.3075 0.5575 9 P 0 ;1
L 10.3075 0.6075 10.3075 0.6075 9 P 0 ;1
L 10.3075 0.6575 10.3075 0.6575 9 P 0 ;1
L 10.3075 0.7075 10.3075 0.7075 9 P 0 ;1
L 10.3075 0.7575 10.3075 0.7575 9 P 0 ;1
L 10.3075 0.8075 10.3075 0.8075 9 P 0 ;1
L 10.3075 0.8575 10.3075 0.8575 9 P 0 ;1
L 10.3075 0.9075 10.3075 0.9075 9 P 0 ;1
L 10.3075 0.9575 10.3075 0.9575 9 P 0 ;1
L 10.3075 1.0075 10.3075 1.0075 9 P 0 ;1
L 10.3075 1.0575 10.3075 1.0575 9 P 0 ;1
L 10.3075 1.1075 10.3075 1.1075 9 P 0 ;1
L 10.3075 1.1575 10.3075 1.1575 9 P 0 ;1
L 10.3075 1.2075 10.3075 1.2075 9 P 0 ;1
L 10.3075 1.2575 10.3075 1.2575 9 P 0 ;1
L 10.3075 1.3075 10.3075 1.3075 9 P 0 ;1
L 10.3075 1.3575 10.3075 1.3575 9 P 0 ;1
L 10.3075 1.4075 10.3075 1.4075 9 P 0 ;1
L 10.3075 1.4575 10.3075 1.4575 9 P 0 ;1
L 10.3075 2.0575 10.3075 2.0575 9 P 0 ;1
L 10.3075 2.1075 10.3075 2.1075 9 P 0 ;1
L 10.3075 2.1575 10.3075 2.1575 9 P 0 ;1
L 10.3075 2.2075 10.3075 2.2075 9 P 0 ;1
L 10.3075 2.2575 10.3075 2.2575 9 P 0 ;1
L 10.3075 2.3075 10.3075 2.3075 9 P 0 ;1
L 10.3075 2.3575 10.3075 2.3575 9 P 0 ;1
L 10.3075 2.4075 10.3075 2.4075 9 P 0 ;1
L 10.3075 2.4575 10.3075 2.4575 9 P 0 ;1
L 10.3075 2.5075 10.3075 2.5075 9 P 0 ;1
L 10.3075 2.5575 10.3075 2.5575 9 P 0 ;1
L 10.3075 2.6075 10.3075 2.6075 9 P 0 ;1
L 10.3075 2.6575 10.3075 2.6575 9 P 0 ;1
L 10.3075 2.9075 10.3075 2.9075 9 P 0 ;1
L 10.3075 2.9575 10.3075 2.9575 9 P 0 ;1
L 10.3075 3.0075 10.3075 3.0075 9 P 0 ;1
L 10.3075 3.0575 10.3075 3.0575 9 P 0 ;1
L 10.3075 3.1075 10.3075 3.1075 9 P 0 ;1
L 10.3075 5.7075 10.3075 5.7075 9 P 0 ;1
L 10.3075 5.7575 10.3075 5.7575 9 P 0 ;1
L 10.3075 5.8075 10.3075 5.8075 9 P 0 ;1
L 10.3075 5.8575 10.3075 5.8575 9 P 0 ;1
L 10.3075 5.9075 10.3075 5.9075 9 P 0 ;1
L 10.3575 0.1575 10.3575 0.1575 9 P 0 ;1
L 10.3575 0.2075 10.3575 0.2075 9 P 0 ;1
L 10.3575 0.2575 10.3575 0.2575 9 P 0 ;1
L 10.3575 0.3075 10.3575 0.3075 9 P 0 ;1
L 10.3575 0.3575 10.3575 0.3575 9 P 0 ;1
L 10.3575 0.4075 10.3575 0.4075 9 P 0 ;1
L 10.3575 0.4575 10.3575 0.4575 9 P 0 ;1
L 10.3575 0.5075 10.3575 0.5075 9 P 0 ;1
L 10.3575 0.5575 10.3575 0.5575 9 P 0 ;1
L 10.3575 0.6075 10.3575 0.6075 9 P 0 ;1
L 10.3575 0.6575 10.3575 0.6575 9 P 0 ;1
L 10.3575 0.7075 10.3575 0.7075 9 P 0 ;1
L 10.3575 0.7575 10.3575 0.7575 9 P 0 ;1
L 10.3575 0.8075 10.3575 0.8075 9 P 0 ;1
L 10.3575 0.8575 10.3575 0.8575 9 P 0 ;1
L 10.3575 0.9075 10.3575 0.9075 9 P 0 ;1
L 10.3575 0.9575 10.3575 0.9575 9 P 0 ;1
L 10.3575 1.0075 10.3575 1.0075 9 P 0 ;1
L 10.3575 1.0575 10.3575 1.0575 9 P 0 ;1
L 10.3575 1.1075 10.3575 1.1075 9 P 0 ;1
L 10.3575 1.1575 10.3575 1.1575 9 P 0 ;1
L 10.3575 1.2075 10.3575 1.2075 9 P 0 ;1
L 10.3575 1.9575 10.3575 1.9575 9 P 0 ;1
L 10.3575 2.0075 10.3575 2.0075 9 P 0 ;1
L 10.3575 2.0575 10.3575 2.0575 9 P 0 ;1
L 10.3575 2.1075 10.3575 2.1075 9 P 0 ;1
L 10.3575 2.1575 10.3575 2.1575 9 P 0 ;1
L 10.3575 2.2075 10.3575 2.2075 9 P 0 ;1
L 10.3575 2.2575 10.3575 2.2575 9 P 0 ;1
L 10.3575 2.3075 10.3575 2.3075 9 P 0 ;1
L 10.3575 2.3575 10.3575 2.3575 9 P 0 ;1
L 10.3575 2.4075 10.3575 2.4075 9 P 0 ;1
L 10.3575 2.4575 10.3575 2.4575 9 P 0 ;1
L 10.3575 2.5075 10.3575 2.5075 9 P 0 ;1
L 10.3575 2.5575 10.3575 2.5575 9 P 0 ;1
L 10.3575 2.6075 10.3575 2.6075 9 P 0 ;1
L 10.3575 2.6575 10.3575 2.6575 9 P 0 ;1
L 10.3575 2.8575 10.3575 2.8575 9 P 0 ;1
L 10.3575 2.9075 10.3575 2.9075 9 P 0 ;1
L 10.3575 2.9575 10.3575 2.9575 9 P 0 ;1
L 10.3575 3.0075 10.3575 3.0075 9 P 0 ;1
L 10.3575 3.0575 10.3575 3.0575 9 P 0 ;1
L 10.3575 5.2075 10.3575 5.2075 9 P 0 ;1
L 10.3575 5.7075 10.3575 5.7075 9 P 0 ;1
L 10.3575 5.7575 10.3575 5.7575 9 P 0 ;1
L 10.3575 5.8075 10.3575 5.8075 9 P 0 ;1
L 10.3575 5.8575 10.3575 5.8575 9 P 0 ;1
L 10.3575 5.9075 10.3575 5.9075 9 P 0 ;1
L 10.4075 0.1575 10.4075 0.1575 9 P 0 ;1
L 10.4075 0.2075 10.4075 0.2075 9 P 0 ;1
L 10.4075 0.2575 10.4075 0.2575 9 P 0 ;1
L 10.4075 0.3075 10.4075 0.3075 9 P 0 ;1
L 10.4075 0.3575 10.4075 0.3575 9 P 0 ;1
L 10.4075 0.4075 10.4075 0.4075 9 P 0 ;1
L 10.4075 0.4575 10.4075 0.4575 9 P 0 ;1
L 10.4075 0.5075 10.4075 0.5075 9 P 0 ;1
L 10.4075 0.5575 10.4075 0.5575 9 P 0 ;1
L 10.4075 0.6075 10.4075 0.6075 9 P 0 ;1
L 10.4075 0.6575 10.4075 0.6575 9 P 0 ;1
L 10.4075 0.7075 10.4075 0.7075 9 P 0 ;1
L 10.4075 0.7575 10.4075 0.7575 9 P 0 ;1
L 10.4075 0.8075 10.4075 0.8075 9 P 0 ;1
L 10.4075 0.8575 10.4075 0.8575 9 P 0 ;1
L 10.4075 0.9075 10.4075 0.9075 9 P 0 ;1
L 10.4075 0.9575 10.4075 0.9575 9 P 0 ;1
L 10.4075 1.0075 10.4075 1.0075 9 P 0 ;1
L 10.4075 1.0575 10.4075 1.0575 9 P 0 ;1
L 10.4075 1.1075 10.4075 1.1075 9 P 0 ;1
L 10.4075 1.1575 10.4075 1.1575 9 P 0 ;1
L 10.4075 1.8575 10.4075 1.8575 9 P 0 ;1
L 10.4075 1.9075 10.4075 1.9075 9 P 0 ;1
L 10.4075 1.9575 10.4075 1.9575 9 P 0 ;1
L 10.4075 2.0075 10.4075 2.0075 9 P 0 ;1
L 10.4075 2.0575 10.4075 2.0575 9 P 0 ;1
L 10.4075 2.1075 10.4075 2.1075 9 P 0 ;1
L 10.4075 2.1575 10.4075 2.1575 9 P 0 ;1
L 10.4075 2.2075 10.4075 2.2075 9 P 0 ;1
L 10.4075 2.2575 10.4075 2.2575 9 P 0 ;1
L 10.4075 2.3075 10.4075 2.3075 9 P 0 ;1
L 10.4075 2.3575 10.4075 2.3575 9 P 0 ;1
L 10.4075 2.4075 10.4075 2.4075 9 P 0 ;1
L 10.4075 2.4575 10.4075 2.4575 9 P 0 ;1
L 10.4075 2.5075 10.4075 2.5075 9 P 0 ;1
L 10.4075 2.5575 10.4075 2.5575 9 P 0 ;1
L 10.4075 2.6075 10.4075 2.6075 9 P 0 ;1
L 10.4075 2.6575 10.4075 2.6575 9 P 0 ;1
L 10.4075 2.8575 10.4075 2.8575 9 P 0 ;1
L 10.4075 2.9075 10.4075 2.9075 9 P 0 ;1
L 10.4075 2.9575 10.4075 2.9575 9 P 0 ;1
L 10.4075 3.0075 10.4075 3.0075 9 P 0 ;1
L 10.4075 5.6575 10.4075 5.6575 9 P 0 ;1
L 10.4075 5.7075 10.4075 5.7075 9 P 0 ;1
L 10.4075 5.7575 10.4075 5.7575 9 P 0 ;1
L 10.4075 5.8075 10.4075 5.8075 9 P 0 ;1
L 10.4075 5.8575 10.4075 5.8575 9 P 0 ;1
L 10.4075 5.9075 10.4075 5.9075 9 P 0 ;1
L 10.4575 0.1575 10.4575 0.1575 9 P 0 ;1
L 10.4575 0.2075 10.4575 0.2075 9 P 0 ;1
L 10.4575 0.2575 10.4575 0.2575 9 P 0 ;1
L 10.4575 0.3075 10.4575 0.3075 9 P 0 ;1
L 10.4575 0.3575 10.4575 0.3575 9 P 0 ;1
L 10.4575 0.4075 10.4575 0.4075 9 P 0 ;1
L 10.4575 0.4575 10.4575 0.4575 9 P 0 ;1
L 10.4575 0.5075 10.4575 0.5075 9 P 0 ;1
L 10.4575 0.5575 10.4575 0.5575 9 P 0 ;1
L 10.4575 0.6075 10.4575 0.6075 9 P 0 ;1
L 10.4575 0.6575 10.4575 0.6575 9 P 0 ;1
L 10.4575 0.7075 10.4575 0.7075 9 P 0 ;1
L 10.4575 0.7575 10.4575 0.7575 9 P 0 ;1
L 10.4575 0.8075 10.4575 0.8075 9 P 0 ;1
L 10.4575 0.8575 10.4575 0.8575 9 P 0 ;1
L 10.4575 0.9075 10.4575 0.9075 9 P 0 ;1
L 10.4575 0.9575 10.4575 0.9575 9 P 0 ;1
L 10.4575 1.0075 10.4575 1.0075 9 P 0 ;1
L 10.4575 1.0575 10.4575 1.0575 9 P 0 ;1
L 10.4575 1.1075 10.4575 1.1075 9 P 0 ;1
L 10.4575 1.1575 10.4575 1.1575 9 P 0 ;1
L 10.4575 1.6075 10.4575 1.6075 9 P 0 ;1
L 10.4575 1.8575 10.4575 1.8575 9 P 0 ;1
L 10.4575 1.9075 10.4575 1.9075 9 P 0 ;1
L 10.4575 1.9575 10.4575 1.9575 9 P 0 ;1
L 10.4575 2.0075 10.4575 2.0075 9 P 0 ;1
L 10.4575 2.0575 10.4575 2.0575 9 P 0 ;1
L 10.4575 2.1075 10.4575 2.1075 9 P 0 ;1
L 10.4575 2.1575 10.4575 2.1575 9 P 0 ;1
L 10.4575 2.2075 10.4575 2.2075 9 P 0 ;1
L 10.4575 2.2575 10.4575 2.2575 9 P 0 ;1
L 10.4575 2.3075 10.4575 2.3075 9 P 0 ;1
L 10.4575 2.3575 10.4575 2.3575 9 P 0 ;1
L 10.4575 2.4075 10.4575 2.4075 9 P 0 ;1
L 10.4575 2.4575 10.4575 2.4575 9 P 0 ;1
L 10.4575 2.5075 10.4575 2.5075 9 P 0 ;1
L 10.4575 2.5575 10.4575 2.5575 9 P 0 ;1
L 10.4575 2.6075 10.4575 2.6075 9 P 0 ;1
L 10.4575 2.6575 10.4575 2.6575 9 P 0 ;1
L 10.4575 2.8575 10.4575 2.8575 9 P 0 ;1
L 10.4575 2.9075 10.4575 2.9075 9 P 0 ;1
L 10.4575 2.9575 10.4575 2.9575 9 P 0 ;1
L 10.4575 5.5575 10.4575 5.5575 9 P 0 ;1
L 10.4575 5.6075 10.4575 5.6075 9 P 0 ;1
L 10.4575 5.6575 10.4575 5.6575 9 P 0 ;1
L 10.4575 5.7075 10.4575 5.7075 9 P 0 ;1
L 10.4575 5.7575 10.4575 5.7575 9 P 0 ;1
L 10.4575 5.8075 10.4575 5.8075 9 P 0 ;1
L 10.4575 5.8575 10.4575 5.8575 9 P 0 ;1
L 10.4575 5.9075 10.4575 5.9075 9 P 0 ;1
L 10.5075 0.1575 10.5075 0.1575 9 P 0 ;1
L 10.5075 0.2075 10.5075 0.2075 9 P 0 ;1
L 10.5075 0.2575 10.5075 0.2575 9 P 0 ;1
L 10.5075 0.3075 10.5075 0.3075 9 P 0 ;1
L 10.5075 0.3575 10.5075 0.3575 9 P 0 ;1
L 10.5075 0.4075 10.5075 0.4075 9 P 0 ;1
L 10.5075 0.4575 10.5075 0.4575 9 P 0 ;1
L 10.5075 0.5075 10.5075 0.5075 9 P 0 ;1
L 10.5075 0.5575 10.5075 0.5575 9 P 0 ;1
L 10.5075 0.6075 10.5075 0.6075 9 P 0 ;1
L 10.5075 0.6575 10.5075 0.6575 9 P 0 ;1
L 10.5075 0.7075 10.5075 0.7075 9 P 0 ;1
L 10.5075 0.7575 10.5075 0.7575 9 P 0 ;1
L 10.5075 0.8075 10.5075 0.8075 9 P 0 ;1
L 10.5075 0.8575 10.5075 0.8575 9 P 0 ;1
L 10.5075 0.9075 10.5075 0.9075 9 P 0 ;1
L 10.5075 0.9575 10.5075 0.9575 9 P 0 ;1
L 10.5075 1.0075 10.5075 1.0075 9 P 0 ;1
L 10.5075 1.0575 10.5075 1.0575 9 P 0 ;1
L 10.5075 1.1075 10.5075 1.1075 9 P 0 ;1
L 10.5075 1.1575 10.5075 1.1575 9 P 0 ;1
L 10.5075 1.2075 10.5075 1.2075 9 P 0 ;1
L 10.5075 1.2575 10.5075 1.2575 9 P 0 ;1
L 10.5075 1.3075 10.5075 1.3075 9 P 0 ;1
L 10.5075 1.5075 10.5075 1.5075 9 P 0 ;1
L 10.5075 1.5575 10.5075 1.5575 9 P 0 ;1
L 10.5075 1.6075 10.5075 1.6075 9 P 0 ;1
L 10.5075 1.8575 10.5075 1.8575 9 P 0 ;1
L 10.5075 1.9075 10.5075 1.9075 9 P 0 ;1
L 10.5075 1.9575 10.5075 1.9575 9 P 0 ;1
L 10.5075 2.0075 10.5075 2.0075 9 P 0 ;1
L 10.5075 2.0575 10.5075 2.0575 9 P 0 ;1
L 10.5075 2.1075 10.5075 2.1075 9 P 0 ;1
L 10.5075 2.1575 10.5075 2.1575 9 P 0 ;1
L 10.5075 2.2075 10.5075 2.2075 9 P 0 ;1
L 10.5075 2.2575 10.5075 2.2575 9 P 0 ;1
L 10.5075 2.3075 10.5075 2.3075 9 P 0 ;1
L 10.5075 2.3575 10.5075 2.3575 9 P 0 ;1
L 10.5075 2.4075 10.5075 2.4075 9 P 0 ;1
L 10.5075 2.4575 10.5075 2.4575 9 P 0 ;1
L 10.5075 2.5075 10.5075 2.5075 9 P 0 ;1
L 10.5075 2.5575 10.5075 2.5575 9 P 0 ;1
L 10.5075 2.6075 10.5075 2.6075 9 P 0 ;1
L 10.5075 2.6575 10.5075 2.6575 9 P 0 ;1
L 10.5075 2.8575 10.5075 2.8575 9 P 0 ;1
L 10.5075 2.9075 10.5075 2.9075 9 P 0 ;1
L 10.5075 5.9075 10.5075 5.9075 9 P 0 ;1
L 10.5575 0.1575 10.5575 0.1575 9 P 0 ;1
L 10.5575 0.2075 10.5575 0.2075 9 P 0 ;1
L 10.5575 0.2575 10.5575 0.2575 9 P 0 ;1
L 10.5575 0.3075 10.5575 0.3075 9 P 0 ;1
L 10.5575 0.3575 10.5575 0.3575 9 P 0 ;1
L 10.5575 0.4075 10.5575 0.4075 9 P 0 ;1
L 10.5575 0.4575 10.5575 0.4575 9 P 0 ;1
L 10.5575 0.5075 10.5575 0.5075 9 P 0 ;1
L 10.5575 0.5575 10.5575 0.5575 9 P 0 ;1
L 10.5575 0.6075 10.5575 0.6075 9 P 0 ;1
L 10.5575 0.6575 10.5575 0.6575 9 P 0 ;1
L 10.5575 0.7075 10.5575 0.7075 9 P 0 ;1
L 10.5575 0.7575 10.5575 0.7575 9 P 0 ;1
L 10.5575 0.8075 10.5575 0.8075 9 P 0 ;1
L 10.5575 0.8575 10.5575 0.8575 9 P 0 ;1
L 10.5575 0.9075 10.5575 0.9075 9 P 0 ;1
L 10.5575 0.9575 10.5575 0.9575 9 P 0 ;1
L 10.5575 1.0075 10.5575 1.0075 9 P 0 ;1
L 10.5575 1.0575 10.5575 1.0575 9 P 0 ;1
L 10.5575 1.1075 10.5575 1.1075 9 P 0 ;1
L 10.5575 1.1575 10.5575 1.1575 9 P 0 ;1
L 10.5575 1.2075 10.5575 1.2075 9 P 0 ;1
L 10.5575 1.2575 10.5575 1.2575 9 P 0 ;1
L 10.5575 1.3075 10.5575 1.3075 9 P 0 ;1
L 10.5575 1.3575 10.5575 1.3575 9 P 0 ;1
L 10.5575 1.4075 10.5575 1.4075 9 P 0 ;1
L 10.5575 1.4575 10.5575 1.4575 9 P 0 ;1
L 10.5575 1.5075 10.5575 1.5075 9 P 0 ;1
L 10.5575 1.5575 10.5575 1.5575 9 P 0 ;1
L 10.5575 1.6075 10.5575 1.6075 9 P 0 ;1
L 10.5575 4.9575 10.5575 4.9575 9 P 0 ;1
L 10.5575 5.0075 10.5575 5.0075 9 P 0 ;1
L 10.5575 5.0575 10.5575 5.0575 9 P 0 ;1
L 10.6075 0.1575 10.6075 0.1575 9 P 0 ;1
L 10.6075 0.2075 10.6075 0.2075 9 P 0 ;1
L 10.6075 0.2575 10.6075 0.2575 9 P 0 ;1
L 10.6075 0.3075 10.6075 0.3075 9 P 0 ;1
L 10.6075 0.3575 10.6075 0.3575 9 P 0 ;1
L 10.6075 0.4075 10.6075 0.4075 9 P 0 ;1
L 10.6075 0.4575 10.6075 0.4575 9 P 0 ;1
L 10.6075 0.5075 10.6075 0.5075 9 P 0 ;1
L 10.6075 0.5575 10.6075 0.5575 9 P 0 ;1
L 10.6075 0.6075 10.6075 0.6075 9 P 0 ;1
L 10.6075 0.6575 10.6075 0.6575 9 P 0 ;1
L 10.6075 0.7075 10.6075 0.7075 9 P 0 ;1
L 10.6075 0.7575 10.6075 0.7575 9 P 0 ;1
L 10.6075 0.8075 10.6075 0.8075 9 P 0 ;1
L 10.6075 0.8575 10.6075 0.8575 9 P 0 ;1
L 10.6075 0.9075 10.6075 0.9075 9 P 0 ;1
L 10.6075 0.9575 10.6075 0.9575 9 P 0 ;1
L 10.6075 1.0075 10.6075 1.0075 9 P 0 ;1
L 10.6075 1.0575 10.6075 1.0575 9 P 0 ;1
L 10.6075 1.1075 10.6075 1.1075 9 P 0 ;1
L 10.6075 1.1575 10.6075 1.1575 9 P 0 ;1
L 10.6075 1.2075 10.6075 1.2075 9 P 0 ;1
L 10.6075 1.2575 10.6075 1.2575 9 P 0 ;1
L 10.6075 1.3075 10.6075 1.3075 9 P 0 ;1
L 10.6075 1.3575 10.6075 1.3575 9 P 0 ;1
L 10.6075 1.4075 10.6075 1.4075 9 P 0 ;1
L 10.6075 1.4575 10.6075 1.4575 9 P 0 ;1
L 10.6075 1.5075 10.6075 1.5075 9 P 0 ;1
L 10.6075 1.5575 10.6075 1.5575 9 P 0 ;1
L 10.6075 1.6075 10.6075 1.6075 9 P 0 ;1
L 10.6575 0.1575 10.6575 0.1575 9 P 0 ;1
L 10.6575 0.2075 10.6575 0.2075 9 P 0 ;1
L 10.6575 0.2575 10.6575 0.2575 9 P 0 ;1
L 10.6575 0.3075 10.6575 0.3075 9 P 0 ;1
L 10.6575 0.3575 10.6575 0.3575 9 P 0 ;1
L 10.6575 0.4075 10.6575 0.4075 9 P 0 ;1
L 10.6575 0.4575 10.6575 0.4575 9 P 0 ;1
L 10.6575 0.5075 10.6575 0.5075 9 P 0 ;1
L 10.6575 0.5575 10.6575 0.5575 9 P 0 ;1
L 10.6575 0.6075 10.6575 0.6075 9 P 0 ;1
L 10.6575 0.6575 10.6575 0.6575 9 P 0 ;1
L 10.6575 0.7075 10.6575 0.7075 9 P 0 ;1
L 10.6575 0.7575 10.6575 0.7575 9 P 0 ;1
L 10.6575 0.8075 10.6575 0.8075 9 P 0 ;1
L 10.6575 0.8575 10.6575 0.8575 9 P 0 ;1
L 10.6575 0.9075 10.6575 0.9075 9 P 0 ;1
L 10.6575 0.9575 10.6575 0.9575 9 P 0 ;1
L 10.6575 1.0075 10.6575 1.0075 9 P 0 ;1
L 10.6575 1.0575 10.6575 1.0575 9 P 0 ;1
L 10.6575 1.1075 10.6575 1.1075 9 P 0 ;1
L 10.6575 1.1575 10.6575 1.1575 9 P 0 ;1
L 10.6575 1.2075 10.6575 1.2075 9 P 0 ;1
L 10.6575 1.2575 10.6575 1.2575 9 P 0 ;1
L 10.6575 1.3075 10.6575 1.3075 9 P 0 ;1
L 10.6575 1.3575 10.6575 1.3575 9 P 0 ;1
L 10.6575 1.4075 10.6575 1.4075 9 P 0 ;1
L 10.6575 1.6075 10.6575 1.6075 9 P 0 ;1
L 10.7075 0.1575 10.7075 0.1575 9 P 0 ;1
L 10.7075 0.2075 10.7075 0.2075 9 P 0 ;1
L 10.7075 0.2575 10.7075 0.2575 9 P 0 ;1
L 10.7075 0.3075 10.7075 0.3075 9 P 0 ;1
L 10.7075 0.3575 10.7075 0.3575 9 P 0 ;1
L 10.7075 0.4075 10.7075 0.4075 9 P 0 ;1
L 10.7075 0.4575 10.7075 0.4575 9 P 0 ;1
L 10.7075 0.5075 10.7075 0.5075 9 P 0 ;1
L 10.7075 0.5575 10.7075 0.5575 9 P 0 ;1
L 10.7075 0.6075 10.7075 0.6075 9 P 0 ;1
L 10.7075 0.6575 10.7075 0.6575 9 P 0 ;1
L 10.7075 0.7075 10.7075 0.7075 9 P 0 ;1
L 10.7075 0.7575 10.7075 0.7575 9 P 0 ;1
L 10.7075 0.8075 10.7075 0.8075 9 P 0 ;1
L 10.7075 0.8575 10.7075 0.8575 9 P 0 ;1
L 10.7075 0.9075 10.7075 0.9075 9 P 0 ;1
L 10.7075 0.9575 10.7075 0.9575 9 P 0 ;1
L 10.7075 1.0075 10.7075 1.0075 9 P 0 ;1
L 10.7075 1.0575 10.7075 1.0575 9 P 0 ;1
L 10.7075 1.1075 10.7075 1.1075 9 P 0 ;1
L 10.7075 1.1575 10.7075 1.1575 9 P 0 ;1
L 10.7075 1.2075 10.7075 1.2075 9 P 0 ;1
L 10.7075 1.2575 10.7075 1.2575 9 P 0 ;1
L 10.7075 1.3075 10.7075 1.3075 9 P 0 ;1
L 10.7575 0.1575 10.7575 0.1575 9 P 0 ;1
L 10.7575 0.2075 10.7575 0.2075 9 P 0 ;1
L 10.7575 0.2575 10.7575 0.2575 9 P 0 ;1
L 10.7575 0.3075 10.7575 0.3075 9 P 0 ;1
L 10.7575 0.3575 10.7575 0.3575 9 P 0 ;1
L 10.7575 0.4075 10.7575 0.4075 9 P 0 ;1
L 10.7575 0.4575 10.7575 0.4575 9 P 0 ;1
L 10.7575 0.5075 10.7575 0.5075 9 P 0 ;1
L 10.7575 0.5575 10.7575 0.5575 9 P 0 ;1
L 10.7575 0.6075 10.7575 0.6075 9 P 0 ;1
L 10.7575 0.6575 10.7575 0.6575 9 P 0 ;1
L 10.7575 0.7075 10.7575 0.7075 9 P 0 ;1
L 10.7575 0.7575 10.7575 0.7575 9 P 0 ;1
L 10.7575 0.8075 10.7575 0.8075 9 P 0 ;1
L 10.7575 0.8575 10.7575 0.8575 9 P 0 ;1
L 10.7575 0.9075 10.7575 0.9075 9 P 0 ;1
L 10.7575 0.9575 10.7575 0.9575 9 P 0 ;1
L 10.7575 1.0075 10.7575 1.0075 9 P 0 ;1
L 10.7575 1.0575 10.7575 1.0575 9 P 0 ;1
L 10.7575 1.1075 10.7575 1.1075 9 P 0 ;1
L 10.7575 1.1575 10.7575 1.1575 9 P 0 ;1
L 10.7575 1.2075 10.7575 1.2075 9 P 0 ;1
L 10.7575 1.2575 10.7575 1.2575 9 P 0 ;1
L 10.7575 1.3075 10.7575 1.3075 9 P 0 ;1
L 10.8075 0.1575 10.8075 0.1575 9 P 0 ;1
L 10.8075 0.2075 10.8075 0.2075 9 P 0 ;1
L 10.8075 0.2575 10.8075 0.2575 9 P 0 ;1
L 10.8075 0.3075 10.8075 0.3075 9 P 0 ;1
L 10.8075 0.3575 10.8075 0.3575 9 P 0 ;1
L 10.8075 0.4075 10.8075 0.4075 9 P 0 ;1
L 10.8075 0.4575 10.8075 0.4575 9 P 0 ;1
L 10.8075 0.5075 10.8075 0.5075 9 P 0 ;1
L 10.8075 0.5575 10.8075 0.5575 9 P 0 ;1
L 10.8075 0.6075 10.8075 0.6075 9 P 0 ;1
L 10.8075 0.6575 10.8075 0.6575 9 P 0 ;1
L 10.8075 0.7075 10.8075 0.7075 9 P 0 ;1
L 10.8075 0.7575 10.8075 0.7575 9 P 0 ;1
L 10.8075 0.8075 10.8075 0.8075 9 P 0 ;1
L 10.8075 0.8575 10.8075 0.8575 9 P 0 ;1
L 10.8075 0.9075 10.8075 0.9075 9 P 0 ;1
L 10.8075 0.9575 10.8075 0.9575 9 P 0 ;1
L 10.8075 1.0075 10.8075 1.0075 9 P 0 ;1
L 10.8075 1.0575 10.8075 1.0575 9 P 0 ;1
L 10.8075 1.1075 10.8075 1.1075 9 P 0 ;1
L 10.8075 1.1575 10.8075 1.1575 9 P 0 ;1
L 10.8075 1.2075 10.8075 1.2075 9 P 0 ;1
L 10.8075 1.2575 10.8075 1.2575 9 P 0 ;1
L 10.8575 0.1575 10.8575 0.1575 9 P 0 ;1
L 10.8575 0.2075 10.8575 0.2075 9 P 0 ;1
L 10.8575 0.2575 10.8575 0.2575 9 P 0 ;1
L 10.8575 0.3075 10.8575 0.3075 9 P 0 ;1
L 10.8575 0.3575 10.8575 0.3575 9 P 0 ;1
L 10.8575 0.4075 10.8575 0.4075 9 P 0 ;1
L 10.8575 0.4575 10.8575 0.4575 9 P 0 ;1
L 10.8575 0.5075 10.8575 0.5075 9 P 0 ;1
L 10.8575 0.5575 10.8575 0.5575 9 P 0 ;1
L 10.8575 0.6075 10.8575 0.6075 9 P 0 ;1
L 10.8575 0.6575 10.8575 0.6575 9 P 0 ;1
L 10.8575 0.7075 10.8575 0.7075 9 P 0 ;1
L 10.8575 0.7575 10.8575 0.7575 9 P 0 ;1
L 10.8575 0.8075 10.8575 0.8075 9 P 0 ;1
L 10.8575 0.8575 10.8575 0.8575 9 P 0 ;1
L 10.8575 0.9075 10.8575 0.9075 9 P 0 ;1
L 10.8575 0.9575 10.8575 0.9575 9 P 0 ;1
L 10.8575 1.0075 10.8575 1.0075 9 P 0 ;1
L 10.8575 1.0575 10.8575 1.0575 9 P 0 ;1
L 10.8575 1.1075 10.8575 1.1075 9 P 0 ;1
L 10.8575 1.1575 10.8575 1.1575 9 P 0 ;1
L 10.8575 1.2075 10.8575 1.2075 9 P 0 ;1
L 10.8575 1.2575 10.8575 1.2575 9 P 0 ;1
L 10.9075 0.1575 10.9075 0.1575 9 P 0 ;1
L 10.9075 0.2075 10.9075 0.2075 9 P 0 ;1
L 10.9075 0.2575 10.9075 0.2575 9 P 0 ;1
L 10.9075 0.3075 10.9075 0.3075 9 P 0 ;1
L 10.9075 0.3575 10.9075 0.3575 9 P 0 ;1
L 10.9075 0.4075 10.9075 0.4075 9 P 0 ;1
L 10.9075 0.4575 10.9075 0.4575 9 P 0 ;1
L 10.9075 0.5075 10.9075 0.5075 9 P 0 ;1
L 10.9075 0.5575 10.9075 0.5575 9 P 0 ;1
L 10.9075 0.6075 10.9075 0.6075 9 P 0 ;1
L 10.9075 0.6575 10.9075 0.6575 9 P 0 ;1
L 10.9075 0.7075 10.9075 0.7075 9 P 0 ;1
L 10.9075 0.7575 10.9075 0.7575 9 P 0 ;1
L 10.9075 0.8075 10.9075 0.8075 9 P 0 ;1
L 10.9075 0.8575 10.9075 0.8575 9 P 0 ;1
L 10.9075 0.9075 10.9075 0.9075 9 P 0 ;1
L 10.9075 0.9575 10.9075 0.9575 9 P 0 ;1
L 10.9075 1.0075 10.9075 1.0075 9 P 0 ;1
L 10.9075 1.0575 10.9075 1.0575 9 P 0 ;1
L 10.9075 1.1075 10.9075 1.1075 9 P 0 ;1
L 10.9075 1.1575 10.9075 1.1575 9 P 0 ;1
L 10.9075 1.2075 10.9075 1.2075 9 P 0 ;1
L 10.9075 1.2575 10.9075 1.2575 9 P 0 ;1
L 10.9075 1.3075 10.9075 1.3075 9 P 0 ;1
L 10.9575 0.1575 10.9575 0.1575 9 P 0 ;1
L 10.9575 0.2075 10.9575 0.2075 9 P 0 ;1
L 10.9575 0.2575 10.9575 0.2575 9 P 0 ;1
L 10.9575 0.3075 10.9575 0.3075 9 P 0 ;1
L 10.9575 0.3575 10.9575 0.3575 9 P 0 ;1
L 10.9575 0.4075 10.9575 0.4075 9 P 0 ;1
L 10.9575 0.4575 10.9575 0.4575 9 P 0 ;1
L 10.9575 0.5075 10.9575 0.5075 9 P 0 ;1
L 10.9575 0.5575 10.9575 0.5575 9 P 0 ;1
L 10.9575 0.6075 10.9575 0.6075 9 P 0 ;1
L 10.9575 0.6575 10.9575 0.6575 9 P 0 ;1
L 10.9575 0.7075 10.9575 0.7075 9 P 0 ;1
L 10.9575 0.7575 10.9575 0.7575 9 P 0 ;1
L 10.9575 0.8075 10.9575 0.8075 9 P 0 ;1
L 10.9575 0.8575 10.9575 0.8575 9 P 0 ;1
L 10.9575 0.9075 10.9575 0.9075 9 P 0 ;1
L 10.9575 0.9575 10.9575 0.9575 9 P 0 ;1
L 10.9575 1.0075 10.9575 1.0075 9 P 0 ;1
L 10.9575 1.0575 10.9575 1.0575 9 P 0 ;1
L 10.9575 1.1075 10.9575 1.1075 9 P 0 ;1
L 10.9575 1.1575 10.9575 1.1575 9 P 0 ;1
L 10.9575 1.2075 10.9575 1.2075 9 P 0 ;1
L 10.9575 1.2575 10.9575 1.2575 9 P 0 ;1
L 10.9575 1.3075 10.9575 1.3075 9 P 0 ;1
L 11.0075 0.1575 11.0075 0.1575 9 P 0 ;1
L 11.0075 0.2075 11.0075 0.2075 9 P 0 ;1
L 11.0075 0.2575 11.0075 0.2575 9 P 0 ;1
L 11.0075 0.3075 11.0075 0.3075 9 P 0 ;1
L 11.0075 0.3575 11.0075 0.3575 9 P 0 ;1
L 11.0075 0.4075 11.0075 0.4075 9 P 0 ;1
L 11.0075 0.4575 11.0075 0.4575 9 P 0 ;1
L 11.0075 0.5075 11.0075 0.5075 9 P 0 ;1
L 11.0075 0.5575 11.0075 0.5575 9 P 0 ;1
L 11.0075 0.6075 11.0075 0.6075 9 P 0 ;1
L 11.0075 0.6575 11.0075 0.6575 9 P 0 ;1
L 11.0075 0.7075 11.0075 0.7075 9 P 0 ;1
L 11.0075 0.7575 11.0075 0.7575 9 P 0 ;1
L 11.0075 0.8075 11.0075 0.8075 9 P 0 ;1
L 11.0075 0.8575 11.0075 0.8575 9 P 0 ;1
L 11.0075 0.9075 11.0075 0.9075 9 P 0 ;1
L 11.0075 0.9575 11.0075 0.9575 9 P 0 ;1
L 11.0075 1.0075 11.0075 1.0075 9 P 0 ;1
L 11.0075 1.0575 11.0075 1.0575 9 P 0 ;1
L 11.0075 1.1075 11.0075 1.1075 9 P 0 ;1
L 11.0075 1.1575 11.0075 1.1575 9 P 0 ;1
L 11.0075 1.2075 11.0075 1.2075 9 P 0 ;1
L 11.0075 1.2575 11.0075 1.2575 9 P 0 ;1
L 11.0075 1.3075 11.0075 1.3075 9 P 0 ;1
L 11.0075 1.3575 11.0075 1.3575 9 P 0 ;1
L 11.0075 1.4075 11.0075 1.4075 9 P 0 ;1
L 11.0075 1.6075 11.0075 1.6075 9 P 0 ;1
L 11.0575 0.1575 11.0575 0.1575 9 P 0 ;1
L 11.0575 0.2075 11.0575 0.2075 9 P 0 ;1
L 11.0575 0.2575 11.0575 0.2575 9 P 0 ;1
L 11.0575 0.3075 11.0575 0.3075 9 P 0 ;1
L 11.0575 0.3575 11.0575 0.3575 9 P 0 ;1
L 11.0575 0.4075 11.0575 0.4075 9 P 0 ;1
L 11.0575 0.4575 11.0575 0.4575 9 P 0 ;1
L 11.0575 0.5075 11.0575 0.5075 9 P 0 ;1
L 11.0575 0.5575 11.0575 0.5575 9 P 0 ;1
L 11.0575 0.6075 11.0575 0.6075 9 P 0 ;1
L 11.0575 0.6575 11.0575 0.6575 9 P 0 ;1
L 11.0575 0.7075 11.0575 0.7075 9 P 0 ;1
L 11.0575 0.7575 11.0575 0.7575 9 P 0 ;1
L 11.0575 0.8075 11.0575 0.8075 9 P 0 ;1
L 11.0575 0.8575 11.0575 0.8575 9 P 0 ;1
L 11.0575 0.9075 11.0575 0.9075 9 P 0 ;1
L 11.0575 0.9575 11.0575 0.9575 9 P 0 ;1
L 11.0575 1.0075 11.0575 1.0075 9 P 0 ;1
L 11.0575 1.0575 11.0575 1.0575 9 P 0 ;1
L 11.0575 1.1075 11.0575 1.1075 9 P 0 ;1
L 11.0575 1.1575 11.0575 1.1575 9 P 0 ;1
L 11.0575 1.2075 11.0575 1.2075 9 P 0 ;1
L 11.0575 1.2575 11.0575 1.2575 9 P 0 ;1
L 11.0575 1.3075 11.0575 1.3075 9 P 0 ;1
L 11.0575 1.3575 11.0575 1.3575 9 P 0 ;1
L 11.0575 1.4075 11.0575 1.4075 9 P 0 ;1
L 11.0575 1.4575 11.0575 1.4575 9 P 0 ;1
L 11.0575 1.5075 11.0575 1.5075 9 P 0 ;1
L 11.0575 1.5575 11.0575 1.5575 9 P 0 ;1
L 11.0575 1.6075 11.0575 1.6075 9 P 0 ;1
L 11.1075 0.1575 11.1075 0.1575 9 P 0 ;1
L 11.1075 0.2075 11.1075 0.2075 9 P 0 ;1
L 11.1075 0.2575 11.1075 0.2575 9 P 0 ;1
L 11.1075 0.3075 11.1075 0.3075 9 P 0 ;1
L 11.1075 0.3575 11.1075 0.3575 9 P 0 ;1
L 11.1075 0.4075 11.1075 0.4075 9 P 0 ;1
L 11.1075 0.4575 11.1075 0.4575 9 P 0 ;1
L 11.1075 0.5075 11.1075 0.5075 9 P 0 ;1
L 11.1075 0.5575 11.1075 0.5575 9 P 0 ;1
L 11.1075 0.6075 11.1075 0.6075 9 P 0 ;1
L 11.1075 0.6575 11.1075 0.6575 9 P 0 ;1
L 11.1075 0.7075 11.1075 0.7075 9 P 0 ;1
L 11.1075 0.7575 11.1075 0.7575 9 P 0 ;1
L 11.1075 0.8075 11.1075 0.8075 9 P 0 ;1
L 11.1075 0.8575 11.1075 0.8575 9 P 0 ;1
L 11.1075 0.9075 11.1075 0.9075 9 P 0 ;1
L 11.1075 0.9575 11.1075 0.9575 9 P 0 ;1
L 11.1075 1.0075 11.1075 1.0075 9 P 0 ;1
L 11.1075 1.0575 11.1075 1.0575 9 P 0 ;1
L 11.1075 1.1075 11.1075 1.1075 9 P 0 ;1
L 11.1075 1.1575 11.1075 1.1575 9 P 0 ;1
L 11.1075 1.2075 11.1075 1.2075 9 P 0 ;1
L 11.1075 1.2575 11.1075 1.2575 9 P 0 ;1
L 11.1075 1.3075 11.1075 1.3075 9 P 0 ;1
L 11.1075 1.3575 11.1075 1.3575 9 P 0 ;1
L 11.1075 1.4075 11.1075 1.4075 9 P 0 ;1
L 11.1075 1.4575 11.1075 1.4575 9 P 0 ;1
L 11.1075 1.5075 11.1075 1.5075 9 P 0 ;1
L 11.1075 1.5575 11.1075 1.5575 9 P 0 ;1
L 11.1075 1.6075 11.1075 1.6075 9 P 0 ;1
L 11.1575 0.1575 11.1575 0.1575 9 P 0 ;1
L 11.1575 0.2075 11.1575 0.2075 9 P 0 ;1
L 11.1575 0.2575 11.1575 0.2575 9 P 0 ;1
L 11.1575 0.3075 11.1575 0.3075 9 P 0 ;1
L 11.1575 0.3575 11.1575 0.3575 9 P 0 ;1
L 11.1575 0.4075 11.1575 0.4075 9 P 0 ;1
L 11.1575 0.4575 11.1575 0.4575 9 P 0 ;1
L 11.1575 0.5075 11.1575 0.5075 9 P 0 ;1
L 11.1575 0.5575 11.1575 0.5575 9 P 0 ;1
L 11.1575 0.6075 11.1575 0.6075 9 P 0 ;1
L 11.1575 0.6575 11.1575 0.6575 9 P 0 ;1
L 11.1575 0.7075 11.1575 0.7075 9 P 0 ;1
L 11.1575 0.7575 11.1575 0.7575 9 P 0 ;1
L 11.1575 0.8075 11.1575 0.8075 9 P 0 ;1
L 11.1575 0.8575 11.1575 0.8575 9 P 0 ;1
L 11.1575 0.9075 11.1575 0.9075 9 P 0 ;1
L 11.1575 0.9575 11.1575 0.9575 9 P 0 ;1
L 11.1575 1.0075 11.1575 1.0075 9 P 0 ;1
L 11.1575 1.0575 11.1575 1.0575 9 P 0 ;1
L 11.1575 1.1075 11.1575 1.1075 9 P 0 ;1
L 11.1575 1.1575 11.1575 1.1575 9 P 0 ;1
L 11.1575 1.2075 11.1575 1.2075 9 P 0 ;1
L 11.1575 1.2575 11.1575 1.2575 9 P 0 ;1
L 11.1575 1.3075 11.1575 1.3075 9 P 0 ;1
L 11.1575 1.3575 11.1575 1.3575 9 P 0 ;1
L 11.1575 1.4075 11.1575 1.4075 9 P 0 ;1
L 11.1575 1.4575 11.1575 1.4575 9 P 0 ;1
L 11.1575 1.5075 11.1575 1.5075 9 P 0 ;1
L 11.1575 1.5575 11.1575 1.5575 9 P 0 ;1
L 11.1575 1.6075 11.1575 1.6075 9 P 0 ;1
L 11.1575 1.6575 11.1575 1.6575 9 P 0 ;1
L 11.2075 0.1575 11.2075 0.1575 9 P 0 ;1
L 11.2075 0.2075 11.2075 0.2075 9 P 0 ;1
L 11.2075 0.2575 11.2075 0.2575 9 P 0 ;1
L 11.2075 0.3075 11.2075 0.3075 9 P 0 ;1
L 11.2075 0.3575 11.2075 0.3575 9 P 0 ;1
L 11.2075 0.4075 11.2075 0.4075 9 P 0 ;1
L 11.2075 0.4575 11.2075 0.4575 9 P 0 ;1
L 11.2075 0.5075 11.2075 0.5075 9 P 0 ;1
L 11.2075 0.5575 11.2075 0.5575 9 P 0 ;1
L 11.2075 0.6075 11.2075 0.6075 9 P 0 ;1
L 11.2075 0.6575 11.2075 0.6575 9 P 0 ;1
L 11.2075 0.7075 11.2075 0.7075 9 P 0 ;1
L 11.2075 0.7575 11.2075 0.7575 9 P 0 ;1
L 11.2075 0.8075 11.2075 0.8075 9 P 0 ;1
L 11.2075 0.8575 11.2075 0.8575 9 P 0 ;1
L 11.2075 0.9075 11.2075 0.9075 9 P 0 ;1
L 11.2075 0.9575 11.2075 0.9575 9 P 0 ;1
L 11.2075 1.0075 11.2075 1.0075 9 P 0 ;1
L 11.2075 1.0575 11.2075 1.0575 9 P 0 ;1
L 11.2075 1.1075 11.2075 1.1075 9 P 0 ;1
L 11.2075 1.1575 11.2075 1.1575 9 P 0 ;1
L 11.2075 1.2075 11.2075 1.2075 9 P 0 ;1
L 11.2075 1.2575 11.2075 1.2575 9 P 0 ;1
L 11.2075 1.3075 11.2075 1.3075 9 P 0 ;1
L 11.2075 1.3575 11.2075 1.3575 9 P 0 ;1
L 11.2075 1.4075 11.2075 1.4075 9 P 0 ;1
L 11.2075 1.4575 11.2075 1.4575 9 P 0 ;1
L 11.2075 1.5075 11.2075 1.5075 9 P 0 ;1
L 11.2075 1.5575 11.2075 1.5575 9 P 0 ;1
L 11.2075 1.6075 11.2075 1.6075 9 P 0 ;1
L 11.2075 1.6575 11.2075 1.6575 9 P 0 ;1
L 11.2075 1.7075 11.2075 1.7075 9 P 0 ;1
L 11.2575 0.1575 11.2575 0.1575 9 P 0 ;1
L 11.2575 0.2075 11.2575 0.2075 9 P 0 ;1
L 11.2575 0.2575 11.2575 0.2575 9 P 0 ;1
L 11.2575 0.3075 11.2575 0.3075 9 P 0 ;1
L 11.2575 0.3575 11.2575 0.3575 9 P 0 ;1
L 11.2575 0.4075 11.2575 0.4075 9 P 0 ;1
L 11.2575 0.4575 11.2575 0.4575 9 P 0 ;1
L 11.2575 0.5075 11.2575 0.5075 9 P 0 ;1
L 11.2575 0.5575 11.2575 0.5575 9 P 0 ;1
L 11.2575 0.6075 11.2575 0.6075 9 P 0 ;1
L 11.2575 0.6575 11.2575 0.6575 9 P 0 ;1
L 11.2575 0.7075 11.2575 0.7075 9 P 0 ;1
L 11.2575 0.7575 11.2575 0.7575 9 P 0 ;1
L 11.2575 0.8075 11.2575 0.8075 9 P 0 ;1
L 11.2575 0.8575 11.2575 0.8575 9 P 0 ;1
L 11.2575 0.9075 11.2575 0.9075 9 P 0 ;1
L 11.2575 0.9575 11.2575 0.9575 9 P 0 ;1
L 11.2575 1.0075 11.2575 1.0075 9 P 0 ;1
L 11.2575 1.0575 11.2575 1.0575 9 P 0 ;1
L 11.2575 1.1075 11.2575 1.1075 9 P 0 ;1
L 11.2575 1.1575 11.2575 1.1575 9 P 0 ;1
L 11.2575 1.2075 11.2575 1.2075 9 P 0 ;1
L 11.2575 1.2575 11.2575 1.2575 9 P 0 ;1
L 11.2575 1.3075 11.2575 1.3075 9 P 0 ;1
L 11.2575 1.3575 11.2575 1.3575 9 P 0 ;1
L 11.2575 1.4075 11.2575 1.4075 9 P 0 ;1
L 11.2575 1.4575 11.2575 1.4575 9 P 0 ;1
L 11.2575 1.5075 11.2575 1.5075 9 P 0 ;1
L 11.2575 1.5575 11.2575 1.5575 9 P 0 ;1
L 11.2575 1.6075 11.2575 1.6075 9 P 0 ;1
L 11.2575 1.6575 11.2575 1.6575 9 P 0 ;1
L 11.2575 1.7075 11.2575 1.7075 9 P 0 ;1
L 11.2575 1.7575 11.2575 1.7575 9 P 0 ;1
L 11.3075 0.1575 11.3075 0.1575 9 P 0 ;1
L 11.3075 0.2075 11.3075 0.2075 9 P 0 ;1
L 11.3075 0.2575 11.3075 0.2575 9 P 0 ;1
L 11.3075 0.3075 11.3075 0.3075 9 P 0 ;1
L 11.3075 0.3575 11.3075 0.3575 9 P 0 ;1
L 11.3075 0.4075 11.3075 0.4075 9 P 0 ;1
L 11.3075 0.4575 11.3075 0.4575 9 P 0 ;1
L 11.3075 0.5075 11.3075 0.5075 9 P 0 ;1
L 11.3075 0.5575 11.3075 0.5575 9 P 0 ;1
L 11.3075 0.6075 11.3075 0.6075 9 P 0 ;1
L 11.3075 0.6575 11.3075 0.6575 9 P 0 ;1
L 11.3075 0.7075 11.3075 0.7075 9 P 0 ;1
L 11.3075 0.7575 11.3075 0.7575 9 P 0 ;1
L 11.3075 0.8075 11.3075 0.8075 9 P 0 ;1
L 11.3075 0.8575 11.3075 0.8575 9 P 0 ;1
L 11.3075 0.9075 11.3075 0.9075 9 P 0 ;1
L 11.3075 0.9575 11.3075 0.9575 9 P 0 ;1
L 11.3075 1.0075 11.3075 1.0075 9 P 0 ;1
L 11.3075 1.0575 11.3075 1.0575 9 P 0 ;1
L 11.3075 1.1075 11.3075 1.1075 9 P 0 ;1
L 11.3075 1.1575 11.3075 1.1575 9 P 0 ;1
L 11.3075 1.2075 11.3075 1.2075 9 P 0 ;1
L 11.3075 1.2575 11.3075 1.2575 9 P 0 ;1
L 11.3075 1.3075 11.3075 1.3075 9 P 0 ;1
L 11.3075 1.3575 11.3075 1.3575 9 P 0 ;1
L 11.3075 1.4075 11.3075 1.4075 9 P 0 ;1
L 11.3075 1.4575 11.3075 1.4575 9 P 0 ;1
L 11.3075 1.5075 11.3075 1.5075 9 P 0 ;1
L 11.3075 1.5575 11.3075 1.5575 9 P 0 ;1
L 11.3075 1.6075 11.3075 1.6075 9 P 0 ;1
L 11.3075 1.6575 11.3075 1.6575 9 P 0 ;1
L 11.3075 1.7075 11.3075 1.7075 9 P 0 ;1
L 11.3075 1.7575 11.3075 1.7575 9 P 0 ;1
L 11.3075 1.8075 11.3075 1.8075 9 P 0 ;1
L 11.3075 1.8575 11.3075 1.8575 9 P 0 ;1
L 11.3075 1.9075 11.3075 1.9075 9 P 0 ;1
L 11.3075 1.9575 11.3075 1.9575 9 P 0 ;1
L 11.3075 2.0075 11.3075 2.0075 9 P 0 ;1
L 11.3075 2.0575 11.3075 2.0575 9 P 0 ;1
L 11.3075 2.1075 11.3075 2.1075 9 P 0 ;1
L 11.3075 2.1575 11.3075 2.1575 9 P 0 ;1
L 11.3075 2.2075 11.3075 2.2075 9 P 0 ;1
L 11.3075 2.2575 11.3075 2.2575 9 P 0 ;1
L 11.3075 2.3075 11.3075 2.3075 9 P 0 ;1
L 11.3075 2.3575 11.3075 2.3575 9 P 0 ;1
L 11.3075 2.4075 11.3075 2.4075 9 P 0 ;1
L 11.3075 2.4575 11.3075 2.4575 9 P 0 ;1
L 11.3075 2.5075 11.3075 2.5075 9 P 0 ;1
L 11.3075 2.5575 11.3075 2.5575 9 P 0 ;1
L 11.3075 2.6075 11.3075 2.6075 9 P 0 ;1
L 11.3075 2.6575 11.3075 2.6575 9 P 0 ;1
L 11.3075 2.7075 11.3075 2.7075 9 P 0 ;1
L 11.3075 2.7575 11.3075 2.7575 9 P 0 ;1
L 11.3075 3.4075 11.3075 3.4075 9 P 0 ;1
L 11.3075 3.4575 11.3075 3.4575 9 P 0 ;1
L 11.3075 3.5075 11.3075 3.5075 9 P 0 ;1
L 11.3075 3.5575 11.3075 3.5575 9 P 0 ;1
L 11.3075 3.6075 11.3075 3.6075 9 P 0 ;1
L 11.3075 3.6575 11.3075 3.6575 9 P 0 ;1
L 11.3075 3.7075 11.3075 3.7075 9 P 0 ;1
L 11.3075 3.7575 11.3075 3.7575 9 P 0 ;1
L 11.3075 3.8075 11.3075 3.8075 9 P 0 ;1
L 11.3075 3.8575 11.3075 3.8575 9 P 0 ;1
L 11.3075 3.9075 11.3075 3.9075 9 P 0 ;1
L 11.3075 3.9575 11.3075 3.9575 9 P 0 ;1
L 11.3075 4.0075 11.3075 4.0075 9 P 0 ;1
L 11.3075 4.0575 11.3075 4.0575 9 P 0 ;1
L 11.3075 4.1075 11.3075 4.1075 9 P 0 ;1
L 11.3075 4.1575 11.3075 4.1575 9 P 0 ;1
L 11.3075 4.2075 11.3075 4.2075 9 P 0 ;1
L 11.3075 4.2575 11.3075 4.2575 9 P 0 ;1
L 11.3075 4.3075 11.3075 4.3075 9 P 0 ;1
L 11.3075 4.3575 11.3075 4.3575 9 P 0 ;1
L 11.3075 4.4075 11.3075 4.4075 9 P 0 ;1
L 11.3075 4.4575 11.3075 4.4575 9 P 0 ;1
L 11.3075 4.5075 11.3075 4.5075 9 P 0 ;1
L 11.3075 4.5575 11.3075 4.5575 9 P 0 ;1
L 11.3075 4.6075 11.3075 4.6075 9 P 0 ;1
L 11.3075 4.6575 11.3075 4.6575 9 P 0 ;1
L 11.3075 4.7075 11.3075 4.7075 9 P 0 ;1
L 11.3575 0.1575 11.3575 0.1575 9 P 0 ;1
L 11.3575 0.2075 11.3575 0.2075 9 P 0 ;1
L 11.3575 0.2575 11.3575 0.2575 9 P 0 ;1
L 11.3575 0.3075 11.3575 0.3075 9 P 0 ;1
L 11.3575 0.3575 11.3575 0.3575 9 P 0 ;1
L 11.3575 0.4075 11.3575 0.4075 9 P 0 ;1
L 11.3575 0.4575 11.3575 0.4575 9 P 0 ;1
L 11.3575 0.5075 11.3575 0.5075 9 P 0 ;1
L 11.3575 0.5575 11.3575 0.5575 9 P 0 ;1
L 11.3575 0.6075 11.3575 0.6075 9 P 0 ;1
L 11.3575 0.6575 11.3575 0.6575 9 P 0 ;1
L 11.3575 0.7075 11.3575 0.7075 9 P 0 ;1
L 11.3575 0.7575 11.3575 0.7575 9 P 0 ;1
L 11.3575 0.8075 11.3575 0.8075 9 P 0 ;1
L 11.3575 0.8575 11.3575 0.8575 9 P 0 ;1
L 11.3575 0.9075 11.3575 0.9075 9 P 0 ;1
L 11.3575 0.9575 11.3575 0.9575 9 P 0 ;1
L 11.3575 1.0075 11.3575 1.0075 9 P 0 ;1
L 11.3575 1.0575 11.3575 1.0575 9 P 0 ;1
L 11.3575 1.1075 11.3575 1.1075 9 P 0 ;1
L 11.3575 1.1575 11.3575 1.1575 9 P 0 ;1
L 11.3575 1.2075 11.3575 1.2075 9 P 0 ;1
L 11.3575 1.2575 11.3575 1.2575 9 P 0 ;1
L 11.3575 1.3075 11.3575 1.3075 9 P 0 ;1
L 11.3575 1.3575 11.3575 1.3575 9 P 0 ;1
L 11.3575 1.4075 11.3575 1.4075 9 P 0 ;1
L 11.3575 1.4575 11.3575 1.4575 9 P 0 ;1
L 11.3575 1.5075 11.3575 1.5075 9 P 0 ;1
L 11.3575 1.5575 11.3575 1.5575 9 P 0 ;1
L 11.3575 1.6075 11.3575 1.6075 9 P 0 ;1
L 11.3575 1.6575 11.3575 1.6575 9 P 0 ;1
L 11.3575 1.7075 11.3575 1.7075 9 P 0 ;1
L 11.3575 1.7575 11.3575 1.7575 9 P 0 ;1
L 11.3575 1.8075 11.3575 1.8075 9 P 0 ;1
L 11.3575 1.8575 11.3575 1.8575 9 P 0 ;1
L 11.3575 1.9075 11.3575 1.9075 9 P 0 ;1
L 11.3575 1.9575 11.3575 1.9575 9 P 0 ;1
L 11.3575 2.0075 11.3575 2.0075 9 P 0 ;1
L 11.3575 2.0575 11.3575 2.0575 9 P 0 ;1
L 11.3575 2.1075 11.3575 2.1075 9 P 0 ;1
L 11.3575 2.1575 11.3575 2.1575 9 P 0 ;1
L 11.3575 2.2075 11.3575 2.2075 9 P 0 ;1
L 11.3575 2.2575 11.3575 2.2575 9 P 0 ;1
L 11.3575 2.3075 11.3575 2.3075 9 P 0 ;1
L 11.3575 2.3575 11.3575 2.3575 9 P 0 ;1
L 11.3575 2.4075 11.3575 2.4075 9 P 0 ;1
L 11.3575 2.4575 11.3575 2.4575 9 P 0 ;1
L 11.3575 2.5075 11.3575 2.5075 9 P 0 ;1
L 11.3575 2.5575 11.3575 2.5575 9 P 0 ;1
L 11.3575 2.6075 11.3575 2.6075 9 P 0 ;1
L 11.3575 2.9075 11.3575 2.9075 9 P 0 ;1
L 11.3575 3.3575 11.3575 3.3575 9 P 0 ;1
L 11.3575 3.4075 11.3575 3.4075 9 P 0 ;1
L 11.3575 3.4575 11.3575 3.4575 9 P 0 ;1
L 11.3575 3.5075 11.3575 3.5075 9 P 0 ;1
L 11.3575 3.5575 11.3575 3.5575 9 P 0 ;1
L 11.3575 3.6075 11.3575 3.6075 9 P 0 ;1
L 11.3575 3.6575 11.3575 3.6575 9 P 0 ;1
L 11.3575 3.7075 11.3575 3.7075 9 P 0 ;1
L 11.3575 3.7575 11.3575 3.7575 9 P 0 ;1
L 11.3575 3.8075 11.3575 3.8075 9 P 0 ;1
L 11.3575 3.8575 11.3575 3.8575 9 P 0 ;1
L 11.3575 3.9075 11.3575 3.9075 9 P 0 ;1
L 11.3575 3.9575 11.3575 3.9575 9 P 0 ;1
L 11.3575 4.0075 11.3575 4.0075 9 P 0 ;1
L 11.3575 4.0575 11.3575 4.0575 9 P 0 ;1
L 11.3575 4.1075 11.3575 4.1075 9 P 0 ;1
L 11.3575 4.1575 11.3575 4.1575 9 P 0 ;1
L 11.3575 4.2075 11.3575 4.2075 9 P 0 ;1
L 11.3575 4.2575 11.3575 4.2575 9 P 0 ;1
L 11.3575 4.3075 11.3575 4.3075 9 P 0 ;1
L 11.3575 4.3575 11.3575 4.3575 9 P 0 ;1
L 11.3575 4.4075 11.3575 4.4075 9 P 0 ;1
L 11.3575 4.4575 11.3575 4.4575 9 P 0 ;1
L 11.3575 4.5075 11.3575 4.5075 9 P 0 ;1
L 11.3575 4.5575 11.3575 4.5575 9 P 0 ;1
L 11.3575 4.6075 11.3575 4.6075 9 P 0 ;1
L 11.3575 4.6575 11.3575 4.6575 9 P 0 ;1
L 11.3575 4.7075 11.3575 4.7075 9 P 0 ;1
L 11.4075 0.1575 11.4075 0.1575 9 P 0 ;1
L 11.4075 0.2075 11.4075 0.2075 9 P 0 ;1
L 11.4075 0.2575 11.4075 0.2575 9 P 0 ;1
L 11.4075 0.3075 11.4075 0.3075 9 P 0 ;1
L 11.4075 0.3575 11.4075 0.3575 9 P 0 ;1
L 11.4075 0.4075 11.4075 0.4075 9 P 0 ;1
L 11.4075 0.4575 11.4075 0.4575 9 P 0 ;1
L 11.4075 0.5075 11.4075 0.5075 9 P 0 ;1
L 11.4075 0.5575 11.4075 0.5575 9 P 0 ;1
L 11.4075 0.6075 11.4075 0.6075 9 P 0 ;1
L 11.4075 0.6575 11.4075 0.6575 9 P 0 ;1
L 11.4075 0.7075 11.4075 0.7075 9 P 0 ;1
L 11.4075 0.7575 11.4075 0.7575 9 P 0 ;1
L 11.4075 0.8075 11.4075 0.8075 9 P 0 ;1
L 11.4075 0.8575 11.4075 0.8575 9 P 0 ;1
L 11.4075 0.9075 11.4075 0.9075 9 P 0 ;1
L 11.4075 0.9575 11.4075 0.9575 9 P 0 ;1
L 11.4075 1.0075 11.4075 1.0075 9 P 0 ;1
L 11.4075 1.0575 11.4075 1.0575 9 P 0 ;1
L 11.4075 1.1075 11.4075 1.1075 9 P 0 ;1
L 11.4075 1.1575 11.4075 1.1575 9 P 0 ;1
L 11.4075 1.2075 11.4075 1.2075 9 P 0 ;1
L 11.4075 1.2575 11.4075 1.2575 9 P 0 ;1
L 11.4075 1.3075 11.4075 1.3075 9 P 0 ;1
L 11.4075 1.3575 11.4075 1.3575 9 P 0 ;1
L 11.4075 1.4075 11.4075 1.4075 9 P 0 ;1
L 11.4075 1.4575 11.4075 1.4575 9 P 0 ;1
L 11.4075 1.5075 11.4075 1.5075 9 P 0 ;1
L 11.4075 1.5575 11.4075 1.5575 9 P 0 ;1
L 11.4075 1.6075 11.4075 1.6075 9 P 0 ;1
L 11.4075 1.6575 11.4075 1.6575 9 P 0 ;1
L 11.4075 1.7075 11.4075 1.7075 9 P 0 ;1
L 11.4075 1.7575 11.4075 1.7575 9 P 0 ;1
L 11.4075 1.8075 11.4075 1.8075 9 P 0 ;1
L 11.4075 1.8575 11.4075 1.8575 9 P 0 ;1
L 11.4075 1.9075 11.4075 1.9075 9 P 0 ;1
L 11.4075 1.9575 11.4075 1.9575 9 P 0 ;1
L 11.4075 2.0075 11.4075 2.0075 9 P 0 ;1
L 11.4075 2.0575 11.4075 2.0575 9 P 0 ;1
L 11.4075 2.1075 11.4075 2.1075 9 P 0 ;1
L 11.4075 2.1575 11.4075 2.1575 9 P 0 ;1
L 11.4075 2.2075 11.4075 2.2075 9 P 0 ;1
L 11.4075 2.2575 11.4075 2.2575 9 P 0 ;1
L 11.4075 2.3075 11.4075 2.3075 9 P 0 ;1
L 11.4075 2.3575 11.4075 2.3575 9 P 0 ;1
L 11.4075 2.4075 11.4075 2.4075 9 P 0 ;1
L 11.4075 2.4575 11.4075 2.4575 9 P 0 ;1
L 11.4075 2.5075 11.4075 2.5075 9 P 0 ;1
L 11.4075 2.5575 11.4075 2.5575 9 P 0 ;1
L 11.4075 2.6075 11.4075 2.6075 9 P 0 ;1
L 11.4075 3.4075 11.4075 3.4075 9 P 0 ;1
L 11.4075 3.4575 11.4075 3.4575 9 P 0 ;1
L 11.4075 3.5075 11.4075 3.5075 9 P 0 ;1
L 11.4075 3.5575 11.4075 3.5575 9 P 0 ;1
L 11.4075 3.6075 11.4075 3.6075 9 P 0 ;1
L 11.4075 3.6575 11.4075 3.6575 9 P 0 ;1
L 11.4075 3.7075 11.4075 3.7075 9 P 0 ;1
L 11.4075 3.7575 11.4075 3.7575 9 P 0 ;1
L 11.4075 3.8075 11.4075 3.8075 9 P 0 ;1
L 11.4075 3.8575 11.4075 3.8575 9 P 0 ;1
L 11.4075 3.9075 11.4075 3.9075 9 P 0 ;1
L 11.4075 3.9575 11.4075 3.9575 9 P 0 ;1
L 11.4075 4.0075 11.4075 4.0075 9 P 0 ;1
L 11.4075 4.0575 11.4075 4.0575 9 P 0 ;1
L 11.4075 4.1075 11.4075 4.1075 9 P 0 ;1
L 11.4075 4.1575 11.4075 4.1575 9 P 0 ;1
L 11.4075 4.2075 11.4075 4.2075 9 P 0 ;1
L 11.4075 4.2575 11.4075 4.2575 9 P 0 ;1
L 11.4075 4.3075 11.4075 4.3075 9 P 0 ;1
L 11.4075 4.3575 11.4075 4.3575 9 P 0 ;1
L 11.4075 4.4075 11.4075 4.4075 9 P 0 ;1
L 11.4075 4.4575 11.4075 4.4575 9 P 0 ;1
L 11.4075 4.5075 11.4075 4.5075 9 P 0 ;1
L 11.4075 4.5575 11.4075 4.5575 9 P 0 ;1
L 11.4075 4.6075 11.4075 4.6075 9 P 0 ;1
L 11.4075 4.6575 11.4075 4.6575 9 P 0 ;1
L 11.4075 4.7075 11.4075 4.7075 9 P 0 ;1
L 11.4575 0.1575 11.4575 0.1575 9 P 0 ;1
L 11.4575 0.2075 11.4575 0.2075 9 P 0 ;1
L 11.4575 0.2575 11.4575 0.2575 9 P 0 ;1
L 11.4575 0.3075 11.4575 0.3075 9 P 0 ;1
L 11.4575 0.3575 11.4575 0.3575 9 P 0 ;1
L 11.4575 0.4075 11.4575 0.4075 9 P 0 ;1
L 11.4575 0.4575 11.4575 0.4575 9 P 0 ;1
L 11.4575 0.5075 11.4575 0.5075 9 P 0 ;1
L 11.4575 0.5575 11.4575 0.5575 9 P 0 ;1
L 11.4575 0.6075 11.4575 0.6075 9 P 0 ;1
L 11.4575 0.6575 11.4575 0.6575 9 P 0 ;1
L 11.4575 0.7075 11.4575 0.7075 9 P 0 ;1
L 11.4575 0.7575 11.4575 0.7575 9 P 0 ;1
L 11.4575 0.8075 11.4575 0.8075 9 P 0 ;1
L 11.4575 0.8575 11.4575 0.8575 9 P 0 ;1
L 11.4575 0.9075 11.4575 0.9075 9 P 0 ;1
L 11.4575 0.9575 11.4575 0.9575 9 P 0 ;1
L 11.4575 1.0075 11.4575 1.0075 9 P 0 ;1
L 11.4575 1.0575 11.4575 1.0575 9 P 0 ;1
L 11.4575 1.1075 11.4575 1.1075 9 P 0 ;1
L 11.4575 1.1575 11.4575 1.1575 9 P 0 ;1
L 11.4575 1.2075 11.4575 1.2075 9 P 0 ;1
L 11.4575 1.2575 11.4575 1.2575 9 P 0 ;1
L 11.4575 1.3075 11.4575 1.3075 9 P 0 ;1
L 11.4575 2.2075 11.4575 2.2075 9 P 0 ;1
L 11.4575 2.2575 11.4575 2.2575 9 P 0 ;1
L 11.4575 2.6575 11.4575 2.6575 9 P 0 ;1
L 11.4575 3.4075 11.4575 3.4075 9 P 0 ;1
L 11.4575 3.4575 11.4575 3.4575 9 P 0 ;1
L 11.4575 3.5075 11.4575 3.5075 9 P 0 ;1
L 11.4575 3.5575 11.4575 3.5575 9 P 0 ;1
L 11.4575 3.6075 11.4575 3.6075 9 P 0 ;1
L 11.4575 3.6575 11.4575 3.6575 9 P 0 ;1
L 11.4575 3.7075 11.4575 3.7075 9 P 0 ;1
L 11.4575 3.7575 11.4575 3.7575 9 P 0 ;1
L 11.4575 3.8075 11.4575 3.8075 9 P 0 ;1
L 11.4575 3.8575 11.4575 3.8575 9 P 0 ;1
L 11.4575 3.9075 11.4575 3.9075 9 P 0 ;1
L 11.4575 3.9575 11.4575 3.9575 9 P 0 ;1
L 11.4575 4.0075 11.4575 4.0075 9 P 0 ;1
L 11.4575 4.0575 11.4575 4.0575 9 P 0 ;1
L 11.4575 4.1075 11.4575 4.1075 9 P 0 ;1
L 11.4575 4.1575 11.4575 4.1575 9 P 0 ;1
L 11.4575 4.2075 11.4575 4.2075 9 P 0 ;1
L 11.4575 4.2575 11.4575 4.2575 9 P 0 ;1
L 11.4575 4.3075 11.4575 4.3075 9 P 0 ;1
L 11.4575 4.3575 11.4575 4.3575 9 P 0 ;1
L 11.4575 4.4075 11.4575 4.4075 9 P 0 ;1
L 11.4575 4.4575 11.4575 4.4575 9 P 0 ;1
L 11.4575 4.5075 11.4575 4.5075 9 P 0 ;1
L 11.4575 4.5575 11.4575 4.5575 9 P 0 ;1
L 11.4575 4.6075 11.4575 4.6075 9 P 0 ;1
L 11.4575 4.6575 11.4575 4.6575 9 P 0 ;1
L 11.4575 4.7075 11.4575 4.7075 9 P 0 ;1
L 11.5075 0.1575 11.5075 0.1575 9 P 0 ;1
L 11.5075 0.2075 11.5075 0.2075 9 P 0 ;1
L 11.5075 0.2575 11.5075 0.2575 9 P 0 ;1
L 11.5075 0.3075 11.5075 0.3075 9 P 0 ;1
L 11.5075 0.3575 11.5075 0.3575 9 P 0 ;1
L 11.5075 0.4075 11.5075 0.4075 9 P 0 ;1
L 11.5075 0.4575 11.5075 0.4575 9 P 0 ;1
L 11.5075 0.5075 11.5075 0.5075 9 P 0 ;1
L 11.5075 0.5575 11.5075 0.5575 9 P 0 ;1
L 11.5075 0.6075 11.5075 0.6075 9 P 0 ;1
L 11.5075 0.6575 11.5075 0.6575 9 P 0 ;1
L 11.5075 0.7075 11.5075 0.7075 9 P 0 ;1
L 11.5075 0.7575 11.5075 0.7575 9 P 0 ;1
L 11.5075 0.8075 11.5075 0.8075 9 P 0 ;1
L 11.5075 0.8575 11.5075 0.8575 9 P 0 ;1
L 11.5075 0.9075 11.5075 0.9075 9 P 0 ;1
L 11.5075 0.9575 11.5075 0.9575 9 P 0 ;1
L 11.5075 1.0075 11.5075 1.0075 9 P 0 ;1
L 11.5075 1.0575 11.5075 1.0575 9 P 0 ;1
L 11.5075 1.1075 11.5075 1.1075 9 P 0 ;1
L 11.5075 1.1575 11.5075 1.1575 9 P 0 ;1
L 11.5075 1.2075 11.5075 1.2075 9 P 0 ;1
L 11.5075 1.2575 11.5075 1.2575 9 P 0 ;1
L 11.5075 1.3075 11.5075 1.3075 9 P 0 ;1
L 11.5075 2.2075 11.5075 2.2075 9 P 0 ;1
L 11.5075 2.2575 11.5075 2.2575 9 P 0 ;1
L 11.5075 3.3575 11.5075 3.3575 9 P 0 ;1
L 11.5075 3.4075 11.5075 3.4075 9 P 0 ;1
L 11.5075 3.4575 11.5075 3.4575 9 P 0 ;1
L 11.5075 3.5075 11.5075 3.5075 9 P 0 ;1
L 11.5075 3.5575 11.5075 3.5575 9 P 0 ;1
L 11.5075 3.6075 11.5075 3.6075 9 P 0 ;1
L 11.5075 3.6575 11.5075 3.6575 9 P 0 ;1
L 11.5075 3.7075 11.5075 3.7075 9 P 0 ;1
L 11.5075 3.7575 11.5075 3.7575 9 P 0 ;1
L 11.5075 3.8075 11.5075 3.8075 9 P 0 ;1
L 11.5075 3.8575 11.5075 3.8575 9 P 0 ;1
L 11.5075 3.9075 11.5075 3.9075 9 P 0 ;1
L 11.5075 3.9575 11.5075 3.9575 9 P 0 ;1
L 11.5075 4.0075 11.5075 4.0075 9 P 0 ;1
L 11.5075 4.0575 11.5075 4.0575 9 P 0 ;1
L 11.5075 4.1075 11.5075 4.1075 9 P 0 ;1
L 11.5075 4.1575 11.5075 4.1575 9 P 0 ;1
L 11.5075 4.2075 11.5075 4.2075 9 P 0 ;1
L 11.5075 4.2575 11.5075 4.2575 9 P 0 ;1
L 11.5075 4.3075 11.5075 4.3075 9 P 0 ;1
L 11.5075 4.3575 11.5075 4.3575 9 P 0 ;1
L 11.5075 4.4075 11.5075 4.4075 9 P 0 ;1
L 11.5075 4.4575 11.5075 4.4575 9 P 0 ;1
L 11.5075 4.5075 11.5075 4.5075 9 P 0 ;1
L 11.5075 4.5575 11.5075 4.5575 9 P 0 ;1
L 11.5075 4.6075 11.5075 4.6075 9 P 0 ;1
L 11.5075 4.6575 11.5075 4.6575 9 P 0 ;1
L 11.5075 4.7075 11.5075 4.7075 9 P 0 ;1
L 11.5575 0.1575 11.5575 0.1575 9 P 0 ;1
L 11.5575 0.2075 11.5575 0.2075 9 P 0 ;1
L 11.5575 0.2575 11.5575 0.2575 9 P 0 ;1
L 11.5575 0.3075 11.5575 0.3075 9 P 0 ;1
L 11.5575 0.3575 11.5575 0.3575 9 P 0 ;1
L 11.5575 0.4075 11.5575 0.4075 9 P 0 ;1
L 11.5575 0.4575 11.5575 0.4575 9 P 0 ;1
L 11.5575 0.5075 11.5575 0.5075 9 P 0 ;1
L 11.5575 0.5575 11.5575 0.5575 9 P 0 ;1
L 11.5575 0.6075 11.5575 0.6075 9 P 0 ;1
L 11.5575 0.6575 11.5575 0.6575 9 P 0 ;1
L 11.5575 0.7075 11.5575 0.7075 9 P 0 ;1
L 11.5575 0.7575 11.5575 0.7575 9 P 0 ;1
L 11.5575 0.8075 11.5575 0.8075 9 P 0 ;1
L 11.5575 0.8575 11.5575 0.8575 9 P 0 ;1
L 11.5575 0.9075 11.5575 0.9075 9 P 0 ;1
L 11.5575 0.9575 11.5575 0.9575 9 P 0 ;1
L 11.5575 1.0075 11.5575 1.0075 9 P 0 ;1
L 11.5575 1.0575 11.5575 1.0575 9 P 0 ;1
L 11.5575 1.1075 11.5575 1.1075 9 P 0 ;1
L 11.5575 1.1575 11.5575 1.1575 9 P 0 ;1
L 11.5575 1.2075 11.5575 1.2075 9 P 0 ;1
L 11.5575 1.2575 11.5575 1.2575 9 P 0 ;1
L 11.5575 1.3075 11.5575 1.3075 9 P 0 ;1
L 11.5575 2.2075 11.5575 2.2075 9 P 0 ;1
L 11.5575 2.2575 11.5575 2.2575 9 P 0 ;1
L 11.5575 2.6575 11.5575 2.6575 9 P 0 ;1
L 11.5575 3.0075 11.5575 3.0075 9 P 0 ;1
L 11.5575 3.0575 11.5575 3.0575 9 P 0 ;1
L 11.5575 3.1075 11.5575 3.1075 9 P 0 ;1
L 11.5575 3.1575 11.5575 3.1575 9 P 0 ;1
L 11.5575 3.2075 11.5575 3.2075 9 P 0 ;1
L 11.5575 3.2575 11.5575 3.2575 9 P 0 ;1
L 11.5575 3.3075 11.5575 3.3075 9 P 0 ;1
L 11.5575 3.3575 11.5575 3.3575 9 P 0 ;1
L 11.5575 3.4075 11.5575 3.4075 9 P 0 ;1
L 11.5575 3.4575 11.5575 3.4575 9 P 0 ;1
L 11.5575 3.5075 11.5575 3.5075 9 P 0 ;1
L 11.5575 3.5575 11.5575 3.5575 9 P 0 ;1
L 11.5575 3.6075 11.5575 3.6075 9 P 0 ;1
L 11.5575 3.6575 11.5575 3.6575 9 P 0 ;1
L 11.5575 3.7075 11.5575 3.7075 9 P 0 ;1
L 11.5575 3.7575 11.5575 3.7575 9 P 0 ;1
L 11.5575 3.8075 11.5575 3.8075 9 P 0 ;1
L 11.5575 3.8575 11.5575 3.8575 9 P 0 ;1
L 11.5575 3.9075 11.5575 3.9075 9 P 0 ;1
L 11.5575 3.9575 11.5575 3.9575 9 P 0 ;1
L 11.5575 4.0075 11.5575 4.0075 9 P 0 ;1
L 11.5575 4.0575 11.5575 4.0575 9 P 0 ;1
L 11.5575 4.1075 11.5575 4.1075 9 P 0 ;1
L 11.5575 4.1575 11.5575 4.1575 9 P 0 ;1
L 11.5575 4.2075 11.5575 4.2075 9 P 0 ;1
L 11.5575 4.2575 11.5575 4.2575 9 P 0 ;1
L 11.5575 4.3075 11.5575 4.3075 9 P 0 ;1
L 11.5575 4.3575 11.5575 4.3575 9 P 0 ;1
L 11.5575 4.4075 11.5575 4.4075 9 P 0 ;1
L 11.5575 4.4575 11.5575 4.4575 9 P 0 ;1
L 11.5575 4.5075 11.5575 4.5075 9 P 0 ;1
L 11.5575 4.5575 11.5575 4.5575 9 P 0 ;1
L 11.5575 4.6075 11.5575 4.6075 9 P 0 ;1
L 11.5575 4.6575 11.5575 4.6575 9 P 0 ;1
L 11.5575 4.7075 11.5575 4.7075 9 P 0 ;1
L 11.6075 0.1575 11.6075 0.1575 9 P 0 ;1
L 11.6075 0.2075 11.6075 0.2075 9 P 0 ;1
L 11.6075 0.2575 11.6075 0.2575 9 P 0 ;1
L 11.6075 0.3075 11.6075 0.3075 9 P 0 ;1
L 11.6075 0.3575 11.6075 0.3575 9 P 0 ;1
L 11.6075 0.4075 11.6075 0.4075 9 P 0 ;1
L 11.6075 0.4575 11.6075 0.4575 9 P 0 ;1
L 11.6075 0.5075 11.6075 0.5075 9 P 0 ;1
L 11.6075 0.5575 11.6075 0.5575 9 P 0 ;1
L 11.6075 0.6075 11.6075 0.6075 9 P 0 ;1
L 11.6075 0.6575 11.6075 0.6575 9 P 0 ;1
L 11.6075 0.7075 11.6075 0.7075 9 P 0 ;1
L 11.6075 0.7575 11.6075 0.7575 9 P 0 ;1
L 11.6075 0.8075 11.6075 0.8075 9 P 0 ;1
L 11.6075 0.8575 11.6075 0.8575 9 P 0 ;1
L 11.6075 0.9075 11.6075 0.9075 9 P 0 ;1
L 11.6075 0.9575 11.6075 0.9575 9 P 0 ;1
L 11.6075 1.0075 11.6075 1.0075 9 P 0 ;1
L 11.6075 1.0575 11.6075 1.0575 9 P 0 ;1
L 11.6075 1.1075 11.6075 1.1075 9 P 0 ;1
L 11.6075 1.1575 11.6075 1.1575 9 P 0 ;1
L 11.6075 1.2075 11.6075 1.2075 9 P 0 ;1
L 11.6075 1.2575 11.6075 1.2575 9 P 0 ;1
L 11.6075 1.3075 11.6075 1.3075 9 P 0 ;1
L 11.6075 1.3575 11.6075 1.3575 9 P 0 ;1
L 11.6075 1.5075 11.6075 1.5075 9 P 0 ;1
L 11.6075 1.6575 11.6075 1.6575 9 P 0 ;1
L 11.6075 1.8075 11.6075 1.8075 9 P 0 ;1
L 11.6075 1.8575 11.6075 1.8575 9 P 0 ;1
L 11.6075 1.9575 11.6075 1.9575 9 P 0 ;1
L 11.6075 2.0075 11.6075 2.0075 9 P 0 ;1
L 11.6075 2.1575 11.6075 2.1575 9 P 0 ;1
L 11.6075 2.2075 11.6075 2.2075 9 P 0 ;1
L 11.6075 2.2575 11.6075 2.2575 9 P 0 ;1
L 11.6075 2.3075 11.6075 2.3075 9 P 0 ;1
L 11.6075 2.4575 11.6075 2.4575 9 P 0 ;1
L 11.6075 2.6075 11.6075 2.6075 9 P 0 ;1
L 11.6075 2.6575 11.6075 2.6575 9 P 0 ;1
L 11.6075 2.7075 11.6075 2.7075 9 P 0 ;1
L 11.6075 4.3575 11.6075 4.3575 9 P 0 ;1
L 11.6075 4.4075 11.6075 4.4075 9 P 0 ;1
L 11.6075 4.4575 11.6075 4.4575 9 P 0 ;1
L 11.6075 4.5075 11.6075 4.5075 9 P 0 ;1
L 11.6075 4.5575 11.6075 4.5575 9 P 0 ;1
L 11.6075 4.6075 11.6075 4.6075 9 P 0 ;1
L 11.6075 4.6575 11.6075 4.6575 9 P 0 ;1
L 11.6075 4.7075 11.6075 4.7075 9 P 0 ;1
L 11.6575 0.1575 11.6575 0.1575 9 P 0 ;1
L 11.6575 0.2075 11.6575 0.2075 9 P 0 ;1
L 11.6575 0.2575 11.6575 0.2575 9 P 0 ;1
L 11.6575 0.3075 11.6575 0.3075 9 P 0 ;1
L 11.6575 0.3575 11.6575 0.3575 9 P 0 ;1
L 11.6575 0.4075 11.6575 0.4075 9 P 0 ;1
L 11.6575 0.4575 11.6575 0.4575 9 P 0 ;1
L 11.6575 0.5075 11.6575 0.5075 9 P 0 ;1
L 11.6575 0.5575 11.6575 0.5575 9 P 0 ;1
L 11.6575 0.6075 11.6575 0.6075 9 P 0 ;1
L 11.6575 0.6575 11.6575 0.6575 9 P 0 ;1
L 11.6575 0.7075 11.6575 0.7075 9 P 0 ;1
L 11.6575 0.7575 11.6575 0.7575 9 P 0 ;1
L 11.6575 0.8075 11.6575 0.8075 9 P 0 ;1
L 11.6575 0.8575 11.6575 0.8575 9 P 0 ;1
L 11.6575 0.9075 11.6575 0.9075 9 P 0 ;1
L 11.6575 0.9575 11.6575 0.9575 9 P 0 ;1
L 11.6575 1.0075 11.6575 1.0075 9 P 0 ;1
L 11.6575 1.0575 11.6575 1.0575 9 P 0 ;1
L 11.6575 1.1075 11.6575 1.1075 9 P 0 ;1
L 11.6575 1.1575 11.6575 1.1575 9 P 0 ;1
L 11.6575 1.2075 11.6575 1.2075 9 P 0 ;1
L 11.6575 1.2575 11.6575 1.2575 9 P 0 ;1
L 11.6575 1.3075 11.6575 1.3075 9 P 0 ;1
L 11.6575 1.3575 11.6575 1.3575 9 P 0 ;1
L 11.6575 1.4075 11.6575 1.4075 9 P 0 ;1
L 11.6575 1.6575 11.6575 1.6575 9 P 0 ;1
L 11.6575 1.7075 11.6575 1.7075 9 P 0 ;1
L 11.6575 4.4075 11.6575 4.4075 9 P 0 ;1
L 11.6575 4.4575 11.6575 4.4575 9 P 0 ;1
L 11.6575 4.5075 11.6575 4.5075 9 P 0 ;1
L 11.6575 4.5575 11.6575 4.5575 9 P 0 ;1
L 11.6575 4.6075 11.6575 4.6075 9 P 0 ;1
L 11.6575 4.6575 11.6575 4.6575 9 P 0 ;1
L 11.6575 4.7075 11.6575 4.7075 9 P 0 ;1
L 11.7075 0.1575 11.7075 0.1575 9 P 0 ;1
L 11.7075 0.2075 11.7075 0.2075 9 P 0 ;1
L 11.7075 0.2575 11.7075 0.2575 9 P 0 ;1
L 11.7075 0.3075 11.7075 0.3075 9 P 0 ;1
L 11.7075 0.3575 11.7075 0.3575 9 P 0 ;1
L 11.7075 0.4075 11.7075 0.4075 9 P 0 ;1
L 11.7075 0.4575 11.7075 0.4575 9 P 0 ;1
L 11.7075 0.5075 11.7075 0.5075 9 P 0 ;1
L 11.7075 0.5575 11.7075 0.5575 9 P 0 ;1
L 11.7075 0.6075 11.7075 0.6075 9 P 0 ;1
L 11.7075 0.6575 11.7075 0.6575 9 P 0 ;1
L 11.7075 0.7075 11.7075 0.7075 9 P 0 ;1
L 11.7075 0.7575 11.7075 0.7575 9 P 0 ;1
L 11.7075 0.8075 11.7075 0.8075 9 P 0 ;1
L 11.7075 0.8575 11.7075 0.8575 9 P 0 ;1
L 11.7075 0.9075 11.7075 0.9075 9 P 0 ;1
L 11.7075 0.9575 11.7075 0.9575 9 P 0 ;1
L 11.7075 1.0075 11.7075 1.0075 9 P 0 ;1
L 11.7075 1.0575 11.7075 1.0575 9 P 0 ;1
L 11.7075 1.1075 11.7075 1.1075 9 P 0 ;1
L 11.7075 1.1575 11.7075 1.1575 9 P 0 ;1
L 11.7075 1.2075 11.7075 1.2075 9 P 0 ;1
L 11.7075 1.2575 11.7075 1.2575 9 P 0 ;1
L 11.7075 1.3075 11.7075 1.3075 9 P 0 ;1
L 11.7075 1.3575 11.7075 1.3575 9 P 0 ;1
L 11.7075 2.7575 11.7075 2.7575 9 P 0 ;1
L 11.7075 4.4575 11.7075 4.4575 9 P 0 ;1
L 11.7075 4.5075 11.7075 4.5075 9 P 0 ;1
L 11.7075 4.5575 11.7075 4.5575 9 P 0 ;1
L 11.7075 4.6075 11.7075 4.6075 9 P 0 ;1
L 11.7075 4.6575 11.7075 4.6575 9 P 0 ;1
L 11.7075 4.7075 11.7075 4.7075 9 P 0 ;1
L 11.7575 0.1575 11.7575 0.1575 9 P 0 ;1
L 11.7575 0.2075 11.7575 0.2075 9 P 0 ;1
L 11.7575 0.2575 11.7575 0.2575 9 P 0 ;1
L 11.7575 0.3075 11.7575 0.3075 9 P 0 ;1
L 11.7575 0.3575 11.7575 0.3575 9 P 0 ;1
L 11.7575 0.4075 11.7575 0.4075 9 P 0 ;1
L 11.7575 0.4575 11.7575 0.4575 9 P 0 ;1
L 11.7575 0.5075 11.7575 0.5075 9 P 0 ;1
L 11.7575 0.5575 11.7575 0.5575 9 P 0 ;1
L 11.7575 0.6075 11.7575 0.6075 9 P 0 ;1
L 11.7575 0.6575 11.7575 0.6575 9 P 0 ;1
L 11.7575 0.7075 11.7575 0.7075 9 P 0 ;1
L 11.7575 0.7575 11.7575 0.7575 9 P 0 ;1
L 11.7575 0.8075 11.7575 0.8075 9 P 0 ;1
L 11.7575 0.8575 11.7575 0.8575 9 P 0 ;1
L 11.7575 0.9075 11.7575 0.9075 9 P 0 ;1
L 11.7575 0.9575 11.7575 0.9575 9 P 0 ;1
L 11.7575 1.0075 11.7575 1.0075 9 P 0 ;1
L 11.7575 1.0575 11.7575 1.0575 9 P 0 ;1
L 11.7575 1.1075 11.7575 1.1075 9 P 0 ;1
L 11.7575 1.1575 11.7575 1.1575 9 P 0 ;1
L 11.7575 1.2075 11.7575 1.2075 9 P 0 ;1
L 11.7575 1.2575 11.7575 1.2575 9 P 0 ;1
L 11.7575 1.3075 11.7575 1.3075 9 P 0 ;1
L 11.7575 1.3575 11.7575 1.3575 9 P 0 ;1
L 11.7575 1.4075 11.7575 1.4075 9 P 0 ;1
L 11.7575 2.7575 11.7575 2.7575 9 P 0 ;1
L 11.7575 2.8075 11.7575 2.8075 9 P 0 ;1
L 11.7575 4.5075 11.7575 4.5075 9 P 0 ;1
L 11.7575 4.5575 11.7575 4.5575 9 P 0 ;1
L 11.7575 4.6075 11.7575 4.6075 9 P 0 ;1
L 11.7575 4.6575 11.7575 4.6575 9 P 0 ;1
L 11.7575 4.7075 11.7575 4.7075 9 P 0 ;1
L 11.8075 0.1575 11.8075 0.1575 9 P 0 ;1
L 11.8075 0.2075 11.8075 0.2075 9 P 0 ;1
L 11.8075 0.2575 11.8075 0.2575 9 P 0 ;1
L 11.8075 0.3075 11.8075 0.3075 9 P 0 ;1
L 11.8075 0.3575 11.8075 0.3575 9 P 0 ;1
L 11.8075 0.4075 11.8075 0.4075 9 P 0 ;1
L 11.8075 0.4575 11.8075 0.4575 9 P 0 ;1
L 11.8075 0.5075 11.8075 0.5075 9 P 0 ;1
L 11.8075 0.5575 11.8075 0.5575 9 P 0 ;1
L 11.8075 0.6075 11.8075 0.6075 9 P 0 ;1
L 11.8075 0.6575 11.8075 0.6575 9 P 0 ;1
L 11.8075 0.7075 11.8075 0.7075 9 P 0 ;1
L 11.8075 0.7575 11.8075 0.7575 9 P 0 ;1
L 11.8075 0.8075 11.8075 0.8075 9 P 0 ;1
L 11.8075 0.8575 11.8075 0.8575 9 P 0 ;1
L 11.8075 0.9075 11.8075 0.9075 9 P 0 ;1
L 11.8075 0.9575 11.8075 0.9575 9 P 0 ;1
L 11.8075 1.0075 11.8075 1.0075 9 P 0 ;1
L 11.8075 1.0575 11.8075 1.0575 9 P 0 ;1
L 11.8075 1.1075 11.8075 1.1075 9 P 0 ;1
L 11.8075 1.1575 11.8075 1.1575 9 P 0 ;1
L 11.8075 1.2075 11.8075 1.2075 9 P 0 ;1
L 11.8075 1.2575 11.8075 1.2575 9 P 0 ;1
L 11.8075 1.3075 11.8075 1.3075 9 P 0 ;1
L 11.8075 1.3575 11.8075 1.3575 9 P 0 ;1
L 11.8075 1.4075 11.8075 1.4075 9 P 0 ;1
L 11.8075 1.4575 11.8075 1.4575 9 P 0 ;1
L 11.8075 1.5575 11.8075 1.5575 9 P 0 ;1
L 11.8075 1.9075 11.8075 1.9075 9 P 0 ;1
L 11.8075 2.0575 11.8075 2.0575 9 P 0 ;1
L 11.8075 2.3575 11.8075 2.3575 9 P 0 ;1
L 11.8075 2.4075 11.8075 2.4075 9 P 0 ;1
L 11.8075 2.5575 11.8075 2.5575 9 P 0 ;1
L 11.8075 2.7075 11.8075 2.7075 9 P 0 ;1
L 11.8075 2.7575 11.8075 2.7575 9 P 0 ;1
L 11.8075 2.9575 11.8075 2.9575 9 P 0 ;1
L 11.8075 3.0075 11.8075 3.0075 9 P 0 ;1
L 11.8075 3.0575 11.8075 3.0575 9 P 0 ;1
L 11.8075 3.1075 11.8075 3.1075 9 P 0 ;1
L 11.8075 3.1575 11.8075 3.1575 9 P 0 ;1
L 11.8075 3.2075 11.8075 3.2075 9 P 0 ;1
L 11.8075 3.2575 11.8075 3.2575 9 P 0 ;1
L 11.8075 3.3075 11.8075 3.3075 9 P 0 ;1
L 11.8075 3.3575 11.8075 3.3575 9 P 0 ;1
L 11.8075 3.4075 11.8075 3.4075 9 P 0 ;1
L 11.8075 3.4575 11.8075 3.4575 9 P 0 ;1
L 11.8075 3.5075 11.8075 3.5075 9 P 0 ;1
L 11.8075 3.5575 11.8075 3.5575 9 P 0 ;1
L 11.8075 3.6075 11.8075 3.6075 9 P 0 ;1
L 11.8075 3.6575 11.8075 3.6575 9 P 0 ;1
L 11.8075 3.7075 11.8075 3.7075 9 P 0 ;1
L 11.8075 3.7575 11.8075 3.7575 9 P 0 ;1
L 11.8075 3.8075 11.8075 3.8075 9 P 0 ;1
L 11.8075 3.8575 11.8075 3.8575 9 P 0 ;1
L 11.8075 3.9075 11.8075 3.9075 9 P 0 ;1
L 11.8075 3.9575 11.8075 3.9575 9 P 0 ;1
L 11.8075 4.0075 11.8075 4.0075 9 P 0 ;1
L 11.8075 4.0575 11.8075 4.0575 9 P 0 ;1
L 11.8075 4.1075 11.8075 4.1075 9 P 0 ;1
L 11.8075 4.1575 11.8075 4.1575 9 P 0 ;1
L 11.8075 4.2075 11.8075 4.2075 9 P 0 ;1
L 11.8075 4.2575 11.8075 4.2575 9 P 0 ;1
L 11.8075 4.5575 11.8075 4.5575 9 P 0 ;1
L 11.8075 4.6075 11.8075 4.6075 9 P 0 ;1
L 11.8075 4.6575 11.8075 4.6575 9 P 0 ;1
L 11.8075 4.7075 11.8075 4.7075 9 P 0 ;1
L 11.8575 0.1575 11.8575 0.1575 9 P 0 ;1
L 11.8575 0.2075 11.8575 0.2075 9 P 0 ;1
L 11.8575 0.2575 11.8575 0.2575 9 P 0 ;1
L 11.8575 0.3075 11.8575 0.3075 9 P 0 ;1
L 11.8575 0.3575 11.8575 0.3575 9 P 0 ;1
L 11.8575 0.4075 11.8575 0.4075 9 P 0 ;1
L 11.8575 0.4575 11.8575 0.4575 9 P 0 ;1
L 11.8575 0.5075 11.8575 0.5075 9 P 0 ;1
L 11.8575 0.5575 11.8575 0.5575 9 P 0 ;1
L 11.8575 0.6075 11.8575 0.6075 9 P 0 ;1
L 11.8575 0.6575 11.8575 0.6575 9 P 0 ;1
L 11.8575 0.7075 11.8575 0.7075 9 P 0 ;1
L 11.8575 0.7575 11.8575 0.7575 9 P 0 ;1
L 11.8575 0.8075 11.8575 0.8075 9 P 0 ;1
L 11.8575 0.8575 11.8575 0.8575 9 P 0 ;1
L 11.8575 0.9075 11.8575 0.9075 9 P 0 ;1
L 11.8575 0.9575 11.8575 0.9575 9 P 0 ;1
L 11.8575 1.0075 11.8575 1.0075 9 P 0 ;1
L 11.8575 1.0575 11.8575 1.0575 9 P 0 ;1
L 11.8575 1.1075 11.8575 1.1075 9 P 0 ;1
L 11.8575 1.1575 11.8575 1.1575 9 P 0 ;1
L 11.8575 1.2075 11.8575 1.2075 9 P 0 ;1
L 11.8575 1.2575 11.8575 1.2575 9 P 0 ;1
L 11.8575 1.3075 11.8575 1.3075 9 P 0 ;1
L 11.8575 1.3575 11.8575 1.3575 9 P 0 ;1
L 11.8575 1.4075 11.8575 1.4075 9 P 0 ;1
L 11.8575 1.4575 11.8575 1.4575 9 P 0 ;1
L 11.8575 1.5075 11.8575 1.5075 9 P 0 ;1
L 11.8575 1.5575 11.8575 1.5575 9 P 0 ;1
L 11.8575 1.6075 11.8575 1.6075 9 P 0 ;1
L 11.8575 1.7575 11.8575 1.7575 9 P 0 ;1
L 11.8575 1.8075 11.8575 1.8075 9 P 0 ;1
L 11.8575 1.8575 11.8575 1.8575 9 P 0 ;1
L 11.8575 1.9075 11.8575 1.9075 9 P 0 ;1
L 11.8575 1.9575 11.8575 1.9575 9 P 0 ;1
L 11.8575 2.0075 11.8575 2.0075 9 P 0 ;1
L 11.8575 2.0575 11.8575 2.0575 9 P 0 ;1
L 11.8575 2.1075 11.8575 2.1075 9 P 0 ;1
L 11.8575 2.3575 11.8575 2.3575 9 P 0 ;1
L 11.8575 2.4075 11.8575 2.4075 9 P 0 ;1
L 11.8575 2.4575 11.8575 2.4575 9 P 0 ;1
L 11.8575 2.5075 11.8575 2.5075 9 P 0 ;1
L 11.8575 2.5575 11.8575 2.5575 9 P 0 ;1
L 11.8575 2.6075 11.8575 2.6075 9 P 0 ;1
L 11.8575 2.6575 11.8575 2.6575 9 P 0 ;1
L 11.8575 2.7075 11.8575 2.7075 9 P 0 ;1
L 11.8575 2.7575 11.8575 2.7575 9 P 0 ;1
L 11.8575 2.9575 11.8575 2.9575 9 P 0 ;1
L 11.8575 3.0075 11.8575 3.0075 9 P 0 ;1
L 11.8575 3.0575 11.8575 3.0575 9 P 0 ;1
L 11.8575 3.1075 11.8575 3.1075 9 P 0 ;1
L 11.8575 3.1575 11.8575 3.1575 9 P 0 ;1
L 11.8575 3.2075 11.8575 3.2075 9 P 0 ;1
L 11.8575 3.2575 11.8575 3.2575 9 P 0 ;1
L 11.8575 3.3075 11.8575 3.3075 9 P 0 ;1
L 11.8575 3.3575 11.8575 3.3575 9 P 0 ;1
L 11.8575 3.4075 11.8575 3.4075 9 P 0 ;1
L 11.8575 3.4575 11.8575 3.4575 9 P 0 ;1
L 11.8575 3.5075 11.8575 3.5075 9 P 0 ;1
L 11.8575 3.5575 11.8575 3.5575 9 P 0 ;1
L 11.8575 3.6075 11.8575 3.6075 9 P 0 ;1
L 11.8575 3.6575 11.8575 3.6575 9 P 0 ;1
L 11.8575 3.7075 11.8575 3.7075 9 P 0 ;1
L 11.8575 3.7575 11.8575 3.7575 9 P 0 ;1
L 11.8575 3.8075 11.8575 3.8075 9 P 0 ;1
L 11.8575 3.8575 11.8575 3.8575 9 P 0 ;1
L 11.8575 3.9075 11.8575 3.9075 9 P 0 ;1
L 11.8575 3.9575 11.8575 3.9575 9 P 0 ;1
L 11.8575 4.0075 11.8575 4.0075 9 P 0 ;1
L 11.8575 4.0575 11.8575 4.0575 9 P 0 ;1
L 11.8575 4.1075 11.8575 4.1075 9 P 0 ;1
L 11.8575 4.1575 11.8575 4.1575 9 P 0 ;1
L 11.8575 4.2075 11.8575 4.2075 9 P 0 ;1
L 11.8575 4.2575 11.8575 4.2575 9 P 0 ;1
L 11.8575 4.3075 11.8575 4.3075 9 P 0 ;1
L 11.8575 4.5575 11.8575 4.5575 9 P 0 ;1
L 11.8575 4.6075 11.8575 4.6075 9 P 0 ;1
L 11.8575 4.6575 11.8575 4.6575 9 P 0 ;1
L 11.8575 4.7075 11.8575 4.7075 9 P 0 ;1
L 11.9075 0.1575 11.9075 0.1575 9 P 0 ;1
L 11.9075 0.2075 11.9075 0.2075 9 P 0 ;1
L 11.9075 0.2575 11.9075 0.2575 9 P 0 ;1
L 11.9075 0.3075 11.9075 0.3075 9 P 0 ;1
L 11.9075 0.3575 11.9075 0.3575 9 P 0 ;1
L 11.9075 0.4075 11.9075 0.4075 9 P 0 ;1
L 11.9075 0.4575 11.9075 0.4575 9 P 0 ;1
L 11.9075 0.5075 11.9075 0.5075 9 P 0 ;1
L 11.9075 0.5575 11.9075 0.5575 9 P 0 ;1
L 11.9075 0.6075 11.9075 0.6075 9 P 0 ;1
L 11.9075 0.6575 11.9075 0.6575 9 P 0 ;1
L 11.9075 0.7075 11.9075 0.7075 9 P 0 ;1
L 11.9075 0.7575 11.9075 0.7575 9 P 0 ;1
L 11.9075 0.8075 11.9075 0.8075 9 P 0 ;1
L 11.9075 0.8575 11.9075 0.8575 9 P 0 ;1
L 11.9075 0.9075 11.9075 0.9075 9 P 0 ;1
L 11.9075 0.9575 11.9075 0.9575 9 P 0 ;1
L 11.9075 1.0075 11.9075 1.0075 9 P 0 ;1
L 11.9075 1.0575 11.9075 1.0575 9 P 0 ;1
L 11.9075 1.1075 11.9075 1.1075 9 P 0 ;1
L 11.9075 1.1575 11.9075 1.1575 9 P 0 ;1
L 11.9075 1.2075 11.9075 1.2075 9 P 0 ;1
L 11.9075 1.2575 11.9075 1.2575 9 P 0 ;1
L 11.9075 1.3075 11.9075 1.3075 9 P 0 ;1
L 11.9075 1.3575 11.9075 1.3575 9 P 0 ;1
L 11.9075 1.4075 11.9075 1.4075 9 P 0 ;1
L 11.9075 1.4575 11.9075 1.4575 9 P 0 ;1
L 11.9075 1.5075 11.9075 1.5075 9 P 0 ;1
L 11.9075 1.5575 11.9075 1.5575 9 P 0 ;1
L 11.9075 1.6075 11.9075 1.6075 9 P 0 ;1
L 11.9075 1.6575 11.9075 1.6575 9 P 0 ;1
L 11.9075 1.7075 11.9075 1.7075 9 P 0 ;1
L 11.9075 1.7575 11.9075 1.7575 9 P 0 ;1
L 11.9075 1.8075 11.9075 1.8075 9 P 0 ;1
L 11.9075 1.8575 11.9075 1.8575 9 P 0 ;1
L 11.9075 1.9075 11.9075 1.9075 9 P 0 ;1
L 11.9075 1.9575 11.9075 1.9575 9 P 0 ;1
L 11.9075 2.0075 11.9075 2.0075 9 P 0 ;1
L 11.9075 2.0575 11.9075 2.0575 9 P 0 ;1
L 11.9075 2.1075 11.9075 2.1075 9 P 0 ;1
L 11.9075 2.1575 11.9075 2.1575 9 P 0 ;1
L 11.9075 2.3075 11.9075 2.3075 9 P 0 ;1
L 11.9075 2.3575 11.9075 2.3575 9 P 0 ;1
L 11.9075 2.4075 11.9075 2.4075 9 P 0 ;1
L 11.9075 2.4575 11.9075 2.4575 9 P 0 ;1
L 11.9075 2.5075 11.9075 2.5075 9 P 0 ;1
L 11.9075 2.5575 11.9075 2.5575 9 P 0 ;1
L 11.9075 2.6075 11.9075 2.6075 9 P 0 ;1
L 11.9075 2.6575 11.9075 2.6575 9 P 0 ;1
L 11.9075 2.7075 11.9075 2.7075 9 P 0 ;1
L 11.9075 2.7575 11.9075 2.7575 9 P 0 ;1
L 11.9075 2.9075 11.9075 2.9075 9 P 0 ;1
L 11.9075 2.9575 11.9075 2.9575 9 P 0 ;1
L 11.9075 3.0075 11.9075 3.0075 9 P 0 ;1
L 11.9075 3.0575 11.9075 3.0575 9 P 0 ;1
L 11.9075 3.1075 11.9075 3.1075 9 P 0 ;1
L 11.9075 3.1575 11.9075 3.1575 9 P 0 ;1
L 11.9075 3.2075 11.9075 3.2075 9 P 0 ;1
L 11.9075 3.2575 11.9075 3.2575 9 P 0 ;1
L 11.9075 3.3075 11.9075 3.3075 9 P 0 ;1
L 11.9075 3.3575 11.9075 3.3575 9 P 0 ;1
L 11.9075 3.4075 11.9075 3.4075 9 P 0 ;1
L 11.9075 3.4575 11.9075 3.4575 9 P 0 ;1
L 11.9075 3.5075 11.9075 3.5075 9 P 0 ;1
L 11.9075 3.5575 11.9075 3.5575 9 P 0 ;1
L 11.9075 3.6075 11.9075 3.6075 9 P 0 ;1
L 11.9075 3.6575 11.9075 3.6575 9 P 0 ;1
L 11.9075 3.7075 11.9075 3.7075 9 P 0 ;1
L 11.9075 3.7575 11.9075 3.7575 9 P 0 ;1
L 11.9075 3.8075 11.9075 3.8075 9 P 0 ;1
L 11.9075 3.8575 11.9075 3.8575 9 P 0 ;1
L 11.9075 3.9075 11.9075 3.9075 9 P 0 ;1
L 11.9075 3.9575 11.9075 3.9575 9 P 0 ;1
L 11.9075 4.0075 11.9075 4.0075 9 P 0 ;1
L 11.9075 4.0575 11.9075 4.0575 9 P 0 ;1
L 11.9075 4.1075 11.9075 4.1075 9 P 0 ;1
L 11.9075 4.1575 11.9075 4.1575 9 P 0 ;1
L 11.9075 4.2075 11.9075 4.2075 9 P 0 ;1
L 11.9075 4.2575 11.9075 4.2575 9 P 0 ;1
L 11.9075 4.3075 11.9075 4.3075 9 P 0 ;1
L 11.9075 4.3575 11.9075 4.3575 9 P 0 ;1
L 11.9075 4.5575 11.9075 4.5575 9 P 0 ;1
L 11.9075 4.6075 11.9075 4.6075 9 P 0 ;1
L 11.9075 4.6575 11.9075 4.6575 9 P 0 ;1
L 11.9075 4.7075 11.9075 4.7075 9 P 0 ;1
L 11.9575 0.1575 11.9575 0.1575 9 P 0 ;1
L 11.9575 0.2075 11.9575 0.2075 9 P 0 ;1
L 11.9575 0.2575 11.9575 0.2575 9 P 0 ;1
L 11.9575 0.3075 11.9575 0.3075 9 P 0 ;1
L 11.9575 0.3575 11.9575 0.3575 9 P 0 ;1
L 11.9575 0.4075 11.9575 0.4075 9 P 0 ;1
L 11.9575 0.4575 11.9575 0.4575 9 P 0 ;1
L 11.9575 0.5075 11.9575 0.5075 9 P 0 ;1
L 11.9575 0.5575 11.9575 0.5575 9 P 0 ;1
L 11.9575 0.6075 11.9575 0.6075 9 P 0 ;1
L 11.9575 0.6575 11.9575 0.6575 9 P 0 ;1
L 11.9575 0.7075 11.9575 0.7075 9 P 0 ;1
L 11.9575 0.7575 11.9575 0.7575 9 P 0 ;1
L 11.9575 0.8075 11.9575 0.8075 9 P 0 ;1
L 11.9575 0.8575 11.9575 0.8575 9 P 0 ;1
L 11.9575 0.9075 11.9575 0.9075 9 P 0 ;1
L 11.9575 0.9575 11.9575 0.9575 9 P 0 ;1
L 11.9575 1.0075 11.9575 1.0075 9 P 0 ;1
L 11.9575 1.0575 11.9575 1.0575 9 P 0 ;1
L 11.9575 1.1075 11.9575 1.1075 9 P 0 ;1
L 11.9575 1.1575 11.9575 1.1575 9 P 0 ;1
L 11.9575 1.2075 11.9575 1.2075 9 P 0 ;1
L 11.9575 1.2575 11.9575 1.2575 9 P 0 ;1
L 11.9575 1.3075 11.9575 1.3075 9 P 0 ;1
L 11.9575 1.3575 11.9575 1.3575 9 P 0 ;1
L 11.9575 1.4075 11.9575 1.4075 9 P 0 ;1
L 11.9575 1.6575 11.9575 1.6575 9 P 0 ;1
L 11.9575 1.7075 11.9575 1.7075 9 P 0 ;1
L 11.9575 1.7575 11.9575 1.7575 9 P 0 ;1
L 11.9575 1.8075 11.9575 1.8075 9 P 0 ;1
L 11.9575 1.8575 11.9575 1.8575 9 P 0 ;1
L 11.9575 1.9075 11.9575 1.9075 9 P 0 ;1
L 11.9575 1.9575 11.9575 1.9575 9 P 0 ;1
L 11.9575 2.0075 11.9575 2.0075 9 P 0 ;1
L 11.9575 2.0575 11.9575 2.0575 9 P 0 ;1
L 11.9575 2.1075 11.9575 2.1075 9 P 0 ;1
L 11.9575 2.1575 11.9575 2.1575 9 P 0 ;1
L 11.9575 2.2075 11.9575 2.2075 9 P 0 ;1
L 11.9575 2.2575 11.9575 2.2575 9 P 0 ;1
L 11.9575 2.3075 11.9575 2.3075 9 P 0 ;1
L 11.9575 2.3575 11.9575 2.3575 9 P 0 ;1
L 11.9575 2.4075 11.9575 2.4075 9 P 0 ;1
L 11.9575 2.4575 11.9575 2.4575 9 P 0 ;1
L 11.9575 2.7075 11.9575 2.7075 9 P 0 ;1
L 11.9575 2.7575 11.9575 2.7575 9 P 0 ;1
L 11.9575 2.8075 11.9575 2.8075 9 P 0 ;1
L 11.9575 2.8575 11.9575 2.8575 9 P 0 ;1
L 11.9575 2.9075 11.9575 2.9075 9 P 0 ;1
L 11.9575 2.9575 11.9575 2.9575 9 P 0 ;1
L 11.9575 3.0075 11.9575 3.0075 9 P 0 ;1
L 11.9575 3.0575 11.9575 3.0575 9 P 0 ;1
L 11.9575 3.1075 11.9575 3.1075 9 P 0 ;1
L 11.9575 3.1575 11.9575 3.1575 9 P 0 ;1
L 11.9575 3.2075 11.9575 3.2075 9 P 0 ;1
L 11.9575 3.2575 11.9575 3.2575 9 P 0 ;1
L 11.9575 3.3075 11.9575 3.3075 9 P 0 ;1
L 11.9575 3.3575 11.9575 3.3575 9 P 0 ;1
L 11.9575 3.4075 11.9575 3.4075 9 P 0 ;1
L 11.9575 3.4575 11.9575 3.4575 9 P 0 ;1
L 11.9575 3.5075 11.9575 3.5075 9 P 0 ;1
L 11.9575 3.5575 11.9575 3.5575 9 P 0 ;1
L 11.9575 3.6075 11.9575 3.6075 9 P 0 ;1
L 11.9575 3.6575 11.9575 3.6575 9 P 0 ;1
L 11.9575 3.7075 11.9575 3.7075 9 P 0 ;1
L 11.9575 3.7575 11.9575 3.7575 9 P 0 ;1
L 11.9575 3.8075 11.9575 3.8075 9 P 0 ;1
L 11.9575 3.8575 11.9575 3.8575 9 P 0 ;1
L 11.9575 3.9075 11.9575 3.9075 9 P 0 ;1
L 11.9575 3.9575 11.9575 3.9575 9 P 0 ;1
L 11.9575 4.0075 11.9575 4.0075 9 P 0 ;1
L 11.9575 4.0575 11.9575 4.0575 9 P 0 ;1
L 11.9575 4.3575 11.9575 4.3575 9 P 0 ;1
L 11.9575 4.4075 11.9575 4.4075 9 P 0 ;1
L 11.9575 4.4575 11.9575 4.4575 9 P 0 ;1
L 11.9575 4.5075 11.9575 4.5075 9 P 0 ;1
L 11.9575 4.5575 11.9575 4.5575 9 P 0 ;1
L 11.9575 4.6075 11.9575 4.6075 9 P 0 ;1
L 11.9575 4.6575 11.9575 4.6575 9 P 0 ;1
L 11.9575 4.7075 11.9575 4.7075 9 P 0 ;1
L 12.0075 0.1575 12.0075 0.1575 9 P 0 ;1
L 12.0075 0.2075 12.0075 0.2075 9 P 0 ;1
L 12.0075 0.2575 12.0075 0.2575 9 P 0 ;1
L 12.0075 0.3075 12.0075 0.3075 9 P 0 ;1
L 12.0075 0.3575 12.0075 0.3575 9 P 0 ;1
L 12.0075 0.4075 12.0075 0.4075 9 P 0 ;1
L 12.0075 0.4575 12.0075 0.4575 9 P 0 ;1
L 12.0075 0.5075 12.0075 0.5075 9 P 0 ;1
L 12.0075 0.5575 12.0075 0.5575 9 P 0 ;1
L 12.0075 0.6075 12.0075 0.6075 9 P 0 ;1
L 12.0075 0.6575 12.0075 0.6575 9 P 0 ;1
L 12.0075 0.7075 12.0075 0.7075 9 P 0 ;1
L 12.0075 0.7575 12.0075 0.7575 9 P 0 ;1
L 12.0075 0.8075 12.0075 0.8075 9 P 0 ;1
L 12.0075 0.8575 12.0075 0.8575 9 P 0 ;1
L 12.0075 0.9075 12.0075 0.9075 9 P 0 ;1
L 12.0075 0.9575 12.0075 0.9575 9 P 0 ;1
L 12.0075 1.0075 12.0075 1.0075 9 P 0 ;1
L 12.0075 1.0575 12.0075 1.0575 9 P 0 ;1
L 12.0075 1.1075 12.0075 1.1075 9 P 0 ;1
L 12.0075 1.1575 12.0075 1.1575 9 P 0 ;1
L 12.0075 1.2075 12.0075 1.2075 9 P 0 ;1
L 12.0075 1.2575 12.0075 1.2575 9 P 0 ;1
L 12.0075 1.3075 12.0075 1.3075 9 P 0 ;1
L 12.0075 1.3575 12.0075 1.3575 9 P 0 ;1
L 12.0075 1.7075 12.0075 1.7075 9 P 0 ;1
L 12.0075 1.7575 12.0075 1.7575 9 P 0 ;1
L 12.0075 1.8075 12.0075 1.8075 9 P 0 ;1
L 12.0075 1.8575 12.0075 1.8575 9 P 0 ;1
L 12.0075 1.9075 12.0075 1.9075 9 P 0 ;1
L 12.0075 1.9575 12.0075 1.9575 9 P 0 ;1
L 12.0075 2.0075 12.0075 2.0075 9 P 0 ;1
L 12.0075 2.0575 12.0075 2.0575 9 P 0 ;1
L 12.0075 2.1075 12.0075 2.1075 9 P 0 ;1
L 12.0075 2.1575 12.0075 2.1575 9 P 0 ;1
L 12.0075 2.2075 12.0075 2.2075 9 P 0 ;1
L 12.0075 2.2575 12.0075 2.2575 9 P 0 ;1
L 12.0075 2.3075 12.0075 2.3075 9 P 0 ;1
L 12.0075 2.3575 12.0075 2.3575 9 P 0 ;1
L 12.0075 2.4075 12.0075 2.4075 9 P 0 ;1
L 12.0075 2.7575 12.0075 2.7575 9 P 0 ;1
L 12.0075 2.8075 12.0075 2.8075 9 P 0 ;1
L 12.0075 2.8575 12.0075 2.8575 9 P 0 ;1
L 12.0075 2.9075 12.0075 2.9075 9 P 0 ;1
L 12.0075 2.9575 12.0075 2.9575 9 P 0 ;1
L 12.0075 3.0075 12.0075 3.0075 9 P 0 ;1
L 12.0075 3.0575 12.0075 3.0575 9 P 0 ;1
L 12.0075 3.1075 12.0075 3.1075 9 P 0 ;1
L 12.0075 3.1575 12.0075 3.1575 9 P 0 ;1
L 12.0075 3.2075 12.0075 3.2075 9 P 0 ;1
L 12.0075 3.2575 12.0075 3.2575 9 P 0 ;1
L 12.0075 3.3075 12.0075 3.3075 9 P 0 ;1
L 12.0075 3.3575 12.0075 3.3575 9 P 0 ;1
L 12.0075 3.4075 12.0075 3.4075 9 P 0 ;1
L 12.0075 3.4575 12.0075 3.4575 9 P 0 ;1
L 12.0075 3.5075 12.0075 3.5075 9 P 0 ;1
L 12.0075 3.5575 12.0075 3.5575 9 P 0 ;1
L 12.0075 3.6075 12.0075 3.6075 9 P 0 ;1
L 12.0075 3.6575 12.0075 3.6575 9 P 0 ;1
L 12.0075 3.7075 12.0075 3.7075 9 P 0 ;1
L 12.0075 3.7575 12.0075 3.7575 9 P 0 ;1
L 12.0075 3.8075 12.0075 3.8075 9 P 0 ;1
L 12.0075 3.8575 12.0075 3.8575 9 P 0 ;1
L 12.0075 3.9075 12.0075 3.9075 9 P 0 ;1
L 12.0075 3.9575 12.0075 3.9575 9 P 0 ;1
L 12.0075 4.0075 12.0075 4.0075 9 P 0 ;1
L 12.0075 4.4075 12.0075 4.4075 9 P 0 ;1
L 12.0075 4.4575 12.0075 4.4575 9 P 0 ;1
L 12.0075 4.5075 12.0075 4.5075 9 P 0 ;1
L 12.0075 4.5575 12.0075 4.5575 9 P 0 ;1
L 12.0075 4.6075 12.0075 4.6075 9 P 0 ;1
L 12.0075 4.6575 12.0075 4.6575 9 P 0 ;1
L 12.0075 4.7075 12.0075 4.7075 9 P 0 ;1
L 12.0575 0.1575 12.0575 0.1575 9 P 0 ;1
L 12.0575 0.2075 12.0575 0.2075 9 P 0 ;1
L 12.0575 0.2575 12.0575 0.2575 9 P 0 ;1
L 12.0575 0.3075 12.0575 0.3075 9 P 0 ;1
L 12.0575 0.3575 12.0575 0.3575 9 P 0 ;1
L 12.0575 0.4075 12.0575 0.4075 9 P 0 ;1
L 12.0575 0.4575 12.0575 0.4575 9 P 0 ;1
L 12.0575 0.5075 12.0575 0.5075 9 P 0 ;1
L 12.0575 0.5575 12.0575 0.5575 9 P 0 ;1
L 12.0575 0.6075 12.0575 0.6075 9 P 0 ;1
L 12.0575 0.6575 12.0575 0.6575 9 P 0 ;1
L 12.0575 0.7075 12.0575 0.7075 9 P 0 ;1
L 12.0575 0.7575 12.0575 0.7575 9 P 0 ;1
L 12.0575 0.8075 12.0575 0.8075 9 P 0 ;1
L 12.0575 0.8575 12.0575 0.8575 9 P 0 ;1
L 12.0575 0.9075 12.0575 0.9075 9 P 0 ;1
L 12.0575 0.9575 12.0575 0.9575 9 P 0 ;1
L 12.0575 1.0075 12.0575 1.0075 9 P 0 ;1
L 12.0575 1.0575 12.0575 1.0575 9 P 0 ;1
L 12.0575 1.1075 12.0575 1.1075 9 P 0 ;1
L 12.0575 1.1575 12.0575 1.1575 9 P 0 ;1
L 12.0575 1.2075 12.0575 1.2075 9 P 0 ;1
L 12.0575 1.2575 12.0575 1.2575 9 P 0 ;1
L 12.0575 1.3075 12.0575 1.3075 9 P 0 ;1
L 12.0575 1.7075 12.0575 1.7075 9 P 0 ;1
L 12.0575 1.7575 12.0575 1.7575 9 P 0 ;1
L 12.0575 1.8075 12.0575 1.8075 9 P 0 ;1
L 12.0575 1.8575 12.0575 1.8575 9 P 0 ;1
L 12.0575 1.9075 12.0575 1.9075 9 P 0 ;1
L 12.0575 1.9575 12.0575 1.9575 9 P 0 ;1
L 12.0575 2.0075 12.0575 2.0075 9 P 0 ;1
L 12.0575 2.0575 12.0575 2.0575 9 P 0 ;1
L 12.0575 2.1075 12.0575 2.1075 9 P 0 ;1
L 12.0575 2.1575 12.0575 2.1575 9 P 0 ;1
L 12.0575 2.2075 12.0575 2.2075 9 P 0 ;1
L 12.0575 2.2575 12.0575 2.2575 9 P 0 ;1
L 12.0575 2.3075 12.0575 2.3075 9 P 0 ;1
L 12.0575 2.3575 12.0575 2.3575 9 P 0 ;1
L 12.0575 2.4075 12.0575 2.4075 9 P 0 ;1
L 12.0575 2.7575 12.0575 2.7575 9 P 0 ;1
L 12.0575 2.8075 12.0575 2.8075 9 P 0 ;1
L 12.0575 2.8575 12.0575 2.8575 9 P 0 ;1
L 12.0575 2.9075 12.0575 2.9075 9 P 0 ;1
L 12.0575 2.9575 12.0575 2.9575 9 P 0 ;1
L 12.0575 3.0075 12.0575 3.0075 9 P 0 ;1
L 12.0575 3.0575 12.0575 3.0575 9 P 0 ;1
L 12.0575 3.1075 12.0575 3.1075 9 P 0 ;1
L 12.0575 3.1575 12.0575 3.1575 9 P 0 ;1
L 12.0575 3.2075 12.0575 3.2075 9 P 0 ;1
L 12.0575 3.2575 12.0575 3.2575 9 P 0 ;1
L 12.0575 3.3075 12.0575 3.3075 9 P 0 ;1
L 12.0575 3.3575 12.0575 3.3575 9 P 0 ;1
L 12.0575 3.4075 12.0575 3.4075 9 P 0 ;1
L 12.0575 3.4575 12.0575 3.4575 9 P 0 ;1
L 12.0575 3.5075 12.0575 3.5075 9 P 0 ;1
L 12.0575 3.5575 12.0575 3.5575 9 P 0 ;1
L 12.0575 3.6075 12.0575 3.6075 9 P 0 ;1
L 12.0575 3.6575 12.0575 3.6575 9 P 0 ;1
L 12.0575 3.7075 12.0575 3.7075 9 P 0 ;1
L 12.0575 3.7575 12.0575 3.7575 9 P 0 ;1
L 12.0575 3.8075 12.0575 3.8075 9 P 0 ;1
L 12.0575 3.8575 12.0575 3.8575 9 P 0 ;1
L 12.0575 3.9075 12.0575 3.9075 9 P 0 ;1
L 12.0575 3.9575 12.0575 3.9575 9 P 0 ;1
L 12.0575 4.0075 12.0575 4.0075 9 P 0 ;1
L 12.0575 4.4075 12.0575 4.4075 9 P 0 ;1
L 12.0575 4.4575 12.0575 4.4575 9 P 0 ;1
L 12.0575 4.5075 12.0575 4.5075 9 P 0 ;1
L 12.0575 4.5575 12.0575 4.5575 9 P 0 ;1
L 12.0575 4.6075 12.0575 4.6075 9 P 0 ;1
L 12.0575 4.6575 12.0575 4.6575 9 P 0 ;1
L 12.0575 4.7075 12.0575 4.7075 9 P 0 ;1
L 12.0575 4.7575 12.0575 4.7575 9 P 0 ;1
L 12.0575 4.8075 12.0575 4.8075 9 P 0 ;1
L 12.1075 0.1575 12.1075 0.1575 9 P 0 ;1
L 12.1075 0.2075 12.1075 0.2075 9 P 0 ;1
L 12.1075 0.2575 12.1075 0.2575 9 P 0 ;1
L 12.1075 0.3075 12.1075 0.3075 9 P 0 ;1
L 12.1075 0.3575 12.1075 0.3575 9 P 0 ;1
L 12.1075 0.4075 12.1075 0.4075 9 P 0 ;1
L 12.1075 0.4575 12.1075 0.4575 9 P 0 ;1
L 12.1075 0.5075 12.1075 0.5075 9 P 0 ;1
L 12.1075 0.5575 12.1075 0.5575 9 P 0 ;1
L 12.1075 0.6075 12.1075 0.6075 9 P 0 ;1
L 12.1075 0.6575 12.1075 0.6575 9 P 0 ;1
L 12.1075 0.7075 12.1075 0.7075 9 P 0 ;1
L 12.1075 0.7575 12.1075 0.7575 9 P 0 ;1
L 12.1075 0.8075 12.1075 0.8075 9 P 0 ;1
L 12.1075 0.8575 12.1075 0.8575 9 P 0 ;1
L 12.1075 0.9075 12.1075 0.9075 9 P 0 ;1
L 12.1075 0.9575 12.1075 0.9575 9 P 0 ;1
L 12.1075 1.0075 12.1075 1.0075 9 P 0 ;1
L 12.1075 1.0575 12.1075 1.0575 9 P 0 ;1
L 12.1075 1.1075 12.1075 1.1075 9 P 0 ;1
L 12.1075 1.1575 12.1075 1.1575 9 P 0 ;1
L 12.1075 1.2075 12.1075 1.2075 9 P 0 ;1
L 12.1075 1.2575 12.1075 1.2575 9 P 0 ;1
L 12.1075 1.3075 12.1075 1.3075 9 P 0 ;1
L 12.1075 1.7575 12.1075 1.7575 9 P 0 ;1
L 12.1075 1.8075 12.1075 1.8075 9 P 0 ;1
L 12.1075 1.8575 12.1075 1.8575 9 P 0 ;1
L 12.1075 1.9075 12.1075 1.9075 9 P 0 ;1
L 12.1075 1.9575 12.1075 1.9575 9 P 0 ;1
L 12.1075 2.0075 12.1075 2.0075 9 P 0 ;1
L 12.1075 2.0575 12.1075 2.0575 9 P 0 ;1
L 12.1075 2.1075 12.1075 2.1075 9 P 0 ;1
L 12.1075 2.1575 12.1075 2.1575 9 P 0 ;1
L 12.1075 2.2075 12.1075 2.2075 9 P 0 ;1
L 12.1075 2.2575 12.1075 2.2575 9 P 0 ;1
L 12.1075 2.3075 12.1075 2.3075 9 P 0 ;1
L 12.1075 2.3575 12.1075 2.3575 9 P 0 ;1
L 12.1075 2.4075 12.1075 2.4075 9 P 0 ;1
L 12.1075 2.7575 12.1075 2.7575 9 P 0 ;1
L 12.1075 2.8075 12.1075 2.8075 9 P 0 ;1
L 12.1075 2.8575 12.1075 2.8575 9 P 0 ;1
L 12.1075 2.9075 12.1075 2.9075 9 P 0 ;1
L 12.1075 2.9575 12.1075 2.9575 9 P 0 ;1
L 12.1075 3.0075 12.1075 3.0075 9 P 0 ;1
L 12.1075 3.0575 12.1075 3.0575 9 P 0 ;1
L 12.1075 3.1075 12.1075 3.1075 9 P 0 ;1
L 12.1075 3.1575 12.1075 3.1575 9 P 0 ;1
L 12.1075 3.2075 12.1075 3.2075 9 P 0 ;1
L 12.1075 3.2575 12.1075 3.2575 9 P 0 ;1
L 12.1075 3.3075 12.1075 3.3075 9 P 0 ;1
L 12.1075 3.3575 12.1075 3.3575 9 P 0 ;1
L 12.1075 3.4075 12.1075 3.4075 9 P 0 ;1
L 12.1075 3.4575 12.1075 3.4575 9 P 0 ;1
L 12.1075 3.5075 12.1075 3.5075 9 P 0 ;1
L 12.1075 3.5575 12.1075 3.5575 9 P 0 ;1
L 12.1075 3.6075 12.1075 3.6075 9 P 0 ;1
L 12.1075 3.6575 12.1075 3.6575 9 P 0 ;1
L 12.1075 3.7075 12.1075 3.7075 9 P 0 ;1
L 12.1075 3.7575 12.1075 3.7575 9 P 0 ;1
L 12.1075 3.8075 12.1075 3.8075 9 P 0 ;1
L 12.1075 3.8575 12.1075 3.8575 9 P 0 ;1
L 12.1075 3.9075 12.1075 3.9075 9 P 0 ;1
L 12.1075 3.9575 12.1075 3.9575 9 P 0 ;1
L 12.1075 4.4575 12.1075 4.4575 9 P 0 ;1
L 12.1075 4.5075 12.1075 4.5075 9 P 0 ;1
L 12.1075 4.5575 12.1075 4.5575 9 P 0 ;1
L 12.1075 4.6075 12.1075 4.6075 9 P 0 ;1
L 12.1075 4.6575 12.1075 4.6575 9 P 0 ;1
L 12.1075 4.7075 12.1075 4.7075 9 P 0 ;1
L 12.1075 4.7575 12.1075 4.7575 9 P 0 ;1
L 12.1075 4.8075 12.1075 4.8075 9 P 0 ;1
L 12.1575 0.1575 12.1575 0.1575 9 P 0 ;1
L 12.1575 0.2075 12.1575 0.2075 9 P 0 ;1
L 12.1575 0.4075 12.1575 0.4075 9 P 0 ;1
L 12.1575 0.4575 12.1575 0.4575 9 P 0 ;1
L 12.1575 0.5075 12.1575 0.5075 9 P 0 ;1
L 12.1575 0.5575 12.1575 0.5575 9 P 0 ;1
L 12.1575 0.6075 12.1575 0.6075 9 P 0 ;1
L 12.1575 0.6575 12.1575 0.6575 9 P 0 ;1
L 12.1575 0.7075 12.1575 0.7075 9 P 0 ;1
L 12.1575 0.7575 12.1575 0.7575 9 P 0 ;1
L 12.1575 0.8075 12.1575 0.8075 9 P 0 ;1
L 12.1575 0.8575 12.1575 0.8575 9 P 0 ;1
L 12.1575 0.9075 12.1575 0.9075 9 P 0 ;1
L 12.1575 0.9575 12.1575 0.9575 9 P 0 ;1
L 12.1575 1.0075 12.1575 1.0075 9 P 0 ;1
L 12.1575 1.0575 12.1575 1.0575 9 P 0 ;1
L 12.1575 1.1075 12.1575 1.1075 9 P 0 ;1
L 12.1575 1.1575 12.1575 1.1575 9 P 0 ;1
L 12.1575 1.2075 12.1575 1.2075 9 P 0 ;1
L 12.1575 1.2575 12.1575 1.2575 9 P 0 ;1
L 12.1575 1.3075 12.1575 1.3075 9 P 0 ;1
L 12.1575 1.7575 12.1575 1.7575 9 P 0 ;1
L 12.1575 1.8075 12.1575 1.8075 9 P 0 ;1
L 12.1575 1.8575 12.1575 1.8575 9 P 0 ;1
L 12.1575 1.9075 12.1575 1.9075 9 P 0 ;1
L 12.1575 1.9575 12.1575 1.9575 9 P 0 ;1
L 12.1575 2.0075 12.1575 2.0075 9 P 0 ;1
L 12.1575 2.0575 12.1575 2.0575 9 P 0 ;1
L 12.1575 2.1075 12.1575 2.1075 9 P 0 ;1
L 12.1575 2.1575 12.1575 2.1575 9 P 0 ;1
L 12.1575 2.2075 12.1575 2.2075 9 P 0 ;1
L 12.1575 2.2575 12.1575 2.2575 9 P 0 ;1
L 12.1575 2.3075 12.1575 2.3075 9 P 0 ;1
L 12.1575 2.3575 12.1575 2.3575 9 P 0 ;1
L 12.1575 2.4075 12.1575 2.4075 9 P 0 ;1
L 12.1575 2.4575 12.1575 2.4575 9 P 0 ;1
L 12.1575 2.7075 12.1575 2.7075 9 P 0 ;1
L 12.1575 2.7575 12.1575 2.7575 9 P 0 ;1
L 12.1575 2.8075 12.1575 2.8075 9 P 0 ;1
L 12.1575 2.8575 12.1575 2.8575 9 P 0 ;1
L 12.1575 2.9075 12.1575 2.9075 9 P 0 ;1
L 12.1575 2.9575 12.1575 2.9575 9 P 0 ;1
L 12.1575 3.0075 12.1575 3.0075 9 P 0 ;1
L 12.1575 3.0575 12.1575 3.0575 9 P 0 ;1
L 12.1575 3.1075 12.1575 3.1075 9 P 0 ;1
L 12.1575 3.1575 12.1575 3.1575 9 P 0 ;1
L 12.1575 3.2075 12.1575 3.2075 9 P 0 ;1
L 12.1575 3.2575 12.1575 3.2575 9 P 0 ;1
L 12.1575 3.3075 12.1575 3.3075 9 P 0 ;1
L 12.1575 3.3575 12.1575 3.3575 9 P 0 ;1
L 12.1575 3.4075 12.1575 3.4075 9 P 0 ;1
L 12.1575 3.4575 12.1575 3.4575 9 P 0 ;1
L 12.1575 3.5075 12.1575 3.5075 9 P 0 ;1
L 12.1575 3.5575 12.1575 3.5575 9 P 0 ;1
L 12.1575 3.6075 12.1575 3.6075 9 P 0 ;1
L 12.1575 3.6575 12.1575 3.6575 9 P 0 ;1
L 12.1575 3.7075 12.1575 3.7075 9 P 0 ;1
L 12.1575 3.7575 12.1575 3.7575 9 P 0 ;1
L 12.1575 3.8075 12.1575 3.8075 9 P 0 ;1
L 12.1575 3.8575 12.1575 3.8575 9 P 0 ;1
L 12.1575 3.9075 12.1575 3.9075 9 P 0 ;1
L 12.1575 3.9575 12.1575 3.9575 9 P 0 ;1
L 12.1575 4.4075 12.1575 4.4075 9 P 0 ;1
L 12.1575 4.4575 12.1575 4.4575 9 P 0 ;1
L 12.1575 4.5075 12.1575 4.5075 9 P 0 ;1
L 12.1575 4.5575 12.1575 4.5575 9 P 0 ;1
L 12.1575 4.6075 12.1575 4.6075 9 P 0 ;1
L 12.1575 4.6575 12.1575 4.6575 9 P 0 ;1
L 12.1575 4.7075 12.1575 4.7075 9 P 0 ;1
L 12.1575 4.7575 12.1575 4.7575 9 P 0 ;1
L 12.1575 4.8075 12.1575 4.8075 9 P 0 ;1
L 12.2075 0.1575 12.2075 0.1575 9 P 0 ;1
L 12.2075 0.4575 12.2075 0.4575 9 P 0 ;1
L 12.2075 0.5075 12.2075 0.5075 9 P 0 ;1
L 12.2075 0.5575 12.2075 0.5575 9 P 0 ;1
L 12.2075 0.6075 12.2075 0.6075 9 P 0 ;1
L 12.2075 0.6575 12.2075 0.6575 9 P 0 ;1
L 12.2075 0.7075 12.2075 0.7075 9 P 0 ;1
L 12.2075 0.7575 12.2075 0.7575 9 P 0 ;1
L 12.2075 0.8075 12.2075 0.8075 9 P 0 ;1
L 12.2075 0.8575 12.2075 0.8575 9 P 0 ;1
L 12.2075 0.9075 12.2075 0.9075 9 P 0 ;1
L 12.2075 0.9575 12.2075 0.9575 9 P 0 ;1
L 12.2075 1.0075 12.2075 1.0075 9 P 0 ;1
L 12.2075 1.0575 12.2075 1.0575 9 P 0 ;1
L 12.2075 1.1075 12.2075 1.1075 9 P 0 ;1
L 12.2075 1.1575 12.2075 1.1575 9 P 0 ;1
L 12.2075 1.2075 12.2075 1.2075 9 P 0 ;1
L 12.2075 1.2575 12.2075 1.2575 9 P 0 ;1
L 12.2075 1.3075 12.2075 1.3075 9 P 0 ;1
L 12.2075 1.3575 12.2075 1.3575 9 P 0 ;1
L 12.2075 1.7075 12.2075 1.7075 9 P 0 ;1
L 12.2075 1.7575 12.2075 1.7575 9 P 0 ;1
L 12.2075 1.8075 12.2075 1.8075 9 P 0 ;1
L 12.2075 1.8575 12.2075 1.8575 9 P 0 ;1
L 12.2075 1.9075 12.2075 1.9075 9 P 0 ;1
L 12.2075 1.9575 12.2075 1.9575 9 P 0 ;1
L 12.2075 2.0075 12.2075 2.0075 9 P 0 ;1
L 12.2075 2.0575 12.2075 2.0575 9 P 0 ;1
L 12.2075 2.1075 12.2075 2.1075 9 P 0 ;1
L 12.2075 2.1575 12.2075 2.1575 9 P 0 ;1
L 12.2075 2.2075 12.2075 2.2075 9 P 0 ;1
L 12.2075 2.2575 12.2075 2.2575 9 P 0 ;1
L 12.2075 2.3075 12.2075 2.3075 9 P 0 ;1
L 12.2075 2.3575 12.2075 2.3575 9 P 0 ;1
L 12.2075 2.4075 12.2075 2.4075 9 P 0 ;1
L 12.2075 2.4575 12.2075 2.4575 9 P 0 ;1
L 12.2075 2.5075 12.2075 2.5075 9 P 0 ;1
L 12.2075 2.5575 12.2075 2.5575 9 P 0 ;1
L 12.2075 2.6075 12.2075 2.6075 9 P 0 ;1
L 12.2075 2.6575 12.2075 2.6575 9 P 0 ;1
L 12.2075 2.7075 12.2075 2.7075 9 P 0 ;1
L 12.2075 2.7575 12.2075 2.7575 9 P 0 ;1
L 12.2075 2.8075 12.2075 2.8075 9 P 0 ;1
L 12.2075 2.8575 12.2075 2.8575 9 P 0 ;1
L 12.2075 2.9075 12.2075 2.9075 9 P 0 ;1
L 12.2075 2.9575 12.2075 2.9575 9 P 0 ;1
L 12.2075 3.0075 12.2075 3.0075 9 P 0 ;1
L 12.2075 3.0575 12.2075 3.0575 9 P 0 ;1
L 12.2075 3.1075 12.2075 3.1075 9 P 0 ;1
L 12.2075 3.1575 12.2075 3.1575 9 P 0 ;1
L 12.2075 3.2075 12.2075 3.2075 9 P 0 ;1
L 12.2075 3.2575 12.2075 3.2575 9 P 0 ;1
L 12.2075 3.3075 12.2075 3.3075 9 P 0 ;1
L 12.2075 3.3575 12.2075 3.3575 9 P 0 ;1
L 12.2075 3.4075 12.2075 3.4075 9 P 0 ;1
L 12.2075 3.4575 12.2075 3.4575 9 P 0 ;1
L 12.2075 3.5075 12.2075 3.5075 9 P 0 ;1
L 12.2075 3.5575 12.2075 3.5575 9 P 0 ;1
L 12.2075 3.6075 12.2075 3.6075 9 P 0 ;1
L 12.2075 3.6575 12.2075 3.6575 9 P 0 ;1
L 12.2075 3.7075 12.2075 3.7075 9 P 0 ;1
L 12.2075 3.7575 12.2075 3.7575 9 P 0 ;1
L 12.2075 3.8075 12.2075 3.8075 9 P 0 ;1
L 12.2075 3.8575 12.2075 3.8575 9 P 0 ;1
L 12.2075 3.9075 12.2075 3.9075 9 P 0 ;1
L 12.2075 3.9575 12.2075 3.9575 9 P 0 ;1
L 12.2075 4.0075 12.2075 4.0075 9 P 0 ;1
L 12.2075 4.4075 12.2075 4.4075 9 P 0 ;1
L 12.2075 4.4575 12.2075 4.4575 9 P 0 ;1
L 12.2075 4.5075 12.2075 4.5075 9 P 0 ;1
L 12.2075 4.5575 12.2075 4.5575 9 P 0 ;1
L 12.2075 4.6075 12.2075 4.6075 9 P 0 ;1
L 12.2075 4.6575 12.2075 4.6575 9 P 0 ;1
L 12.2075 4.7075 12.2075 4.7075 9 P 0 ;1
L 12.2075 4.7575 12.2075 4.7575 9 P 0 ;1
L 12.2075 4.8075 12.2075 4.8075 9 P 0 ;1
L 12.2575 0.4575 12.2575 0.4575 9 P 0 ;1
L 12.2575 0.5075 12.2575 0.5075 9 P 0 ;1
L 12.2575 0.5575 12.2575 0.5575 9 P 0 ;1
L 12.2575 0.6075 12.2575 0.6075 9 P 0 ;1
L 12.2575 0.6575 12.2575 0.6575 9 P 0 ;1
L 12.2575 0.7075 12.2575 0.7075 9 P 0 ;1
L 12.2575 0.7575 12.2575 0.7575 9 P 0 ;1
L 12.2575 0.8075 12.2575 0.8075 9 P 0 ;1
L 12.2575 0.8575 12.2575 0.8575 9 P 0 ;1
L 12.2575 0.9075 12.2575 0.9075 9 P 0 ;1
L 12.2575 0.9575 12.2575 0.9575 9 P 0 ;1
L 12.2575 1.0075 12.2575 1.0075 9 P 0 ;1
L 12.2575 1.0575 12.2575 1.0575 9 P 0 ;1
L 12.2575 1.1075 12.2575 1.1075 9 P 0 ;1
L 12.2575 1.1575 12.2575 1.1575 9 P 0 ;1
L 12.2575 1.2075 12.2575 1.2075 9 P 0 ;1
L 12.2575 1.2575 12.2575 1.2575 9 P 0 ;1
L 12.2575 1.3075 12.2575 1.3075 9 P 0 ;1
L 12.2575 1.3575 12.2575 1.3575 9 P 0 ;1
L 12.2575 1.7075 12.2575 1.7075 9 P 0 ;1
L 12.2575 1.7575 12.2575 1.7575 9 P 0 ;1
L 12.2575 1.8075 12.2575 1.8075 9 P 0 ;1
L 12.2575 1.8575 12.2575 1.8575 9 P 0 ;1
L 12.2575 1.9075 12.2575 1.9075 9 P 0 ;1
L 12.2575 1.9575 12.2575 1.9575 9 P 0 ;1
L 12.2575 2.0075 12.2575 2.0075 9 P 0 ;1
L 12.2575 2.0575 12.2575 2.0575 9 P 0 ;1
L 12.2575 2.1075 12.2575 2.1075 9 P 0 ;1
L 12.2575 2.1575 12.2575 2.1575 9 P 0 ;1
L 12.2575 2.2075 12.2575 2.2075 9 P 0 ;1
L 12.2575 2.2575 12.2575 2.2575 9 P 0 ;1
L 12.2575 2.3075 12.2575 2.3075 9 P 0 ;1
L 12.2575 2.3575 12.2575 2.3575 9 P 0 ;1
L 12.2575 2.4075 12.2575 2.4075 9 P 0 ;1
L 12.2575 2.4575 12.2575 2.4575 9 P 0 ;1
L 12.2575 2.5075 12.2575 2.5075 9 P 0 ;1
L 12.2575 2.5575 12.2575 2.5575 9 P 0 ;1
L 12.2575 2.6075 12.2575 2.6075 9 P 0 ;1
L 12.2575 2.6575 12.2575 2.6575 9 P 0 ;1
L 12.2575 2.7075 12.2575 2.7075 9 P 0 ;1
L 12.2575 2.7575 12.2575 2.7575 9 P 0 ;1
L 12.2575 2.8075 12.2575 2.8075 9 P 0 ;1
L 12.2575 2.8575 12.2575 2.8575 9 P 0 ;1
L 12.2575 2.9075 12.2575 2.9075 9 P 0 ;1
L 12.2575 2.9575 12.2575 2.9575 9 P 0 ;1
L 12.2575 3.0075 12.2575 3.0075 9 P 0 ;1
L 12.2575 3.0575 12.2575 3.0575 9 P 0 ;1
L 12.2575 3.1075 12.2575 3.1075 9 P 0 ;1
L 12.2575 3.1575 12.2575 3.1575 9 P 0 ;1
L 12.2575 3.2075 12.2575 3.2075 9 P 0 ;1
L 12.2575 3.2575 12.2575 3.2575 9 P 0 ;1
L 12.2575 3.3075 12.2575 3.3075 9 P 0 ;1
L 12.2575 3.3575 12.2575 3.3575 9 P 0 ;1
L 12.2575 3.4075 12.2575 3.4075 9 P 0 ;1
L 12.2575 3.4575 12.2575 3.4575 9 P 0 ;1
L 12.2575 3.5075 12.2575 3.5075 9 P 0 ;1
L 12.2575 3.5575 12.2575 3.5575 9 P 0 ;1
L 12.2575 3.6075 12.2575 3.6075 9 P 0 ;1
L 12.2575 3.6575 12.2575 3.6575 9 P 0 ;1
L 12.2575 3.7075 12.2575 3.7075 9 P 0 ;1
L 12.2575 3.7575 12.2575 3.7575 9 P 0 ;1
L 12.2575 3.8075 12.2575 3.8075 9 P 0 ;1
L 12.2575 3.8575 12.2575 3.8575 9 P 0 ;1
L 12.2575 3.9075 12.2575 3.9075 9 P 0 ;1
L 12.2575 3.9575 12.2575 3.9575 9 P 0 ;1
L 12.2575 4.0075 12.2575 4.0075 9 P 0 ;1
L 12.2575 4.4075 12.2575 4.4075 9 P 0 ;1
L 12.2575 4.4575 12.2575 4.4575 9 P 0 ;1
L 12.2575 4.5075 12.2575 4.5075 9 P 0 ;1
L 12.2575 4.5575 12.2575 4.5575 9 P 0 ;1
L 12.2575 4.6075 12.2575 4.6075 9 P 0 ;1
L 12.2575 4.6575 12.2575 4.6575 9 P 0 ;1
L 12.2575 4.7075 12.2575 4.7075 9 P 0 ;1
L 12.2575 4.7575 12.2575 4.7575 9 P 0 ;1
L 12.2575 4.8075 12.2575 4.8075 9 P 0 ;1
L 12.3075 0.1575 12.3075 0.1575 9 P 0 ;1
L 12.3075 0.4575 12.3075 0.4575 9 P 0 ;1
L 12.3075 0.5075 12.3075 0.5075 9 P 0 ;1
L 12.3075 0.5575 12.3075 0.5575 9 P 0 ;1
L 12.3075 0.6075 12.3075 0.6075 9 P 0 ;1
L 12.3075 0.6575 12.3075 0.6575 9 P 0 ;1
L 12.3075 0.7075 12.3075 0.7075 9 P 0 ;1
L 12.3075 0.7575 12.3075 0.7575 9 P 0 ;1
L 12.3075 0.8075 12.3075 0.8075 9 P 0 ;1
L 12.3075 0.8575 12.3075 0.8575 9 P 0 ;1
L 12.3075 0.9075 12.3075 0.9075 9 P 0 ;1
L 12.3075 0.9575 12.3075 0.9575 9 P 0 ;1
L 12.3075 1.0075 12.3075 1.0075 9 P 0 ;1
L 12.3075 1.0575 12.3075 1.0575 9 P 0 ;1
L 12.3075 1.1075 12.3075 1.1075 9 P 0 ;1
L 12.3075 1.1575 12.3075 1.1575 9 P 0 ;1
L 12.3075 1.2075 12.3075 1.2075 9 P 0 ;1
L 12.3075 1.2575 12.3075 1.2575 9 P 0 ;1
L 12.3075 1.3075 12.3075 1.3075 9 P 0 ;1
L 12.3075 1.3575 12.3075 1.3575 9 P 0 ;1
L 12.3075 1.4075 12.3075 1.4075 9 P 0 ;1
L 12.3075 1.4575 12.3075 1.4575 9 P 0 ;1
L 12.3075 1.6075 12.3075 1.6075 9 P 0 ;1
L 12.3075 1.6575 12.3075 1.6575 9 P 0 ;1
L 12.3075 1.7075 12.3075 1.7075 9 P 0 ;1
L 12.3075 1.7575 12.3075 1.7575 9 P 0 ;1
L 12.3075 1.8075 12.3075 1.8075 9 P 0 ;1
L 12.3075 1.8575 12.3075 1.8575 9 P 0 ;1
L 12.3075 1.9075 12.3075 1.9075 9 P 0 ;1
L 12.3075 1.9575 12.3075 1.9575 9 P 0 ;1
L 12.3075 2.0075 12.3075 2.0075 9 P 0 ;1
L 12.3075 2.0575 12.3075 2.0575 9 P 0 ;1
L 12.3075 2.1075 12.3075 2.1075 9 P 0 ;1
L 12.3075 2.3075 12.3075 2.3075 9 P 0 ;1
L 12.3075 2.3575 12.3075 2.3575 9 P 0 ;1
L 12.3075 2.4075 12.3075 2.4075 9 P 0 ;1
L 12.3075 2.4575 12.3075 2.4575 9 P 0 ;1
L 12.3075 2.5075 12.3075 2.5075 9 P 0 ;1
L 12.3075 2.5575 12.3075 2.5575 9 P 0 ;1
L 12.3075 2.6075 12.3075 2.6075 9 P 0 ;1
L 12.3075 2.6575 12.3075 2.6575 9 P 0 ;1
L 12.3075 2.7075 12.3075 2.7075 9 P 0 ;1
L 12.3075 2.7575 12.3075 2.7575 9 P 0 ;1
L 12.3075 2.8075 12.3075 2.8075 9 P 0 ;1
L 12.3075 2.8575 12.3075 2.8575 9 P 0 ;1
L 12.3075 2.9075 12.3075 2.9075 9 P 0 ;1
L 12.3075 2.9575 12.3075 2.9575 9 P 0 ;1
L 12.3075 3.0075 12.3075 3.0075 9 P 0 ;1
L 12.3075 3.0575 12.3075 3.0575 9 P 0 ;1
L 12.3075 3.1075 12.3075 3.1075 9 P 0 ;1
L 12.3075 3.1575 12.3075 3.1575 9 P 0 ;1
L 12.3075 3.2075 12.3075 3.2075 9 P 0 ;1
L 12.3075 3.2575 12.3075 3.2575 9 P 0 ;1
L 12.3075 3.3075 12.3075 3.3075 9 P 0 ;1
L 12.3075 3.3575 12.3075 3.3575 9 P 0 ;1
L 12.3075 3.4075 12.3075 3.4075 9 P 0 ;1
L 12.3075 3.4575 12.3075 3.4575 9 P 0 ;1
L 12.3075 3.5075 12.3075 3.5075 9 P 0 ;1
L 12.3075 3.5575 12.3075 3.5575 9 P 0 ;1
L 12.3075 3.6075 12.3075 3.6075 9 P 0 ;1
L 12.3075 3.6575 12.3075 3.6575 9 P 0 ;1
L 12.3075 3.7075 12.3075 3.7075 9 P 0 ;1
L 12.3075 3.7575 12.3075 3.7575 9 P 0 ;1
L 12.3075 3.8075 12.3075 3.8075 9 P 0 ;1
L 12.3075 3.8575 12.3075 3.8575 9 P 0 ;1
L 12.3075 3.9075 12.3075 3.9075 9 P 0 ;1
L 12.3075 3.9575 12.3075 3.9575 9 P 0 ;1
L 12.3075 4.0075 12.3075 4.0075 9 P 0 ;1
L 12.3075 4.0575 12.3075 4.0575 9 P 0 ;1
L 12.3075 4.1075 12.3075 4.1075 9 P 0 ;1
L 12.3075 4.3075 12.3075 4.3075 9 P 0 ;1
L 12.3075 4.3575 12.3075 4.3575 9 P 0 ;1
L 12.3075 4.4075 12.3075 4.4075 9 P 0 ;1
L 12.3075 4.4575 12.3075 4.4575 9 P 0 ;1
L 12.3075 4.5075 12.3075 4.5075 9 P 0 ;1
L 12.3075 4.5575 12.3075 4.5575 9 P 0 ;1
L 12.3075 4.6075 12.3075 4.6075 9 P 0 ;1
L 12.3075 4.6575 12.3075 4.6575 9 P 0 ;1
L 12.3075 4.7075 12.3075 4.7075 9 P 0 ;1
L 12.3075 4.7575 12.3075 4.7575 9 P 0 ;1
L 12.3075 4.8075 12.3075 4.8075 9 P 0 ;1
L 12.3075 4.8575 12.3075 4.8575 9 P 0 ;1
L 12.3075 4.9075 12.3075 4.9075 9 P 0 ;1
L 12.3075 4.9575 12.3075 4.9575 9 P 0 ;1
L 12.3575 0.1575 12.3575 0.1575 9 P 0 ;1
L 12.3575 0.4075 12.3575 0.4075 9 P 0 ;1
L 12.3575 0.4575 12.3575 0.4575 9 P 0 ;1
L 12.3575 0.5075 12.3575 0.5075 9 P 0 ;1
L 12.3575 0.5575 12.3575 0.5575 9 P 0 ;1
L 12.3575 0.6075 12.3575 0.6075 9 P 0 ;1
L 12.3575 0.6575 12.3575 0.6575 9 P 0 ;1
L 12.3575 0.7075 12.3575 0.7075 9 P 0 ;1
L 12.3575 0.7575 12.3575 0.7575 9 P 0 ;1
L 12.3575 0.8075 12.3575 0.8075 9 P 0 ;1
L 12.3575 0.8575 12.3575 0.8575 9 P 0 ;1
L 12.3575 0.9075 12.3575 0.9075 9 P 0 ;1
L 12.3575 0.9575 12.3575 0.9575 9 P 0 ;1
L 12.3575 1.0075 12.3575 1.0075 9 P 0 ;1
L 12.3575 1.0575 12.3575 1.0575 9 P 0 ;1
L 12.3575 1.1075 12.3575 1.1075 9 P 0 ;1
L 12.3575 1.1575 12.3575 1.1575 9 P 0 ;1
L 12.3575 1.2075 12.3575 1.2075 9 P 0 ;1
L 12.3575 1.2575 12.3575 1.2575 9 P 0 ;1
L 12.3575 1.3075 12.3575 1.3075 9 P 0 ;1
L 12.3575 1.3575 12.3575 1.3575 9 P 0 ;1
L 12.3575 1.4075 12.3575 1.4075 9 P 0 ;1
L 12.3575 1.4575 12.3575 1.4575 9 P 0 ;1
L 12.3575 1.5075 12.3575 1.5075 9 P 0 ;1
L 12.3575 1.5575 12.3575 1.5575 9 P 0 ;1
L 12.3575 1.6075 12.3575 1.6075 9 P 0 ;1
L 12.3575 1.6575 12.3575 1.6575 9 P 0 ;1
L 12.3575 1.7075 12.3575 1.7075 9 P 0 ;1
L 12.3575 1.7575 12.3575 1.7575 9 P 0 ;1
L 12.3575 1.8075 12.3575 1.8075 9 P 0 ;1
L 12.3575 1.8575 12.3575 1.8575 9 P 0 ;1
L 12.3575 1.9075 12.3575 1.9075 9 P 0 ;1
L 12.3575 1.9575 12.3575 1.9575 9 P 0 ;1
L 12.3575 2.0075 12.3575 2.0075 9 P 0 ;1
L 12.3575 2.0575 12.3575 2.0575 9 P 0 ;1
L 12.3575 2.1075 12.3575 2.1075 9 P 0 ;1
L 12.3575 2.3075 12.3575 2.3075 9 P 0 ;1
L 12.3575 2.3575 12.3575 2.3575 9 P 0 ;1
L 12.3575 2.4075 12.3575 2.4075 9 P 0 ;1
L 12.3575 2.4575 12.3575 2.4575 9 P 0 ;1
L 12.3575 2.5075 12.3575 2.5075 9 P 0 ;1
L 12.3575 2.5575 12.3575 2.5575 9 P 0 ;1
L 12.3575 2.6075 12.3575 2.6075 9 P 0 ;1
L 12.3575 2.6575 12.3575 2.6575 9 P 0 ;1
L 12.3575 2.7075 12.3575 2.7075 9 P 0 ;1
L 12.3575 2.7575 12.3575 2.7575 9 P 0 ;1
L 12.3575 2.8075 12.3575 2.8075 9 P 0 ;1
L 12.3575 2.8575 12.3575 2.8575 9 P 0 ;1
L 12.3575 2.9075 12.3575 2.9075 9 P 0 ;1
L 12.3575 2.9575 12.3575 2.9575 9 P 0 ;1
L 12.3575 3.0075 12.3575 3.0075 9 P 0 ;1
L 12.3575 3.0575 12.3575 3.0575 9 P 0 ;1
L 12.3575 3.1075 12.3575 3.1075 9 P 0 ;1
L 12.3575 3.1575 12.3575 3.1575 9 P 0 ;1
L 12.3575 3.2075 12.3575 3.2075 9 P 0 ;1
L 12.3575 3.2575 12.3575 3.2575 9 P 0 ;1
L 12.3575 3.3075 12.3575 3.3075 9 P 0 ;1
L 12.3575 3.3575 12.3575 3.3575 9 P 0 ;1
L 12.3575 3.4075 12.3575 3.4075 9 P 0 ;1
L 12.3575 3.4575 12.3575 3.4575 9 P 0 ;1
L 12.3575 3.5075 12.3575 3.5075 9 P 0 ;1
L 12.3575 3.5575 12.3575 3.5575 9 P 0 ;1
L 12.3575 3.6075 12.3575 3.6075 9 P 0 ;1
L 12.3575 3.6575 12.3575 3.6575 9 P 0 ;1
L 12.3575 3.7075 12.3575 3.7075 9 P 0 ;1
L 12.3575 3.7575 12.3575 3.7575 9 P 0 ;1
L 12.3575 3.8075 12.3575 3.8075 9 P 0 ;1
L 12.3575 3.8575 12.3575 3.8575 9 P 0 ;1
L 12.3575 3.9075 12.3575 3.9075 9 P 0 ;1
L 12.3575 3.9575 12.3575 3.9575 9 P 0 ;1
L 12.3575 4.0075 12.3575 4.0075 9 P 0 ;1
L 12.3575 4.0575 12.3575 4.0575 9 P 0 ;1
L 12.3575 4.1075 12.3575 4.1075 9 P 0 ;1
L 12.3575 4.1575 12.3575 4.1575 9 P 0 ;1
L 12.3575 4.2075 12.3575 4.2075 9 P 0 ;1
L 12.3575 4.2575 12.3575 4.2575 9 P 0 ;1
L 12.3575 4.3075 12.3575 4.3075 9 P 0 ;1
L 12.3575 4.3575 12.3575 4.3575 9 P 0 ;1
L 12.3575 4.4075 12.3575 4.4075 9 P 0 ;1
L 12.3575 4.4575 12.3575 4.4575 9 P 0 ;1
L 12.3575 4.5075 12.3575 4.5075 9 P 0 ;1
L 12.3575 4.5575 12.3575 4.5575 9 P 0 ;1
L 12.3575 4.6075 12.3575 4.6075 9 P 0 ;1
L 12.3575 4.6575 12.3575 4.6575 9 P 0 ;1
L 12.3575 4.7075 12.3575 4.7075 9 P 0 ;1
L 12.3575 4.7575 12.3575 4.7575 9 P 0 ;1
L 12.3575 4.8075 12.3575 4.8075 9 P 0 ;1
L 12.3575 4.8575 12.3575 4.8575 9 P 0 ;1
L 12.3575 4.9075 12.3575 4.9075 9 P 0 ;1
L 12.3575 4.9575 12.3575 4.9575 9 P 0 ;1
L 12.3575 5.0075 12.3575 5.0075 9 P 0 ;1
L 12.4075 0.1575 12.4075 0.1575 9 P 0 ;1
L 12.4075 0.2075 12.4075 0.2075 9 P 0 ;1
L 12.4075 0.2575 12.4075 0.2575 9 P 0 ;1
L 12.4075 0.3075 12.4075 0.3075 9 P 0 ;1
L 12.4075 0.3575 12.4075 0.3575 9 P 0 ;1
L 12.4075 0.4075 12.4075 0.4075 9 P 0 ;1
L 12.4075 0.4575 12.4075 0.4575 9 P 0 ;1
L 12.4075 0.5075 12.4075 0.5075 9 P 0 ;1
L 12.4075 0.5575 12.4075 0.5575 9 P 0 ;1
L 12.4075 0.6075 12.4075 0.6075 9 P 0 ;1
L 12.4075 0.6575 12.4075 0.6575 9 P 0 ;1
L 12.4075 0.7075 12.4075 0.7075 9 P 0 ;1
L 12.4075 0.7575 12.4075 0.7575 9 P 0 ;1
L 12.4075 0.8075 12.4075 0.8075 9 P 0 ;1
L 12.4075 0.8575 12.4075 0.8575 9 P 0 ;1
L 12.4075 0.9075 12.4075 0.9075 9 P 0 ;1
L 12.4075 0.9575 12.4075 0.9575 9 P 0 ;1
L 12.4075 1.0075 12.4075 1.0075 9 P 0 ;1
L 12.4075 1.0575 12.4075 1.0575 9 P 0 ;1
L 12.4075 1.1075 12.4075 1.1075 9 P 0 ;1
L 12.4075 1.1575 12.4075 1.1575 9 P 0 ;1
L 12.4075 1.2075 12.4075 1.2075 9 P 0 ;1
L 12.4075 1.2575 12.4075 1.2575 9 P 0 ;1
L 12.4075 1.3075 12.4075 1.3075 9 P 0 ;1
L 12.4075 1.3575 12.4075 1.3575 9 P 0 ;1
L 12.4075 1.4075 12.4075 1.4075 9 P 0 ;1
L 12.4075 1.4575 12.4075 1.4575 9 P 0 ;1
L 12.4075 1.5075 12.4075 1.5075 9 P 0 ;1
L 12.4075 1.5575 12.4075 1.5575 9 P 0 ;1
L 12.4075 1.6075 12.4075 1.6075 9 P 0 ;1
L 12.4075 1.6575 12.4075 1.6575 9 P 0 ;1
L 12.4075 1.7075 12.4075 1.7075 9 P 0 ;1
L 12.4075 1.7575 12.4075 1.7575 9 P 0 ;1
L 12.4075 1.8075 12.4075 1.8075 9 P 0 ;1
L 12.4075 1.8575 12.4075 1.8575 9 P 0 ;1
L 12.4075 1.9075 12.4075 1.9075 9 P 0 ;1
L 12.4075 1.9575 12.4075 1.9575 9 P 0 ;1
L 12.4075 2.0075 12.4075 2.0075 9 P 0 ;1
L 12.4075 2.0575 12.4075 2.0575 9 P 0 ;1
L 12.4075 2.1075 12.4075 2.1075 9 P 0 ;1
L 12.4075 2.2575 12.4075 2.2575 9 P 0 ;1
L 12.4075 2.3075 12.4075 2.3075 9 P 0 ;1
L 12.4075 2.3575 12.4075 2.3575 9 P 0 ;1
L 12.4075 2.4075 12.4075 2.4075 9 P 0 ;1
L 12.4075 2.4575 12.4075 2.4575 9 P 0 ;1
L 12.4075 2.5075 12.4075 2.5075 9 P 0 ;1
L 12.4075 2.5575 12.4075 2.5575 9 P 0 ;1
L 12.4075 2.6075 12.4075 2.6075 9 P 0 ;1
L 12.4075 2.6575 12.4075 2.6575 9 P 0 ;1
L 12.4075 2.7075 12.4075 2.7075 9 P 0 ;1
L 12.4075 2.7575 12.4075 2.7575 9 P 0 ;1
L 12.4075 2.8075 12.4075 2.8075 9 P 0 ;1
L 12.4075 2.8575 12.4075 2.8575 9 P 0 ;1
L 12.4075 2.9075 12.4075 2.9075 9 P 0 ;1
L 12.4075 2.9575 12.4075 2.9575 9 P 0 ;1
L 12.4075 3.0075 12.4075 3.0075 9 P 0 ;1
L 12.4075 3.0575 12.4075 3.0575 9 P 0 ;1
L 12.4075 3.1075 12.4075 3.1075 9 P 0 ;1
L 12.4075 3.1575 12.4075 3.1575 9 P 0 ;1
L 12.4075 3.2075 12.4075 3.2075 9 P 0 ;1
L 12.4075 3.2575 12.4075 3.2575 9 P 0 ;1
L 12.4075 3.3075 12.4075 3.3075 9 P 0 ;1
L 12.4075 3.3575 12.4075 3.3575 9 P 0 ;1
L 12.4075 3.4075 12.4075 3.4075 9 P 0 ;1
L 12.4075 3.4575 12.4075 3.4575 9 P 0 ;1
L 12.4075 3.5075 12.4075 3.5075 9 P 0 ;1
L 12.4075 3.5575 12.4075 3.5575 9 P 0 ;1
L 12.4075 3.6075 12.4075 3.6075 9 P 0 ;1
L 12.4075 3.6575 12.4075 3.6575 9 P 0 ;1
L 12.4075 3.7075 12.4075 3.7075 9 P 0 ;1
L 12.4075 3.7575 12.4075 3.7575 9 P 0 ;1
L 12.4075 3.8075 12.4075 3.8075 9 P 0 ;1
L 12.4075 3.8575 12.4075 3.8575 9 P 0 ;1
L 12.4075 3.9075 12.4075 3.9075 9 P 0 ;1
L 12.4075 3.9575 12.4075 3.9575 9 P 0 ;1
L 12.4075 4.0075 12.4075 4.0075 9 P 0 ;1
L 12.4075 4.0575 12.4075 4.0575 9 P 0 ;1
L 12.4075 4.1075 12.4075 4.1075 9 P 0 ;1
L 12.4075 4.1575 12.4075 4.1575 9 P 0 ;1
L 12.4075 4.2075 12.4075 4.2075 9 P 0 ;1
L 12.4075 4.2575 12.4075 4.2575 9 P 0 ;1
L 12.4075 4.3075 12.4075 4.3075 9 P 0 ;1
L 12.4075 4.3575 12.4075 4.3575 9 P 0 ;1
L 12.4075 4.4075 12.4075 4.4075 9 P 0 ;1
L 12.4075 4.4575 12.4075 4.4575 9 P 0 ;1
L 12.4075 4.5075 12.4075 4.5075 9 P 0 ;1
L 12.4075 4.5575 12.4075 4.5575 9 P 0 ;1
L 12.4075 4.6075 12.4075 4.6075 9 P 0 ;1
L 12.4075 4.6575 12.4075 4.6575 9 P 0 ;1
L 12.4075 4.7075 12.4075 4.7075 9 P 0 ;1
L 12.4075 4.7575 12.4075 4.7575 9 P 0 ;1
L 12.4075 4.8075 12.4075 4.8075 9 P 0 ;1
L 12.4075 4.8575 12.4075 4.8575 9 P 0 ;1
L 12.4075 4.9075 12.4075 4.9075 9 P 0 ;1
L 12.4075 4.9575 12.4075 4.9575 9 P 0 ;1
L 12.4075 5.0075 12.4075 5.0075 9 P 0 ;1
L 12.4075 5.0575 12.4075 5.0575 9 P 0 ;1
L 12.4575 0.1575 12.4575 0.1575 9 P 0 ;1
L 12.4575 0.2075 12.4575 0.2075 9 P 0 ;1
L 12.4575 0.2575 12.4575 0.2575 9 P 0 ;1
L 12.4575 0.3075 12.4575 0.3075 9 P 0 ;1
L 12.4575 0.3575 12.4575 0.3575 9 P 0 ;1
L 12.4575 0.4075 12.4575 0.4075 9 P 0 ;1
L 12.4575 0.4575 12.4575 0.4575 9 P 0 ;1
L 12.4575 0.5075 12.4575 0.5075 9 P 0 ;1
L 12.4575 0.5575 12.4575 0.5575 9 P 0 ;1
L 12.4575 0.6075 12.4575 0.6075 9 P 0 ;1
L 12.4575 0.6575 12.4575 0.6575 9 P 0 ;1
L 12.4575 0.7075 12.4575 0.7075 9 P 0 ;1
L 12.4575 0.7575 12.4575 0.7575 9 P 0 ;1
L 12.4575 0.8075 12.4575 0.8075 9 P 0 ;1
L 12.4575 0.8575 12.4575 0.8575 9 P 0 ;1
L 12.4575 0.9075 12.4575 0.9075 9 P 0 ;1
L 12.4575 0.9575 12.4575 0.9575 9 P 0 ;1
L 12.4575 1.0075 12.4575 1.0075 9 P 0 ;1
L 12.4575 1.0575 12.4575 1.0575 9 P 0 ;1
L 12.4575 1.1075 12.4575 1.1075 9 P 0 ;1
L 12.4575 1.1575 12.4575 1.1575 9 P 0 ;1
L 12.4575 1.2075 12.4575 1.2075 9 P 0 ;1
L 12.4575 1.2575 12.4575 1.2575 9 P 0 ;1
L 12.4575 1.3075 12.4575 1.3075 9 P 0 ;1
L 12.4575 1.3575 12.4575 1.3575 9 P 0 ;1
L 12.4575 1.4075 12.4575 1.4075 9 P 0 ;1
L 12.4575 1.4575 12.4575 1.4575 9 P 0 ;1
L 12.4575 1.5075 12.4575 1.5075 9 P 0 ;1
L 12.4575 1.5575 12.4575 1.5575 9 P 0 ;1
L 12.4575 1.6075 12.4575 1.6075 9 P 0 ;1
L 12.4575 1.6575 12.4575 1.6575 9 P 0 ;1
L 12.4575 1.7075 12.4575 1.7075 9 P 0 ;1
L 12.4575 1.7575 12.4575 1.7575 9 P 0 ;1
L 12.4575 1.8075 12.4575 1.8075 9 P 0 ;1
L 12.4575 1.8575 12.4575 1.8575 9 P 0 ;1
L 12.4575 1.9075 12.4575 1.9075 9 P 0 ;1
L 12.4575 1.9575 12.4575 1.9575 9 P 0 ;1
L 12.4575 2.0075 12.4575 2.0075 9 P 0 ;1
L 12.4575 2.0575 12.4575 2.0575 9 P 0 ;1
L 12.4575 2.1075 12.4575 2.1075 9 P 0 ;1
L 12.4575 2.1575 12.4575 2.1575 9 P 0 ;1
L 12.4575 2.2075 12.4575 2.2075 9 P 0 ;1
L 12.4575 2.2575 12.4575 2.2575 9 P 0 ;1
L 12.4575 2.3075 12.4575 2.3075 9 P 0 ;1
L 12.4575 2.3575 12.4575 2.3575 9 P 0 ;1
L 12.4575 2.4075 12.4575 2.4075 9 P 0 ;1
L 12.4575 2.4575 12.4575 2.4575 9 P 0 ;1
L 12.4575 2.5075 12.4575 2.5075 9 P 0 ;1
L 12.4575 2.5575 12.4575 2.5575 9 P 0 ;1
L 12.4575 2.6075 12.4575 2.6075 9 P 0 ;1
L 12.4575 2.6575 12.4575 2.6575 9 P 0 ;1
L 12.4575 2.7075 12.4575 2.7075 9 P 0 ;1
L 12.4575 2.7575 12.4575 2.7575 9 P 0 ;1
L 12.4575 2.8075 12.4575 2.8075 9 P 0 ;1
L 12.4575 2.8575 12.4575 2.8575 9 P 0 ;1
L 12.4575 2.9075 12.4575 2.9075 9 P 0 ;1
L 12.4575 2.9575 12.4575 2.9575 9 P 0 ;1
L 12.4575 3.0075 12.4575 3.0075 9 P 0 ;1
L 12.4575 3.0575 12.4575 3.0575 9 P 0 ;1
L 12.4575 3.1075 12.4575 3.1075 9 P 0 ;1
L 12.4575 3.1575 12.4575 3.1575 9 P 0 ;1
L 12.4575 3.2075 12.4575 3.2075 9 P 0 ;1
L 12.4575 3.2575 12.4575 3.2575 9 P 0 ;1
L 12.4575 3.3075 12.4575 3.3075 9 P 0 ;1
L 12.4575 3.3575 12.4575 3.3575 9 P 0 ;1
L 12.4575 3.4075 12.4575 3.4075 9 P 0 ;1
L 12.4575 3.4575 12.4575 3.4575 9 P 0 ;1
L 12.4575 3.5075 12.4575 3.5075 9 P 0 ;1
L 12.4575 3.5575 12.4575 3.5575 9 P 0 ;1
L 12.4575 3.6075 12.4575 3.6075 9 P 0 ;1
L 12.4575 3.6575 12.4575 3.6575 9 P 0 ;1
L 12.4575 3.7075 12.4575 3.7075 9 P 0 ;1
L 12.4575 3.7575 12.4575 3.7575 9 P 0 ;1
L 12.4575 3.8075 12.4575 3.8075 9 P 0 ;1
L 12.4575 3.8575 12.4575 3.8575 9 P 0 ;1
L 12.4575 3.9075 12.4575 3.9075 9 P 0 ;1
L 12.4575 3.9575 12.4575 3.9575 9 P 0 ;1
L 12.4575 4.0075 12.4575 4.0075 9 P 0 ;1
L 12.4575 4.0575 12.4575 4.0575 9 P 0 ;1
L 12.4575 4.1075 12.4575 4.1075 9 P 0 ;1
L 12.4575 4.1575 12.4575 4.1575 9 P 0 ;1
L 12.4575 4.2075 12.4575 4.2075 9 P 0 ;1
L 12.4575 4.2575 12.4575 4.2575 9 P 0 ;1
L 12.4575 4.3075 12.4575 4.3075 9 P 0 ;1
L 12.4575 4.3575 12.4575 4.3575 9 P 0 ;1
L 12.4575 4.4075 12.4575 4.4075 9 P 0 ;1
L 12.4575 4.4575 12.4575 4.4575 9 P 0 ;1
L 12.4575 4.5075 12.4575 4.5075 9 P 0 ;1
L 12.4575 4.5575 12.4575 4.5575 9 P 0 ;1
L 12.4575 4.6075 12.4575 4.6075 9 P 0 ;1
L 12.4575 4.6575 12.4575 4.6575 9 P 0 ;1
L 12.4575 4.7075 12.4575 4.7075 9 P 0 ;1
L 12.4575 4.7575 12.4575 4.7575 9 P 0 ;1
L 12.4575 4.8075 12.4575 4.8075 9 P 0 ;1
L 12.4575 4.8575 12.4575 4.8575 9 P 0 ;1
L 12.4575 4.9075 12.4575 4.9075 9 P 0 ;1
L 12.4575 4.9575 12.4575 4.9575 9 P 0 ;1
L 12.4575 5.0075 12.4575 5.0075 9 P 0 ;1
L 12.4575 5.0575 12.4575 5.0575 9 P 0 ;1
L 12.4575 5.1075 12.4575 5.1075 9 P 0 ;1
L 12.5075 0.1575 12.5075 0.1575 9 P 0 ;1
L 12.5075 0.2075 12.5075 0.2075 9 P 0 ;1
L 12.5075 0.2575 12.5075 0.2575 9 P 0 ;1
L 12.5075 0.3075 12.5075 0.3075 9 P 0 ;1
L 12.5075 0.3575 12.5075 0.3575 9 P 0 ;1
L 12.5075 0.4075 12.5075 0.4075 9 P 0 ;1
L 12.5075 0.4575 12.5075 0.4575 9 P 0 ;1
L 12.5075 0.5075 12.5075 0.5075 9 P 0 ;1
L 12.5075 0.5575 12.5075 0.5575 9 P 0 ;1
L 12.5075 0.6075 12.5075 0.6075 9 P 0 ;1
L 12.5075 0.6575 12.5075 0.6575 9 P 0 ;1
L 12.5075 0.8075 12.5075 0.8075 9 P 0 ;1
L 12.5075 0.8575 12.5075 0.8575 9 P 0 ;1
L 12.5075 0.9075 12.5075 0.9075 9 P 0 ;1
L 12.5075 0.9575 12.5075 0.9575 9 P 0 ;1
L 12.5075 1.0075 12.5075 1.0075 9 P 0 ;1
L 12.5075 1.0575 12.5075 1.0575 9 P 0 ;1
L 12.5075 1.1075 12.5075 1.1075 9 P 0 ;1
L 12.5075 1.1575 12.5075 1.1575 9 P 0 ;1
L 12.5075 1.2075 12.5075 1.2075 9 P 0 ;1
L 12.5075 1.2575 12.5075 1.2575 9 P 0 ;1
L 12.5075 1.3075 12.5075 1.3075 9 P 0 ;1
L 12.5075 1.8075 12.5075 1.8075 9 P 0 ;1
L 12.5075 4.7575 12.5075 4.7575 9 P 0 ;1
L 12.5075 4.8075 12.5075 4.8075 9 P 0 ;1
L 12.5075 4.8575 12.5075 4.8575 9 P 0 ;1
L 12.5075 4.9075 12.5075 4.9075 9 P 0 ;1
L 12.5075 4.9575 12.5075 4.9575 9 P 0 ;1
L 12.5075 5.0075 12.5075 5.0075 9 P 0 ;1
L 12.5075 5.0575 12.5075 5.0575 9 P 0 ;1
L 12.5575 0.1575 12.5575 0.1575 9 P 0 ;1
L 12.5575 0.2075 12.5575 0.2075 9 P 0 ;1
L 12.5575 0.2575 12.5575 0.2575 9 P 0 ;1
L 12.5575 0.3075 12.5575 0.3075 9 P 0 ;1
L 12.5575 0.3575 12.5575 0.3575 9 P 0 ;1
L 12.5575 0.4075 12.5575 0.4075 9 P 0 ;1
L 12.5575 0.5575 12.5575 0.5575 9 P 0 ;1
L 12.5575 0.9075 12.5575 0.9075 9 P 0 ;1
L 12.5575 0.9575 12.5575 0.9575 9 P 0 ;1
L 12.5575 1.0075 12.5575 1.0075 9 P 0 ;1
L 12.5575 1.0575 12.5575 1.0575 9 P 0 ;1
L 12.5575 1.1075 12.5575 1.1075 9 P 0 ;1
L 12.5575 1.1575 12.5575 1.1575 9 P 0 ;1
L 12.5575 1.2075 12.5575 1.2075 9 P 0 ;1
L 12.5575 1.2575 12.5575 1.2575 9 P 0 ;1
L 12.5575 1.3075 12.5575 1.3075 9 P 0 ;1
L 12.5575 4.7575 12.5575 4.7575 9 P 0 ;1
L 12.5575 4.8075 12.5575 4.8075 9 P 0 ;1
L 12.5575 4.8575 12.5575 4.8575 9 P 0 ;1
L 12.5575 4.9075 12.5575 4.9075 9 P 0 ;1
L 12.5575 4.9575 12.5575 4.9575 9 P 0 ;1
L 12.6075 0.1575 12.6075 0.1575 9 P 0 ;1
L 12.6075 0.2075 12.6075 0.2075 9 P 0 ;1
L 12.6075 0.2575 12.6075 0.2575 9 P 0 ;1
L 12.6075 0.3075 12.6075 0.3075 9 P 0 ;1
L 12.6075 1.1075 12.6075 1.1075 9 P 0 ;1
L 12.6075 1.1575 12.6075 1.1575 9 P 0 ;1
L 12.6075 1.2075 12.6075 1.2075 9 P 0 ;1
L 12.6075 1.2575 12.6075 1.2575 9 P 0 ;1
L 12.6075 4.8075 12.6075 4.8075 9 P 0 ;1
L 12.6075 5.5575 12.6075 5.5575 9 P 0 ;1
L 12.6075 5.6075 12.6075 5.6075 9 P 0 ;1
L 12.6075 5.6575 12.6075 5.6575 9 P 0 ;1
L 12.6075 5.7075 12.6075 5.7075 9 P 0 ;1
L 12.6075 5.7575 12.6075 5.7575 9 P 0 ;1
L 12.6075 5.8075 12.6075 5.8075 9 P 0 ;1
L 12.6075 5.8575 12.6075 5.8575 9 P 0 ;1
L 12.6075 5.9075 12.6075 5.9075 9 P 0 ;1
L 12.6575 0.1575 12.6575 0.1575 9 P 0 ;1
L 12.6575 0.2075 12.6575 0.2075 9 P 0 ;1
L 12.6575 0.2575 12.6575 0.2575 9 P 0 ;1
L 12.6575 0.3075 12.6575 0.3075 9 P 0 ;1
L 12.6575 1.1075 12.6575 1.1075 9 P 0 ;1
L 12.6575 1.1575 12.6575 1.1575 9 P 0 ;1
L 12.6575 1.2075 12.6575 1.2075 9 P 0 ;1
L 12.6575 1.2575 12.6575 1.2575 9 P 0 ;1
L 12.6575 5.6075 12.6575 5.6075 9 P 0 ;1
L 12.6575 5.6575 12.6575 5.6575 9 P 0 ;1
L 12.6575 5.7075 12.6575 5.7075 9 P 0 ;1
L 12.6575 5.7575 12.6575 5.7575 9 P 0 ;1
L 12.6575 5.8075 12.6575 5.8075 9 P 0 ;1
L 12.6575 5.8575 12.6575 5.8575 9 P 0 ;1
L 12.6575 5.9075 12.6575 5.9075 9 P 0 ;1
L 12.7075 0.1575 12.7075 0.1575 9 P 0 ;1
L 12.7075 0.2075 12.7075 0.2075 9 P 0 ;1
L 12.7075 0.2575 12.7075 0.2575 9 P 0 ;1
L 12.7075 0.3075 12.7075 0.3075 9 P 0 ;1
L 12.7075 1.1075 12.7075 1.1075 9 P 0 ;1
L 12.7075 1.1575 12.7075 1.1575 9 P 0 ;1
L 12.7075 1.2075 12.7075 1.2075 9 P 0 ;1
L 12.7075 1.2575 12.7075 1.2575 9 P 0 ;1
L 12.7075 5.6075 12.7075 5.6075 9 P 0 ;1
L 12.7075 5.6575 12.7075 5.6575 9 P 0 ;1
L 12.7075 5.7075 12.7075 5.7075 9 P 0 ;1
L 12.7075 5.7575 12.7075 5.7575 9 P 0 ;1
L 12.7075 5.8075 12.7075 5.8075 9 P 0 ;1
L 12.7075 5.8575 12.7075 5.8575 9 P 0 ;1
L 12.7075 5.9075 12.7075 5.9075 9 P 0 ;1
L 12.7575 0.1575 12.7575 0.1575 9 P 0 ;1
L 12.7575 0.2075 12.7575 0.2075 9 P 0 ;1
L 12.7575 0.2575 12.7575 0.2575 9 P 0 ;1
L 12.7575 0.3075 12.7575 0.3075 9 P 0 ;1
L 12.7575 1.1075 12.7575 1.1075 9 P 0 ;1
L 12.7575 1.1575 12.7575 1.1575 9 P 0 ;1
L 12.7575 1.2075 12.7575 1.2075 9 P 0 ;1
L 12.7575 1.2575 12.7575 1.2575 9 P 0 ;1
L 12.7575 5.5575 12.7575 5.5575 9 P 0 ;1
L 12.7575 5.6075 12.7575 5.6075 9 P 0 ;1
L 12.7575 5.6575 12.7575 5.6575 9 P 0 ;1
L 12.7575 5.7075 12.7575 5.7075 9 P 0 ;1
L 12.7575 5.7575 12.7575 5.7575 9 P 0 ;1
L 12.7575 5.8075 12.7575 5.8075 9 P 0 ;1
L 12.7575 5.8575 12.7575 5.8575 9 P 0 ;1
L 12.7575 5.9075 12.7575 5.9075 9 P 0 ;1
L 12.8075 0.1575 12.8075 0.1575 9 P 0 ;1
L 12.8075 0.2075 12.8075 0.2075 9 P 0 ;1
L 12.8075 0.2575 12.8075 0.2575 9 P 0 ;1
L 12.8075 0.3075 12.8075 0.3075 9 P 0 ;1
L 12.8075 0.3575 12.8075 0.3575 9 P 0 ;1
L 12.8075 0.5575 12.8075 0.5575 9 P 0 ;1
L 12.8075 0.9075 12.8075 0.9075 9 P 0 ;1
L 12.8075 1.0075 12.8075 1.0075 9 P 0 ;1
L 12.8075 1.0575 12.8075 1.0575 9 P 0 ;1
L 12.8075 1.1075 12.8075 1.1075 9 P 0 ;1
L 12.8075 1.1575 12.8075 1.1575 9 P 0 ;1
L 12.8075 1.2075 12.8075 1.2075 9 P 0 ;1
L 12.8075 1.2575 12.8075 1.2575 9 P 0 ;1
L 12.8075 1.3075 12.8075 1.3075 9 P 0 ;1
L 12.8075 4.7575 12.8075 4.7575 9 P 0 ;1
L 12.8075 4.8075 12.8075 4.8075 9 P 0 ;1
L 12.8075 4.8575 12.8075 4.8575 9 P 0 ;1
L 12.8075 4.9575 12.8075 4.9575 9 P 0 ;1
L 12.8075 5.5075 12.8075 5.5075 9 P 0 ;1
L 12.8075 5.5575 12.8075 5.5575 9 P 0 ;1
L 12.8075 5.6075 12.8075 5.6075 9 P 0 ;1
L 12.8075 5.6575 12.8075 5.6575 9 P 0 ;1
L 12.8075 5.7075 12.8075 5.7075 9 P 0 ;1
L 12.8075 5.7575 12.8075 5.7575 9 P 0 ;1
L 12.8075 5.8075 12.8075 5.8075 9 P 0 ;1
L 12.8075 5.8575 12.8075 5.8575 9 P 0 ;1
L 12.8075 5.9075 12.8075 5.9075 9 P 0 ;1

### steps/drc/layers/l4/features
#
#Feature symbol names
#
$0 r2
$1 r5
$2 r6
$3 r10
$4 r15
$5 r20
$6 r28
$7 r30
$8 r32
$9 r33
$10 r40
$11 r50
$12 r57.09
$13 r78.74
$14 r86.61
$15 r90.55
$16 r100
$17 r131.89
$18 r137.8
$19 r161.42
$20 r168.31
$21 r173.23
$22 r181.1
$23 r204.72
$24 r224.41
$25 r440.94
$26 null
$27 oval236.22x177.17
$28 thr61.02x49.21x45x4x15.75
$29 thr96.46x76.77x45x4x19.69

#
#Feature attribute names
#
@0 .nomenclature
@1 .geometry

#
#Feature attribute text strings
#
&0 TPB30V20D10AT28BPM
&1 C1_11P0_7
&2 C1_11P0_7TP
&3 V17D8AT30SM11
&4 V20D10AT28SM14
&5 C2_5N
&6 S1_11P0_7TP
&7 S1_11P0_7
&8 V20D10AT28PG
&9 C1_17P0_76TPM
&10 C1_9P1_4
&11 S1_9P1_4
&12 SP-8C5_2P0_254
&13 SP-9C5_7P0_254
&14 C3_175N-A
&15 C10N
&16 C3_3N
&17 C4_5N-B
&18 C4N-B
&19 C3_5N
&20 O5X3_5N
&21 C3N
&22 C1_3N
&23 C2_35N
&24 C1N

#
#Layer features
#
P 7.785 4.45 6 P 0 0;1=0
P 7.835 4.45 6 P 0 0;1=0
P 1.8 4.485 6 P 0 0;1=0
P 1.86 4.485 6 P 0 0;1=0
P 0.27165 1.72835 12 P 0 0;1=1
P 0.17323002 2.12205 12 P 0 0;1=1
P 12.73621004 1.76771998 12 P 0 0;1=1
P 12.81495 2.59448996 12 P 0 0;1=1
P 12.63778996 2.16141998 12 P 0 0;1=1
P 0.725 -0.25 12 P 0 0;1=2
P 0.875 -0.25 12 P 0 0;1=2
P 1.065 6.26 12 P 0 0;1=2
P 1.065 6.36 12 P 0 0;1=2
P 1.29 6.26 12 P 0 0;1=2
P 1.29 6.36 12 P 0 0;1=2
P 1.515 6.26 12 P 0 0;1=2
P 1.515 6.36 12 P 0 0;1=2
P 0.84 6.26 12 P 0 0;1=2
P 0.84 6.36 12 P 0 0;1=2
P 1.74 6.26 12 P 0 0;1=2
P 1.74 6.36 12 P 0 0;1=2
P 2.09606004 3.56615 7 P 0 0;1=3
P 8.1 3.56615 7 P 0 0;1=3
P 12.55905 3.38188996 12 P 0 0;1=1
P 12.81495 4.64173996 12 P 0 0;1=1
P 12.81495 1.88583002 12 P 0 0;1=1
P 0.35038996 4.60236998 12 P 0 0;1=1
P 0.35038996 2.55511998 12 P 0 0;1=1
P 0.35038996 1.84646004 12 P 0 0;1=1
P 0.09448996 3.34251998 12 P 0 0;1=1
P 6.385 5.03 6 P 0 0;1=4
P 12.68701998 0.97243996 18 P 0 0;1=5
P 0.22245 0.93306998 18 P 0 0;1=5
P 12.68701004 4.91338002 18 P 0 0;1=5
P 3.94 4.545 6 P 0 0;1=0
P 4.91 5.375 6 P 0 0;1=4
P 1.08 5.85 6 P 0 0;1=0
P 3.6817 5.74 6 P 0 0;1=4
P 10.07 2.928 6 P 0 0;1=4
P 4.105 4.985 6 P 0 0;1=0
P 4.125 2.725 6 P 0 0;1=4
P 4.02 4.355 6 P 0 0;1=0
P 1.16 5.85 6 P 0 0;1=0
P 3.815 5.815 6 P 0 0;1=4
P 1.19 6.36 28 P 0 3;1=6
P 1.19 6.26 28 P 0 3;1=6
P 1.415 6.36 28 P 0 3;1=6
P 1.415 6.26 28 P 0 3;1=6
P 1.64 6.36 28 P 0 3;1=6
P 1.64 6.26 28 P 0 3;1=6
P 0.965 6.26 28 P 0 3;1=6
P 0.965 6.36 28 P 0 3;1=6
P 0.74 6.26 28 P 0 3;1=6
P 0.74 6.36 28 P 0 3;1=6
P 12.63778996 1.37401998 12 P 0 0;1=7
P 0.17323002 1.33465 12 P 0 0;1=7
P 6.501 5.017 6 P 0 0;1=0
P 7.425 3.43 6 P 0 0;1=0
P 7.445 1.705 6 P 0 0;1=4
P 11.03661004 3.81615 7 P 0 0;1=3
P 11.135 2.845 6 P 0 0;1=4
P 11.03661004 2.16615 7 P 0 0;1=3
P 3.8899 4.765 6 P 0 0;1=0
P 4.93268002 2.41615 7 P 0 0;1=3
P 4.93268002 2.46615 7 P 0 0;1=3
P 7.2926 5.04351004 6 P 0 0;1=0
P 7.2426 5.04351004 6 P 0 0;1=0
P 3.45646004 5.3 6 P 0 0;1=0
P 1.28906004 5.04351004 6 P 0 0;1=0
P 1.23906004 5.04351004 6 P 0 0;1=0
P 9.46 5.3 6 P 0 0;1=0
P 4.68268002 2.36615 7 P 0 0;1=3
P 0.27165 4.01181004 12 P 0 0;1=1
P 4.58268002 2.36615 7 P 0 0;1=3
P 0.27165 4.16928996 12 P 0 0;1=1
P 4.63268002 2.41615 7 P 0 0;1=3
P 0.27165 4.32676998 12 P 0 0;1=1
P 4.73268002 2.26615 7 P 0 0;1=3
P 0.27165 3.38188996 12 P 0 0;1=1
P 4.73268002 2.41615 7 P 0 0;1=3
P 0.27165 4.48425 12 P 0 0;1=1
P 4.68268002 2.21615 7 P 0 0;1=3
P 0.27165 3.53936998 12 P 0 0;1=1
P 4.63268002 2.26615 7 P 0 0;1=3
P 0.27165 3.85433002 12 P 0 0;1=1
P 4.58268002 2.06615 7 P 0 0;1=3
P 0.35038996 3.02756004 12 P 0 0;1=1
P 4.58268002 2.11615 7 P 0 0;1=3
P 0.27165 2.98818996 12 P 0 0;1=1
P 4.63268002 1.86615 7 P 0 0;1=3
P 0.35038996 2.3189 12 P 0 0;1=1
P 4.58268002 1.96615 7 P 0 0;1=3
P 0.27165 2.43701004 12 P 0 0;1=1
P 4.68268002 2.06615 7 P 0 0;1=3
P 0.35038996 3.18503996 12 P 0 0;1=1
P 4.58268002 1.91615 7 P 0 0;1=3
P 0.35038996 2.47638002 12 P 0 0;1=1
P 0.27165 2.27953002 12 P 0 0;1=1
P 4.63268002 1.91615 7 P 0 0;1=3
P 5.42048002 1.7396 7 P 0 0;1=3
P 0.09448996 2.55511998 12 P 0 0;1=1
P 4.68268002 2.11615 7 P 0 0;1=3
P 0.27165 3.14566998 12 P 0 0;1=1
P 5.42048002 1.7796 7 P 0 0;1=3
P 0.17323002 2.51575 12 P 0 0;1=1
P 4.68268002 1.91615 7 P 0 0;1=3
P 0.35038996 2.16141998 12 P 0 0;1=1
P 4.68268002 1.96615 7 P 0 0;1=3
P 0.27165 2.12205 12 P 0 0;1=1
P 5.57531004 2.0878 7 P 0 0;1=3
P 0.09448996 3.1063 12 P 0 0;1=1
P 5.57531004 2.1278 7 P 0 0;1=3
P 0.17323002 3.06693002 12 P 0 0;1=1
P 5.57531004 2.2232 7 P 0 0;1=3
P 0.17323002 3.46063002 12 P 0 0;1=1
P 5.57531004 2.2632 7 P 0 0;1=3
P 0.09448996 3.42126004 12 P 0 0;1=1
P 5.42048002 2.4662 7 P 0 0;1=3
P 0.09448996 4.05118002 12 P 0 0;1=1
P 5.57531004 2.3986 7 P 0 0;1=3
P 0.09448996 3.8937 12 P 0 0;1=1
P 5.57531004 2.673 7 P 0 0;1=3
P 0.09448996 4.36613996 12 P 0 0;1=1
P 5.57531004 1.9869 7 P 0 0;1=3
P 0.17323002 2.75196998 12 P 0 0;1=1
P 5.57531004 2.4978 7 P 0 0;1=3
P 0.17323002 4.24803002 12 P 0 0;1=1
P 5.57531004 1.6718 7 P 0 0;1=3
P 0.17323002 2.20078996 12 P 0 0;1=1
P 5.57531004 2.633 7 P 0 0;1=3
P 0.17323002 4.40551004 12 P 0 0;1=1
P 5.57531004 1.7118 7 P 0 0;1=3
P 0.09448996 2.24016004 12 P 0 0;1=1
P 5.57531004 2.5378 7 P 0 0;1=3
P 0.09448996 4.20866004 12 P 0 0;1=1
P 5.42048002 1.6433 7 P 0 0;1=3
P 0.09448996 2.39763996 12 P 0 0;1=1
P 5.42048002 2.6054 7 P 0 0;1=3
P 0.09448996 4.52361998 12 P 0 0;1=1
P 5.42048002 1.87835 7 P 0 0;1=3
P 0.09448996 2.94881998 12 P 0 0;1=1
P 5.57531004 2.3586 7 P 0 0;1=3
P 0.17323002 3.93306998 12 P 0 0;1=1
P 5.42048002 1.6033 7 P 0 0;1=3
P 0.17323002 2.35826998 12 P 0 0;1=1
P 5.42048002 2.4262 7 P 0 0;1=3
P 0.17323002 4.09055 12 P 0 0;1=1
P 5.42048002 1.91835 7 P 0 0;1=3
P 0.17323002 2.90945 12 P 0 0;1=1
P 5.42048002 2.0547 7 P 0 0;1=3
P 0.17323002 3.22441004 12 P 0 0;1=1
P 5.57531004 1.9469 7 P 0 0;1=3
P 0.09448996 2.79133996 12 P 0 0;1=1
P 5.42048002 2.0147 7 P 0 0;1=3
P 0.09448996 3.26378002 12 P 0 0;1=1
P 5.57531004 1.8508 7 P 0 0;1=3
P 0.09448996 2.00393996 12 P 0 0;1=1
P 5.57531004 1.8108 7 P 0 0;1=3
P 0.17323002 2.04331004 12 P 0 0;1=1
P 0.35038996 3.97243996 12 P 0 0;1=1
P 4.68268002 2.41615 7 P 0 0;1=3
P 4.73268002 2.46615 7 P 0 0;1=3
P 0.35038996 4.44488002 12 P 0 0;1=1
P 4.63268002 2.46615 7 P 0 0;1=3
P 0.35038996 4.2874 12 P 0 0;1=1
P 0.35038996 4.12991998 12 P 0 0;1=1
P 4.58268002 2.41615 7 P 0 0;1=3
P 4.68268002 2.26615 7 P 0 0;1=3
P 0.35038996 3.5 12 P 0 0;1=1
P 5.42048002 2.1554 7 P 0 0;1=3
P 0.17323002 3.77558996 12 P 0 0;1=1
P 4.73268002 2.31615 7 P 0 0;1=3
P 0.35038996 3.34251998 12 P 0 0;1=1
P 4.63268002 2.31615 7 P 0 0;1=3
P 0.35038996 3.81496004 12 P 0 0;1=1
P 4.58268002 2.26615 7 P 0 0;1=3
P 0.35038996 3.65748002 12 P 0 0;1=1
P 5.42048002 2.5654 7 P 0 0;1=3
P 0.17323002 4.563 12 P 0 0;1=1
P 5.42048002 2.1954 7 P 0 0;1=3
P 0.09448996 3.73621998 12 P 0 0;1=1
P 0.09448996 3.57873996 12 P 0 0;1=1
P 5.42048002 2.3308 7 P 0 0;1=3
P 0.17323002 3.61811004 12 P 0 0;1=1
P 5.42048002 2.2908 7 P 0 0;1=3
P 0.35038996 1.9252 12 P 0 0;1=1
P 4.73268002 1.91615 7 P 0 0;1=3
P 4.73268002 1.86615 7 P 0 0;1=3
P 0.27165 1.96456998 12 P 0 0;1=1
P 4.58268002 2.21615 7 P 0 0;1=3
P 0.27165 3.69685 12 P 0 0;1=1
P 4.73268002 2.06615 7 P 0 0;1=3
P 0.27165 2.67323002 12 P 0 0;1=1
P 4.73268002 2.01615 7 P 0 0;1=3
P 0.35038996 2.7126 12 P 0 0;1=1
P 4.63268002 2.01615 7 P 0 0;1=3
P 0.35038996 2.87008002 12 P 0 0;1=1
P 4.63268002 2.06615 7 P 0 0;1=3
P 0.27165 2.83071004 12 P 0 0;1=1
P 6.785 4.725 6 P 0 0;1=4
P 6.785 4.685 6 P 0 0;1=4
P 6.74018996 4.765 6 P 0 0;1=4
P 6.74 4.805 6 P 0 0;1=0
P 6.785 4.845 6 P 0 0;1=4
P 6.785 4.805 6 P 0 0;1=4
P 6.785 4.765 6 P 0 0;1=4
P 6.74 4.845 6 P 0 0;1=4
P 6.65 5.055 6 P 0 0;1=0
P 6.49205 5.09705 6 P 0 0;1=0
P 6.495 4.9328 6 P 0 0;1=0
P 6.55118996 5.04705 6 P 0 0;1=0
P 6.78 4.94705 6 P 0 0;1=0
P 6.755 4.89705 6 P 0 0;1=0
P 6.74 4.987 6 P 0 0;1=0
P 12.73621004 2.08268002 12 P 0 0;1=1
P 12.73621004 2.63386004 12 P 0 0;1=1
P 12.81495 3.30315 12 P 0 0;1=1
P 12.73621004 4.60236998 12 P 0 0;1=1
P 12.55905 1.96456998 12 P 0 0;1=1
P 12.63778996 1.9252 12 P 0 0;1=1
P 0.09448996 1.9252 12 P 0 0;1=1
P 0.17323002 1.88583002 12 P 0 0;1=1
P 0.27165 2.04331004 12 P 0 0;1=1
P 0.27165 4.563 12 P 0 0;1=1
P 0.35038996 3.26378002 12 P 0 0;1=1
P 0.27165 2.59448996 12 P 0 0;1=1
P 0.17323002 1.72835 12 P 0 0;1=1
P 5.03268002 1.91615 7 P 0 0;1=3
P 1.025 -0.25 12 P 0 0;1=2
P 1.175 -0.25 12 P 0 0;1=2
P 1.325 -0.25 12 P 0 0;1=2
P 5.03268002 2.06615 7 P 0 0;1=3
P 12.63778996 4.12991998 12 P 0 0;1=1
P 11.53316004 2.372 7 P 0 0;1=3
P 5.08268002 2.26615 7 P 0 0;1=3
P 11.53316004 1.892 7 P 0 0;1=3
P 12.55905 3.30315 12 P 0 0;1=1
P 12.81495 2.51575 12 P 0 0;1=1
P 10.58661004 1.91615 7 P 0 0;1=3
P 10.26 1.66445 7 P 0 0;1=3
P 11.03998996 4.8431 6 P 0 0;1=4
P 11.08498996 4.8431 6 P 0 0;1=4
P 11.13498996 4.8431 6 P 0 0;1=4
P 11.17998996 4.8431 6 P 0 0;1=4
P 11.17998996 4.8031 6 P 0 0;1=4
P 11.17998996 4.7581 6 P 0 0;1=4
P 11.17998996 4.7131 6 P 0 0;1=4
P 11.17998996 4.6731 6 P 0 0;1=4
P 11.03998996 4.6731 6 P 0 0;1=4
P 11.08498996 4.6731 6 P 0 0;1=4
P 11.13498996 4.6731 6 P 0 0;1=4
P 11.03998996 4.7131 6 P 0 0;1=4
P 11.03998996 4.8031 6 P 0 0;1=4
P 11.03998996 4.7581 6 P 0 0;1=4
P 10.81998996 4.6631 6 P 0 0;1=4
P 10.85998996 4.6631 6 P 0 0;1=4
P 10.65998996 4.6631 6 P 0 0;1=4
P 10.69998996 4.6631 6 P 0 0;1=4
P 10.81998996 4.7031 6 P 0 0;1=4
P 10.81998996 4.8381 6 P 0 0;1=4
P 10.81998996 4.7931 6 P 0 0;1=4
P 10.81998996 4.7481 6 P 0 0;1=4
P 10.85998996 4.7031 6 P 0 0;1=4
P 10.85998996 4.8381 6 P 0 0;1=4
P 10.85998996 4.7931 6 P 0 0;1=4
P 10.85998996 4.7481 6 P 0 0;1=4
P 10.65998996 4.7031 6 P 0 0;1=4
P 10.65998996 4.8381 6 P 0 0;1=4
P 10.65998996 4.7931 6 P 0 0;1=4
P 10.65998996 4.7481 6 P 0 0;1=4
P 10.69998996 4.7031 6 P 0 0;1=4
P 10.69998996 4.8381 6 P 0 0;1=4
P 10.69998996 4.7931 6 P 0 0;1=4
P 10.69998996 4.7481 6 P 0 0;1=4
P 10.77998996 4.6431 6 P 0 0;1=4
P 10.73498996 4.6431 6 P 0 0;1=4
P 10.73998996 4.8381 6 P 0 0;1=4
P 10.77998996 4.8381 6 P 0 0;1=4
P 10.30998996 4.6631 6 P 0 0;1=4
P 10.26998996 4.6631 6 P 0 0;1=4
P 10.34498996 4.6431 6 P 0 0;1=4
P 10.38998996 4.6431 6 P 0 0;1=4
P 10.42998996 4.6631 6 P 0 0;1=4
P 10.46998996 4.6631 6 P 0 0;1=4
P 10.30998996 4.7481 6 P 0 0;1=4
P 10.30998996 4.7931 6 P 0 0;1=4
P 10.30998996 4.7031 6 P 0 0;1=4
P 10.26998996 4.7481 6 P 0 0;1=4
P 10.26998996 4.7931 6 P 0 0;1=4
P 10.26998996 4.7031 6 P 0 0;1=4
P 10.26998996 4.8381 6 P 0 0;1=4
P 10.30998996 4.8381 6 P 0 0;1=4
P 10.38998996 4.8381 6 P 0 0;1=4
P 10.34998996 4.8381 6 P 0 0;1=4
P 10.46998996 4.8381 6 P 0 0;1=4
P 10.42998996 4.8381 6 P 0 0;1=4
P 10.42998996 4.7031 6 P 0 0;1=4
P 10.42998996 4.7931 6 P 0 0;1=4
P 10.42998996 4.7481 6 P 0 0;1=4
P 10.46998996 4.7031 6 P 0 0;1=4
P 10.46998996 4.7931 6 P 0 0;1=4
P 10.46998996 4.7481 6 P 0 0;1=4
P 10.58661004 3.16615 7 P 0 0;1=3
P 10.63661004 3.01615 7 P 0 0;1=3
P 10.58661004 3.11615 7 P 0 0;1=3
P 10.58661004 3.01615 7 P 0 0;1=3
P 10.63661004 3.11615 7 P 0 0;1=3
P 10.63661004 2.96615 7 P 0 0;1=3
P 10.58661004 2.96615 7 P 0 0;1=3
P 10.58661004 3.41615 7 P 0 0;1=3
P 10.63661004 3.16615 7 P 0 0;1=3
P 10.63661004 3.26615 7 P 0 0;1=3
P 10.58661004 3.31615 7 P 0 0;1=3
P 10.58661004 3.26615 7 P 0 0;1=3
P 10.63661004 3.31615 7 P 0 0;1=3
P 10.63661004 3.56615 7 P 0 0;1=3
P 10.63661004 3.61615 7 P 0 0;1=3
P 10.58661004 3.56615 7 P 0 0;1=3
P 10.58661004 3.61615 7 P 0 0;1=3
P 10.63661004 3.46615 7 P 0 0;1=3
P 10.63661004 3.41615 7 P 0 0;1=3
P 10.58661004 3.46615 7 P 0 0;1=3
P 10.63661004 3.86615 7 P 0 0;1=3
P 10.63661004 3.76615 7 P 0 0;1=3
P 10.58661004 3.86615 7 P 0 0;1=3
P 10.58661004 3.76615 7 P 0 0;1=3
P 10.63661004 3.71615 7 P 0 0;1=3
P 10.58661004 3.71615 7 P 0 0;1=3
P 10.88661004 2.96615 7 P 0 0;1=3
P 10.83661004 2.96615 7 P 0 0;1=3
P 10.88661004 3.01615 7 P 0 0;1=3
P 10.83661004 3.01615 7 P 0 0;1=3
P 10.88661004 3.11615 7 P 0 0;1=3
P 10.83661004 3.11615 7 P 0 0;1=3
P 10.83661004 3.16615 7 P 0 0;1=3
P 10.78661004 3.16615 7 P 0 0;1=3
P 10.68661004 3.16615 7 P 0 0;1=3
P 10.73661004 3.16615 7 P 0 0;1=3
P 10.78661004 3.01615 7 P 0 0;1=3
P 10.78661004 3.11615 7 P 0 0;1=3
P 10.73661004 3.01615 7 P 0 0;1=3
P 10.73661004 3.11615 7 P 0 0;1=3
P 10.68661004 3.01615 7 P 0 0;1=3
P 10.68661004 3.11615 7 P 0 0;1=3
P 10.78661004 2.96615 7 P 0 0;1=3
P 10.73661004 2.96615 7 P 0 0;1=3
P 10.68661004 2.96615 7 P 0 0;1=3
P 10.88661004 3.16615 7 P 0 0;1=3
P 10.88661004 3.26615 7 P 0 0;1=3
P 10.83661004 3.26615 7 P 0 0;1=3
P 10.83661004 3.31615 7 P 0 0;1=3
P 10.88661004 3.31615 7 P 0 0;1=3
P 10.83661004 3.41615 7 P 0 0;1=3
P 10.78661004 3.41615 7 P 0 0;1=3
P 10.68661004 3.41615 7 P 0 0;1=3
P 10.73661004 3.41615 7 P 0 0;1=3
P 10.78661004 3.31615 7 P 0 0;1=3
P 10.78661004 3.26615 7 P 0 0;1=3
P 10.68661004 3.31615 7 P 0 0;1=3
P 10.68661004 3.26615 7 P 0 0;1=3
P 10.73661004 3.26615 7 P 0 0;1=3
P 10.73661004 3.31615 7 P 0 0;1=3
P 10.88661004 3.41615 7 P 0 0;1=3
P 10.83661004 3.46615 7 P 0 0;1=3
P 10.88661004 3.46615 7 P 0 0;1=3
P 10.83661004 3.56615 7 P 0 0;1=3
P 10.88661004 3.56615 7 P 0 0;1=3
P 10.83661004 3.61615 7 P 0 0;1=3
P 10.88661004 3.61615 7 P 0 0;1=3
P 10.78661004 3.56615 7 P 0 0;1=3
P 10.78661004 3.61615 7 P 0 0;1=3
P 10.68661004 3.61615 7 P 0 0;1=3
P 10.68661004 3.56615 7 P 0 0;1=3
P 10.73661004 3.61615 7 P 0 0;1=3
P 10.73661004 3.56615 7 P 0 0;1=3
P 10.78661004 3.46615 7 P 0 0;1=3
P 10.73661004 3.46615 7 P 0 0;1=3
P 10.68661004 3.46615 7 P 0 0;1=3
P 10.83661004 3.71615 7 P 0 0;1=3
P 10.88661004 3.71615 7 P 0 0;1=3
P 10.83661004 3.76615 7 P 0 0;1=3
P 10.88661004 3.76615 7 P 0 0;1=3
P 10.83661004 3.86615 7 P 0 0;1=3
P 10.88661004 3.86615 7 P 0 0;1=3
P 10.78661004 3.86615 7 P 0 0;1=3
P 10.78661004 3.76615 7 P 0 0;1=3
P 10.68661004 3.86615 7 P 0 0;1=3
P 10.68661004 3.76615 7 P 0 0;1=3
P 10.73661004 3.86615 7 P 0 0;1=3
P 10.73661004 3.76615 7 P 0 0;1=3
P 10.78661004 3.71615 7 P 0 0;1=3
P 10.68661004 3.71615 7 P 0 0;1=3
P 10.73661004 3.71615 7 P 0 0;1=3
P 11.03661004 2.96615 7 P 0 0;1=3
P 10.93661004 2.96615 7 P 0 0;1=3
P 10.98661004 2.96615 7 P 0 0;1=3
P 11.03661004 3.01615 7 P 0 0;1=3
P 10.93661004 3.01615 7 P 0 0;1=3
P 10.98661004 3.01615 7 P 0 0;1=3
P 11.03661004 3.11615 7 P 0 0;1=3
P 10.93661004 3.11615 7 P 0 0;1=3
P 10.98661004 3.11615 7 P 0 0;1=3
P 11.03661004 3.16615 7 P 0 0;1=3
P 10.93661004 3.16615 7 P 0 0;1=3
P 10.98661004 3.16615 7 P 0 0;1=3
P 11.03661004 3.26615 7 P 0 0;1=3
P 10.93661004 3.26615 7 P 0 0;1=3
P 10.98661004 3.26615 7 P 0 0;1=3
P 10.98661004 3.31615 7 P 0 0;1=3
P 10.93661004 3.31615 7 P 0 0;1=3
P 11.03661004 3.31615 7 P 0 0;1=3
P 10.98661004 3.41615 7 P 0 0;1=3
P 10.93661004 3.41615 7 P 0 0;1=3
P 11.03661004 3.41615 7 P 0 0;1=3
P 10.98661004 3.46615 7 P 0 0;1=3
P 10.93661004 3.46615 7 P 0 0;1=3
P 11.03661004 3.46615 7 P 0 0;1=3
P 10.98661004 3.56615 7 P 0 0;1=3
P 10.93661004 3.56615 7 P 0 0;1=3
P 11.03661004 3.56615 7 P 0 0;1=3
P 10.98661004 3.61615 7 P 0 0;1=3
P 10.93661004 3.61615 7 P 0 0;1=3
P 11.03661004 3.61615 7 P 0 0;1=3
P 10.98661004 3.71615 7 P 0 0;1=3
P 10.93661004 3.71615 7 P 0 0;1=3
P 11.03661004 3.71615 7 P 0 0;1=3
P 10.98661004 3.76615 7 P 0 0;1=3
P 10.93661004 3.76615 7 P 0 0;1=3
P 11.03661004 3.76615 7 P 0 0;1=3
P 10.98661004 3.86615 7 P 0 0;1=3
P 10.93661004 3.86615 7 P 0 0;1=3
P 11.03661004 3.86615 7 P 0 0;1=3
P 5.08268002 2.06615 7 P 0 0;1=3
P 10.58661004 2.36615 7 P 0 0;1=3
P 9.975 2.4709 7 P 0 0;1=3
P 12.73621004 4.20866004 12 P 0 0;1=1
P 11.08661004 2.36615 7 P 0 0;1=3
P 5.08268002 2.11615 7 P 0 0;1=3
P 11.08661004 2.41615 7 P 0 0;1=3
P 12.73621004 2.47638002 12 P 0 0;1=1
P 10.58661004 1.96615 7 P 0 0;1=3
P 10.26 1.70445 7 P 0 0;1=3
P 10.98661004 2.41615 7 P 0 0;1=3
P 8.5 3.76615 7 P 0 0;1=3
P 9.35271004 5.1035 7 P 0 0;1=3
P 4.98268002 2.06615 7 P 0 0;1=3
P 8.5 3.81615 7 P 0 0;1=3
P 9.31271004 5.1035 7 P 0 0;1=3
P 12.55905 2.59448996 12 P 0 0;1=1
P 11.53316004 1.572 7 P 0 0;1=3
P 4.98268002 2.11615 7 P 0 0;1=3
P 10.98661004 2.36615 7 P 0 0;1=3
P 8.5 3.61615 7 P 0 0;1=3
P 9.56531004 5.14 7 P 0 0;1=3
P 4.93268002 2.01615 7 P 0 0;1=3
P 11.53316004 1.412 7 P 0 0;1=3
P 12.63778996 2.39763996 12 P 0 0;1=1
P 8.5 3.66615 7 P 0 0;1=3
P 9.52531004 5.14 7 P 0 0;1=3
P 12.73621004 2.87008002 12 P 0 0;1=1
P 10.63661004 2.06615 7 P 0 0;1=3
P 10.225 1.96645 7 P 0 0;1=3
P 11.53316004 1.452 7 P 0 0;1=3
P 12.55905 2.43701004 12 P 0 0;1=1
P 8.35 3.66615 7 P 0 0;1=3
P 9.56531004 4.71973002 7 P 0 0;1=3
P 4.93268002 2.06615 7 P 0 0;1=3
P 8.35 3.71615 7 P 0 0;1=3
P 9.52531004 4.71973002 7 P 0 0;1=3
P 11.83316004 2.212 7 P 0 0;1=3
P 12.63778996 3.65748002 12 P 0 0;1=1
P 12.73621004 3.02756004 12 P 0 0;1=1
P 10.58661004 2.11615 7 P 0 0;1=3
P 10.09 2.05655 7 P 0 0;1=3
P 11.53316004 1.932 7 P 0 0;1=3
P 12.63778996 3.26378002 12 P 0 0;1=1
P 8.74578996 5.14 7 P 0 0;1=3
P 8.05 3.61615 7 P 0 0;1=3
P 12.81495 4.01181004 12 P 0 0;1=1
P 10.09 2.57845 7 P 0 0;1=3
P 10.68661004 2.41615 7 P 0 0;1=3
P 11.73316004 1.492 7 P 0 0;1=3
P 12.63778996 2.24016004 12 P 0 0;1=1
P 8.78578996 5.14 7 P 0 0;1=3
P 8.05 3.66615 7 P 0 0;1=3
P 12.73621004 2.7126 12 P 0 0;1=1
P 10.73661004 2.06615 7 P 0 0;1=3
P 10.26025 1.86845 7 P 0 0;1=3
P 11.03661004 2.46615 7 P 0 0;1=3
P 8.15 3.61615 7 P 0 0;1=3
P 8.88441004 5.17001998 7 P 0 0;1=3
P 12.55905 4.09055 12 P 0 0;1=1
P 11.53316004 2.412 7 P 0 0;1=3
P 11.03661004 2.51615 7 P 0 0;1=3
P 8.15 3.66615 7 P 0 0;1=3
P 8.92441004 5.17001998 7 P 0 0;1=3
P 1.057 5.027 6 P 0 0;1=0
P 12.73621004 3.18503996 12 P 0 0;1=1
P 10.68661004 2.11615 7 P 0 0;1=3
P 10.09 2.17095 7 P 0 0;1=3
P 11.78316004 1.692 7 P 0 0;1=3
P 12.55905 2.04331004 12 P 0 0;1=1
P 12.81495 2.90945 12 P 0 0;1=1
P 10.63661004 2.01615 7 P 0 0;1=3
P 10.225 1.92645 7 P 0 0;1=3
P 11.78316004 1.652 7 P 0 0;1=3
P 12.63778996 2.08268002 12 P 0 0;1=1
P 1.122 5.417 6 P 0 0;1=4
P 5.855 0.925 6 P 0 0;1=4
P 3.88 4.545 6 P 0 0;1=0
P 0.96555 5.78055 6 P 0 0;1=0
P 4.07 4.625 6 P 0 0;1=4
P 10.58661004 2.71615 7 P 0 0;1=3
P 9.91 4.433 6 P 0 0;1=0
P 9.995 2.936 6 P 0 0;1=4
P 11.83316004 2.252 7 P 0 0;1=3
P 12.55905 3.61811004 12 P 0 0;1=1
P 12.81495 3.06693002 12 P 0 0;1=1
P 10.58661004 2.06615 7 P 0 0;1=3
P 10.09 2.01655 7 P 0 0;1=3
P 8.1 3.81615 7 P 0 0;1=3
P 9.10011004 5.0535 7 P 0 0;1=3
P 8.1 3.86615 7 P 0 0;1=3
P 9.14011004 5.0535 7 P 0 0;1=3
P 3.9599 5.395 6 P 0 0;1=0
P 0.88681004 5.78181004 6 P 0 0;1=4
P 12.73621004 2.3189 12 P 0 0;1=1
P 10.63661004 1.91615 7 P 0 0;1=3
P 10.38371998 1.49328002 7 P 0 0;1=3
P 8.35 3.81615 7 P 0 0;1=3
P 9.28185 5.22001998 7 P 0 0;1=3
P 0.72933002 5.463 6 P 0 0;1=0
P 11.53316004 2.572 7 P 0 0;1=3
P 12.55905 4.56298996 12 P 0 0;1=1
P 8.35 3.86615 7 P 0 0;1=3
P 9.24185 5.22001998 7 P 0 0;1=3
P 4.125 2.682 6 P 0 0;1=4
P 3.94 4.42 6 P 0 0;1=0
P 5.03 5.4 6 P 0 0;1=4
P 4.58268002 2.71615 7 P 0 0;1=3
P 8.45 3.81615 7 P 0 0;1=3
P 9.21098002 4.78291998 7 P 0 0;1=3
P 8.45 3.86615 7 P 0 0;1=3
P 9.17098002 4.78291998 7 P 0 0;1=3
P 3.75998996 0.24001004 6 P 0 0;1=0
P 9.55795 0.26133996 6 P 0 0;1=0
P 3.71203002 0.77535 6 P 0 0;1=4
P 3.70998996 0.7 6 P 0 0;1=4
P 9.50795 0.72133002 6 P 0 0;1=4
P 9.46795 0.82631998 6 P 0 0;1=4
P 4.02893002 2.59336998 6 P 0 0;1=4
P 11.395 2.725 6 P 0 0;1=0
P 11.395 2.8 6 P 0 0;1=4
P 11.58613002 2.905 6 P 0 0;1=4
P 11.58613002 2.785 6 P 0 0;1=4
P 1.33906004 4.60351004 6 P 0 0;1=0
P 3.67 4.45 6 P 0 0;1=4
P 3.72 4.545 6 P 0 0;1=4
P 5.37968996 2.8 6 P 0 0;1=4
P 5.387 2.725 6 P 0 0;1=0
P 5.5822 2.785 6 P 0 0;1=4
P 5.5822 2.905 6 P 0 0;1=4
P 7.2426 4.69351004 6 P 0 0;1=4
P 7.2926 4.60351004 6 P 0 0;1=4
P 9.98 4.51 6 P 0 0;1=4
P 10.07286004 2.82336998 6 P 0 0;1=4
P 10.03 4.61 6 P 0 0;1=4
P 1.23906004 4.69351004 6 P 0 0;1=4
P 3.89 4.655 6 P 0 0;1=4
P 3.9899 4.765 6 P 0 0;1=4
P 4.1049 4.86 6 P 0 0;1=4
P 4.0599 5.395 6 P 0 0;1=4
P 3.91 5.51 6 P 0 0;1=4
P 5.125 5.4 6 P 0 0;1=4
P 1.37925 5.78 6 P 0 0;1=4
P 1.45798996 5.78 6 P 0 0;1=4
P 1.42 5.78 6 P 0 0;1=4
P 1.335 5.78 6 P 0 0;1=4
P 12.63778996 2.55511998 12 P 0 0;1=1
P 11.53316004 1.612 7 P 0 0;1=3
P 8.4 3.76615 7 P 0 0;1=3
P 9.28185 4.642 7 P 0 0;1=3
P 12.73621004 4.36613996 12 P 0 0;1=1
P 10.63661004 2.41615 7 P 0 0;1=3
P 9.975 2.66445 7 P 0 0;1=3
P 8.4 3.81615 7 P 0 0;1=3
P 9.24185 4.642 7 P 0 0;1=3
P 11.53316004 2.532 7 P 0 0;1=3
P 12.63778996 4.60236998 12 P 0 0;1=1
P 8.45 3.66615 7 P 0 0;1=3
P 9.42358002 4.78291998 7 P 0 0;1=3
P 0.95951004 5.4595 6 P 0 0;1=0
P 8.45 3.71615 7 P 0 0;1=3
P 9.38358002 4.78291998 7 P 0 0;1=3
P 8.4 3.61615 7 P 0 0;1=3
P 9.49445 4.587 7 P 0 0;1=3
P 8.4 3.66615 7 P 0 0;1=3
P 9.45445 4.587 7 P 0 0;1=3
P 9.07353996 4.42 6 P 0 0;1=4
P 7.1926 5.15351004 6 P 0 0;1=0
P 8.1 3.66615 7 P 0 0;1=3
P 8.74578996 4.667 7 P 0 0;1=3
P 8.1 3.71615 7 P 0 0;1=3
P 8.78578996 4.667 7 P 0 0;1=3
P 8.2 3.66615 7 P 0 0;1=3
P 8.81665 4.78291998 7 P 0 0;1=3
P 8.2 3.71615 7 P 0 0;1=3
P 8.85665 4.78291998 7 P 0 0;1=3
P 8.05 3.76615 7 P 0 0;1=3
P 8.89061998 4.667 7 P 0 0;1=3
P 8.05 3.81615 7 P 0 0;1=3
P 8.93061998 4.667 7 P 0 0;1=3
P 9.02925 4.667 7 P 0 0;1=3
P 8.2 3.81615 7 P 0 0;1=3
P 9.06925 4.667 7 P 0 0;1=3
P 8.2 3.86615 7 P 0 0;1=3
P 4.68268002 2.71615 7 P 0 0;1=3
P 4.98268002 2.71615 7 P 0 0;1=3
P 2.14606004 2.51615 7 P 0 0;1=3
P 8.45 3.41615 7 P 0 0;1=3
P 8.18811004 5.0535 7 P 0 0;1=3
P 5.03268002 3.81615 7 P 0 0;1=3
P 4.07408002 4.01978996 6 P 0 0;1=0
P 8.45 3.46615 7 P 0 0;1=3
P 8.14811004 5.0535 7 P 0 0;1=3
P 5.03268002 2.16615 7 P 0 0;1=3
P 3.9099 5.395 6 P 0 0;1=0
P 8.45 3.26615 7 P 0 0;1=3
P 8.40071004 5.115 7 P 0 0;1=3
P 8.45 3.31615 7 P 0 0;1=3
P 8.36071004 5.115 7 P 0 0;1=3
P 8.35 3.26615 7 P 0 0;1=3
P 8.40071004 4.742 7 P 0 0;1=3
P 8.35 3.31615 7 P 0 0;1=3
P 8.36071004 4.742 7 P 0 0;1=3
P 8.3 3.56615 7 P 0 0;1=3
P 8.05 3.31615 7 P 0 0;1=3
P 7.58118996 5.169 7 P 0 0;1=3
P 8.25 3.56615 7 P 0 0;1=3
P 8.05 3.36615 7 P 0 0;1=3
P 7.62118996 5.169 7 P 0 0;1=3
P 2.24606004 2.86615 7 P 0 0;1=3
P 8.05 2.61615 26 P 0 0;1=3
P 8.05 2.66615 26 P 0 0;1=3
P 8.1 2.46615 26 P 0 0;1=3
P 8.1 2.41615 26 P 0 0;1=3
P 8.2 2.46615 26 P 0 0;1=3
P 8.2 2.41615 26 P 0 0;1=3
P 8.15 2.41615 26 P 0 0;1=3
P 8.15 2.36615 26 P 0 0;1=3
P 8.05 2.41615 26 P 0 0;1=3
P 8.05 2.36615 26 P 0 0;1=3
P 8.2 2.31615 26 P 0 0;1=3
P 8.2 2.26615 26 P 0 0;1=3
P 8.15 2.26615 26 P 0 0;1=3
P 8.15 2.21615 26 P 0 0;1=3
P 8.1 2.31615 26 P 0 0;1=3
P 8.1 2.26615 26 P 0 0;1=3
P 8.05 2.26615 26 P 0 0;1=3
P 8.05 2.21615 26 P 0 0;1=3
P 8.1 2.11615 26 P 0 0;1=3
P 8.1 2.06615 26 P 0 0;1=3
P 8.2 2.11615 26 P 0 0;1=3
P 8.2 2.06615 26 P 0 0;1=3
P 8.15 2.06615 26 P 0 0;1=3
P 8.15 2.01615 26 P 0 0;1=3
P 8.05 2.06615 26 P 0 0;1=3
P 8.05 2.01615 26 P 0 0;1=3
P 8.2 1.96615 26 P 0 0;1=3
P 8.2 1.91615 26 P 0 0;1=3
P 8.15 1.91615 26 P 0 0;1=3
P 8.15 1.86615 26 P 0 0;1=3
P 8.1 1.96615 26 P 0 0;1=3
P 8.1 1.91615 26 P 0 0;1=3
P 8.05 1.91615 26 P 0 0;1=3
P 8.05 1.86615 26 P 0 0;1=3
P 8.1 3.16615 26 P 0 0;1=3
P 8.1 3.11615 26 P 0 0;1=3
P 8.2 3.16615 26 P 0 0;1=3
P 8.2 3.11615 26 P 0 0;1=3
P 8.15 3.11615 26 P 0 0;1=3
P 8.15 3.06615 26 P 0 0;1=3
P 8.05 3.11615 26 P 0 0;1=3
P 8.05 3.06615 26 P 0 0;1=3
P 8.2 3.01615 26 P 0 0;1=3
P 8.2 2.96615 26 P 0 0;1=3
P 8.15 2.96615 26 P 0 0;1=3
P 8.15 2.91615 26 P 0 0;1=3
P 8.1 3.01615 26 P 0 0;1=3
P 8.1 2.96615 26 P 0 0;1=3
P 8.05 2.96615 26 P 0 0;1=3
P 8.05 2.91615 26 P 0 0;1=3
P 8 2.81615 26 P 0 0;1=3
P 8 2.76615 26 P 0 0;1=3
P 8.15 2.81615 26 P 0 0;1=3
P 8.15 2.76615 26 P 0 0;1=3
P 8.2 2.76615 26 P 0 0;1=3
P 8.2 2.71615 26 P 0 0;1=3
P 8.1 2.76615 26 P 0 0;1=3
P 8.1 2.71615 26 P 0 0;1=3
P 8.15 2.66615 26 P 0 0;1=3
P 8.15 2.61615 26 P 0 0;1=3
P 8.2 2.61615 26 P 0 0;1=3
P 8.2 2.56615 26 P 0 0;1=3
P 8.1 2.61615 26 P 0 0;1=3
P 8.1 2.56615 26 P 0 0;1=3
P 8.35 2.56615 26 P 0 0;1=3
P 8.35 2.61615 26 P 0 0;1=3
P 8.35 2.46615 26 P 0 0;1=3
P 8.35 2.41615 26 P 0 0;1=3
P 8.45 2.46615 26 P 0 0;1=3
P 8.45 2.41615 26 P 0 0;1=3
P 8.5 2.41615 26 P 0 0;1=3
P 8.5 2.36615 26 P 0 0;1=3
P 8.4 2.41615 26 P 0 0;1=3
P 8.4 2.36615 26 P 0 0;1=3
P 8.45 2.31615 26 P 0 0;1=3
P 8.45 2.26615 26 P 0 0;1=3
P 8.5 2.26615 26 P 0 0;1=3
P 8.5 2.21615 26 P 0 0;1=3
P 8.4 2.26615 26 P 0 0;1=3
P 8.4 2.21615 26 P 0 0;1=3
P 8.35 2.31615 26 P 0 0;1=3
P 8.35 2.26615 26 P 0 0;1=3
P 8.35 2.11615 26 P 0 0;1=3
P 8.35 2.06615 26 P 0 0;1=3
P 8.45 2.11615 26 P 0 0;1=3
P 8.45 2.06615 26 P 0 0;1=3
P 8.5 2.06615 26 P 0 0;1=3
P 8.5 2.01615 26 P 0 0;1=3
P 8.4 2.06615 26 P 0 0;1=3
P 8.4 2.01615 26 P 0 0;1=3
P 8.45 1.96615 26 P 0 0;1=3
P 8.45 1.91615 26 P 0 0;1=3
P 8.5 1.91615 26 P 0 0;1=3
P 8.5 1.86615 26 P 0 0;1=3
P 8.4 1.91615 26 P 0 0;1=3
P 8.4 1.86615 26 P 0 0;1=3
P 8.35 1.96615 26 P 0 0;1=3
P 8.35 1.91615 26 P 0 0;1=3
P 8.35 3.16615 26 P 0 0;1=3
P 8.35 3.11615 26 P 0 0;1=3
P 8.45 3.16615 26 P 0 0;1=3
P 8.45 3.11615 26 P 0 0;1=3
P 8.5 3.11615 26 P 0 0;1=3
P 8.5 3.06615 26 P 0 0;1=3
P 8.4 3.11615 26 P 0 0;1=3
P 8.4 3.06615 26 P 0 0;1=3
P 8.45 3.01615 26 P 0 0;1=3
P 8.45 2.96615 26 P 0 0;1=3
P 8.5 2.96615 26 P 0 0;1=3
P 8.5 2.91615 26 P 0 0;1=3
P 8.4 2.96615 26 P 0 0;1=3
P 8.4 2.91615 26 P 0 0;1=3
P 8.35 3.01615 26 P 0 0;1=3
P 8.35 2.96615 26 P 0 0;1=3
P 8.4 2.81615 26 P 0 0;1=3
P 8.4 2.76615 26 P 0 0;1=3
P 8.5 2.81615 26 P 0 0;1=3
P 8.5 2.76615 26 P 0 0;1=3
P 8.45 2.76615 26 P 0 0;1=3
P 8.45 2.71615 26 P 0 0;1=3
P 8.35 2.76615 26 P 0 0;1=3
P 8.35 2.71615 26 P 0 0;1=3
P 8.5 2.66615 26 P 0 0;1=3
P 8.5 2.61615 26 P 0 0;1=3
P 8.45 2.61615 26 P 0 0;1=3
P 8.45 2.56615 26 P 0 0;1=3
P 8.4 2.66615 26 P 0 0;1=3
P 8.4 2.61615 26 P 0 0;1=3
P 2.04606024 2.61615 26 P 0 0;1=3
P 2.04606024 2.66615 26 P 0 0;1=3
P 2.09606024 2.46615 26 P 0 0;1=3
P 2.09606024 2.41615 26 P 0 0;1=3
P 2.19606024 2.46615 26 P 0 0;1=3
P 2.19606024 2.41615 26 P 0 0;1=3
P 2.14606024 2.41615 26 P 0 0;1=3
P 2.14606024 2.36615 26 P 0 0;1=3
P 2.04606024 2.41615 26 P 0 0;1=3
P 2.04606024 2.36615 26 P 0 0;1=3
P 2.19606024 2.31615 26 P 0 0;1=3
P 2.19606024 2.26615 26 P 0 0;1=3
P 2.14606024 2.26615 26 P 0 0;1=3
P 2.14606024 2.21615 26 P 0 0;1=3
P 2.09606024 2.31615 26 P 0 0;1=3
P 2.09606024 2.26615 26 P 0 0;1=3
P 2.04606024 2.26615 26 P 0 0;1=3
P 2.04606024 2.21615 26 P 0 0;1=3
P 2.09606024 2.11615 26 P 0 0;1=3
P 2.09606024 2.06615 26 P 0 0;1=3
P 2.19606024 2.11615 26 P 0 0;1=3
P 2.19606024 2.06615 26 P 0 0;1=3
P 2.14606024 2.06615 26 P 0 0;1=3
P 2.14606024 2.01615 26 P 0 0;1=3
P 2.04606024 2.06615 26 P 0 0;1=3
P 2.04606024 2.01615 26 P 0 0;1=3
P 2.19606024 1.96615 26 P 0 0;1=3
P 2.19606024 1.91615 26 P 0 0;1=3
P 2.14606024 1.91615 26 P 0 0;1=3
P 2.14606024 1.86615 26 P 0 0;1=3
P 2.09606024 1.96615 26 P 0 0;1=3
P 2.09606024 1.91615 26 P 0 0;1=3
P 2.04606024 1.91615 26 P 0 0;1=3
P 2.04606024 1.86615 26 P 0 0;1=3
P 2.09606024 3.16615 26 P 0 0;1=3
P 2.09606024 3.11615 26 P 0 0;1=3
P 2.19606024 3.16615 26 P 0 0;1=3
P 2.19606024 3.11615 26 P 0 0;1=3
P 2.14606024 3.11615 26 P 0 0;1=3
P 2.14606024 3.06615 26 P 0 0;1=3
P 2.04606024 3.11615 26 P 0 0;1=3
P 2.04606024 3.06615 26 P 0 0;1=3
P 2.19606024 3.01615 26 P 0 0;1=3
P 2.19606024 2.96615 26 P 0 0;1=3
P 2.14606024 2.96615 26 P 0 0;1=3
P 2.14606024 2.91615 26 P 0 0;1=3
P 2.09606024 3.01615 26 P 0 0;1=3
P 2.09606024 2.96615 26 P 0 0;1=3
P 2.04606024 2.96615 26 P 0 0;1=3
P 2.04606024 2.91615 26 P 0 0;1=3
P 1.99605974 2.81615 26 P 0 0;1=3
P 1.99605974 2.76615 26 P 0 0;1=3
P 2.14606024 2.81615 26 P 0 0;1=3
P 2.14606024 2.76615 26 P 0 0;1=3
P 2.19606024 2.76615 26 P 0 0;1=3
P 2.19606024 2.71615 26 P 0 0;1=3
P 2.09606024 2.76615 26 P 0 0;1=3
P 2.09606024 2.71615 26 P 0 0;1=3
P 2.14606024 2.66615 26 P 0 0;1=3
P 2.14606024 2.61615 26 P 0 0;1=3
P 2.19606024 2.61615 26 P 0 0;1=3
P 2.19606024 2.56615 26 P 0 0;1=3
P 2.09606024 2.61615 26 P 0 0;1=3
P 2.09606024 2.56615 26 P 0 0;1=3
P 2.34606024 2.56615 26 P 0 0;1=3
P 2.34606024 2.61615 26 P 0 0;1=3
P 2.34606024 2.46615 26 P 0 0;1=3
P 2.34606024 2.41615 26 P 0 0;1=3
P 2.44606024 2.46615 26 P 0 0;1=3
P 2.44606024 2.41615 26 P 0 0;1=3
P 2.49606024 2.41615 26 P 0 0;1=3
P 2.49606024 2.36615 26 P 0 0;1=3
P 2.39606024 2.41615 26 P 0 0;1=3
P 2.39606024 2.36615 26 P 0 0;1=3
P 2.44606024 2.31615 26 P 0 0;1=3
P 2.44606024 2.26615 26 P 0 0;1=3
P 2.49606024 2.26615 26 P 0 0;1=3
P 2.49606024 2.21615 26 P 0 0;1=3
P 2.39606024 2.26615 26 P 0 0;1=3
P 2.39606024 2.21615 26 P 0 0;1=3
P 2.34606024 2.31615 26 P 0 0;1=3
P 2.34606024 2.26615 26 P 0 0;1=3
P 2.34606024 2.11615 26 P 0 0;1=3
P 2.34606024 2.06615 26 P 0 0;1=3
P 2.44606024 2.11615 26 P 0 0;1=3
P 2.44606024 2.06615 26 P 0 0;1=3
P 2.49606024 2.06615 26 P 0 0;1=3
P 2.49606024 2.01615 26 P 0 0;1=3
P 2.39606024 2.06615 26 P 0 0;1=3
P 2.39606024 2.01615 26 P 0 0;1=3
P 2.44606024 1.96615 26 P 0 0;1=3
P 2.44606024 1.91615 26 P 0 0;1=3
P 2.49606024 1.91615 26 P 0 0;1=3
P 2.49606024 1.86615 26 P 0 0;1=3
P 2.39606024 1.91615 26 P 0 0;1=3
P 2.39606024 1.86615 26 P 0 0;1=3
P 2.34606024 1.96615 26 P 0 0;1=3
P 2.34606024 1.91615 26 P 0 0;1=3
P 2.34606024 3.16615 26 P 0 0;1=3
P 2.34606024 3.11615 26 P 0 0;1=3
P 2.44606024 3.16615 26 P 0 0;1=3
P 2.44606024 3.11615 26 P 0 0;1=3
P 2.49606024 3.11615 26 P 0 0;1=3
P 2.49606024 3.06615 26 P 0 0;1=3
P 2.39606024 3.11615 26 P 0 0;1=3
P 2.39606024 3.06615 26 P 0 0;1=3
P 2.44606024 3.01615 26 P 0 0;1=3
P 2.44606024 2.96615 26 P 0 0;1=3
P 2.49606024 2.96615 26 P 0 0;1=3
P 2.49606024 2.91615 26 P 0 0;1=3
P 2.39606024 2.96615 26 P 0 0;1=3
P 2.39606024 2.91615 26 P 0 0;1=3
P 2.34606024 3.01615 26 P 0 0;1=3
P 2.34606024 2.96615 26 P 0 0;1=3
P 2.39606024 2.81615 26 P 0 0;1=3
P 2.39606024 2.76615 26 P 0 0;1=3
P 2.49606024 2.81615 26 P 0 0;1=3
P 2.49606024 2.76615 26 P 0 0;1=3
P 2.44606024 2.76615 26 P 0 0;1=3
P 2.44606024 2.71615 26 P 0 0;1=3
P 2.34606024 2.76615 26 P 0 0;1=3
P 2.34606024 2.71615 26 P 0 0;1=3
P 2.49606024 2.66615 26 P 0 0;1=3
P 2.49606024 2.61615 26 P 0 0;1=3
P 2.44606024 2.61615 26 P 0 0;1=3
P 2.44606024 2.56615 26 P 0 0;1=3
P 2.39606024 2.66615 26 P 0 0;1=3
P 2.39606024 2.61615 26 P 0 0;1=3
P 8.94061998 4.70574026 26 P 0 0;1=4
P 9.01925 4.70574026 26 P 0 0;1=4
P 9.07925 4.70574026 26 P 0 0;1=4
P 8.73579006 4.70573996 26 P 0 0;1=4
P 8.79579006 4.70573996 26 P 0 0;1=4
P 8.86665 4.74417972 26 P 0 0;1=4
P 8.80665 4.74417972 26 P 0 0;1=4
P 9.43358002 4.74417972 26 P 0 0;1=4
P 9.51531004 4.68098996 26 P 0 0;1=4
P 9.57531004 4.68098996 26 P 0 0;1=4
P 9.44445 4.62574026 26 P 0 0;1=4
P 9.50445 4.62574026 26 P 0 0;1=4
P 9.23185 4.68074026 26 P 0 0;1=4
P 9.29185 4.68074026 26 P 0 0;1=4
P 9.16098002 4.74417972 26 P 0 0;1=4
P 9.37358002 4.74417972 26 P 0 0;1=4
P 9.22098002 4.74417972 26 P 0 0;1=4
P 9.51531004 5.17873996 26 P 0 0;1=4
P 9.57531004 5.17873996 26 P 0 0;1=4
P 9.43358002 5.18127972 26 P 0 0;1=4
P 9.23185 5.18127972 26 P 0 0;1=4
P 9.29185 5.18127972 26 P 0 0;1=4
P 9.37358002 5.18127972 26 P 0 0;1=4
P 9.36271004 5.14223996 26 P 0 0;1=4
P 9.30271004 5.14223996 26 P 0 0;1=4
P 9.15011004 5.09223996 26 P 0 0;1=4
P 9.09011004 5.09223996 26 P 0 0;1=4
P 9.07925 5.20374026 26 P 0 0;1=4
P 9.01925 5.20374026 26 P 0 0;1=4
P 8.93440994 5.20876004 26 P 0 0;1=4
P 8.73579006 5.17873996 26 P 0 0;1=4
P 8.79579006 5.17873996 26 P 0 0;1=4
P 8.87440994 5.20876004 26 P 0 0;1=4
P 7.64205 4.74417972 26 P 0 0;1=4
P 7.70205 4.74417972 26 P 0 0;1=4
P 7.63118996 4.66826004 26 P 0 0;1=4
P 7.57118996 4.66826004 26 P 0 0;1=4
P 7.91465 4.61825974 26 P 0 0;1=4
P 7.78378996 4.74418002 26 P 0 0;1=4
P 7.84378996 4.74418002 26 P 0 0;1=4
P 7.85465 4.61825974 26 P 0 0;1=4
P 8.06725 4.74417972 26 P 0 0;1=4
P 8.12725 4.74417972 26 P 0 0;1=4
P 8.02207028 4.62815 26 P 0 0;1=4
P 8.08207028 4.62815 26 P 0 0;1=4
P 8.41070994 4.70326004 26 P 0 0;1=4
P 8.35070994 4.70326004 26 P 0 0;1=4
P 8.20898002 4.74417972 26 P 0 0;1=4
P 8.26898002 4.74417972 26 P 0 0;1=4
P 8.21208996 4.62826004 26 P 0 0;1=4
P 8.27208996 4.62826004 26 P 0 0;1=4
P 8.19811004 5.09223996 26 P 0 0;1=4
P 8.12725 5.13025974 26 P 0 0;1=4
P 8.06725 5.13025974 26 P 0 0;1=4
P 7.91465 5.13025974 26 P 0 0;1=4
P 7.92551004 5.09223996 26 P 0 0;1=4
P 7.98551004 5.09223996 26 P 0 0;1=4
P 7.85465 5.13025974 26 P 0 0;1=4
P 7.64204006 5.09223996 26 P 0 0;1=4
P 7.70204006 5.09223996 26 P 0 0;1=4
P 7.57118996 5.13026004 26 P 0 0;1=4
P 7.63118996 5.13026004 26 P 0 0;1=4
P 2.73225 4.70574026 26 P 0 0;1=4
P 2.79225 4.70574026 26 P 0 0;1=4
P 3.22830994 5.18128002 26 P 0 0;1=4
P 3.28830994 5.18128002 26 P 0 0;1=4
P 3.01571004 5.20373996 26 P 0 0;1=4
P 3.07571004 5.20373996 26 P 0 0;1=4
P 2.73225 5.17874026 26 P 0 0;1=4
P 2.79225 5.17874026 26 P 0 0;1=4
P 1.56765 4.66825974 26 P 0 0;1=4
P 1.62765 4.66825974 26 P 0 0;1=4
P 1.56765 5.13025974 26 P 0 0;1=4
P 1.62765 5.13025974 26 P 0 0;1=4
P 1.91110994 5.13026004 26 P 0 0;1=4
P 1.85110994 5.13026004 26 P 0 0;1=4
P 5.08267972 2.76615 26 P 0 0;1=3
P 5.03267972 2.76615 26 P 0 0;1=3
P 5.03267972 2.71615 26 P 0 0;1=3
P 4.93267972 2.76615 26 P 0 0;1=3
P 4.98267972 2.76615 26 P 0 0;1=3
P 4.93267972 2.71615 26 P 0 0;1=3
P 5.08267972 2.66615 26 P 0 0;1=3
P 4.98267972 2.66615 26 P 0 0;1=3
P 5.03267972 2.56615 26 P 0 0;1=3
P 4.93267972 2.56615 26 P 0 0;1=3
P 4.98267972 2.46615 26 P 0 0;1=3
P 4.98267972 2.51615 26 P 0 0;1=3
P 4.93267972 2.51615 26 P 0 0;1=3
P 5.08267972 2.51615 26 P 0 0;1=3
P 5.08267972 2.46615 26 P 0 0;1=3
P 5.03267972 2.21615 26 P 0 0;1=3
P 4.93267972 2.21615 26 P 0 0;1=3
P 4.98267972 2.31615 26 P 0 0;1=3
P 4.93267972 2.36615 26 P 0 0;1=3
P 5.08267972 2.31615 26 P 0 0;1=3
P 5.08267972 2.16615 26 P 0 0;1=3
P 4.93267972 2.16615 26 P 0 0;1=3
P 4.98267972 2.16615 26 P 0 0;1=3
P 4.93267972 1.96615 26 P 0 0;1=3
P 5.03267972 1.96615 26 P 0 0;1=3
P 5.03267972 2.11615 26 P 0 0;1=3
P 4.93267972 2.11615 26 P 0 0;1=3
P 4.98267972 2.01615 26 P 0 0;1=3
P 5.08267972 2.01615 26 P 0 0;1=3
P 4.98267972 1.86615 26 P 0 0;1=3
P 5.08267972 1.86615 26 P 0 0;1=3
P 4.78267972 3.81615 26 P 0 0;1=3
P 4.78267972 3.66615 26 P 0 0;1=3
P 4.73267972 3.81615 26 P 0 0;1=3
P 4.73267972 3.66615 26 P 0 0;1=3
P 4.68267972 3.81615 26 P 0 0;1=3
P 4.68267972 3.66615 26 P 0 0;1=3
P 4.78267972 3.51615 26 P 0 0;1=3
P 4.73267972 3.51615 26 P 0 0;1=3
P 4.68267972 3.51615 26 P 0 0;1=3
P 4.78267972 3.36615 26 P 0 0;1=3
P 4.73267972 3.36615 26 P 0 0;1=3
P 4.78267972 3.21615 26 P 0 0;1=3
P 4.73267972 3.21615 26 P 0 0;1=3
P 4.68267972 3.36615 26 P 0 0;1=3
P 4.68267972 3.21615 26 P 0 0;1=3
P 4.78267972 3.06615 26 P 0 0;1=3
P 4.73267972 3.06615 26 P 0 0;1=3
P 4.68267972 3.06615 26 P 0 0;1=3
P 4.78267972 2.91615 26 P 0 0;1=3
P 4.73267972 2.91615 26 P 0 0;1=3
P 4.68267972 2.91615 26 P 0 0;1=3
P 4.88267972 2.76615 26 P 0 0;1=3
P 4.88267972 2.66615 26 P 0 0;1=3
P 4.78267972 2.46615 26 P 0 0;1=3
P 4.88267972 2.56615 26 P 0 0;1=3
P 4.88267972 2.61615 26 P 0 0;1=3
P 4.68267972 2.46615 26 P 0 0;1=3
P 4.88267972 2.46615 26 P 0 0;1=3
P 4.88267972 2.51615 26 P 0 0;1=3
P 4.78267972 2.41615 26 P 0 0;1=3
P 4.88267972 2.41615 26 P 0 0;1=3
P 4.78267972 2.36615 26 P 0 0;1=3
P 4.78267972 2.31615 26 P 0 0;1=3
P 4.78267972 2.26615 26 P 0 0;1=3
P 4.78267972 2.21615 26 P 0 0;1=3
P 4.73267972 2.36615 26 P 0 0;1=3
P 4.68267972 2.31615 26 P 0 0;1=3
P 4.73267972 2.21615 26 P 0 0;1=3
P 4.88267972 2.21615 26 P 0 0;1=3
P 4.88267972 2.26615 26 P 0 0;1=3
P 4.88267972 2.31615 26 P 0 0;1=3
P 4.88267972 2.36615 26 P 0 0;1=3
P 4.73267972 2.16615 26 P 0 0;1=3
P 4.68267972 2.16615 26 P 0 0;1=3
P 4.78267972 1.96615 26 P 0 0;1=3
P 4.78267972 2.06615 26 P 0 0;1=3
P 4.78267972 2.01615 26 P 0 0;1=3
P 4.88267972 1.96615 26 P 0 0;1=3
P 4.88267972 2.06615 26 P 0 0;1=3
P 4.88267972 2.01615 26 P 0 0;1=3
P 4.78267972 2.11615 26 P 0 0;1=3
P 4.88267972 2.11615 26 P 0 0;1=3
P 4.73267972 2.11615 26 P 0 0;1=3
P 4.68267972 2.01615 26 P 0 0;1=3
P 4.73267972 1.96615 26 P 0 0;1=3
P 4.78267972 1.86615 26 P 0 0;1=3
P 4.88267972 1.86615 26 P 0 0;1=3
P 4.68267972 1.86615 26 P 0 0;1=3
P 4.63267972 3.81615 26 P 0 0;1=3
P 4.63267972 3.66615 26 P 0 0;1=3
P 4.58267972 3.81615 26 P 0 0;1=3
P 4.58267972 3.66615 26 P 0 0;1=3
P 4.63267972 3.51615 26 P 0 0;1=3
P 4.58267972 3.51615 26 P 0 0;1=3
P 4.63267972 3.36615 26 P 0 0;1=3
P 4.58267972 3.36615 26 P 0 0;1=3
P 4.63267972 3.21615 26 P 0 0;1=3
P 4.58267972 3.21615 26 P 0 0;1=3
P 4.63267972 3.06615 26 P 0 0;1=3
P 4.58267972 3.06615 26 P 0 0;1=3
P 4.63267972 2.91615 26 P 0 0;1=3
P 4.58267972 2.91615 26 P 0 0;1=3
P 4.58267972 2.46615 26 P 0 0;1=3
P 4.63267972 2.21615 26 P 0 0;1=3
P 4.58267972 2.31615 26 P 0 0;1=3
P 4.63267972 2.36615 26 P 0 0;1=3
P 4.58267972 2.01615 26 P 0 0;1=3
P 4.63267972 2.11615 26 P 0 0;1=3
P 4.63267972 1.96615 26 P 0 0;1=3
P 4.58267972 1.86615 26 P 0 0;1=3
P 2.04606024 3.41615 26 P 0 0;1=3
P 2.09606024 3.51615 26 P 0 0;1=3
P 3.37003996 5.18128002 26 P 0 0;1=4
P 3.43003996 5.18128002 26 P 0 0;1=4
P 3.29916998 5.14224026 26 P 0 0;1=4
P 3.35916998 5.14224026 26 P 0 0;1=4
P 2.93708002 4.70573996 26 P 0 0;1=4
P 3.07571004 4.70573996 26 P 0 0;1=4
P 3.01571004 4.70573996 26 P 0 0;1=4
P 2.87708002 4.70573996 26 P 0 0;1=4
P 2.93086998 5.20876024 26 P 0 0;1=4
P 2.87086998 5.20876024 26 P 0 0;1=4
P 2.80310994 4.74418002 26 P 0 0;1=4
P 2.86310994 4.74418002 26 P 0 0;1=4
P 3.08656998 5.09224026 26 P 0 0;1=4
P 3.14656998 5.09224026 26 P 0 0;1=4
P 2.26855 4.62825974 26 P 0 0;1=4
P 2.20855 4.62825974 26 P 0 0;1=4
P 2.26543996 4.74418002 26 P 0 0;1=4
P 2.20543996 4.74418002 26 P 0 0;1=4
P 2.34716998 4.70326004 26 P 0 0;1=4
P 2.07853002 4.62815 26 P 0 0;1=4
P 2.01853002 4.62815 26 P 0 0;1=4
P 2.12370994 4.74418002 26 P 0 0;1=4
P 2.06370994 4.74418002 26 P 0 0;1=4
P 2.19456998 5.09224026 26 P 0 0;1=4
P 2.13456998 5.09224026 26 P 0 0;1=4
P 2.12370994 5.13026004 26 P 0 0;1=4
P 2.06370994 5.13026004 26 P 0 0;1=4
P 1.6985 5.09224026 26 P 0 0;1=4
P 1.6385 5.09224026 26 P 0 0;1=4
P 1.85110994 4.61826004 26 P 0 0;1=4
P 1.63850994 4.74418002 26 P 0 0;1=4
P 1.69850994 4.74418002 26 P 0 0;1=4
P 1.98196998 5.09224026 26 P 0 0;1=4
P 1.92196998 5.09224026 26 P 0 0;1=4
P 1.84025 4.74417972 26 P 0 0;1=4
P 1.78025 4.74417972 26 P 0 0;1=4
P 11.03660974 2.71615 26 P 0 0;1=3
P 10.93660974 2.71615 26 P 0 0;1=3
P 11.03660974 2.76615 26 P 0 0;1=3
P 10.98660974 2.76615 26 P 0 0;1=3
P 10.93660974 2.76615 26 P 0 0;1=3
P 11.08660974 2.76615 26 P 0 0;1=3
P 11.03660974 2.56615 26 P 0 0;1=3
P 10.93660974 2.56615 26 P 0 0;1=3
P 10.98660974 2.66615 26 P 0 0;1=3
P 10.98660974 2.51615 26 P 0 0;1=3
P 10.93660974 2.51615 26 P 0 0;1=3
P 11.08660974 2.66615 26 P 0 0;1=3
P 11.08660974 2.51615 26 P 0 0;1=3
P 11.08660974 2.46615 26 P 0 0;1=3
P 10.98660974 2.46615 26 P 0 0;1=3
P 11.08660974 2.31615 26 P 0 0;1=3
P 10.93660974 2.36615 26 P 0 0;1=3
P 10.98660974 2.31615 26 P 0 0;1=3
P 10.93660974 2.21615 26 P 0 0;1=3
P 11.03660974 2.21615 26 P 0 0;1=3
P 11.03660974 2.11615 26 P 0 0;1=3
P 10.93660974 2.11615 26 P 0 0;1=3
P 10.98660974 2.01615 26 P 0 0;1=3
P 10.93660974 1.96615 26 P 0 0;1=3
P 11.03660974 1.96615 26 P 0 0;1=3
P 11.08660974 2.01615 26 P 0 0;1=3
P 10.98660974 2.16615 26 P 0 0;1=3
P 10.93660974 2.16615 26 P 0 0;1=3
P 11.08660974 2.16615 26 P 0 0;1=3
P 10.98660974 1.86615 26 P 0 0;1=3
P 11.08660974 1.86615 26 P 0 0;1=3
P 10.73660974 2.71615 26 P 0 0;1=3
P 10.73660974 2.76615 26 P 0 0;1=3
P 10.88660974 2.76615 26 P 0 0;1=3
P 10.78660974 2.76615 26 P 0 0;1=3
P 10.73660974 2.56615 26 P 0 0;1=3
P 10.68660974 2.66615 26 P 0 0;1=3
P 10.73660974 2.51615 26 P 0 0;1=3
P 10.68660974 2.51615 26 P 0 0;1=3
P 10.88660974 2.61615 26 P 0 0;1=3
P 10.88660974 2.56615 26 P 0 0;1=3
P 10.88660974 2.51615 26 P 0 0;1=3
P 10.78660974 2.56615 26 P 0 0;1=3
P 10.78660974 2.61615 26 P 0 0;1=3
P 10.78660974 2.66615 26 P 0 0;1=3
P 10.78660974 2.51615 26 P 0 0;1=3
P 10.78660974 2.46615 26 P 0 0;1=3
P 10.68660974 2.46615 26 P 0 0;1=3
P 10.88660974 2.46615 26 P 0 0;1=3
P 10.78660974 2.21615 26 P 0 0;1=3
P 10.78660974 2.26615 26 P 0 0;1=3
P 10.78660974 2.31615 26 P 0 0;1=3
P 10.78660974 2.36615 26 P 0 0;1=3
P 10.68660974 2.31615 26 P 0 0;1=3
P 10.73660974 2.36615 26 P 0 0;1=3
P 10.73660974 2.21615 26 P 0 0;1=3
P 10.78660974 2.41615 26 P 0 0;1=3
P 10.88660974 2.36615 26 P 0 0;1=3
P 10.88660974 2.31615 26 P 0 0;1=3
P 10.88660974 2.26615 26 P 0 0;1=3
P 10.88660974 2.21615 26 P 0 0;1=3
P 10.73660974 1.96615 26 P 0 0;1=3
P 10.68660974 2.01615 26 P 0 0;1=3
P 10.73660974 2.11615 26 P 0 0;1=3
P 10.78660974 2.11615 26 P 0 0;1=3
P 10.78660974 2.01615 26 P 0 0;1=3
P 10.78660974 1.96615 26 P 0 0;1=3
P 10.78660974 2.06615 26 P 0 0;1=3
P 10.68660974 2.16615 26 P 0 0;1=3
P 10.73660974 2.16615 26 P 0 0;1=3
P 10.88660974 2.01615 26 P 0 0;1=3
P 10.88660974 2.06615 26 P 0 0;1=3
P 10.88660974 2.11615 26 P 0 0;1=3
P 10.88660974 1.96615 26 P 0 0;1=3
P 10.78660974 1.91615 26 P 0 0;1=3
P 10.68660974 1.86615 26 P 0 0;1=3
P 10.78660974 1.86615 26 P 0 0;1=3
P 10.88660974 1.86615 26 P 0 0;1=3
P 10.63660974 2.71615 26 P 0 0;1=3
P 10.63660974 2.76615 26 P 0 0;1=3
P 10.63660974 2.56615 26 P 0 0;1=3
P 10.58660974 2.66615 26 P 0 0;1=3
P 10.63660974 2.51615 26 P 0 0;1=3
P 10.58660974 2.51615 26 P 0 0;1=3
P 10.58660974 2.46615 26 P 0 0;1=3
P 10.63660974 2.36615 26 P 0 0;1=3
P 10.58660974 2.31615 26 P 0 0;1=3
P 10.58660974 2.01615 26 P 0 0;1=3
P 10.63660974 1.96615 26 P 0 0;1=3
P 10.63660974 2.11615 26 P 0 0;1=3
P 10.58660974 1.86615 26 P 0 0;1=3
P 1.92345974 5.377 26 P 0 0;1=4
P 2.14345974 5.377 26 P 0 0;1=4
P 7.927 5.377 26 P 0 0;1=4
P 8.147 5.377 26 P 0 0;1=4
P 3.43003996 4.74418002 26 P 0 0;1=4
P 3.51177008 4.68098996 26 P 0 0;1=4
P 3.57177008 4.68098996 26 P 0 0;1=4
P 3.21743996 4.74418002 26 P 0 0;1=4
P 3.37003996 4.74418002 26 P 0 0;1=4
P 3.41 5.332 26 P 0 0;1=4
P 5.38047972 1.5957 26 P 0 0;1=4
P 5.38047972 1.7891 26 P 0 0;1=4
P 5.38047972 1.732 26 P 0 0;1=4
P 5.38047972 1.6528 26 P 0 0;1=4
P 5.53530974 1.8603 26 P 0 0;1=4
P 5.53530974 1.8032 26 P 0 0;1=4
P 5.53530974 2.2727 26 P 0 0;1=4
P 5.53530974 2.1373 26 P 0 0;1=4
P 5.53530974 1.9964 26 P 0 0;1=4
P 5.38047972 2.3403 26 P 0 0;1=4
P 5.38047972 2.2832 26 P 0 0;1=4
P 5.38047972 2.2049 26 P 0 0;1=4
P 5.38047972 2.1478 26 P 0 0;1=4
P 5.38047972 2.0642 26 P 0 0;1=4
P 5.38047972 2.0071 26 P 0 0;1=4
P 5.38047972 1.9288 26 P 0 0;1=4
P 5.38047972 1.8717 26 P 0 0;1=4
P 5.53530974 2.351 26 P 0 0;1=4
P 5.38047972 2.4757 26 P 0 0;1=4
P 5.38047972 2.4186 26 P 0 0;1=4
P 5.53530974 2.4902 26 P 0 0;1=4
P 5.53530974 2.6825 26 P 0 0;1=4
P 5.53530974 2.6254 26 P 0 0;1=4
P 5.38047972 2.5578 26 P 0 0;1=4
P 5.38047972 2.6149 26 P 0 0;1=4
P 10.43 1.3341 26 P 0 0;1=4
P 10.43 1.277 26 P 0 0;1=4
P 10.4159 1.43 26 P 0 0;1=4
P 10.473 1.43 26 P 0 0;1=4
P 10.37313996 1.55333474 26 P 0 0;1=4
P 10.41451004 1.51195472 26 P 0 0;1=4
P 10.295 1.713 26 P 0 0;1=4
P 10.295 1.6559 26 P 0 0;1=4
P 10.26 1.9179 26 P 0 0;1=4
P 10.29525 1.877 26 P 0 0;1=4
P 10.29525 1.8199 26 P 0 0;1=4
P 10.26 1.975 26 P 0 0;1=4
P 10.125 2.0651 26 P 0 0;1=4
P 10.125 2.1224 26 P 0 0;1=4
P 10.125 2.1795 26 P 0 0;1=4
P 10.01 2.2481 26 P 0 0;1=4
P 10.01 2.191 26 P 0 0;1=4
P 10.01 2.38435 26 P 0 0;1=4
P 10.01 2.32725 26 P 0 0;1=4
P 10.125 2.3168 26 P 0 0;1=4
P 10.125 2.2597 26 P 0 0;1=4
P 10.125 2.4519 26 P 0 0;1=4
P 10.125 2.3948 26 P 0 0;1=4
P 10.01 2.51945 26 P 0 0;1=4
P 10.01 2.46235 26 P 0 0;1=4
P 10.125 2.587 26 P 0 0;1=4
P 10.125 2.5299 26 P 0 0;1=4
P 10.01 2.673 26 P 0 0;1=4
P 10.01 2.6159 26 P 0 0;1=4
P 11.74315974 1.7035 26 P 0 0;1=4
P 11.74315974 1.6405 26 P 0 0;1=4
P 11.69315974 1.4805 26 P 0 0;1=4
P 11.69315974 1.5435 26 P 0 0;1=4
P 11.49315974 1.5605 26 P 0 0;1=4
P 11.49315974 1.6235 26 P 0 0;1=4
P 11.49315974 1.4635 26 P 0 0;1=4
P 11.49365974 1.401 26 P 0 0;1=4
P 11.69315974 2.6005 26 P 0 0;1=4
P 11.69315974 2.5035 26 P 0 0;1=4
P 11.69315974 2.4405 26 P 0 0;1=4
P 11.69315974 2.3435 26 P 0 0;1=4
P 11.69315974 2.2805 26 P 0 0;1=4
P 11.69315974 2.1835 26 P 0 0;1=4
P 11.69315974 1.9605 26 P 0 0;1=4
P 11.69315974 2.0235 26 P 0 0;1=4
P 11.69315974 2.1205 26 P 0 0;1=4
P 11.69315974 1.8005 26 P 0 0;1=4
P 11.69315974 1.8635 26 P 0 0;1=4
P 11.49315974 2.5205 26 P 0 0;1=4
P 11.49315974 2.5835 26 P 0 0;1=4
P 11.49315974 2.4235 26 P 0 0;1=4
P 11.49315974 2.3605 26 P 0 0;1=4
P 11.79315974 2.2635 26 P 0 0;1=4
P 11.79315974 2.2005 26 P 0 0;1=4
P 11.49315974 1.9435 26 P 0 0;1=4
P 11.49315974 2.1035 26 P 0 0;1=4
P 11.49315974 2.0405 26 P 0 0;1=4
P 11.49315974 1.8805 26 P 0 0;1=4
P 11.49365974 1.721 26 P 0 0;1=4
P 11.49315974 1.7835 26 P 0 0;1=4
P 10.125 2.7451 26 P 0 0;1=4
P 10.125 2.688 26 P 0 0;1=4
P 12.34 2.19 26 P 0 0;1=4
P 9.415 5.332 26 P 0 0;1=4
P 9.265 5.332 26 P 0 0;1=4
P 9.07 5.332 26 P 0 0;1=4
P 4.7 5.54929026 26 P 0 0;1=4
P 4.81 5.375 26 P 0 0;1=4
P 4.96 5.375 26 P 0 0;1=4
P 5.16 5.645 26 P 0 0;1=4
P 5.04440974 5.605 26 P 0 0;1=4
P 4.92 5.7 26 P 0 0;1=4
P 9.91 4.7 26 P 0 0;1=4
P 3.57 4.45 26 P 0 0;1=4
P 10.465 5.195 26 P 0 0;1=4
P 10.515 5.32 26 P 0 0;1=4
P 10.465 5.275 26 P 0 0;1=4
P 12.025 4.915 26 P 0 0;1=4
P 12.12 4.965 26 P 0 0;1=4
P 12.185 4.915 26 P 0 0;1=4
P 3.72 4.45 26 P 0 0;1=4
P 3.66 4.63 26 P 0 0;1=4
P 3.77 4.86 26 P 0 0;1=4
P 9.96 4.69 26 P 0 0;1=4
P 10.03 4.51 26 P 0 0;1=4
P 3.835 4.6 26 P 0 0;1=4
P 3.9865 4.635 26 P 0 0;1=4
P 4.14 4.655 26 P 0 0;1=4
P 4.1049 4.7649 26 P 0 0;1=4
P 1.28050974 5.78 26 P 0 0;1=4
P 3.87 5.125 26 P 0 0;1=4
P 0.4826 5.8976 26 P 0 0;1=4
P 0.84952972 5.17 26 P 0 0;1=4
P 0.955 5.325 26 P 0 0;1=4
P 1.31 5.355 26 P 0 0;1=4
P 1.20176998 5.78 26 P 0 0;1=4
P 6.31295 4.99705 26 P 0 0;1=4
P 6.87 5 26 P 0 0;1=4
P 9.64795974 0.79643002 26 P 0 0;1=4
P 9.40795 0.26133002 26 P 0 0;1=4
P 3.60998976 0.24 26 P 0 0;1=4
P 3.65998976 0.345 26 P 0 0;1=4
P 3.86 0.7751 26 P 0 0;1=0
P 6.905 4.94705 26 P 0 0;1=4
P 6.905 4.88705 26 P 0 0;1=4
P 6.955 4.8 26 P 0 0;1=4
P 6.955 4.84 26 P 0 0;1=4
P 6.955 4.72 26 P 0 0;1=4
P 6.955 4.76 26 P 0 0;1=4
P 6.59708976 5.0502 26 P 0 0;1=4
P 6.65218976 4.77 26 P 0 0;1=4
P 6.62119006 4.95641998 26 P 0 0;1=8
P 6.6015 4.93674026 26 P 0 0;1=8
P 6.64088002 4.93673996 26 P 0 0;1=8
P 6.62118976 4.91705 26 P 0 0;1=8
P 6.62118976 4.87768002 26 P 0 0;1=8
P 6.6015 4.89736024 26 P 0 0;1=8
P 6.64087992 4.89736004 26 P 0 0;1=8
P 6.62 4.69 26 P 0 0;1=4
P 6.62 4.725 26 P 0 0;1=4
P 6.385 5.07 26 P 0 0;1=4
P 5.53594026 4.55505 26 P 0 0;1=4
P 6.05708976 4.5102 26 P 0 0;1=4
P 6.01708976 4.5102 26 P 0 0;1=4
P 5.97708976 4.5102 26 P 0 0;1=4
P 5.93708976 4.5102 26 P 0 0;1=4
P 5.89708976 4.5102 26 P 0 0;1=4
P 6.09708976 4.5102 26 P 0 0;1=4
P 5.61708976 4.5102 26 P 0 0;1=4
P 5.65708976 4.5102 26 P 0 0;1=4
P 5.85708976 4.5102 26 P 0 0;1=4
P 5.81708976 4.5102 26 P 0 0;1=4
P 5.77708976 4.5102 26 P 0 0;1=4
P 5.73708976 4.5102 26 P 0 0;1=4
P 5.69708976 4.5102 26 P 0 0;1=4
P 5.57708976 4.5102 26 P 0 0;1=4
P 0.036 0.10868002 26 P 0 0;1=4
P 0.036 0.15868002 26 P 0 0;1=4
P 0.036 0.20868002 26 P 0 0;1=4
P 0.22873976 0.036 26 P 0 0;1=4
P 0.17873976 0.036 26 P 0 0;1=4
P 0.12873976 0.036 26 P 0 0;1=4
P 0.07873976 0.036 26 P 0 0;1=4
P 0.47873976 0.036 26 P 0 0;1=4
P 0.42873976 0.036 26 P 0 0;1=4
P 0.37873976 0.036 26 P 0 0;1=4
P 0.32873976 0.036 26 P 0 0;1=4
P 0.27873976 0.036 26 P 0 0;1=4
P 0.77873976 0.036 26 P 0 0;1=4
P 0.72873976 0.036 26 P 0 0;1=4
P 0.67873976 0.036 26 P 0 0;1=4
P 0.62873976 0.036 26 P 0 0;1=4
P 0.57873976 0.036 26 P 0 0;1=4
P 0.52873976 0.036 26 P 0 0;1=4
P 1.02873976 0.036 26 P 0 0;1=4
P 0.97873976 0.036 26 P 0 0;1=4
P 0.92873976 0.036 26 P 0 0;1=4
P 0.87873976 0.036 26 P 0 0;1=4
P 0.82873976 0.036 26 P 0 0;1=4
P 1.27873976 0.036 26 P 0 0;1=4
P 1.22873976 0.036 26 P 0 0;1=4
P 1.17873976 0.036 26 P 0 0;1=4
P 1.12873976 0.036 26 P 0 0;1=4
P 1.07873976 0.036 26 P 0 0;1=4
P 1.52873976 0.036 26 P 0 0;1=4
P 1.47873976 0.036 26 P 0 0;1=4
P 1.42873976 0.036 26 P 0 0;1=4
P 1.37873976 0.036 26 P 0 0;1=4
P 1.32873976 0.036 26 P 0 0;1=4
P 1.82873976 0.036 26 P 0 0;1=4
P 1.77873976 0.036 26 P 0 0;1=4
P 1.72873976 0.036 26 P 0 0;1=4
P 1.67873976 0.036 26 P 0 0;1=4
P 1.62873976 0.036 26 P 0 0;1=4
P 1.57873976 0.036 26 P 0 0;1=4
P 2.07873976 0.036 26 P 0 0;1=4
P 2.02873976 0.036 26 P 0 0;1=4
P 1.97873976 0.036 26 P 0 0;1=4
P 1.92873976 0.036 26 P 0 0;1=4
P 1.87873976 0.036 26 P 0 0;1=4
P 2.32873976 0.036 26 P 0 0;1=4
P 2.27873976 0.036 26 P 0 0;1=4
P 2.22873976 0.036 26 P 0 0;1=4
P 2.17873976 0.036 26 P 0 0;1=4
P 2.12873976 0.036 26 P 0 0;1=4
P 2.62873976 0.036 26 P 0 0;1=4
P 2.57873976 0.036 26 P 0 0;1=4
P 2.52873976 0.036 26 P 0 0;1=4
P 2.47873976 0.036 26 P 0 0;1=4
P 2.42873976 0.036 26 P 0 0;1=4
P 2.37873976 0.036 26 P 0 0;1=4
P 2.87873976 0.036 26 P 0 0;1=4
P 2.82873976 0.036 26 P 0 0;1=4
P 2.77873976 0.036 26 P 0 0;1=4
P 2.72873976 0.036 26 P 0 0;1=4
P 2.67873976 0.036 26 P 0 0;1=4
P 3.12873976 0.036 26 P 0 0;1=4
P 3.07873976 0.036 26 P 0 0;1=4
P 3.02873976 0.036 26 P 0 0;1=4
P 2.97873976 0.036 26 P 0 0;1=4
P 2.92873976 0.036 26 P 0 0;1=4
P 3.37873976 0.036 26 P 0 0;1=4
P 3.32873976 0.036 26 P 0 0;1=4
P 3.27873976 0.036 26 P 0 0;1=4
P 3.22873976 0.036 26 P 0 0;1=4
P 3.17873976 0.036 26 P 0 0;1=4
P 3.67873976 0.036 26 P 0 0;1=4
P 3.62873976 0.036 26 P 0 0;1=4
P 3.57873976 0.036 26 P 0 0;1=4
P 3.52873976 0.036 26 P 0 0;1=4
P 3.47873976 0.036 26 P 0 0;1=4
P 3.42873976 0.036 26 P 0 0;1=4
P 3.92873976 0.036 26 P 0 0;1=4
P 3.87873976 0.036 26 P 0 0;1=4
P 3.82873976 0.036 26 P 0 0;1=4
P 3.77873976 0.036 26 P 0 0;1=4
P 3.72873976 0.036 26 P 0 0;1=4
P 4.17873976 0.036 26 P 0 0;1=4
P 4.12873976 0.036 26 P 0 0;1=4
P 4.07873976 0.036 26 P 0 0;1=4
P 4.02873976 0.036 26 P 0 0;1=4
P 3.97873976 0.036 26 P 0 0;1=4
P 4.42873976 0.036 26 P 0 0;1=4
P 4.37873976 0.036 26 P 0 0;1=4
P 4.32873976 0.036 26 P 0 0;1=4
P 4.27873976 0.036 26 P 0 0;1=4
P 4.22873976 0.036 26 P 0 0;1=4
P 4.72873976 0.036 26 P 0 0;1=4
P 4.67873976 0.036 26 P 0 0;1=4
P 4.62873976 0.036 26 P 0 0;1=4
P 4.57873976 0.036 26 P 0 0;1=4
P 4.52873976 0.036 26 P 0 0;1=4
P 4.47873976 0.036 26 P 0 0;1=4
P 4.81833976 0.21825 26 P 0 0;1=4
P 4.81833976 0.16825 26 P 0 0;1=4
P 4.81833976 0.11825 26 P 0 0;1=4
P 4.81703888 0.06825906 26 P 0 0;1=4
P 4.77873809 0.03612175 26 P 0 0;1=4
P 6.80730974 0.036 26 P 0 0;1=4
P 6.75730974 0.036 26 P 0 0;1=4
P 6.70730974 0.036 26 P 0 0;1=4
P 6.65730955 0.03676043 26 P 0 0;1=4
P 6.62298947 0.07311939 26 P 0 0;1=4
P 6.62261998 0.12311998 26 P 0 0;1=4
P 6.62261998 0.17311998 26 P 0 0;1=4
P 6.62261998 0.22311998 26 P 0 0;1=4
P 7.00730974 0.036 26 P 0 0;1=4
P 6.95730974 0.036 26 P 0 0;1=4
P 6.90730974 0.036 26 P 0 0;1=4
P 6.85730974 0.036 26 P 0 0;1=4
P 0.036 0.25868002 26 P 0 0;1=4
P 0.036 0.30868002 26 P 0 0;1=4
P 0.036 0.35868002 26 P 0 0;1=4
P 0.036 0.40868002 26 P 0 0;1=4
P 0.036 0.45868002 26 P 0 0;1=4
P 4.96804006 0.46906998 26 P 0 0;1=4
P 4.91804941 0.46808051 26 P 0 0;1=4
P 4.87108927 0.45089055 26 P 0 0;1=4
P 4.83591132 0.41536132 26 P 0 0;1=4
P 4.81919035 0.36823996 26 P 0 0;1=4
P 4.81833976 0.31825 26 P 0 0;1=4
P 4.81833976 0.26825 26 P 0 0;1=4
P 5.21804006 0.46906998 26 P 0 0;1=4
P 5.16804006 0.46906998 26 P 0 0;1=4
P 5.11804006 0.46906998 26 P 0 0;1=4
P 5.06804006 0.46906998 26 P 0 0;1=4
P 5.01804006 0.46906998 26 P 0 0;1=4
P 5.51804006 0.46906998 26 P 0 0;1=4
P 5.46804006 0.46906998 26 P 0 0;1=4
P 5.41804006 0.46906998 26 P 0 0;1=4
P 5.36804006 0.46906998 26 P 0 0;1=4
P 5.31804006 0.46906998 26 P 0 0;1=4
P 5.26804006 0.46906998 26 P 0 0;1=4
P 5.76804006 0.46906998 26 P 0 0;1=4
P 5.71804006 0.46906998 26 P 0 0;1=4
P 5.66804006 0.46906998 26 P 0 0;1=4
P 5.61804006 0.46906998 26 P 0 0;1=4
P 5.56804006 0.46906998 26 P 0 0;1=4
P 6.01804006 0.46906998 26 P 0 0;1=4
P 5.96804006 0.46906998 26 P 0 0;1=4
P 5.91804006 0.46906998 26 P 0 0;1=4
P 5.86804006 0.46906998 26 P 0 0;1=4
P 5.81804006 0.46906998 26 P 0 0;1=4
P 6.31804006 0.46906998 26 P 0 0;1=4
P 6.26804006 0.46906998 26 P 0 0;1=4
P 6.21804006 0.46906998 26 P 0 0;1=4
P 6.16804006 0.46906998 26 P 0 0;1=4
P 6.11804006 0.46906998 26 P 0 0;1=4
P 6.06804006 0.46906998 26 P 0 0;1=4
P 6.56567894 0.45345098 26 P 0 0;1=4
P 6.5180314 0.46861841 26 P 0 0;1=4
P 6.46804006 0.46906998 26 P 0 0;1=4
P 6.41804006 0.46906998 26 P 0 0;1=4
P 6.36804006 0.46906998 26 P 0 0;1=4
P 6.62261998 0.27311998 26 P 0 0;1=4
P 6.62261998 0.32311998 26 P 0 0;1=4
P 6.62106949 0.37309951 26 P 0 0;1=4
P 6.60234085 0.41946063 26 P 0 0;1=4
P 0.036 0.50868002 26 P 0 0;1=4
P 0.036 0.55868002 26 P 0 0;1=4
P 11.845 2.85 26 P 0 0;1=4
P 8.98115 2.7861 26 P 0 0;1=4
P 8.98115 2.8989 26 P 0 0;1=4
P 11.58612972 2.855 26 P 0 0;1=4
P 11.50361998 2.8 26 P 0 0;1=4
P 11.50361998 2.73 26 P 0 0;1=4
P 5.5722 3 26 P 0 0;1=4
P 5.75779006 3.02558996 26 P 0 0;1=4
P 5.9192 2.943 26 P 0 0;1=4
P 4.07385974 2.55 26 P 0 0;1=4
P 3.86826998 2.64559026 26 P 0 0;1=4
P 9.995 2.87559026 26 P 0 0;1=4
P 10.11778976 2.78 26 P 0 0;1=4
P 7.2426 4.60351024 26 P 0 0;1=4
P 7.3401 4.85601024 26 P 0 0;1=4
P 7.1926 5.04351024 26 P 0 0;1=4
P 0.66 2.045 26 P 0 0;1=0
P 1.792 2.4781 26 P 0 0;1=4
P 2.97720974 2.8989 26 P 0 0;1=4
P 2.97720974 2.7861 26 P 0 0;1=4
P 2.9422 2.925 26 P 0 0;1=4
P 8.94278976 2.925 26 P 0 0;1=4
P 5.5822 2.855 26 P 0 0;1=4
P 5.84969026 2.85 26 P 0 0;1=4
P 0.65348996 1.85608996 26 P 0 0;1=4
P 0.65348996 1.91628996 26 P 0 0;1=4
P 0.09448996 4.60236998 28 P 0 3;1=1
P 0.35038996 4.20865994 28 P 0 3;1=1
P 0.09448996 4.2874 28 P 0 3;1=1
P 0.09448996 4.12991998 28 P 0 3;1=1
P 0.17322992 4.16928996 28 P 0 3;1=1
P 0.27165 4.09055 28 P 0 3;1=1
P 0.27165 3.93306998 28 P 0 3;1=1
P 0.35038996 4.05117992 28 P 0 3;1=1
P 0.35038996 3.8937 28 P 0 3;1=1
P 0.09448996 3.97243996 28 P 0 3;1=1
P 0.09448996 3.81495994 28 P 0 3;1=1
P 0.17322992 4.01180994 28 P 0 3;1=1
P 0.17322992 3.85432992 28 P 0 3;1=1
P 0.27165 3.77558996 28 P 0 3;1=1
P 0.27165 3.61810994 28 P 0 3;1=1
P 0.35038996 3.73621998 28 P 0 3;1=1
P 0.35038996 3.57873996 28 P 0 3;1=1
P 0.09448996 3.65747992 28 P 0 3;1=1
P 0.09448996 3.5 28 P 0 3;1=1
P 0.17322992 3.69685 28 P 0 3;1=1
P 0.17322992 3.53936998 28 P 0 3;1=1
P 0.27165 3.46062992 28 P 0 3;1=1
P 0.35038996 3.42125994 28 P 0 3;1=1
P 0.27165 3.30315 28 P 0 3;1=1
P 0.27165 3.22440994 28 P 0 3;1=1
P 0.17322992 3.38188996 28 P 0 3;1=1
P 0.17322992 3.30315 28 P 0 3;1=1
P 0.35038996 3.1063 28 P 0 3;1=1
P 0.35038996 2.94881998 28 P 0 3;1=1
P 0.27165 3.06692992 28 P 0 3;1=1
P 0.27165 2.90945 28 P 0 3;1=1
P 0.17322992 3.14566998 28 P 0 3;1=1
P 0.17322992 2.98818996 28 P 0 3;1=1
P 0.09448996 3.18503996 28 P 0 3;1=1
P 0.09448996 3.02755994 28 P 0 3;1=1
P 0.35038996 2.79133996 28 P 0 3;1=1
P 0.27165 2.75196998 28 P 0 3;1=1
P 0.35038996 2.63385994 28 P 0 3;1=1
P 0.17322992 2.83070994 28 P 0 3;1=1
P 0.09448996 2.87007992 28 P 0 3;1=1
P 0.09448996 2.7126 28 P 0 3;1=1
P 0.35038996 2.39763996 28 P 0 3;1=1
P 0.27165 2.51575 28 P 0 3;1=1
P 0.27165 2.35826998 28 P 0 3;1=1
P 0.17322992 2.59448996 28 P 0 3;1=1
P 0.17322992 2.43700994 28 P 0 3;1=1
P 0.09448996 2.47637992 28 P 0 3;1=1
P 0.09448996 2.3189 28 P 0 3;1=1
P 0.35038996 2.24015994 28 P 0 3;1=1
P 0.35038996 2.08267992 28 P 0 3;1=1
P 0.35038996 2.00393996 28 P 0 3;1=1
P 0.27165 2.20078996 28 P 0 3;1=1
P 0.17322992 2.27952992 28 P 0 3;1=1
P 0.09448996 2.16141998 28 P 0 3;1=1
P 0.09448996 2.08267992 28 P 0 3;1=1
P 0.17322992 1.96456998 28 P 0 3;1=1
P 0.09448996 1.84645994 28 P 0 3;1=1
P 0.09448996 4.44487992 28 P 0 3;1=1
P 12.63778996 2.00393996 28 P 0 3;1=1
P 12.55905 2.12205 28 P 0 3;1=1
P 12.55905 1.88582992 28 P 0 3;1=1
P 12.81495 2.12205 28 P 0 3;1=1
P 12.81495 2.04330994 28 P 0 3;1=1
P 12.73620994 2.39763996 28 P 0 3;1=1
P 12.73620994 2.24015994 28 P 0 3;1=1
P 12.63778996 2.3189 28 P 0 3;1=1
P 12.55905 2.35826998 28 P 0 3;1=1
P 12.55905 2.20078996 28 P 0 3;1=1
P 12.81495 2.43700994 28 P 0 3;1=1
P 12.81495 2.27952992 28 P 0 3;1=1
P 12.73620994 2.55511998 28 P 0 3;1=1
P 12.63778996 2.63385994 28 P 0 3;1=1
P 12.63778996 2.47637992 28 P 0 3;1=1
P 12.55905 2.51575 28 P 0 3;1=1
P 12.81495 2.67322992 28 P 0 3;1=1
P 12.73620994 2.94881998 28 P 0 3;1=1
P 12.73620994 2.79133996 28 P 0 3;1=1
P 12.63778996 3.02755994 28 P 0 3;1=1
P 12.63778996 2.87007992 28 P 0 3;1=1
P 12.55905 2.90945 28 P 0 3;1=1
P 12.55905 2.75196998 28 P 0 3;1=1
P 12.81495 2.98818996 28 P 0 3;1=1
P 12.81495 2.83070994 28 P 0 3;1=1
P 12.73620994 3.26377992 28 P 0 3;1=1
P 12.73620994 3.1063 28 P 0 3;1=1
P 12.63778996 3.18503996 28 P 0 3;1=1
P 12.55905 3.22440994 28 P 0 3;1=1
P 12.55905 3.06692992 28 P 0 3;1=1
P 12.81495 3.14566998 28 P 0 3;1=1
P 12.55905 3.53936998 28 P 0 3;1=1
P 12.63778996 3.57873996 28 P 0 3;1=1
P 12.63778996 3.42125994 28 P 0 3;1=1
P 12.73620994 3.5 28 P 0 3;1=1
P 12.73620994 3.34251998 28 P 0 3;1=1
P 12.63778996 3.34251998 28 P 0 3;1=1
P 12.81495 3.61810994 28 P 0 3;1=1
P 12.81495 3.46062992 28 P 0 3;1=1
P 12.55905 3.85432992 28 P 0 3;1=1
P 12.55905 3.69685 28 P 0 3;1=1
P 12.63778996 3.8937 28 P 0 3;1=1
P 12.63778996 3.73621998 28 P 0 3;1=1
P 12.73620994 3.81495994 28 P 0 3;1=1
P 12.73620994 3.65747992 28 P 0 3;1=1
P 12.81495 3.93306998 28 P 0 3;1=1
P 12.81495 3.77558996 28 P 0 3;1=1
P 12.55905 4.16928996 28 P 0 3;1=1
P 12.55905 4.01180994 28 P 0 3;1=1
P 12.63778996 4.20865994 28 P 0 3;1=1
P 12.63778996 4.05117992 28 P 0 3;1=1
P 12.73620994 4.12991998 28 P 0 3;1=1
P 12.73620994 3.97243996 28 P 0 3;1=1
P 12.81495 4.09055 28 P 0 3;1=1
P 12.55905 4.48425 28 P 0 3;1=1
P 12.55905 4.32676998 28 P 0 3;1=1
P 12.63778996 4.52361998 28 P 0 3;1=1
P 12.63778996 4.36613996 28 P 0 3;1=1
P 12.73620994 4.44487992 28 P 0 3;1=1
P 12.73620994 4.2874 28 P 0 3;1=1
P 12.81495 4.40550994 28 P 0 3;1=1
P 12.81495 4.24802992 28 P 0 3;1=1
P 12.55905 4.64173996 28 P 0 3;1=1
P 12.81495 4.56298996 28 P 0 3;1=1
P 0.27165 4.40550994 28 P 0 3;1=1
P 0.35038996 4.52361998 28 P 0 3;1=1
P 0.17322992 4.48425 28 P 0 3;1=1
P 0.27165 4.24802992 28 P 0 3;1=1
P 0.35038996 4.36613996 28 P 0 3;1=1
P 0.17322992 4.32676998 28 P 0 3;1=1
P 5.49220974 2.73 26 P 0 0;1=4
P 5.44885974 2.9414 26 P 0 0;1=4
P 5.44885974 3.0214 26 P 0 0;1=4
P 5.44885974 3.0564 26 P 0 0;1=4
P 5.44885974 3.1014 26 P 0 0;1=4
P 5.44885974 3.1364 26 P 0 0;1=4
P 5.44885974 3.2164 26 P 0 0;1=4
P 5.44885974 3.1814 26 P 0 0;1=4
P 5.44885974 2.9764 26 P 0 0;1=4
P 5.44885974 3.2614 26 P 0 0;1=4
P 5.44885974 3.2964 26 P 0 0;1=4
P 10.33998976 4.9231 26 P 0 0;1=4
P 10.38498976 4.9231 26 P 0 0;1=0
P 10.77498976 4.9231 26 P 0 0;1=4
P 10.72998976 4.9231 26 P 0 0;1=4
P 10.30498976 4.9431 26 P 0 0;1=4
P 10.26498976 4.9431 26 P 0 0;1=4
P 10.30498976 5.0281 26 P 0 0;1=4
P 10.30498976 5.0731 26 P 0 0;1=4
P 10.30498976 4.9831 26 P 0 0;1=4
P 10.26498976 5.0281 26 P 0 0;1=4
P 10.26498976 5.0731 26 P 0 0;1=4
P 10.26498976 4.9831 26 P 0 0;1=4
P 10.26498976 5.1181 26 P 0 0;1=4
P 10.30498976 5.1181 26 P 0 0;1=4
P 10.34498976 5.1181 26 P 0 0;1=4
P 10.42498976 4.9431 26 P 0 0;1=4
P 10.46498976 4.9431 26 P 0 0;1=4
P 10.38498976 5.1181 26 P 0 0;1=4
P 10.46498976 5.1181 26 P 0 0;1=4
P 10.42498976 5.1181 26 P 0 0;1=4
P 10.42498976 4.9831 26 P 0 0;1=4
P 10.42498976 5.0731 26 P 0 0;1=4
P 10.42498976 5.0281 26 P 0 0;1=4
P 10.46498976 4.9831 26 P 0 0;1=4
P 10.46498976 5.0731 26 P 0 0;1=4
P 10.46498976 5.0281 26 P 0 0;1=4
P 10.85498976 4.9431 26 P 0 0;1=4
P 10.81498976 4.9431 26 P 0 0;1=4
P 10.65498976 4.9431 26 P 0 0;1=4
P 10.69498976 4.9431 26 P 0 0;1=4
P 10.85498976 5.0281 26 P 0 0;1=4
P 10.85498976 5.0731 26 P 0 0;1=4
P 10.85498976 4.9831 26 P 0 0;1=4
P 10.81498976 5.0281 26 P 0 0;1=4
P 10.81498976 5.0731 26 P 0 0;1=4
P 10.81498976 4.9831 26 P 0 0;1=4
P 10.81498976 5.1181 26 P 0 0;1=4
P 10.85498976 5.1181 26 P 0 0;1=4
P 10.73498976 5.1181 26 P 0 0;1=4
P 10.69498976 5.1181 26 P 0 0;1=4
P 10.65498976 5.1181 26 P 0 0;1=4
P 10.77498976 5.1181 26 P 0 0;1=4
P 10.65498976 4.9831 26 P 0 0;1=4
P 10.65498976 5.0731 26 P 0 0;1=4
P 10.65498976 5.0281 26 P 0 0;1=4
P 10.69498976 4.9831 26 P 0 0;1=4
P 10.69498976 5.0731 26 P 0 0;1=4
P 10.69498976 5.0281 26 P 0 0;1=4
P 1.23905994 4.60351004 26 P 0 0;1=4
P 1.18905994 5.04351004 26 P 0 0;1=4
P 1.33655994 4.85601004 26 P 0 0;1=4
P 10.16606998 2.81 26 P 0 0;1=4
P 4.15220974 2.9281 26 P 0 0;1=4
P 11.45278976 2.9414 26 P 0 0;1=4
P 11.45278976 3.0214 26 P 0 0;1=4
P 11.45278976 3.0564 26 P 0 0;1=4
P 11.45278976 3.1014 26 P 0 0;1=4
P 11.45278976 3.1364 26 P 0 0;1=4
P 11.45278976 3.2164 26 P 0 0;1=4
P 11.45278976 3.1814 26 P 0 0;1=4
P 11.45278976 2.9764 26 P 0 0;1=4
P 11.45278976 3.2614 26 P 0 0;1=4
P 11.45278976 3.2964 26 P 0 0;1=4
P 0.09448996 1.45275994 28 P 0 3;1=1
P 0.27165 1.57086998 28 P 0 3;1=1
P 0.35038996 1.45275994 28 P 0 3;1=1
P 12.81495 1.49212992 28 P 0 3;1=1
P 12.73620994 1.61023996 28 P 0 3;1=1
P 12.55905 1.49212992 28 P 0 3;1=1
P 0.27165 1.88582992 28 P 0 3;1=1
P 12.73620994 1.9252 28 P 0 3;1=1
P 7.35730974 0.036 26 P 0 0;1=4
P 7.60730974 0.036 26 P 0 0;1=4
P 7.55730974 0.036 26 P 0 0;1=4
P 7.50730974 0.036 26 P 0 0;1=4
P 7.45730974 0.036 26 P 0 0;1=4
P 7.40730974 0.036 26 P 0 0;1=4
P 7.85730974 0.036 26 P 0 0;1=4
P 7.80730974 0.036 26 P 0 0;1=4
P 7.75730974 0.036 26 P 0 0;1=4
P 7.70730974 0.036 26 P 0 0;1=4
P 7.65730974 0.036 26 P 0 0;1=4
P 8.15730974 0.036 26 P 0 0;1=4
P 8.10730974 0.036 26 P 0 0;1=4
P 8.05730974 0.036 26 P 0 0;1=4
P 8.00730974 0.036 26 P 0 0;1=4
P 7.95730974 0.036 26 P 0 0;1=4
P 7.90730974 0.036 26 P 0 0;1=4
P 8.40730974 0.036 26 P 0 0;1=4
P 8.35730974 0.036 26 P 0 0;1=4
P 8.30730974 0.036 26 P 0 0;1=4
P 8.25730974 0.036 26 P 0 0;1=4
P 8.20730974 0.036 26 P 0 0;1=4
P 8.65730974 0.036 26 P 0 0;1=4
P 8.60730974 0.036 26 P 0 0;1=4
P 8.55730974 0.036 26 P 0 0;1=4
P 8.50730974 0.036 26 P 0 0;1=4
P 8.45730974 0.036 26 P 0 0;1=4
P 8.90730974 0.036 26 P 0 0;1=4
P 8.85730974 0.036 26 P 0 0;1=4
P 8.80730974 0.036 26 P 0 0;1=4
P 8.75730974 0.036 26 P 0 0;1=4
P 8.70730974 0.036 26 P 0 0;1=4
P 9.20730974 0.036 26 P 0 0;1=4
P 9.15730974 0.036 26 P 0 0;1=4
P 9.10730974 0.036 26 P 0 0;1=4
P 9.05730974 0.036 26 P 0 0;1=4
P 9.00730974 0.036 26 P 0 0;1=4
P 8.95730974 0.036 26 P 0 0;1=4
P 9.45730974 0.036 26 P 0 0;1=4
P 9.40730974 0.036 26 P 0 0;1=4
P 9.35730974 0.036 26 P 0 0;1=4
P 9.30730974 0.036 26 P 0 0;1=4
P 9.25730974 0.036 26 P 0 0;1=4
P 9.70730974 0.036 26 P 0 0;1=4
P 9.65730974 0.036 26 P 0 0;1=4
P 9.60730974 0.036 26 P 0 0;1=4
P 9.55730974 0.036 26 P 0 0;1=4
P 9.50730974 0.036 26 P 0 0;1=4
P 10.00730974 0.036 26 P 0 0;1=4
P 9.95730974 0.036 26 P 0 0;1=4
P 9.90730974 0.036 26 P 0 0;1=4
P 9.85730974 0.036 26 P 0 0;1=4
P 9.80730974 0.036 26 P 0 0;1=4
P 9.75730974 0.036 26 P 0 0;1=4
P 10.25730974 0.036 26 P 0 0;1=4
P 10.20730974 0.036 26 P 0 0;1=4
P 10.15730974 0.036 26 P 0 0;1=4
P 10.10730974 0.036 26 P 0 0;1=4
P 10.05730974 0.036 26 P 0 0;1=4
P 10.50730974 0.036 26 P 0 0;1=4
P 10.45730974 0.036 26 P 0 0;1=4
P 10.40730974 0.036 26 P 0 0;1=4
P 10.35730974 0.036 26 P 0 0;1=4
P 10.30730974 0.036 26 P 0 0;1=4
P 10.75730974 0.036 26 P 0 0;1=4
P 10.70730974 0.036 26 P 0 0;1=4
P 10.65730974 0.036 26 P 0 0;1=4
P 10.60730974 0.036 26 P 0 0;1=4
P 10.55730974 0.036 26 P 0 0;1=4
P 11.05730974 0.036 26 P 0 0;1=4
P 11.00730974 0.036 26 P 0 0;1=4
P 10.95730974 0.036 26 P 0 0;1=4
P 10.90730974 0.036 26 P 0 0;1=4
P 10.85730974 0.036 26 P 0 0;1=4
P 10.80730974 0.036 26 P 0 0;1=4
P 11.30730974 0.036 26 P 0 0;1=4
P 11.25730974 0.036 26 P 0 0;1=4
P 11.20730974 0.036 26 P 0 0;1=4
P 11.15730974 0.036 26 P 0 0;1=4
P 11.10730974 0.036 26 P 0 0;1=4
P 11.55730974 0.036 26 P 0 0;1=4
P 11.50730974 0.036 26 P 0 0;1=4
P 11.45730974 0.036 26 P 0 0;1=4
P 11.40730974 0.036 26 P 0 0;1=4
P 11.35730974 0.036 26 P 0 0;1=4
P 11.80730974 0.036 26 P 0 0;1=4
P 11.75730974 0.036 26 P 0 0;1=4
P 11.70730974 0.036 26 P 0 0;1=4
P 11.65730974 0.036 26 P 0 0;1=4
P 11.60730974 0.036 26 P 0 0;1=4
P 12.10730974 0.036 26 P 0 0;1=4
P 12.05730974 0.036 26 P 0 0;1=4
P 12.00730974 0.036 26 P 0 0;1=4
P 11.95730974 0.036 26 P 0 0;1=4
P 11.90730974 0.036 26 P 0 0;1=4
P 11.85730974 0.036 26 P 0 0;1=4
P 12.35730974 0.036 26 P 0 0;1=4
P 12.30730974 0.036 26 P 0 0;1=4
P 12.25730974 0.036 26 P 0 0;1=4
P 12.20730974 0.036 26 P 0 0;1=4
P 12.15730974 0.036 26 P 0 0;1=4
P 12.60730974 0.036 26 P 0 0;1=4
P 12.55730974 0.036 26 P 0 0;1=4
P 12.50730974 0.036 26 P 0 0;1=4
P 12.45730974 0.036 26 P 0 0;1=4
P 12.40730974 0.036 26 P 0 0;1=4
P 12.8892 0.22595974 26 P 0 0;1=4
P 12.8892 0.17595974 26 P 0 0;1=4
P 12.8892 0.12595974 26 P 0 0;1=4
P 12.88911073 0.07596083 26 P 0 0;1=4
P 12.85728868 0.03739114 26 P 0 0;1=4
P 12.80730974 0.036 26 P 0 0;1=4
P 12.75730974 0.036 26 P 0 0;1=4
P 12.70730974 0.036 26 P 0 0;1=4
P 12.65730974 0.036 26 P 0 0;1=4
P 12.8892 0.47595974 26 P 0 0;1=4
P 12.8892 0.42595974 26 P 0 0;1=4
P 12.8892 0.37595974 26 P 0 0;1=4
P 12.8892 0.32595974 26 P 0 0;1=4
P 12.8892 0.27595974 26 P 0 0;1=4
P 12.8892 0.62595974 26 P 0 0;1=4
P 12.8892 0.57595974 26 P 0 0;1=4
P 12.8892 0.52595974 26 P 0 0;1=4
P 0.036 1.00868002 26 P 0 0;1=4
P 0.036 1.05868002 26 P 0 0;1=4
P 0.036 1.10868002 26 P 0 0;1=4
P 0.036 1.15868002 26 P 0 0;1=4
P 0.036 1.20868002 26 P 0 0;1=4
P 0.036 1.25868002 26 P 0 0;1=4
P 0.036 1.30868002 26 P 0 0;1=4
P 0.036 1.35868002 26 P 0 0;1=4
P 0.036 1.40868002 26 P 0 0;1=4
P 0.036 1.45868002 26 P 0 0;1=4
P 0.036 1.50868002 26 P 0 0;1=4
P 0.036 1.55868002 26 P 0 0;1=4
P 0.036 1.60868002 26 P 0 0;1=4
P 0.036 1.65868002 26 P 0 0;1=4
P 0.036 1.70868002 26 P 0 0;1=4
P 0.036 1.75868002 26 P 0 0;1=4
P 0.036 1.80868002 26 P 0 0;1=4
P 0.036 1.85868002 26 P 0 0;1=4
P 0.036 1.90868002 26 P 0 0;1=4
P 0.036 1.95868002 26 P 0 0;1=4
P 0.036 2.00868002 26 P 0 0;1=4
P 0.036 2.05868002 26 P 0 0;1=4
P 0.036 2.10868002 26 P 0 0;1=4
P 0.036 2.15868002 26 P 0 0;1=4
P 0.036 2.20868002 26 P 0 0;1=4
P 0.036 2.25868002 26 P 0 0;1=4
P 0.036 2.30868002 26 P 0 0;1=4
P 0.036 2.35868002 26 P 0 0;1=4
P 0.036 2.40868002 26 P 0 0;1=4
P 0.036 2.45868002 26 P 0 0;1=4
P 0.036 2.50868002 26 P 0 0;1=4
P 0.036 2.55868002 26 P 0 0;1=4
P 0.036 2.60868002 26 P 0 0;1=4
P 0.036 2.65868002 26 P 0 0;1=4
P 0.036 2.70868002 26 P 0 0;1=4
P 0.036 2.75868002 26 P 0 0;1=4
P 0.036 2.80868002 26 P 0 0;1=4
P 0.036 2.85868002 26 P 0 0;1=4
P 0.036 2.90868002 26 P 0 0;1=4
P 0.036 2.95868002 26 P 0 0;1=4
P 0.036 3.00868002 26 P 0 0;1=4
P 0.036 3.05868002 26 P 0 0;1=4
P 0.036 3.10868002 26 P 0 0;1=4
P 0.036 3.15868002 26 P 0 0;1=4
P 0.036 3.20868002 26 P 0 0;1=4
P 0.036 3.25868002 26 P 0 0;1=4
P 0.036 3.30868002 26 P 0 0;1=4
P 0.036 3.35868002 26 P 0 0;1=4
P 0.036 3.40868002 26 P 0 0;1=4
P 0.036 3.45868002 26 P 0 0;1=4
P 0.036 3.50868002 26 P 0 0;1=4
P 0.036 3.55868002 26 P 0 0;1=4
P 0.036 3.60868002 26 P 0 0;1=4
P 0.036 3.65868002 26 P 0 0;1=4
P 0.036 3.70868002 26 P 0 0;1=4
P 0.036 3.75868002 26 P 0 0;1=4
P 0.036 3.80868002 26 P 0 0;1=4
P 0.036 3.85868002 26 P 0 0;1=4
P 0.036 3.90868002 26 P 0 0;1=4
P 0.036 3.95868002 26 P 0 0;1=4
P 0.036 4.00868002 26 P 0 0;1=4
P 0.036 4.05868002 26 P 0 0;1=4
P 0.036 4.10868002 26 P 0 0;1=4
P 0.036 4.15868002 26 P 0 0;1=4
P 0.036 4.20868002 26 P 0 0;1=4
P 0.036 4.25868002 26 P 0 0;1=4
P 0.036 4.30868002 26 P 0 0;1=4
P 0.036 4.35868002 26 P 0 0;1=4
P 0.036 4.40868002 26 P 0 0;1=4
P 0.036 4.45868002 26 P 0 0;1=4
P 0.036 4.50868002 26 P 0 0;1=4
P 0.036 4.55868002 26 P 0 0;1=4
P 0.036 4.60868002 26 P 0 0;1=4
P 0.036 4.65868002 26 P 0 0;1=4
P 0.036 4.70868002 26 P 0 0;1=4
P 0.036 4.75868002 26 P 0 0;1=4
P 12.8892 1.02595974 26 P 0 0;1=4
P 12.8892 1.27595974 26 P 0 0;1=4
P 12.8892 1.22595974 26 P 0 0;1=4
P 12.8892 1.17595974 26 P 0 0;1=4
P 12.8892 1.12595974 26 P 0 0;1=4
P 12.8892 1.07595974 26 P 0 0;1=4
P 12.8892 1.52595974 26 P 0 0;1=4
P 12.8892 1.47595974 26 P 0 0;1=4
P 12.8892 1.42595974 26 P 0 0;1=4
P 12.8892 1.37595974 26 P 0 0;1=4
P 12.8892 1.32595974 26 P 0 0;1=4
P 12.8892 1.77595974 26 P 0 0;1=4
P 12.8892 1.72595974 26 P 0 0;1=4
P 12.8892 1.67595974 26 P 0 0;1=4
P 12.8892 1.62595974 26 P 0 0;1=4
P 12.8892 1.57595974 26 P 0 0;1=4
P 12.8892 2.07595974 26 P 0 0;1=4
P 12.8892 2.02595974 26 P 0 0;1=4
P 12.8892 1.97595974 26 P 0 0;1=4
P 12.8892 1.92595974 26 P 0 0;1=4
P 12.8892 1.87595974 26 P 0 0;1=4
P 12.8892 1.82595974 26 P 0 0;1=4
P 12.8892 2.32595974 26 P 0 0;1=4
P 12.8892 2.27595974 26 P 0 0;1=4
P 12.8892 2.22595974 26 P 0 0;1=4
P 12.8892 2.17595974 26 P 0 0;1=4
P 12.8892 2.57595974 26 P 0 0;1=4
P 12.8892 2.52595974 26 P 0 0;1=4
P 12.8892 2.47595974 26 P 0 0;1=4
P 12.8892 2.42595974 26 P 0 0;1=4
P 12.8892 2.37595974 26 P 0 0;1=4
P 12.8892 2.82595974 26 P 0 0;1=4
P 12.8892 2.77595974 26 P 0 0;1=4
P 12.8892 2.72595974 26 P 0 0;1=4
P 12.8892 2.67595974 26 P 0 0;1=4
P 12.8892 2.62595974 26 P 0 0;1=4
P 12.8892 3.12595974 26 P 0 0;1=4
P 12.8892 3.07595974 26 P 0 0;1=4
P 12.8892 3.02595974 26 P 0 0;1=4
P 12.8892 2.97595974 26 P 0 0;1=4
P 12.8892 2.92595974 26 P 0 0;1=4
P 12.8892 2.87595974 26 P 0 0;1=4
P 12.8892 3.37595974 26 P 0 0;1=4
P 12.8892 3.32595974 26 P 0 0;1=4
P 12.8892 3.27595974 26 P 0 0;1=4
P 12.8892 3.22595974 26 P 0 0;1=4
P 12.8892 3.17595974 26 P 0 0;1=4
P 12.8892 3.62595974 26 P 0 0;1=4
P 12.8892 3.57595974 26 P 0 0;1=4
P 12.8892 3.52595974 26 P 0 0;1=4
P 12.8892 3.47595974 26 P 0 0;1=4
P 12.8892 3.42595974 26 P 0 0;1=4
P 12.8892 3.92595974 26 P 0 0;1=4
P 12.8892 3.87595974 26 P 0 0;1=4
P 12.8892 3.82595974 26 P 0 0;1=4
P 12.8892 3.77595974 26 P 0 0;1=4
P 12.8892 3.72595974 26 P 0 0;1=4
P 12.8892 3.67595974 26 P 0 0;1=4
P 12.8892 4.17595974 26 P 0 0;1=4
P 12.8892 4.12595974 26 P 0 0;1=4
P 12.8892 4.07595974 26 P 0 0;1=4
P 12.8892 4.02595974 26 P 0 0;1=4
P 12.8892 3.97595974 26 P 0 0;1=4
P 12.8892 4.42595974 26 P 0 0;1=4
P 12.8892 4.37595974 26 P 0 0;1=4
P 12.8892 4.32595974 26 P 0 0;1=4
P 12.8892 4.27595974 26 P 0 0;1=4
P 12.8892 4.22595974 26 P 0 0;1=4
P 12.8892 4.67595974 26 P 0 0;1=4
P 12.8892 4.62595974 26 P 0 0;1=4
P 12.8892 4.57595974 26 P 0 0;1=4
P 12.8892 4.52595974 26 P 0 0;1=4
P 12.8892 4.47595974 26 P 0 0;1=4
P 12.8892 4.82595974 26 P 0 0;1=4
P 12.8892 4.77595974 26 P 0 0;1=4
P 12.8892 4.72595974 26 P 0 0;1=4
P 0.036 5.25868002 26 P 0 0;1=4
P 0.036 5.30868002 26 P 0 0;1=4
P 0.036 5.35868002 26 P 0 0;1=4
P 0.036 5.40868002 26 P 0 0;1=4
P 0.036 5.45868002 26 P 0 0;1=4
P 0.036 5.50868002 26 P 0 0;1=4
P 0.036 5.55868002 26 P 0 0;1=4
P 0.036 5.60868002 26 P 0 0;1=4
P 0.036 5.65868002 26 P 0 0;1=4
P 0.036 5.70868002 26 P 0 0;1=4
P 0.036 5.75868002 26 P 0 0;1=4
P 0.036 5.80868002 26 P 0 0;1=4
P 0.036 5.85868002 26 P 0 0;1=4
P 0.036 5.90868002 26 P 0 0;1=4
P 0.03826998 5.95863002 26 P 0 0;1=4
P 0.07901024 5.98761998 26 P 0 0;1=4
P 0.12901024 5.98761998 26 P 0 0;1=4
P 0.17901024 5.98761998 26 P 0 0;1=4
P 0.22901024 5.98761998 26 P 0 0;1=4
P 0.27901024 5.98761998 26 P 0 0;1=4
P 0.32901024 5.98761998 26 P 0 0;1=4
P 0.37901024 5.98761998 26 P 0 0;1=4
P 0.42901024 5.98761998 26 P 0 0;1=4
P 0.47901024 5.98761998 26 P 0 0;1=4
P 0.52901024 5.98761998 26 P 0 0;1=4
P 0.57901024 5.98761998 26 P 0 0;1=4
P 0.62901024 5.98761998 26 P 0 0;1=4
P 0.67901024 5.98761998 26 P 0 0;1=4
P 0.72901024 5.98761998 26 P 0 0;1=4
P 0.77901024 5.98761998 26 P 0 0;1=4
P 0.82901024 5.98761998 26 P 0 0;1=4
P 0.87901024 5.98761998 26 P 0 0;1=4
P 0.92901024 5.98761998 26 P 0 0;1=4
P 0.97901024 5.98761998 26 P 0 0;1=4
P 1.02901024 5.98761998 26 P 0 0;1=4
P 1.07901024 5.98761998 26 P 0 0;1=4
P 1.12901024 5.98761998 26 P 0 0;1=4
P 1.17901024 5.98761998 26 P 0 0;1=4
P 1.22901024 5.98761998 26 P 0 0;1=4
P 1.27901024 5.98761998 26 P 0 0;1=4
P 1.32901024 5.98761998 26 P 0 0;1=4
P 1.37901024 5.98761998 26 P 0 0;1=4
P 1.42901024 5.98761998 26 P 0 0;1=4
P 1.47901024 5.98761998 26 P 0 0;1=4
P 1.52901024 5.98761998 26 P 0 0;1=4
P 1.57901024 5.98761998 26 P 0 0;1=4
P 1.62901024 5.98761998 26 P 0 0;1=4
P 1.67901024 5.98761998 26 P 0 0;1=4
P 1.72901024 5.98761998 26 P 0 0;1=4
P 1.77901024 5.98761998 26 P 0 0;1=4
P 1.82901024 5.98761998 26 P 0 0;1=4
P 1.87901024 5.98761998 26 P 0 0;1=4
P 1.92901024 5.98761998 26 P 0 0;1=4
P 1.97901024 5.98761998 26 P 0 0;1=4
P 2.02901024 5.98761998 26 P 0 0;1=4
P 2.07901024 5.98761998 26 P 0 0;1=4
P 2.12901024 5.98761998 26 P 0 0;1=4
P 2.17901024 5.98761998 26 P 0 0;1=4
P 2.22901024 5.98761998 26 P 0 0;1=4
P 2.27901024 5.98761998 26 P 0 0;1=4
P 2.32901024 5.98761998 26 P 0 0;1=4
P 2.37901024 5.98761998 26 P 0 0;1=4
P 2.42901024 5.98761998 26 P 0 0;1=4
P 2.47901024 5.98761998 26 P 0 0;1=4
P 2.52901024 5.98761998 26 P 0 0;1=4
P 2.57901024 5.98761998 26 P 0 0;1=4
P 2.62901024 5.98761998 26 P 0 0;1=4
P 2.67901024 5.98761998 26 P 0 0;1=4
P 2.72901024 5.98761998 26 P 0 0;1=4
P 2.77901024 5.98761998 26 P 0 0;1=4
P 2.82901024 5.98761998 26 P 0 0;1=4
P 2.87901024 5.98761998 26 P 0 0;1=4
P 2.92901024 5.98761998 26 P 0 0;1=4
P 2.97901024 5.98761998 26 P 0 0;1=4
P 3.02901024 5.98761998 26 P 0 0;1=4
P 3.07901024 5.98761998 26 P 0 0;1=4
P 3.12901024 5.98761998 26 P 0 0;1=4
P 3.17901024 5.98761998 26 P 0 0;1=4
P 3.22901024 5.98761998 26 P 0 0;1=4
P 3.27901024 5.98761998 26 P 0 0;1=4
P 3.32901024 5.98761998 26 P 0 0;1=4
P 3.37901024 5.98761998 26 P 0 0;1=4
P 3.42901024 5.98761998 26 P 0 0;1=4
P 3.47901024 5.98761998 26 P 0 0;1=4
P 3.52901024 5.98761998 26 P 0 0;1=4
P 3.57901024 5.98761998 26 P 0 0;1=4
P 3.62901024 5.98761998 26 P 0 0;1=4
P 3.67901024 5.98761998 26 P 0 0;1=4
P 3.72901024 5.98761998 26 P 0 0;1=4
P 3.77901024 5.98761998 26 P 0 0;1=4
P 3.82901024 5.98761998 26 P 0 0;1=4
P 3.87901024 5.98761998 26 P 0 0;1=4
P 3.92901024 5.98761998 26 P 0 0;1=4
P 3.97901024 5.98761998 26 P 0 0;1=4
P 4.02901024 5.98761998 26 P 0 0;1=4
P 4.07901024 5.98761998 26 P 0 0;1=4
P 4.12901024 5.98761998 26 P 0 0;1=4
P 4.17901024 5.98761998 26 P 0 0;1=4
P 4.22901024 5.98761998 26 P 0 0;1=4
P 4.27901024 5.98761998 26 P 0 0;1=4
P 4.32901024 5.98761998 26 P 0 0;1=4
P 4.37901024 5.98761998 26 P 0 0;1=4
P 4.42901024 5.98761998 26 P 0 0;1=4
P 4.47901024 5.98761998 26 P 0 0;1=4
P 4.52901024 5.98761998 26 P 0 0;1=4
P 4.57901024 5.98761998 26 P 0 0;1=4
P 4.62901024 5.98761998 26 P 0 0;1=4
P 4.67901024 5.98761998 26 P 0 0;1=4
P 4.72901024 5.98761998 26 P 0 0;1=4
P 4.77901024 5.98761998 26 P 0 0;1=4
P 4.82901024 5.98761998 26 P 0 0;1=4
P 4.87901024 5.98761998 26 P 0 0;1=4
P 4.92901024 5.98761998 26 P 0 0;1=4
P 4.97901024 5.98761998 26 P 0 0;1=4
P 5.02901024 5.98761998 26 P 0 0;1=4
P 5.07901024 5.98761998 26 P 0 0;1=4
P 5.12901024 5.98761998 26 P 0 0;1=4
P 5.17901024 5.98761998 26 P 0 0;1=4
P 5.22901024 5.98761998 26 P 0 0;1=4
P 5.27901024 5.98761998 26 P 0 0;1=4
P 5.32901024 5.98761998 26 P 0 0;1=4
P 5.37901024 5.98761998 26 P 0 0;1=4
P 5.42901024 5.98761998 26 P 0 0;1=4
P 5.47901024 5.98761998 26 P 0 0;1=4
P 5.52901024 5.98761998 26 P 0 0;1=4
P 5.57901024 5.98761998 26 P 0 0;1=4
P 5.62901024 5.98761998 26 P 0 0;1=4
P 5.67901024 5.98761998 26 P 0 0;1=4
P 5.72901024 5.98761998 26 P 0 0;1=4
P 5.77901024 5.98761998 26 P 0 0;1=4
P 5.82901024 5.98761998 26 P 0 0;1=4
P 5.87901024 5.98761998 26 P 0 0;1=4
P 5.92901024 5.98761998 26 P 0 0;1=4
P 5.97901024 5.98761998 26 P 0 0;1=4
P 6.02901024 5.98761998 26 P 0 0;1=4
P 6.07901024 5.98761998 26 P 0 0;1=4
P 6.12901024 5.98761998 26 P 0 0;1=4
P 6.17901024 5.98761998 26 P 0 0;1=4
P 6.22901024 5.98761998 26 P 0 0;1=4
P 6.27901024 5.98761998 26 P 0 0;1=4
P 6.32901024 5.98761998 26 P 0 0;1=4
P 6.37901024 5.98761998 26 P 0 0;1=4
P 6.42901024 5.98761998 26 P 0 0;1=4
P 6.47901024 5.98761998 26 P 0 0;1=4
P 6.52901024 5.98761998 26 P 0 0;1=4
P 6.57901024 5.98761998 26 P 0 0;1=4
P 6.62901024 5.98761998 26 P 0 0;1=4
P 6.67901024 5.98761998 26 P 0 0;1=4
P 6.72901024 5.98761998 26 P 0 0;1=4
P 6.77901024 5.98761998 26 P 0 0;1=4
P 6.82901024 5.98761998 26 P 0 0;1=4
P 6.87901024 5.98761998 26 P 0 0;1=4
P 6.92901024 5.98761998 26 P 0 0;1=4
P 6.97901024 5.98761998 26 P 0 0;1=4
P 12.8892 5.47595974 26 P 0 0;1=4
P 12.8892 5.42595974 26 P 0 0;1=4
P 12.8892 5.37595974 26 P 0 0;1=4
P 12.8892 5.32595974 26 P 0 0;1=4
P 12.8892 5.27595974 26 P 0 0;1=4
P 12.8892 5.72595974 26 P 0 0;1=4
P 12.8892 5.67595974 26 P 0 0;1=4
P 12.8892 5.62595974 26 P 0 0;1=4
P 12.8892 5.57595974 26 P 0 0;1=4
P 12.8892 5.52595974 26 P 0 0;1=4
P 7.37901024 5.98761998 26 P 0 0;1=4
P 7.42901024 5.98761998 26 P 0 0;1=4
P 7.47901024 5.98761998 26 P 0 0;1=4
P 7.52901024 5.98761998 26 P 0 0;1=4
P 7.57901024 5.98761998 26 P 0 0;1=4
P 7.62901024 5.98761998 26 P 0 0;1=4
P 7.67901024 5.98761998 26 P 0 0;1=4
P 7.72901024 5.98761998 26 P 0 0;1=4
P 7.77901024 5.98761998 26 P 0 0;1=4
P 7.82901024 5.98761998 26 P 0 0;1=4
P 7.87901024 5.98761998 26 P 0 0;1=4
P 7.92901024 5.98761998 26 P 0 0;1=4
P 7.97901024 5.98761998 26 P 0 0;1=4
P 8.02901024 5.98761998 26 P 0 0;1=4
P 8.07901024 5.98761998 26 P 0 0;1=4
P 8.12901024 5.98761998 26 P 0 0;1=4
P 8.17901024 5.98761998 26 P 0 0;1=4
P 8.22901024 5.98761998 26 P 0 0;1=4
P 8.27901024 5.98761998 26 P 0 0;1=4
P 8.32901024 5.98761998 26 P 0 0;1=4
P 8.37901024 5.98761998 26 P 0 0;1=4
P 8.42901024 5.98761998 26 P 0 0;1=4
P 8.47901024 5.98761998 26 P 0 0;1=4
P 8.52901024 5.98761998 26 P 0 0;1=4
P 8.57901024 5.98761998 26 P 0 0;1=4
P 8.62901024 5.98761998 26 P 0 0;1=4
P 8.67901024 5.98761998 26 P 0 0;1=4
P 8.72901024 5.98761998 26 P 0 0;1=4
P 8.77901024 5.98761998 26 P 0 0;1=4
P 8.82901024 5.98761998 26 P 0 0;1=4
P 8.87901024 5.98761998 26 P 0 0;1=4
P 8.92901024 5.98761998 26 P 0 0;1=4
P 8.97901024 5.98761998 26 P 0 0;1=4
P 9.02901024 5.98761998 26 P 0 0;1=4
P 9.07901024 5.98761998 26 P 0 0;1=4
P 9.12901024 5.98761998 26 P 0 0;1=4
P 9.17901024 5.98761998 26 P 0 0;1=4
P 9.22901024 5.98761998 26 P 0 0;1=4
P 9.27901024 5.98761998 26 P 0 0;1=4
P 9.32901024 5.98761998 26 P 0 0;1=4
P 9.37901024 5.98761998 26 P 0 0;1=4
P 9.42901024 5.98761998 26 P 0 0;1=4
P 9.47901024 5.98761998 26 P 0 0;1=4
P 9.52901024 5.98761998 26 P 0 0;1=4
P 9.57901024 5.98761998 26 P 0 0;1=4
P 9.62901024 5.98761998 26 P 0 0;1=4
P 9.67901024 5.98761998 26 P 0 0;1=4
P 9.72901024 5.98761998 26 P 0 0;1=4
P 9.77901024 5.98761998 26 P 0 0;1=4
P 9.82901024 5.98761998 26 P 0 0;1=4
P 9.87901024 5.98761998 26 P 0 0;1=4
P 9.92901024 5.98761998 26 P 0 0;1=4
P 9.97901024 5.98761998 26 P 0 0;1=4
P 10.02901024 5.98761998 26 P 0 0;1=4
P 10.07901024 5.98761998 26 P 0 0;1=4
P 10.12901024 5.98761998 26 P 0 0;1=4
P 10.17901024 5.98761998 26 P 0 0;1=4
P 10.22901024 5.98761998 26 P 0 0;1=4
P 10.27901024 5.98761998 26 P 0 0;1=4
P 10.32901024 5.98761998 26 P 0 0;1=4
P 10.37901024 5.98761998 26 P 0 0;1=4
P 10.42901024 5.98761998 26 P 0 0;1=4
P 10.47901024 5.98761998 26 P 0 0;1=4
P 10.52901024 5.98761998 26 P 0 0;1=4
P 10.57901024 5.98761998 26 P 0 0;1=4
P 10.62901024 5.98761998 26 P 0 0;1=4
P 10.67901024 5.98761998 26 P 0 0;1=4
P 10.72901024 5.98761998 26 P 0 0;1=4
P 10.77901024 5.98761998 26 P 0 0;1=4
P 10.82901024 5.98761998 26 P 0 0;1=4
P 10.87901024 5.98761998 26 P 0 0;1=4
P 10.92901024 5.98761998 26 P 0 0;1=4
P 10.97901024 5.98761998 26 P 0 0;1=4
P 11.02901024 5.98761998 26 P 0 0;1=4
P 11.07901024 5.98761998 26 P 0 0;1=4
P 11.12901024 5.98761998 26 P 0 0;1=4
P 11.17901024 5.98761998 26 P 0 0;1=4
P 11.22901024 5.98761998 26 P 0 0;1=4
P 11.27901024 5.98761998 26 P 0 0;1=4
P 11.32901024 5.98761998 26 P 0 0;1=4
P 11.37901024 5.98761998 26 P 0 0;1=4
P 11.42901024 5.98761998 26 P 0 0;1=4
P 11.47901024 5.98761998 26 P 0 0;1=4
P 11.52901024 5.98761998 26 P 0 0;1=4
P 11.57901024 5.98761998 26 P 0 0;1=4
P 11.62901024 5.98761998 26 P 0 0;1=4
P 11.67901024 5.98761998 26 P 0 0;1=4
P 11.72901024 5.98761998 26 P 0 0;1=4
P 11.77901024 5.98761998 26 P 0 0;1=4
P 11.82901024 5.98761998 26 P 0 0;1=4
P 11.87901024 5.98761998 26 P 0 0;1=4
P 11.92901024 5.98761998 26 P 0 0;1=4
P 11.97901024 5.98761998 26 P 0 0;1=4
P 12.02901024 5.98761998 26 P 0 0;1=4
P 12.07901024 5.98761998 26 P 0 0;1=4
P 12.12901024 5.98761998 26 P 0 0;1=4
P 12.17901024 5.98761998 26 P 0 0;1=4
P 12.22901024 5.98761998 26 P 0 0;1=4
P 12.27901024 5.98761998 26 P 0 0;1=4
P 12.32901024 5.98761998 26 P 0 0;1=4
P 12.37901024 5.98761998 26 P 0 0;1=4
P 12.42901024 5.98761998 26 P 0 0;1=4
P 12.47901024 5.98761998 26 P 0 0;1=4
P 12.52901024 5.98761998 26 P 0 0;1=4
P 12.57901024 5.98761998 26 P 0 0;1=4
P 12.62901024 5.98761998 26 P 0 0;1=4
P 12.67901024 5.98761998 26 P 0 0;1=4
P 12.72901024 5.98761998 26 P 0 0;1=4
P 12.77901024 5.98761998 26 P 0 0;1=4
P 12.82901024 5.98761998 26 P 0 0;1=4
P 12.87725994 5.97451004 26 P 0 0;1=4
P 12.8892 5.92595974 26 P 0 0;1=4
P 12.8892 5.87595974 26 P 0 0;1=4
P 12.8892 5.82595974 26 P 0 0;1=4
P 12.8892 5.77595974 26 P 0 0;1=4
P 4.33605 4.9231 26 P 0 0;1=4
P 4.38105 4.9231 26 P 0 0;1=4
P 4.30105 4.9431 26 P 0 0;1=4
P 4.42105 4.9431 26 P 0 0;1=4
P 4.46105 4.9431 26 P 0 0;1=4
P 4.26105 4.9431 26 P 0 0;1=4
P 4.72605 4.9231 26 P 0 0;1=4
P 4.65105 4.9431 26 P 0 0;1=4
P 4.69105 4.9431 26 P 0 0;1=4
P 4.85105 4.9431 26 P 0 0;1=4
P 4.81105 4.9431 26 P 0 0;1=4
P 4.77105 4.9231 26 P 0 0;1=4
P 4.30105 5.0281 26 P 0 0;1=4
P 4.30105 5.0731 26 P 0 0;1=4
P 4.30105 4.9831 26 P 0 0;1=4
P 4.34105 5.1181 26 P 0 0;1=4
P 4.38105 5.1181 26 P 0 0;1=4
P 4.46105 5.1181 26 P 0 0;1=4
P 4.42105 5.1181 26 P 0 0;1=4
P 4.42105 4.9831 26 P 0 0;1=4
P 4.42105 5.0731 26 P 0 0;1=4
P 4.42105 5.0281 26 P 0 0;1=4
P 4.46105 4.9831 26 P 0 0;1=4
P 4.46105 5.0731 26 P 0 0;1=4
P 4.46105 5.0281 26 P 0 0;1=4
P 4.26105 5.0281 26 P 0 0;1=4
P 4.26105 5.0731 26 P 0 0;1=4
P 4.26105 4.9831 26 P 0 0;1=4
P 4.73105 5.1181 26 P 0 0;1=4
P 4.69105 5.1181 26 P 0 0;1=4
P 4.65105 5.1181 26 P 0 0;1=4
P 4.65105 4.9831 26 P 0 0;1=4
P 4.65105 5.0731 26 P 0 0;1=4
P 4.65105 5.0281 26 P 0 0;1=4
P 4.69105 4.9831 26 P 0 0;1=4
P 4.69105 5.0731 26 P 0 0;1=4
P 4.69105 5.0281 26 P 0 0;1=4
P 4.85105 5.0281 26 P 0 0;1=4
P 4.85105 5.0731 26 P 0 0;1=4
P 4.85105 4.9831 26 P 0 0;1=4
P 4.81105 5.0281 26 P 0 0;1=4
P 4.81105 5.0731 26 P 0 0;1=4
P 4.81105 4.9831 26 P 0 0;1=4
P 4.81105 5.1181 26 P 0 0;1=4
P 4.85105 5.1181 26 P 0 0;1=4
P 4.77105 5.1181 26 P 0 0;1=4
P 4.30105 5.1181 26 P 0 0;1=4
P 4.26105 5.1181 26 P 0 0;1=4
P 9.45795 0.36633002 26 P 0 0;1=4
P 6.62 4.645 26 P 0 0;1=4
P 6.62 4.61 26 P 0 0;1=4
P 6.605 4.77 26 P 0 0;1=4
P 6.315 4.9 26 P 0 0;1=4
P 6.315 4.865 26 P 0 0;1=4
P 6.315 4.82 26 P 0 0;1=4
P 6.315 4.785 26 P 0 0;1=4
P 6.315 4.705 26 P 0 0;1=4
P 6.315 4.74 26 P 0 0;1=4
P 6.315 4.66 26 P 0 0;1=4
P 6.315 4.625 26 P 0 0;1=4
P 1.51672972 5.78 26 P 0 0;1=4
P 1.12303002 5.46015974 26 P 0 0;1=4
P 1.20176998 5.46016004 26 P 0 0;1=4
P 1.51673002 5.46015974 26 P 0 0;1=4
P 1.36 5.355 26 P 0 0;1=4
P 1.41 5.355 26 P 0 0;1=4
P 1.46 5.355 26 P 0 0;1=4
P 1.305 5.885 26 P 0 0;1=4
P 1.355 5.885 26 P 0 0;1=4
P 1.405 5.885 26 P 0 0;1=4
P 1.455 5.885 26 P 0 0;1=4
P 0.705 5.355 26 P 0 0;1=4
P 0.7 5.267 26 P 0 0;1=0
P 0.73 5.175 26 P 0 0;1=4
P 1.03 5.065 26 P 0 0;1=4
P 1.28050994 5.46016004 26 P 0 0;1=4
P 12.215 4.915 26 P 0 0;1=4
P 12.055 4.915 26 P 0 0;1=4
P 10.465 5.245 26 P 0 0;1=4
P 10.465 5.165 26 P 0 0;1=4
P 11.7719 4.80998976 26 P 0 0;1=4
P 11.7719 4.85498976 26 P 0 0;1=4
P 11.7719 4.90498976 26 P 0 0;1=4
P 11.7719 4.94998976 26 P 0 0;1=4
P 11.9719 4.94998976 26 P 0 0;1=4
P 11.9719 4.80998976 26 P 0 0;1=4
P 11.9719 4.85498976 26 P 0 0;1=4
P 11.9719 4.90498976 26 P 0 0;1=4
P 11.9219 4.94998976 26 P 0 0;1=4
P 11.9219 4.80998976 26 P 0 0;1=4
P 11.8719 4.94998976 26 P 0 0;1=4
P 11.8719 4.80998976 26 P 0 0;1=4
P 11.8219 4.80998976 26 P 0 0;1=4
P 11.8219 4.94998976 26 P 0 0;1=4
P 11.69315974 2.6635 26 P 0 0;1=4
P 10.125 2.008 26 P 0 0;1=4
P 5.53530974 1.6642 26 P 0 0;1=4
P 5.53530974 1.7213 26 P 0 0;1=4
P 5.53530974 2.0802 26 P 0 0;1=4
P 5.53530974 1.9393 26 P 0 0;1=4
P 5.53530974 2.2156 26 P 0 0;1=4
P 5.53530974 2.4081 26 P 0 0;1=4
P 5.53530974 2.5473 26 P 0 0;1=4
P 2.86855 4.92 26 P 0 0;1=4
P 2.79767972 4.92 26 P 0 0;1=4
P 3.08113976 4.92 26 P 0 0;1=4
P 3.36460974 4.926 26 P 0 0;1=4
P 3.22287972 4.92 26 P 0 0;1=4
P 3.50633976 4.92 26 P 0 0;1=4
P 3.43546998 4.928 26 P 0 0;1=4
P 3.15398002 4.81401998 26 P 0 0;1=4
P 3.22288002 4.81401998 26 P 0 0;1=4
P 3.36461024 4.81401998 26 P 0 0;1=4
P 3.43547028 4.81401998 26 P 0 0;1=4
P 3.50634026 4.81401998 26 P 0 0;1=4
P 3.22287972 5.023 26 P 0 0;1=4
P 3.50633976 5.023 26 P 0 0;1=4
P 3.43546998 5.023 26 P 0 0;1=4
P 3.14 4.92 26 P 0 0;1=4
P 3.275 4.92 26 P 0 0;1=4
P 3.26 5.332 26 P 0 0;1=4
P 3.06792028 5.332 26 P 0 0;1=4
P 3.51176998 5.17874026 26 P 0 0;1=4
P 3.57176998 5.17874026 26 P 0 0;1=4
P 3.15743996 4.74418002 26 P 0 0;1=4
P 1.63307972 4.92 26 P 0 0;1=4
P 1.84567972 4.92 26 P 0 0;1=4
P 1.77480974 4.92 26 P 0 0;1=4
P 1.70395 4.92 26 P 0 0;1=4
P 2.12913976 4.92 26 P 0 0;1=4
P 2.05827972 4.92 26 P 0 0;1=4
P 1.98740974 4.92 26 P 0 0;1=4
P 1.91653976 4.92 26 P 0 0;1=4
P 2.34173976 4.92 26 P 0 0;1=4
P 2.27086998 4.92 26 P 0 0;1=4
P 2.20000974 4.926 26 P 0 0;1=4
P 2.34173976 4.81 26 P 0 0;1=4
P 2.27086998 4.81 26 P 0 0;1=4
P 2.20000974 4.81 26 P 0 0;1=4
P 1.63173002 4.81526998 26 P 0 0;1=4
P 1.7 4.812 26 P 0 0;1=4
P 1.84567972 4.81 26 P 0 0;1=4
P 1.776 4.812 26 P 0 0;1=4
P 2.12913976 4.81 26 P 0 0;1=4
P 1.99 4.81 26 P 0 0;1=4
P 1.92 4.81 26 P 0 0;1=4
P 2.40716998 5.15374026 26 P 0 0;1=4
P 2.34716998 5.15374026 26 P 0 0;1=4
P 10.58660974 2.16615 26 P 0 0;1=3
P 10.63660974 2.16615 26 P 0 0;1=3
P 10.63660974 2.21615 26 P 0 0;1=3
P 10.88660974 1.91615 26 P 0 0;1=3
P 10.88660974 2.41615 26 P 0 0;1=3
P 10.88660974 2.66615 26 P 0 0;1=3
P 11.03660974 2.41615 26 P 0 0;1=3
P 11.03660974 2.36615 26 P 0 0;1=3
P 1.91110994 4.61826004 26 P 0 0;1=4
P 2.40716998 4.70326004 26 P 0 0;1=4
P 2.945 4.92 26 P 0 0;1=4
P 3.01027972 4.92 26 P 0 0;1=4
P 7.78 2.4781 26 P 0 0;1=0
P 2.24606024 3.86615 26 P 0 0;1=3
P 2.49606024 3.86615 26 P 0 0;1=3
P 2.24606024 3.81615 26 P 0 0;1=3
P 2.19606024 3.76615 26 P 0 0;1=3
P 2.24606024 3.76615 26 P 0 0;1=3
P 2.29606024 3.76615 26 P 0 0;1=3
P 2.49606024 3.71615 26 P 0 0;1=3
P 2.49606024 3.56615 26 P 0 0;1=3
P 2.44606024 3.56615 26 P 0 0;1=3
P 2.39606024 3.56615 26 P 0 0;1=3
P 2.29606024 3.61615 26 P 0 0;1=3
P 2.24606024 3.71615 26 P 0 0;1=3
P 2.24606024 3.66615 26 P 0 0;1=3
P 2.24606024 3.61615 26 P 0 0;1=3
P 2.19606024 3.61615 26 P 0 0;1=3
P 2.19606024 3.56615 26 P 0 0;1=3
P 2.14606024 3.56615 26 P 0 0;1=3
P 2.04606024 3.56615 26 P 0 0;1=3
P 1.99605974 3.56615 26 P 0 0;1=3
P 2.04606024 3.51615 26 P 0 0;1=3
P 2.04605974 3.46615 26 P 0 0;1=3
P 2.19606024 3.51615 26 P 0 0;1=3
P 2.24606024 3.51615 26 P 0 0;1=3
P 2.29606024 3.51615 26 P 0 0;1=3
P 2.49606024 3.41615 26 P 0 0;1=3
P 2.44606024 3.36615 26 P 0 0;1=3
P 2.24606024 3.46615 26 P 0 0;1=3
P 2.24606024 3.41615 26 P 0 0;1=3
P 2.29606024 3.36615 26 P 0 0;1=3
P 2.24606024 3.36615 26 P 0 0;1=3
P 2.19606024 3.36615 26 P 0 0;1=3
P 1.99605974 3.41615 26 P 0 0;1=3
P 2.09606024 3.36615 26 P 0 0;1=3
P 2.24606024 3.31615 26 P 0 0;1=3
P 2.24606024 3.26615 26 P 0 0;1=3
P 2.29606024 3.21615 26 P 0 0;1=3
P 2.24606024 3.21615 26 P 0 0;1=3
P 2.19606024 3.21615 26 P 0 0;1=3
P 2.09606024 3.21615 26 P 0 0;1=3
P 2.14606024 3.16615 26 P 0 0;1=3
P 2.04606024 3.16615 26 P 0 0;1=3
P 2.24606024 3.16615 26 P 0 0;1=3
P 2.29606024 3.16615 26 P 0 0;1=3
P 2.34606024 3.21615 26 P 0 0;1=3
P 2.44606024 3.21615 26 P 0 0;1=3
P 2.49606024 3.21615 26 P 0 0;1=3
P 2.49606024 3.26615 26 P 0 0;1=3
P 2.49606024 3.16615 26 P 0 0;1=3
P 2.39606024 3.16615 26 P 0 0;1=3
P 2.29606024 3.06615 26 P 0 0;1=3
P 2.29606024 3.11615 26 P 0 0;1=3
P 2.29606024 2.96615 26 P 0 0;1=3
P 2.29606024 3.01615 26 P 0 0;1=3
P 2.24606024 3.06615 26 P 0 0;1=3
P 2.24606024 3.11615 26 P 0 0;1=3
P 2.24606024 2.96615 26 P 0 0;1=3
P 2.24606024 3.01615 26 P 0 0;1=3
P 2.34606024 2.86615 26 P 0 0;1=3
P 2.34606024 2.91615 26 P 0 0;1=3
P 2.29606024 2.76615 26 P 0 0;1=3
P 2.29606024 2.81615 26 P 0 0;1=3
P 2.24606024 2.76615 26 P 0 0;1=3
P 2.24606024 2.81615 26 P 0 0;1=3
P 2.19606024 2.81615 26 P 0 0;1=3
P 2.09606024 2.81615 26 P 0 0;1=3
P 2.09606024 2.86615 26 P 0 0;1=3
P 2.19606024 3.06615 26 P 0 0;1=3
P 2.14606024 3.01615 26 P 0 0;1=3
P 2.09606024 3.06615 26 P 0 0;1=3
P 2.04606024 3.01615 26 P 0 0;1=3
P 2.09606024 2.91615 26 P 0 0;1=3
P 2.14606024 2.86615 26 P 0 0;1=3
P 2.04606024 2.86615 26 P 0 0;1=3
P 2.19606024 2.91615 26 P 0 0;1=3
P 2.24606024 2.91615 26 P 0 0;1=3
P 2.29606024 2.91615 26 P 0 0;1=3
P 2.39606024 3.01615 26 P 0 0;1=3
P 2.34606024 3.06615 26 P 0 0;1=3
P 2.44606024 3.06615 26 P 0 0;1=3
P 2.49606024 3.01615 26 P 0 0;1=3
P 2.44606024 2.91615 26 P 0 0;1=3
P 2.44606024 2.86615 26 P 0 0;1=3
P 2.39606024 2.86615 26 P 0 0;1=3
P 2.34606024 2.81615 26 P 0 0;1=3
P 2.44606024 2.81615 26 P 0 0;1=3
P 2.49606024 2.86615 26 P 0 0;1=3
P 2.49606024 2.71615 26 P 0 0;1=3
P 2.44606024 2.66615 26 P 0 0;1=3
P 2.39606024 2.71615 26 P 0 0;1=3
P 2.34606024 2.66615 26 P 0 0;1=3
P 2.29606024 2.71615 26 P 0 0;1=3
P 2.29606024 2.66615 26 P 0 0;1=3
P 2.24606024 2.71615 26 P 0 0;1=3
P 2.24606024 2.66615 26 P 0 0;1=3
P 2.19606024 2.66615 26 P 0 0;1=3
P 2.14606024 2.71615 26 P 0 0;1=3
P 2.09606024 2.66615 26 P 0 0;1=3
P 2.04606024 2.71615 26 P 0 0;1=3
P 2.04606024 2.56615 26 P 0 0;1=3
P 2.04606024 2.51615 26 P 0 0;1=3
P 2.04606024 2.46615 26 P 0 0;1=3
P 2.09606024 2.51615 26 P 0 0;1=3
P 2.14606024 2.56615 26 P 0 0;1=3
P 2.24606024 2.61615 26 P 0 0;1=3
P 2.24606024 2.56615 26 P 0 0;1=3
P 2.29606024 2.61615 26 P 0 0;1=3
P 2.29606024 2.56615 26 P 0 0;1=3
P 2.34606024 2.51615 26 P 0 0;1=3
P 2.29606024 2.51615 26 P 0 0;1=3
P 2.24606024 2.51615 26 P 0 0;1=3
P 2.19606024 2.51615 26 P 0 0;1=3
P 2.14606024 2.46615 26 P 0 0;1=3
P 2.24606024 2.46615 26 P 0 0;1=3
P 2.29606024 2.46615 26 P 0 0;1=3
P 2.29606024 2.41615 26 P 0 0;1=3
P 2.24606024 2.41615 26 P 0 0;1=3
P 2.24606024 2.36615 26 P 0 0;1=3
P 2.19606024 2.36615 26 P 0 0;1=3
P 2.29606024 2.36615 26 P 0 0;1=3
P 2.39606024 2.46615 26 P 0 0;1=3
P 2.39606024 2.51615 26 P 0 0;1=3
P 2.39606024 2.56615 26 P 0 0;1=3
P 2.44606024 2.51615 26 P 0 0;1=3
P 2.49606024 2.56615 26 P 0 0;1=3
P 2.49606024 2.51615 26 P 0 0;1=3
P 2.49606024 2.46615 26 P 0 0;1=3
P 2.44606024 2.36615 26 P 0 0;1=3
P 2.49606024 2.31615 26 P 0 0;1=3
P 2.39606024 2.31615 26 P 0 0;1=3
P 2.34606024 2.36615 26 P 0 0;1=3
P 2.29606024 2.31615 26 P 0 0;1=3
P 2.24606024 2.31615 26 P 0 0;1=3
P 2.04606024 2.31615 26 P 0 0;1=3
P 2.04606024 2.16615 26 P 0 0;1=3
P 2.04606024 2.11615 26 P 0 0;1=3
P 2.04606024 1.96615 26 P 0 0;1=3
P 2.09606024 2.01615 26 P 0 0;1=3
P 2.14606024 1.96615 26 P 0 0;1=3
P 2.09606024 1.86615 26 P 0 0;1=3
P 2.19606024 1.86615 26 P 0 0;1=3
P 2.24606024 1.86615 26 P 0 0;1=3
P 2.29606024 1.86615 26 P 0 0;1=3
P 2.34606024 1.86615 26 P 0 0;1=3
P 2.24606024 1.91615 26 P 0 0;1=3
P 2.29606024 1.91615 26 P 0 0;1=3
P 2.24606024 1.96615 26 P 0 0;1=3
P 2.29606024 1.96615 26 P 0 0;1=3
P 2.19606024 2.01615 26 P 0 0;1=3
P 2.24606024 2.01615 26 P 0 0;1=3
P 2.29606024 2.01615 26 P 0 0;1=3
P 2.34606024 2.01615 26 P 0 0;1=3
P 2.39606024 1.96615 26 P 0 0;1=3
P 2.44606024 2.01615 26 P 0 0;1=3
P 2.49606024 1.96615 26 P 0 0;1=3
P 2.44606024 1.86615 26 P 0 0;1=3
P 2.49606024 2.11615 26 P 0 0;1=3
P 2.44606024 2.16615 26 P 0 0;1=3
P 2.49606024 2.16615 26 P 0 0;1=3
P 2.44606024 2.21615 26 P 0 0;1=3
P 2.39606024 2.16615 26 P 0 0;1=3
P 2.39606024 2.11615 26 P 0 0;1=3
P 2.34606024 2.16615 26 P 0 0;1=3
P 2.34606024 2.21615 26 P 0 0;1=3
P 2.29606024 2.21615 26 P 0 0;1=3
P 2.29606024 2.16615 26 P 0 0;1=3
P 2.29606024 2.06615 26 P 0 0;1=3
P 2.29606024 2.11615 26 P 0 0;1=3
P 2.24606024 2.11615 26 P 0 0;1=3
P 2.24606024 2.16615 26 P 0 0;1=3
P 2.24606024 2.06615 26 P 0 0;1=3
P 2.24606024 2.21615 26 P 0 0;1=3
P 2.29606024 2.26615 26 P 0 0;1=3
P 2.24606024 2.26615 26 P 0 0;1=3
P 2.19606024 2.21615 26 P 0 0;1=3
P 2.19606024 2.16615 26 P 0 0;1=3
P 2.14606024 2.11615 26 P 0 0;1=3
P 2.14606024 2.16615 26 P 0 0;1=3
P 2.09606024 2.21615 26 P 0 0;1=3
P 2.09606024 2.16615 26 P 0 0;1=3
P 2.09606024 2.36615 26 P 0 0;1=3
P 2.14606024 2.31615 26 P 0 0;1=3
P 1.99605974 2.71615 26 P 0 0;1=3
P 1.99605974 2.86615 26 P 0 0;1=3
P 2.04605974 2.81615 26 P 0 0;1=3
P 2.04605974 2.76615 26 P 0 0;1=3
P 3.29373976 5.023 26 P 0 0;1=4
P 2.14606024 3.26615 26 P 0 0;1=3
P 2.04606024 3.26615 26 P 0 0;1=3
P 2.04606024 3.21615 26 P 0 0;1=3
P 2.14606024 3.21615 26 P 0 0;1=3
P 2.39606024 3.21615 26 P 0 0;1=3
P 2.39606024 3.26615 26 P 0 0;1=3
P 2.29606024 3.26615 26 P 0 0;1=3
P 2.29606024 3.31615 26 P 0 0;1=3
P 2.34606024 3.36615 26 P 0 0;1=3
P 2.14606024 3.41615 26 P 0 0;1=3
P 2.09606024 3.61615 26 P 0 0;1=3
P 2.29606024 3.46615 26 P 0 0;1=3
P 2.29606024 3.41615 26 P 0 0;1=3
P 2.39606024 3.41615 26 P 0 0;1=3
P 2.34606024 3.51615 26 P 0 0;1=3
P 2.34606024 3.61615 26 P 0 0;1=3
P 2.34606024 3.56615 26 P 0 0;1=3
P 2.44606024 3.51615 26 P 0 0;1=3
P 2.44606024 3.61615 26 P 0 0;1=3
P 2.14606024 3.71615 26 P 0 0;1=3
P 2.04606024 3.71615 26 P 0 0;1=3
P 2.09606024 3.76615 26 P 0 0;1=3
P 2.14606024 3.86615 26 P 0 0;1=3
P 2.04606024 3.86615 26 P 0 0;1=3
P 2.29606024 3.71615 26 P 0 0;1=3
P 2.29606024 3.66615 26 P 0 0;1=3
P 2.39606024 3.71615 26 P 0 0;1=3
P 2.34606024 3.76615 26 P 0 0;1=3
P 2.29606024 3.81615 26 P 0 0;1=3
P 2.39606024 3.86615 26 P 0 0;1=3
P 2.29606024 3.86615 26 P 0 0;1=3
P 2.44606024 3.76615 26 P 0 0;1=3
P 2.19606024 2.86615 26 P 0 0;1=3
P 3.36460974 5.023 26 P 0 0;1=4
P 3.29374026 4.81401998 26 P 0 0;1=4
P 3.01028002 4.81401998 26 P 0 0;1=4
P 2.94141024 4.81401998 26 P 0 0;1=4
P 2.86555 4.81401998 26 P 0 0;1=4
P 2.79768002 4.81401998 26 P 0 0;1=4
P 3.15200974 5.023 26 P 0 0;1=4
P 3.08113976 5.023 26 P 0 0;1=4
P 3.01027972 5.023 26 P 0 0;1=4
P 2.93940974 5.023 26 P 0 0;1=4
P 2.86855 5.023 26 P 0 0;1=4
P 2.79767972 5.023 26 P 0 0;1=4
P 1.70395 5.023 26 P 0 0;1=4
P 1.63307972 5.023 26 P 0 0;1=4
P 1.77480974 5.023 26 P 0 0;1=4
P 1.91653976 5.023 26 P 0 0;1=4
P 1.84567972 5.023 26 P 0 0;1=4
P 1.98740974 5.023 26 P 0 0;1=4
P 2.05827972 5.023 26 P 0 0;1=4
P 2.12913976 5.023 26 P 0 0;1=4
P 2.20000974 5.023 26 P 0 0;1=4
P 2.27086998 5.023 26 P 0 0;1=4
P 2.34173976 5.023 26 P 0 0;1=4
P 1.56220974 5.023 26 P 0 0;1=4
P 1.56221024 4.81401998 26 P 0 0;1=4
P 2.06086998 4.81 26 P 0 0;1=4
P 2.41260974 5.023 26 P 0 0;1=4
P 2.41261024 4.81401998 26 P 0 0;1=4
P 2.72680974 5.023 26 P 0 0;1=4
P 2.72681024 4.81401998 26 P 0 0;1=4
P 3.57721024 4.81401998 26 P 0 0;1=4
P 3.57720974 5.023 26 P 0 0;1=4
P 4.88267972 1.91615 26 P 0 0;1=3
P 4.78267972 1.91615 26 P 0 0;1=3
P 5.03267972 2.36615 26 P 0 0;1=3
P 5.03267972 2.41615 26 P 0 0;1=3
P 4.88267972 3.66615 26 P 0 0;1=3
P 4.83267972 3.66615 26 P 0 0;1=3
P 5.03267972 3.66615 26 P 0 0;1=3
P 4.93267972 3.66615 26 P 0 0;1=3
P 4.98267972 3.66615 26 P 0 0;1=3
P 4.88267972 3.51615 26 P 0 0;1=3
P 4.83267972 3.51615 26 P 0 0;1=3
P 5.03267972 3.51615 26 P 0 0;1=3
P 4.93267972 3.51615 26 P 0 0;1=3
P 4.98267972 3.51615 26 P 0 0;1=3
P 4.88267972 3.81615 26 P 0 0;1=3
P 4.83267972 3.81615 26 P 0 0;1=3
P 4.93267972 3.81615 26 P 0 0;1=3
P 4.98267972 3.81615 26 P 0 0;1=3
P 4.88267972 3.36615 26 P 0 0;1=3
P 4.83267972 3.36615 26 P 0 0;1=3
P 5.03267972 3.36615 26 P 0 0;1=3
P 4.93267972 3.36615 26 P 0 0;1=3
P 4.98267972 3.36615 26 P 0 0;1=3
P 4.83267972 3.21615 26 P 0 0;1=3
P 4.88267972 3.21615 26 P 0 0;1=3
P 4.98267972 3.21615 26 P 0 0;1=3
P 4.93267972 3.21615 26 P 0 0;1=3
P 5.03267972 3.21615 26 P 0 0;1=3
P 4.83267972 3.06615 26 P 0 0;1=3
P 4.88267972 3.06615 26 P 0 0;1=3
P 4.98267972 3.06615 26 P 0 0;1=3
P 4.93267972 3.06615 26 P 0 0;1=3
P 5.03267972 3.06615 26 P 0 0;1=3
P 4.83267972 2.91615 26 P 0 0;1=3
P 4.88267972 2.91615 26 P 0 0;1=3
P 4.98267972 2.91615 26 P 0 0;1=3
P 4.93267972 2.91615 26 P 0 0;1=3
P 5.03267972 2.91615 26 P 0 0;1=3
P 4.78268002 2.51615 26 P 0 0;1=3
P 4.73268002 2.51615 26 P 0 0;1=3
P 4.68268002 2.51615 26 P 0 0;1=3
P 4.63268002 2.51615 26 P 0 0;1=3
P 4.58268002 2.51615 26 P 0 0;1=3
P 4.63268002 2.56615 26 P 0 0;1=3
P 4.73268002 2.56615 26 P 0 0;1=3
P 4.78268002 2.56615 26 P 0 0;1=3
P 4.78268002 2.61615 26 P 0 0;1=3
P 4.78268002 2.66615 26 P 0 0;1=3
P 4.68268002 2.66615 26 P 0 0;1=3
P 4.58268002 2.66615 26 P 0 0;1=3
P 4.73268002 2.71615 26 P 0 0;1=3
P 4.63268002 2.71615 26 P 0 0;1=3
P 4.63268002 2.76615 26 P 0 0;1=3
P 4.73268002 2.76615 26 P 0 0;1=3
P 4.78268002 2.76615 26 P 0 0;1=3
P 4.63267972 2.16615 26 P 0 0;1=3
P 4.78267972 2.16615 26 P 0 0;1=3
P 10.63660974 2.91615 26 P 0 0;1=3
P 10.58660974 2.91615 26 P 0 0;1=3
P 10.63660974 3.06615 26 P 0 0;1=3
P 10.58660974 3.06615 26 P 0 0;1=3
P 10.63660974 3.36615 26 P 0 0;1=3
P 10.58660974 3.36615 26 P 0 0;1=3
P 10.63660974 3.21615 26 P 0 0;1=3
P 10.58660974 3.21615 26 P 0 0;1=3
P 10.58660974 3.66615 26 P 0 0;1=3
P 10.63660974 3.51615 26 P 0 0;1=3
P 10.58660974 3.51615 26 P 0 0;1=3
P 10.63660974 3.81615 26 P 0 0;1=3
P 10.63660974 3.66615 26 P 0 0;1=3
P 10.58660974 3.81615 26 P 0 0;1=3
P 10.83660974 2.91615 26 P 0 0;1=3
P 10.78660974 2.91615 26 P 0 0;1=3
P 10.73660974 2.91615 26 P 0 0;1=3
P 10.68660974 2.91615 26 P 0 0;1=3
P 10.88660974 2.91615 26 P 0 0;1=3
P 10.88660974 3.06615 26 P 0 0;1=3
P 10.83660974 3.06615 26 P 0 0;1=3
P 10.78660974 3.06615 26 P 0 0;1=3
P 10.73660974 3.06615 26 P 0 0;1=3
P 10.68660974 3.06615 26 P 0 0;1=3
P 10.88660974 3.21615 26 P 0 0;1=3
P 10.83660974 3.21615 26 P 0 0;1=3
P 10.83660974 3.36615 26 P 0 0;1=3
P 10.88660974 3.36615 26 P 0 0;1=3
P 10.78660974 3.36615 26 P 0 0;1=3
P 10.73660974 3.36615 26 P 0 0;1=3
P 10.78660974 3.21615 26 P 0 0;1=3
P 10.73660974 3.21615 26 P 0 0;1=3
P 10.68660974 3.36615 26 P 0 0;1=3
P 10.68660974 3.21615 26 P 0 0;1=3
P 10.83660974 3.51615 26 P 0 0;1=3
P 10.88660974 3.51615 26 P 0 0;1=3
P 10.83660974 3.66615 26 P 0 0;1=3
P 10.78660974 3.66615 26 P 0 0;1=3
P 10.73660974 3.66615 26 P 0 0;1=3
P 10.68660974 3.66615 26 P 0 0;1=3
P 10.78660974 3.51615 26 P 0 0;1=3
P 10.73660974 3.51615 26 P 0 0;1=3
P 10.68660974 3.51615 26 P 0 0;1=3
P 10.83660974 3.81615 26 P 0 0;1=3
P 10.88660974 3.81615 26 P 0 0;1=3
P 10.88660974 3.66615 26 P 0 0;1=3
P 10.78660974 3.81615 26 P 0 0;1=3
P 10.73660974 3.81615 26 P 0 0;1=3
P 10.68660974 3.81615 26 P 0 0;1=3
P 11.03660974 2.91615 26 P 0 0;1=3
P 10.93660974 2.91615 26 P 0 0;1=3
P 10.98660974 2.91615 26 P 0 0;1=3
P 11.03660974 3.06615 26 P 0 0;1=3
P 10.93660974 3.06615 26 P 0 0;1=3
P 10.98660974 3.06615 26 P 0 0;1=3
P 11.03660974 3.21615 26 P 0 0;1=3
P 10.93660974 3.21615 26 P 0 0;1=3
P 10.98660974 3.21615 26 P 0 0;1=3
P 10.98660974 3.36615 26 P 0 0;1=3
P 10.93660974 3.36615 26 P 0 0;1=3
P 11.03660974 3.36615 26 P 0 0;1=3
P 10.98660974 3.51615 26 P 0 0;1=3
P 10.93660974 3.51615 26 P 0 0;1=3
P 11.03660974 3.51615 26 P 0 0;1=3
P 10.98660974 3.66615 26 P 0 0;1=3
P 10.93660974 3.66615 26 P 0 0;1=3
P 11.03660974 3.66615 26 P 0 0;1=3
P 10.98660974 3.81615 26 P 0 0;1=3
P 10.93660974 3.81615 26 P 0 0;1=3
P 3.07691024 4.81401998 26 P 0 0;1=4
P 8.1 1.86615 26 P 0 0;1=3
P 8.15 2.16615 26 P 0 0;1=3
P 8.15 2.11615 26 P 0 0;1=3
P 8.15 1.96615 26 P 0 0;1=3
P 8.1 2.01615 26 P 0 0;1=3
P 8.05 1.96615 26 P 0 0;1=3
P 8.05 2.11615 26 P 0 0;1=3
P 8.05 2.16615 26 P 0 0;1=3
P 8.15 2.31615 26 P 0 0;1=3
P 8.1 2.36615 26 P 0 0;1=3
P 8.1 2.16615 26 P 0 0;1=3
P 8.1 2.21615 26 P 0 0;1=3
P 8.05 2.31615 26 P 0 0;1=3
P 8.15 2.46615 26 P 0 0;1=3
P 8.15 2.56615 26 P 0 0;1=3
P 8.1 2.51615 26 P 0 0;1=3
P 8.05 2.46615 26 P 0 0;1=3
P 8.05 2.51615 26 P 0 0;1=3
P 8.05 2.56615 26 P 0 0;1=3
P 8.1 2.66615 26 P 0 0;1=3
P 8.05 2.76615 26 P 0 0;1=3
P 8.05 2.81615 26 P 0 0;1=3
P 8 2.86615 26 P 0 0;1=3
P 8 2.71615 26 P 0 0;1=3
P 8.05 2.71615 26 P 0 0;1=3
P 8.15 2.71615 26 P 0 0;1=3
P 8.05 2.86615 26 P 0 0;1=3
P 8.15 2.86615 26 P 0 0;1=3
P 8.1 2.91615 26 P 0 0;1=3
P 8.1 2.86615 26 P 0 0;1=3
P 8.1 2.81615 26 P 0 0;1=3
P 8.05 3.01615 26 P 0 0;1=3
P 8.1 3.06615 26 P 0 0;1=3
P 8.15 3.01615 26 P 0 0;1=3
P 8.15 3.16615 26 P 0 0;1=3
P 8.05 3.16615 26 P 0 0;1=3
P 8 3.41615 26 P 0 0;1=3
P 8.05 3.41615 26 P 0 0;1=3
P 8.1 3.36615 26 P 0 0;1=3
P 8.1 3.21615 26 P 0 0;1=3
P 8.15 3.56615 26 P 0 0;1=3
P 8.05 3.56615 26 P 0 0;1=3
P 8 3.56615 26 P 0 0;1=3
P 8.05 3.51615 26 P 0 0;1=3
P 8.05 3.46615 26 P 0 0;1=3
P 8.1 3.51615 26 P 0 0;1=3
P 8.35 1.86615 26 P 0 0;1=3
P 8.3 1.86615 26 P 0 0;1=3
P 8.25 1.86615 26 P 0 0;1=3
P 8.2 1.86615 26 P 0 0;1=3
P 8.25 2.06615 26 P 0 0;1=3
P 8.25 2.16615 26 P 0 0;1=3
P 8.25 2.11615 26 P 0 0;1=3
P 8.3 2.11615 26 P 0 0;1=3
P 8.3 2.06615 26 P 0 0;1=3
P 8.4 2.11615 26 P 0 0;1=3
P 8.4 2.16615 26 P 0 0;1=3
P 8.4 1.96615 26 P 0 0;1=3
P 8.35 2.01615 26 P 0 0;1=3
P 8.3 2.01615 26 P 0 0;1=3
P 8.25 2.01615 26 P 0 0;1=3
P 8.2 2.01615 26 P 0 0;1=3
P 8.3 1.96615 26 P 0 0;1=3
P 8.25 1.96615 26 P 0 0;1=3
P 8.3 1.91615 26 P 0 0;1=3
P 8.25 1.91615 26 P 0 0;1=3
P 8.2 2.16615 26 P 0 0;1=3
P 8.2 2.21615 26 P 0 0;1=3
P 8.25 2.26615 26 P 0 0;1=3
P 8.3 2.26615 26 P 0 0;1=3
P 8.25 2.21615 26 P 0 0;1=3
P 8.3 2.16615 26 P 0 0;1=3
P 8.3 2.21615 26 P 0 0;1=3
P 8.35 2.21615 26 P 0 0;1=3
P 8.35 2.16615 26 P 0 0;1=3
P 8.25 2.31615 26 P 0 0;1=3
P 8.3 2.31615 26 P 0 0;1=3
P 8.35 2.36615 26 P 0 0;1=3
P 8.4 2.31615 26 P 0 0;1=3
P 8.3 2.36615 26 P 0 0;1=3
P 8.2 2.36615 26 P 0 0;1=3
P 8.25 2.36615 26 P 0 0;1=3
P 8.25 2.41615 26 P 0 0;1=3
P 8.3 2.41615 26 P 0 0;1=3
P 8.4 2.56615 26 P 0 0;1=3
P 8.4 2.51615 26 P 0 0;1=3
P 8.4 2.46615 26 P 0 0;1=3
P 8.3 2.46615 26 P 0 0;1=3
P 8.25 2.46615 26 P 0 0;1=3
P 8.2 2.51615 26 P 0 0;1=3
P 8.25 2.51615 26 P 0 0;1=3
P 8.3 2.51615 26 P 0 0;1=3
P 8.35 2.51615 26 P 0 0;1=3
P 8.3 2.56615 26 P 0 0;1=3
P 8.3 2.61615 26 P 0 0;1=3
P 8.25 2.56615 26 P 0 0;1=3
P 8.25 2.61615 26 P 0 0;1=3
P 8.2 2.66615 26 P 0 0;1=3
P 8.25 2.66615 26 P 0 0;1=3
P 8.3 2.66615 26 P 0 0;1=3
P 8.35 2.66615 26 P 0 0;1=3
P 8.25 2.71615 26 P 0 0;1=3
P 8.3 2.71615 26 P 0 0;1=3
P 8.4 2.71615 26 P 0 0;1=3
P 8.35 2.81615 26 P 0 0;1=3
P 8.4 2.86615 26 P 0 0;1=3
P 8.3 2.91615 26 P 0 0;1=3
P 8.25 2.91615 26 P 0 0;1=3
P 8.2 2.91615 26 P 0 0;1=3
P 8.2 2.81615 26 P 0 0;1=3
P 8.25 2.81615 26 P 0 0;1=3
P 8.25 2.76615 26 P 0 0;1=3
P 8.3 2.81615 26 P 0 0;1=3
P 8.3 2.76615 26 P 0 0;1=3
P 8.35 2.91615 26 P 0 0;1=3
P 8.35 2.86615 26 P 0 0;1=3
P 8.35 3.06615 26 P 0 0;1=3
P 8.4 3.01615 26 P 0 0;1=3
P 8.2 3.06615 26 P 0 0;1=3
P 8.25 3.01615 26 P 0 0;1=3
P 8.25 2.96615 26 P 0 0;1=3
P 8.25 3.11615 26 P 0 0;1=3
P 8.25 3.06615 26 P 0 0;1=3
P 8.3 3.01615 26 P 0 0;1=3
P 8.3 2.96615 26 P 0 0;1=3
P 8.3 3.11615 26 P 0 0;1=3
P 8.3 3.06615 26 P 0 0;1=3
P 8.25 3.16615 26 P 0 0;1=3
P 8.3 3.16615 26 P 0 0;1=3
P 8.4 3.16615 26 P 0 0;1=3
P 8.25 3.41615 26 P 0 0;1=3
P 8.3 3.36615 26 P 0 0;1=3
P 8.25 3.36615 26 P 0 0;1=3
P 8.2 3.36615 26 P 0 0;1=3
P 8.25 3.31615 26 P 0 0;1=3
P 8.25 3.26615 26 P 0 0;1=3
P 8.3 3.21615 26 P 0 0;1=3
P 8.25 3.21615 26 P 0 0;1=3
P 8.2 3.21615 26 P 0 0;1=3
P 8.35 3.21615 26 P 0 0;1=3
P 8.4 3.56615 26 P 0 0;1=3
P 8.3 3.61615 26 P 0 0;1=3
P 8.25 3.66615 26 P 0 0;1=3
P 8.25 3.61615 26 P 0 0;1=3
P 8.2 3.61615 26 P 0 0;1=3
P 8.2 3.56615 26 P 0 0;1=3
P 8.2 3.51615 26 P 0 0;1=3
P 8.25 3.51615 26 P 0 0;1=3
P 8.3 3.51615 26 P 0 0;1=3
P 8.25 3.46615 26 P 0 0;1=3
P 8.25 3.86615 26 P 0 0;1=3
P 8.25 3.81615 26 P 0 0;1=3
P 8.2 3.76615 26 P 0 0;1=3
P 8.25 3.76615 26 P 0 0;1=3
P 8.3 3.76615 26 P 0 0;1=3
P 8.25 3.71615 26 P 0 0;1=3
P 8.45 1.86615 26 P 0 0;1=3
P 8.5 2.16615 26 P 0 0;1=3
P 8.5 2.11615 26 P 0 0;1=3
P 8.5 1.96615 26 P 0 0;1=3
P 8.45 2.01615 26 P 0 0;1=3
P 8.45 2.21615 26 P 0 0;1=3
P 8.45 2.16615 26 P 0 0;1=3
P 8.5 2.31615 26 P 0 0;1=3
P 8.45 2.36615 26 P 0 0;1=3
P 8.5 2.46615 26 P 0 0;1=3
P 8.5 2.51615 26 P 0 0;1=3
P 8.5 2.56615 26 P 0 0;1=3
P 8.45 2.51615 26 P 0 0;1=3
P 8.45 2.66615 26 P 0 0;1=3
P 8.5 2.71615 26 P 0 0;1=3
P 8.5 2.86615 26 P 0 0;1=3
P 8.45 2.81615 26 P 0 0;1=3
P 8.45 2.86615 26 P 0 0;1=3
P 8.45 2.91615 26 P 0 0;1=3
P 8.5 3.01615 26 P 0 0;1=3
P 8.45 3.06615 26 P 0 0;1=3
P 8.5 3.16615 26 P 0 0;1=3
P 8.5 3.41615 26 P 0 0;1=3
P 8.45 3.36615 26 P 0 0;1=3
P 8.45 3.21615 26 P 0 0;1=3
P 8.5 3.21615 26 P 0 0;1=3
P 8.5 3.26615 26 P 0 0;1=3
P 8.5 3.56615 26 P 0 0;1=3
P 8.45 3.56615 26 P 0 0;1=3
P 8.5 3.86615 26 P 0 0;1=3
P 8.5 3.71615 26 P 0 0;1=3
P 8.2 2.86615 26 P 0 0;1=3
P 8.05 3.26615 26 P 0 0;1=3
P 8.05 3.21615 26 P 0 0;1=3
P 8.3 3.26615 26 P 0 0;1=3
P 8.3 3.31615 26 P 0 0;1=3
P 8.35 3.36615 26 P 0 0;1=3
P 8.15 3.26615 26 P 0 0;1=3
P 8.15 3.21615 26 P 0 0;1=3
P 8.4 3.21615 26 P 0 0;1=3
P 8.4 3.26615 26 P 0 0;1=3
P 8.1 3.61615 26 P 0 0;1=3
P 8.3 3.46615 26 P 0 0;1=3
P 8.3 3.41615 26 P 0 0;1=3
P 8.35 3.51615 26 P 0 0;1=3
P 8.35 3.61615 26 P 0 0;1=3
P 8.35 3.56615 26 P 0 0;1=3
P 8.15 3.41615 26 P 0 0;1=3
P 8.45 3.51615 26 P 0 0;1=3
P 8.45 3.61615 26 P 0 0;1=3
P 8.4 3.41615 26 P 0 0;1=3
P 8.05 3.71615 26 P 0 0;1=3
P 8.1 3.76615 26 P 0 0;1=3
P 8.05 3.86615 26 P 0 0;1=3
P 8.3 3.71615 26 P 0 0;1=3
P 8.3 3.66615 26 P 0 0;1=3
P 8.35 3.76615 26 P 0 0;1=3
P 8.3 3.81615 26 P 0 0;1=3
P 8.3 3.86615 26 P 0 0;1=3
P 8.15 3.71615 26 P 0 0;1=3
P 8.15 3.86615 26 P 0 0;1=3
P 8.45 3.76615 26 P 0 0;1=3
P 8.4 3.71615 26 P 0 0;1=3
P 8.4 3.86615 26 P 0 0;1=3
P 3.28831004 4.68073996 26 P 0 0;1=4
P 3.22831004 4.68073996 26 P 0 0;1=4
P 3.50091004 4.62573996 26 P 0 0;1=4
P 3.44091004 4.62573996 26 P 0 0;1=4
P 7.56575 5.023 26 P 0 0;1=4
P 7.63661998 5.023 26 P 0 0;1=4
P 7.84921998 5.023 26 P 0 0;1=4
P 7.77835 5.023 26 P 0 0;1=4
P 7.70748976 5.023 26 P 0 0;1=4
P 7.92007972 5.023 26 P 0 0;1=4
P 8.06181998 5.023 26 P 0 0;1=4
P 8.13267972 5.023 26 P 0 0;1=4
P 7.99095 5.023 26 P 0 0;1=4
P 8.34527972 5.023 26 P 0 0;1=4
P 8.27440974 5.023 26 P 0 0;1=4
P 8.20355 5.023 26 P 0 0;1=4
P 8.41615 5.023 26 P 0 0;1=4
P 7.63661998 4.92 26 P 0 0;1=4
P 7.84921998 4.9207 26 P 0 0;1=4
P 7.70748976 4.9207 26 P 0 0;1=4
P 7.77835 4.9207 26 P 0 0;1=4
P 7.99095 4.9207 26 P 0 0;1=4
P 7.92007972 4.9207 26 P 0 0;1=4
P 8.06181998 4.9207 26 P 0 0;1=4
P 8.13267972 4.9207 26 P 0 0;1=4
P 8.27440974 4.9207 26 P 0 0;1=4
P 8.20355 4.9267 26 P 0 0;1=4
P 8.34527972 4.9207 26 P 0 0;1=4
P 7.63526998 4.81527028 26 P 0 0;1=4
P 7.84921998 4.81 26 P 0 0;1=4
P 7.77953976 4.812 26 P 0 0;1=4
P 7.70353976 4.812 26 P 0 0;1=4
P 8.13267972 4.81 26 P 0 0;1=4
P 8.06440974 4.81 26 P 0 0;1=4
P 7.99353976 4.81 26 P 0 0;1=4
P 7.92353976 4.81 26 P 0 0;1=4
P 8.27440974 4.81 26 P 0 0;1=4
P 8.34527972 4.81 26 P 0 0;1=4
P 8.20355 4.81 26 P 0 0;1=4
P 8.41615 4.81401998 26 P 0 0;1=4
P 8.86909026 4.81401998 26 P 0 0;1=4
P 8.73035 4.81401998 26 P 0 0;1=4
P 8.80122028 4.81401998 26 P 0 0;1=4
P 8.94495 4.81401998 26 P 0 0;1=4
P 9.08045 4.81401998 26 P 0 0;1=4
P 9.01382028 4.81401998 26 P 0 0;1=4
P 9.36815 4.81401998 26 P 0 0;1=4
P 9.29728002 4.81401998 26 P 0 0;1=4
P 9.22642028 4.81401998 26 P 0 0;1=4
P 9.15752028 4.81401998 26 P 0 0;1=4
P 9.43901024 4.81401998 26 P 0 0;1=4
P 9.50988002 4.81401998 26 P 0 0;1=4
P 9.58075 4.81401998 26 P 0 0;1=4
P 8.80121998 5.023 26 P 0 0;1=4
P 8.73035 5.023 26 P 0 0;1=4
P 8.87208976 5.023 26 P 0 0;1=4
P 9.08467972 5.023 26 P 0 0;1=4
P 9.01381998 5.023 26 P 0 0;1=4
P 8.94295 5.023 26 P 0 0;1=4
P 8.87208976 4.92 26 P 0 0;1=4
P 8.80121998 4.92 26 P 0 0;1=4
P 9.01381998 4.92 26 P 0 0;1=4
P 9.08467972 4.92 26 P 0 0;1=4
P 9.22641998 4.92 26 P 0 0;1=4
P 9.36815 4.926 26 P 0 0;1=4
P 9.50987972 4.92 26 P 0 0;1=4
P 9.43900974 4.928 26 P 0 0;1=4
P 9.36815 5.023 26 P 0 0;1=4
P 9.29727972 5.023 26 P 0 0;1=4
P 9.22641998 5.023 26 P 0 0;1=4
P 9.15555 5.023 26 P 0 0;1=4
P 9.50987972 5.023 26 P 0 0;1=4
P 9.43900974 5.023 26 P 0 0;1=4
P 9.58075 5.023 26 P 0 0;1=4
P 8.94853976 4.92 26 P 0 0;1=4
P 9.27853976 4.92 26 P 0 0;1=4
P 9.14353976 4.92 26 P 0 0;1=4
P 8.13811004 5.09223996 26 P 0 0;1=4
P 8.35071004 5.15373996 26 P 0 0;1=4
P 8.41071004 5.15373996 26 P 0 0;1=4
P 7.56575 4.81401998 26 P 0 0;1=4
P 8.88061998 4.70574026 26 P 0 0;1=4
P 2.45985 4.77875 28 P 0 0;1=9
P 1.51496998 4.77875 28 P 0 0;1=9
P 2.44016998 5.05826998 28 P 0 0;1=9
P 1.53465 5.05826998 28 P 0 0;1=9
P 3.60476998 4.77875 28 P 0 0;1=9
P 2.67956998 4.77875 28 P 0 0;1=9
P 3.60476998 5.05826998 28 P 0 0;1=9
P 2.69925 5.05826998 28 P 0 0;1=9
P 8.46338996 4.77875 28 P 0 0;1=9
P 7.51850994 4.77875 28 P 0 0;1=9
P 8.44370994 5.05826998 28 P 0 0;1=9
P 7.53818996 5.05826998 28 P 0 0;1=9
P 9.60830994 4.77875 28 P 0 0;1=9
P 8.68310994 4.77875 28 P 0 0;1=9
P 9.60830994 5.05826998 28 P 0 0;1=9
P 8.70278996 5.05826998 28 P 0 0;1=9
P 10.82676998 5.49685 29 P 0 2;1=10
P 10.99213002 5.49685 29 P 0 2;1=10
P 11.15748002 5.49685 29 P 0 2;1=10
P 11.32283996 5.49685 29 P 0 2;1=10
P 11.48818996 5.49685 29 P 0 2;1=10
P 11.65353996 5.49685 29 P 0 2;1=10
P 11.8189 5.49685 29 P 0 2;1=10
P 11.98425 5.49685 29 P 0 2;1=10
P 12.14961004 5.49685 29 P 0 2;1=11
P 10.83662028 1.37795 26 P 0 2;1=12
P 10.83661998 1.6378 26 P 0 2;1=12
P 8.25 1.6378 26 P 0 2;1=12
P 8.25 1.37795 26 P 0 2;1=12
P 6.96457008 1.39763996 26 P 0 2;1=12
P 6.96456998 1.65748002 26 P 0 2;1=12
P 6.96457028 4.0748 26 P 0 2;1=12
P 6.96456998 4.33465 26 P 0 2;1=12
P 8.25 4.09448976 26 P 0 2;1=12
P 8.25 4.35433002 26 P 0 2;1=12
P 10.83662008 4.09448996 26 P 0 2;1=12
P 10.83661998 4.35433002 26 P 0 2;1=12
P 12.12205 4.0748 26 P 0 2;1=12
P 12.12205 4.33465 26 P 0 2;1=12
P 12.12205 1.65748002 26 P 0 2;1=12
P 12.12205 1.39763976 26 P 0 2;1=12
P 11.99212972 4.20473002 26 P 0 2;1=4
P 12.03020522 4.11286004 26 P 0 2;1=4
P 12.03018002 4.2965747 26 P 0 2;1=4
P 12.21391998 4.11288524 26 P 0 2;1=4
P 12.25196998 4.20473002 26 P 0 2;1=4
P 12.21389469 4.2966 26 P 0 2;1=4
P 10.7067 4.22441024 26 P 0 2;1=4
P 10.7447752 4.13253996 26 P 0 2;1=4
P 10.74475 4.31625472 26 P 0 2;1=4
P 10.92848996 4.13256516 26 P 0 2;1=4
P 10.96653996 4.22441004 26 P 0 2;1=4
P 10.92846467 4.31628002 26 P 0 2;1=4
P 8.12007992 4.22441004 26 P 0 2;1=4
P 8.15815522 4.13253996 26 P 0 2;1=4
P 8.15813002 4.31625472 26 P 0 2;1=4
P 8.34186998 4.13256516 26 P 0 2;1=4
P 8.37991998 4.22441004 26 P 0 2;1=4
P 8.34184469 4.31628002 26 P 0 2;1=4
P 6.83465 4.20473002 26 P 0 2;1=4
P 6.8727252 4.11286004 26 P 0 2;1=4
P 6.8727 4.2965747 26 P 0 2;1=4
P 7.05643996 4.11288524 26 P 0 2;1=4
P 7.09448996 4.20473002 26 P 0 2;1=4
P 7.05641467 4.2966 26 P 0 2;1=4
P 6.83465 1.52756024 26 P 0 2;1=4
P 6.8727252 1.43568996 26 P 0 2;1=4
P 6.8727 1.61940472 26 P 0 2;1=4
P 7.05643996 1.43571516 26 P 0 2;1=4
P 7.09448996 1.52756004 26 P 0 2;1=4
P 7.05641467 1.61943002 26 P 0 2;1=4
P 8.15815522 1.416 26 P 0 2;1=4
P 8.12008002 1.50786998 26 P 0 2;1=4
P 8.15813002 1.5997247 26 P 0 2;1=4
P 8.34186998 1.4160252 26 P 0 2;1=4
P 8.34184469 1.59975 26 P 0 2;1=4
P 8.37992028 1.50786998 26 P 0 2;1=4
P 10.74475 1.5997247 26 P 0 2;1=4
P 10.92846467 1.59975 26 P 0 2;1=4
P 10.96654026 1.50786998 26 P 0 2;1=4
P 10.92848996 1.4160252 26 P 0 2;1=4
P 10.7447752 1.416 26 P 0 2;1=4
P 10.7067 1.50787028 26 P 0 2;1=4
P 12.2126 1.43700974 26 P 0 2;1=4
P 12.25196998 1.52756004 26 P 0 2;1=4
P 12.2126 1.61810974 26 P 0 2;1=4
P 12.0315 1.61810974 26 P 0 2;1=4
P 11.99213002 1.52755974 26 P 0 2;1=4
P 12.0315 1.43700974 26 P 0 2;1=4
P 4.83268002 1.37795 26 P 0 2;1=12
P 4.83267972 1.6378 26 P 0 2;1=12
P 2.24605974 1.6378 26 P 0 2;1=12
P 2.24606024 1.37795 26 P 0 2;1=12
P 0.96063002 1.39763976 26 P 0 2;1=12
P 0.96062972 1.65748002 26 P 0 2;1=12
P 0.96063002 4.0748 26 P 0 2;1=12
P 0.96062972 4.33465 26 P 0 2;1=12
P 2.24606004 4.09448996 26 P 0 2;1=12
P 2.24605974 4.35433002 26 P 0 2;1=12
P 4.83268002 4.09448976 26 P 0 2;1=12
P 4.83267972 4.35433002 26 P 0 2;1=12
P 6.11811024 4.0748 26 P 0 2;1=12
P 6.11810974 4.33465 26 P 0 2;1=12
P 6.11810974 1.65748002 26 P 0 2;1=12
P 6.11811004 1.39763996 26 P 0 2;1=12
P 5.98818976 4.20473002 26 P 0 2;1=4
P 6.02626516 4.11286004 26 P 0 2;1=4
P 6.02623996 4.2965747 26 P 0 2;1=4
P 6.20998002 4.11288524 26 P 0 2;1=4
P 6.24803002 4.20472972 26 P 0 2;1=4
P 6.20995472 4.2966 26 P 0 2;1=4
P 4.70275994 4.22441004 26 P 0 2;1=4
P 4.74083524 4.13253996 26 P 0 2;1=4
P 4.74081004 4.31625472 26 P 0 2;1=4
P 4.92455 4.13256516 26 P 0 2;1=4
P 4.9626 4.22440974 26 P 0 2;1=4
P 4.9245247 4.31628002 26 P 0 2;1=4
P 2.11613996 4.22441004 26 P 0 2;1=4
P 2.15421516 4.13253996 26 P 0 2;1=4
P 2.15418996 4.31625472 26 P 0 2;1=4
P 2.33793002 4.13256516 26 P 0 2;1=4
P 2.37598002 4.22440974 26 P 0 2;1=4
P 2.33790472 4.31628002 26 P 0 2;1=4
P 0.83070974 4.20473002 26 P 0 2;1=4
P 0.86878524 4.11286004 26 P 0 2;1=4
P 0.86876004 4.2965747 26 P 0 2;1=4
P 1.0525 4.11288524 26 P 0 2;1=4
P 1.09055 4.20472972 26 P 0 2;1=4
P 1.0524747 4.2966 26 P 0 2;1=4
P 0.83070994 1.52756004 26 P 0 2;1=4
P 0.86878524 1.43568996 26 P 0 2;1=4
P 0.86876004 1.61940472 26 P 0 2;1=4
P 1.0525 1.43571516 26 P 0 2;1=4
P 1.09055 1.52755974 26 P 0 2;1=4
P 1.0524747 1.61943002 26 P 0 2;1=4
P 2.15421516 1.416 26 P 0 2;1=4
P 2.11614006 1.50786998 26 P 0 2;1=4
P 2.15418996 1.5997247 26 P 0 2;1=4
P 2.33793002 1.4160252 26 P 0 2;1=4
P 2.33790472 1.59975 26 P 0 2;1=4
P 2.37598002 1.50786998 26 P 0 2;1=4
P 4.74081004 1.5997247 26 P 0 2;1=4
P 4.9245247 1.59975 26 P 0 2;1=4
P 4.9626 1.50786998 26 P 0 2;1=4
P 4.92455 1.4160252 26 P 0 2;1=4
P 4.74083524 1.416 26 P 0 2;1=4
P 4.70276004 1.50786998 26 P 0 2;1=4
P 6.20865994 1.43701004 26 P 0 2;1=4
P 6.24803002 1.52755974 26 P 0 2;1=4
P 6.20865994 1.61811004 26 P 0 2;1=4
P 6.02755994 1.61811004 26 P 0 2;1=4
P 5.98818996 1.52756004 26 P 0 2;1=4
P 6.02755994 1.43701004 26 P 0 2;1=4
P 12.59646998 0.8189 26 P 0 0;1=4
P 12.5571 0.72835 26 P 0 0;1=4
P 12.59646998 0.6378 26 P 0 0;1=4
P 12.68701998 0.59843002 26 P 0 0;1=12
P 12.77756998 0.6378 26 P 0 0;1=4
P 12.81693976 0.72835 26 P 0 0;1=4
P 12.77756998 0.8189 26 P 0 0;1=4
P 12.68701998 0.85827028 26 P 0 0;1=12
P 12.59646998 5.24803002 26 P 0 0;1=4
P 12.5571 5.15748002 26 P 0 0;1=4
P 12.59646998 5.06693002 26 P 0 0;1=4
P 12.68701998 5.02756004 26 P 0 0;1=12
P 12.77756998 5.06693002 26 P 0 0;1=4
P 12.81693976 5.15748002 26 P 0 0;1=4
P 12.77756998 5.24803002 26 P 0 0;1=4
P 12.68701998 5.2874 26 P 0 0;1=12
P 0.1319 5.20866024 26 P 0 0;1=4
P 0.09252992 5.11811004 26 P 0 0;1=4
P 0.1319 5.02756024 26 P 0 0;1=4
P 0.22245 4.98818976 26 P 0 0;1=12
P 0.313 5.02756024 26 P 0 0;1=4
P 0.35236998 5.11811024 26 P 0 0;1=4
P 0.313 5.20866024 26 P 0 0;1=4
P 0.22245 5.24803002 26 P 0 0;1=12
P 0.1319 0.77953002 26 P 0 0;1=4
P 0.09252972 0.68898002 26 P 0 0;1=4
P 0.1319 0.59843002 26 P 0 0;1=4
P 0.22245 0.55905974 26 P 0 0;1=12
P 0.313 0.59843002 26 P 0 0;1=4
P 0.35236998 0.68898002 26 P 0 0;1=4
P 0.313 0.77953002 26 P 0 0;1=4
P 0.22245 0.8189 26 P 0 0;1=12
P 10.80498996 5.56656004 26 P 0 0;1=4
P 10.84498996 5.56656004 26 P 0 0;1=4
P 10.80498996 5.42656004 26 P 0 0;1=4
P 10.84498996 5.42656004 26 P 0 0;1=4
P 11.01035 5.42656024 26 P 0 0;1=4
P 10.97035 5.42656024 26 P 0 0;1=4
P 11.01035 5.56656024 26 P 0 0;1=4
P 10.97035 5.56656024 26 P 0 0;1=4
P 11.17570994 5.42656004 26 P 0 0;1=4
P 11.13570994 5.42656004 26 P 0 0;1=4
P 11.17570994 5.56656004 26 P 0 0;1=4
P 11.13570994 5.56656004 26 P 0 0;1=4
P 11.34106998 5.42656024 26 P 0 0;1=4
P 11.30106998 5.42656024 26 P 0 0;1=4
P 11.34106998 5.56656024 26 P 0 0;1=4
P 11.30106998 5.56656024 26 P 0 0;1=4
P 11.50642992 5.42656004 26 P 0 0;1=4
P 11.46642992 5.42656004 26 P 0 0;1=4
P 11.50642992 5.56656004 26 P 0 0;1=4
P 11.46642992 5.56656004 26 P 0 0;1=4
P 11.67178996 5.42656004 26 P 0 0;1=4
P 11.63178996 5.42656004 26 P 0 0;1=4
P 11.67178996 5.56656004 26 P 0 0;1=4
P 11.63178996 5.56656004 26 P 0 0;1=4
P 11.83715 5.42656024 26 P 0 0;1=4
P 11.79715 5.42656024 26 P 0 0;1=4
P 11.83715 5.56656024 26 P 0 0;1=4
P 11.79715 5.56656024 26 P 0 0;1=4
P 12.00250994 5.42656004 26 P 0 0;1=4
P 11.96250994 5.42656004 26 P 0 0;1=4
P 12.00250994 5.56656004 26 P 0 0;1=4
P 11.96250994 5.56656004 26 P 0 0;1=4
P 12.16786998 5.42656024 26 P 0 0;1=4
P 12.12786998 5.42656024 26 P 0 0;1=4
P 12.16786998 5.56656024 26 P 0 0;1=4
P 12.12786998 5.56656024 26 P 0 0;1=4
P 7.32284006 0.23621998 26 P 0 0;1=4
P 7.28019518 0.33921998 26 P 0 0;1=4
P 7.17716998 0.38189026 26 P 0 0;1=13
P 7.28016998 0.13319469 26 P 0 0;1=4
P 7.17717028 0.09055 26 P 0 0;1=13
P 7.07414469 0.13321998 26 P 0 0;1=4
P 7.0315 0.23621998 26 P 0 0;1=4
P 7.07416998 0.33924518 26 P 0 0;1=4
P 7.32283976 5.7874 26 P 0 0;1=4
P 7.28019518 5.8904 26 P 0 0;1=4
P 7.17716998 5.93307028 26 P 0 0;1=13
P 7.28016998 5.6843747 26 P 0 0;1=4
P 7.17716998 5.64173002 26 P 0 0;1=13
P 7.07414469 5.6844 26 P 0 0;1=4
P 7.0315 5.7874 26 P 0 0;1=4
P 7.07416998 5.8904252 26 P 0 0;1=4
P 2.24606004 3.56615 7 P 0 0;1=3
P 8.2 3.26615 7 P 0 0;1=3
P 7.65203996 5.0535 7 P 0 0;1=3
P 2.29606004 2.86615 7 P 0 0;1=3
P 2.29606004 3.56615 7 P 0 0;1=3
P 7.69203996 5.0535 7 P 0 0;1=3
P 8.2 3.31615 7 P 0 0;1=3
P 1.33906004 4.69351004 6 P 0 0;1=0
P 0.80806998 5.46193996 6 P 0 0;1=0
P 3.733 5.075 6 P 0 0;1=4
P 1.28906004 4.69351004 6 P 0 0;1=0
P 8.2 3.41615 7 P 0 0;1=3
P 7.86465 5.169 7 P 0 0;1=3
P 3.94 4.765 6 P 0 0;1=0
P 2.34606004 3.26615 7 P 0 0;1=3
P 2.39716998 4.742 7 P 0 0;1=3
P 8.2 3.46615 7 P 0 0;1=3
P 7.90465 5.169 7 P 0 0;1=3
P 2.06646004 5.29 6 P 0 0;1=0
P 2.34606004 3.31615 7 P 0 0;1=3
P 2.35716998 4.742 7 P 0 0;1=3
P 1.33906004 5.15351004 6 P 0 0;1=0
P 3.105 4.47 6 P 0 0;1=4
P 8 3.46615 7 P 0 0;1=3
P 7.93551004 5.0535 7 P 0 0;1=3
P 2.00146004 5.29 6 P 0 0;1=0
P 2.25855 4.667 7 P 0 0;1=3
P 2.39606004 3.31615 7 P 0 0;1=3
P 1.18906004 5.15351004 6 P 0 0;1=0
P 3.07 4.42 6 P 0 0;1=4
P 8 3.51615 7 P 0 0;1=3
P 7.97551004 5.0535 7 P 0 0;1=3
P 2.21855 4.667 7 P 0 0;1=3
P 2.39606004 3.36615 7 P 0 0;1=3
P 8.11725 5.169 7 P 0 0;1=3
P 8.4 3.46615 7 P 0 0;1=3
P 3.635 0.715 6 P 0 0;1=0
P 4.63268002 2.81615 7 P 0 0;1=3
P 2.44606004 3.26615 7 P 0 0;1=3
P 2.39716998 5.115 7 P 0 0;1=3
P 8.07725 5.169 7 P 0 0;1=3
P 8.4 3.51615 7 P 0 0;1=3
P 2.44606004 3.31615 7 P 0 0;1=3
P 2.35716998 5.115 7 P 0 0;1=3
P 8.5 3.46615 7 P 0 0;1=3
P 8.07206998 4.66688996 7 P 0 0;1=3
P 2.25543996 4.78291998 7 P 0 0;1=3
P 2.49606004 3.31615 7 P 0 0;1=3
P 8.5 3.51615 7 P 0 0;1=3
P 8.03206998 4.66688996 7 P 0 0;1=3
P 4.02 4.42 6 P 0 0;1=0
P 4.58268002 2.76615 7 P 0 0;1=3
P 2.21543996 4.78291998 7 P 0 0;1=3
P 2.49606004 3.36615 7 P 0 0;1=3
P 8.35 3.41615 7 P 0 0;1=3
P 8.11725 4.78291998 7 P 0 0;1=3
P 4.78268002 2.71615 7 P 0 0;1=3
P 2.11371004 4.78291998 7 P 0 0;1=3
P 2.34606004 3.41615 7 P 0 0;1=3
P 8.35 3.46615 7 P 0 0;1=3
P 8.07725 4.78291998 7 P 0 0;1=3
P 5.08268002 2.71615 7 P 0 0;1=3
P 4.06 4.86 6 P 0 0;1=0
P 2.07371004 4.78291998 7 P 0 0;1=3
P 2.34606004 3.46615 7 P 0 0;1=3
P 2.18456998 5.0535 7 P 0 0;1=3
P 2.44606004 3.41615 7 P 0 0;1=3
P 10.93661004 2.41615 7 P 0 0;1=3
P 2.14456998 5.0535 7 P 0 0;1=3
P 2.44606004 3.46615 7 P 0 0;1=3
P 10.93661004 2.46615 7 P 0 0;1=3
P 8.5 3.31615 7 P 0 0;1=3
P 8.25898002 4.78291998 7 P 0 0;1=3
P 4.88268002 2.71615 7 P 0 0;1=3
P 2.06853002 4.66688996 7 P 0 0;1=3
P 2.49606004 3.46615 7 P 0 0;1=3
P 8.5 3.36615 7 P 0 0;1=3
P 8.21898002 4.78291998 7 P 0 0;1=3
P 2.02853002 4.66688996 7 P 0 0;1=3
P 2.49606004 3.51615 7 P 0 0;1=3
P 8.4 3.31615 7 P 0 0;1=3
P 8.26208996 4.667 7 P 0 0;1=3
P 2.11371004 5.169 7 P 0 0;1=3
P 2.39606004 3.46615 7 P 0 0;1=3
P 8.4 3.36615 7 P 0 0;1=3
P 8.22208996 4.667 7 P 0 0;1=3
P 3.84 0.69 6 P 0 0;1=0
P 4.68268002 2.76615 7 P 0 0;1=3
P 2.07371004 5.169 7 P 0 0;1=3
P 2.39606004 3.51615 7 P 0 0;1=3
P 3.56 0.49 6 P 0 0;1=0
P 4.73268002 2.81615 7 P 0 0;1=3
P 1.57765 5.169 7 P 0 0;1=3
P 2.04606004 3.31615 7 P 0 0;1=3
P 9.10853996 4.47 6 P 0 0;1=4
P 7.3426 5.15351004 6 P 0 0;1=0
P 3.785 0.69 6 P 0 0;1=0
P 4.78268002 2.81615 7 P 0 0;1=3
P 1.61765 5.169 7 P 0 0;1=3
P 2.04606004 3.36615 7 P 0 0;1=3
P 8.1 3.26615 7 P 0 0;1=3
P 7.58118996 4.707 7 P 0 0;1=3
P 2.09606004 3.26615 7 P 0 0;1=3
P 1.57765 4.707 7 P 0 0;1=3
P 5.08268002 1.96615 7 P 0 0;1=3
P 8.1 3.31615 7 P 0 0;1=3
P 7.62118996 4.707 7 P 0 0;1=3
P 3.75998996 0.345 6 P 0 0;1=0
P 4.68268002 2.81615 7 P 0 0;1=3
P 2.09606004 3.31615 7 P 0 0;1=3
P 1.61765 4.707 7 P 0 0;1=3
P 0.58 5.591 6 P 0 0;1=0
P 11.67761998 2.85 6 P 0 0;1=4
P 11.865 4.455 6 P 0 0;1=0
P 5.67368996 2.85 6 P 0 0;1=4
P 5.855 3.07 6 P 0 0;1=4
P 5.8522 2.97 6 P 0 0;1=4
P 7.2926 5.15351004 6 P 0 0;1=4
P 7.2426 5.15351004 6 P 0 0;1=4
P 7.1926 4.95351004 6 P 0 0;1=4
P 7.42603996 5.15895 6 P 0 0;1=0
P 3.94 4.655 6 P 0 0;1=4
P 3.77 4.765 6 P 0 0;1=4
P 4.14 4.745 6 P 0 0;1=4
P 4.76 5.375 6 P 0 0;1=4
P 4.96 5.5 6 P 0 0;1=4
P 5.16 5.555 6 P 0 0;1=4
P 4.892 5.767 6 P 0 0;1=4
P 5.088 5.767 6 P 0 0;1=4
P 0.91 5.075 6 P 0 0;1=4
P 1.03 4.96 6 P 0 0;1=4
P 1.03 5.155 6 P 0 0;1=4
P 1.38906004 5.15351004 6 P 0 0;1=0
P 1.23906004 5.15351004 6 P 0 0;1=4
P 1.28906004 5.15351004 6 P 0 0;1=4
P 1.18906004 4.95351004 6 P 0 0;1=4
P 0.83 5.355 6 P 0 0;1=4
P 0.9 5.355 6 P 0 0;1=4
P 0.755 5.355 6 P 0 0;1=4
P 0.73 5.205 6 P 0 0;1=4
P 0.81016004 5.17 6 P 0 0;1=4
P 1.094 5.356 6 P 0 0;1=0
P 1.044 5.448 6 P 0 0;1=4
P 1.4 5.46 6 P 0 0;1=4
P 1.32 5.46 6 P 0 0;1=4
P 1.43798996 5.46016004 6 P 0 0;1=4
P 1.35925 5.46016004 6 P 0 0;1=4
P 0.89 5.885 6 P 0 0;1=4
P 0.81 5.885 6 P 0 0;1=4
P 0.73 5.885 6 P 0 0;1=4
P 0.97 5.885 6 P 0 0;1=4
P 1.04 5.885 6 P 0 0;1=4
P 1.12 5.885 6 P 0 0;1=4
P 8.15 3.31615 7 P 0 0;1=3
P 7.65205 4.78291998 7 P 0 0;1=3
P 11.235 3.3 6 P 0 0;1=4
P 5.815 0.925 6 P 0 0;1=0
P 3.635 0.49 6 P 0 0;1=0
P 4.58268002 2.81615 7 P 0 0;1=3
P 2.19606004 3.26615 7 P 0 0;1=3
P 1.6485 5.0535 7 P 0 0;1=3
P 8.15 3.36615 7 P 0 0;1=3
P 7.69205 4.78291998 7 P 0 0;1=3
P 2.19606004 3.31615 7 P 0 0;1=3
P 1.6885 5.0535 7 P 0 0;1=3
P 8.1 3.41615 7 P 0 0;1=3
P 7.79378996 4.78291998 7 P 0 0;1=3
P 2.14606004 3.31615 7 P 0 0;1=3
P 1.64851004 4.78291998 7 P 0 0;1=3
P 8.1 3.46615 7 P 0 0;1=3
P 7.83378996 4.78291998 7 P 0 0;1=3
P 2.14606004 3.36615 7 P 0 0;1=3
P 1.68851004 4.78291998 7 P 0 0;1=3
P 0.73 4.96 6 P 0 0;1=0
P 3.795 4.6 6 P 0 0;1=4
P 4.86 5.375 6 P 0 0;1=4
P 8.15 3.46615 7 P 0 0;1=3
P 7.86465 4.657 7 P 0 0;1=3
P 2.09606004 3.41615 7 P 0 0;1=3
P 1.79025 4.78291998 7 P 0 0;1=3
P 8.15 3.51615 7 P 0 0;1=3
P 7.90465 4.657 7 P 0 0;1=3
P 2.09606004 3.46615 7 P 0 0;1=3
P 1.83025 4.78291998 7 P 0 0;1=3
P 2.19606004 3.41615 7 P 0 0;1=3
P 1.86111004 5.169 7 P 0 0;1=3
P 2.19606004 3.46615 7 P 0 0;1=3
P 1.90111004 5.169 7 P 0 0;1=3
P 6.72708996 4.5652 6 P 0 0;1=4
P 6.76208996 4.5652 6 P 0 0;1=4
P 6.79708996 4.5652 6 P 0 0;1=4
P 6.83708996 4.5652 6 P 0 0;1=0
P 6.90208996 4.5652 6 P 0 0;1=4
P 6.87208996 4.5652 6 P 0 0;1=4
P 10.99998996 4.9531 6 P 0 0;1=4
P 11.03998996 4.9531 6 P 0 0;1=4
P 10.99998996 4.9131 6 P 0 0;1=4
P 11.03998996 4.9131 6 P 0 0;1=4
P 11.21998996 4.9531 6 P 0 0;1=4
P 11.17998996 4.9531 6 P 0 0;1=4
P 11.13498996 4.9531 6 P 0 0;1=4
P 11.08498996 4.9531 6 P 0 0;1=4
P 11.21998996 4.9131 6 P 0 0;1=4
P 11.17998996 4.9131 6 P 0 0;1=4
P 11.08498996 4.9131 6 P 0 0;1=4
P 11.13498996 4.9131 6 P 0 0;1=4
P 10.99998996 5.1631 6 P 0 0;1=4
P 11.03998996 5.1631 6 P 0 0;1=4
P 10.99998996 5.1231 6 P 0 0;1=4
P 10.99998996 5.0381 6 P 0 0;1=4
P 10.99998996 5.0831 6 P 0 0;1=4
P 10.99998996 4.9931 6 P 0 0;1=4
P 11.03998996 4.9931 6 P 0 0;1=4
P 11.03998996 5.0831 6 P 0 0;1=4
P 11.03998996 5.0381 6 P 0 0;1=4
P 11.03998996 5.1231 6 P 0 0;1=4
P 11.21998996 5.1631 6 P 0 0;1=4
P 11.17998996 5.1631 6 P 0 0;1=4
P 11.08498996 5.1631 6 P 0 0;1=4
P 11.13498996 5.1631 6 P 0 0;1=4
P 11.21998996 5.1231 6 P 0 0;1=4
P 11.21998996 5.0381 6 P 0 0;1=4
P 11.21998996 5.0831 6 P 0 0;1=4
P 11.21998996 4.9931 6 P 0 0;1=4
P 11.17998996 4.9931 6 P 0 0;1=4
P 11.17998996 5.1231 6 P 0 0;1=4
P 11.17998996 5.0831 6 P 0 0;1=4
P 11.17998996 5.0381 6 P 0 0;1=4
P 11.13498996 5.1231 6 P 0 0;1=4
P 11.08498996 5.1231 6 P 0 0;1=4
P 11.6269 4.90498996 6 P 0 0;1=4
P 11.6269 4.85498996 6 P 0 0;1=4
P 11.4269 4.80998996 6 P 0 0;1=4
P 11.4269 4.85498996 6 P 0 0;1=4
P 11.4269 4.90498996 6 P 0 0;1=4
P 11.4269 4.94998996 6 P 0 0;1=4
P 11.4769 4.94998996 6 P 0 0;1=4
P 11.4769 4.80998996 6 P 0 0;1=4
P 11.5269 4.94998996 6 P 0 0;1=4
P 11.5269 4.80998996 6 P 0 0;1=4
P 11.5769 4.94998996 6 P 0 0;1=4
P 11.6269 4.94998996 6 P 0 0;1=4
P 11.6269 4.80998996 6 P 0 0;1=4
P 11.5769 4.80998996 6 P 0 0;1=4
P 10.82676998 5.71338996 14 P 0 0;1=10
P 10.99213002 5.71338996 14 P 0 0;1=10
P 11.15748002 5.71338996 14 P 0 0;1=10
P 11.32283996 5.71338996 14 P 0 0;1=10
P 11.48818996 5.71338996 14 P 0 0;1=10
P 11.65353996 5.71338996 14 P 0 0;1=10
P 11.8189 5.71338996 14 P 0 0;1=10
P 11.98425 5.71338996 14 P 0 0;1=10
P 12.14961004 5.71338996 14 P 0 0;1=10
P 10.80498996 5.7831 6 P 0 0;1=4
P 10.84498996 5.7831 6 P 0 0;1=4
P 10.80498996 5.6431 6 P 0 0;1=4
P 10.84498996 5.6431 6 P 0 0;1=4
P 11.01035 5.6431 6 P 0 0;1=4
P 10.97035 5.6431 6 P 0 0;1=4
P 11.01035 5.7831 6 P 0 0;1=4
P 10.97035 5.7831 6 P 0 0;1=4
P 11.17571004 5.6431 6 P 0 0;1=4
P 11.13571004 5.6431 6 P 0 0;1=4
P 11.17571004 5.7831 6 P 0 0;1=4
P 11.13571004 5.7831 6 P 0 0;1=4
P 11.34106998 5.6431 6 P 0 0;1=4
P 11.30106998 5.6431 6 P 0 0;1=4
P 11.34106998 5.7831 6 P 0 0;1=4
P 11.30106998 5.7831 6 P 0 0;1=4
P 11.50643002 5.6431 6 P 0 0;1=4
P 11.46643002 5.6431 6 P 0 0;1=4
P 11.50643002 5.7831 6 P 0 0;1=4
P 11.46643002 5.7831 6 P 0 0;1=4
P 11.67178996 5.6431 6 P 0 0;1=4
P 11.63178996 5.6431 6 P 0 0;1=4
P 11.67178996 5.7831 6 P 0 0;1=4
P 11.63178996 5.7831 6 P 0 0;1=4
P 11.83715 5.6431 6 P 0 0;1=4
P 11.79715 5.6431 6 P 0 0;1=4
P 11.83715 5.7831 6 P 0 0;1=4
P 11.79715 5.7831 6 P 0 0;1=4
P 12.00251004 5.6431 6 P 0 0;1=4
P 11.96251004 5.6431 6 P 0 0;1=4
P 12.00251004 5.7831 6 P 0 0;1=4
P 11.96251004 5.7831 6 P 0 0;1=4
P 12.16786998 5.6431 6 P 0 0;1=4
P 12.12786998 5.6431 6 P 0 0;1=4
P 12.16786998 5.7831 6 P 0 0;1=4
P 12.12786998 5.7831 6 P 0 0;1=4
P 5.03605 5.1631 6 P 0 0;1=4
P 5.03605 4.9931 6 P 0 0;1=4
P 5.03605 5.0831 6 P 0 0;1=4
P 5.03605 5.0381 6 P 0 0;1=4
P 5.03605 5.1231 6 P 0 0;1=4
P 5.21605 5.1631 6 P 0 0;1=4
P 5.17605 5.1631 6 P 0 0;1=4
P 5.08105 5.1631 6 P 0 0;1=4
P 5.13105 5.1631 6 P 0 0;1=4
P 5.21605 5.1231 6 P 0 0;1=4
P 5.21605 5.0381 6 P 0 0;1=4
P 5.21605 5.0831 6 P 0 0;1=4
P 5.21605 4.9931 6 P 0 0;1=4
P 5.17605 4.9931 6 P 0 0;1=4
P 5.17605 5.1231 6 P 0 0;1=4
P 5.17605 5.0831 6 P 0 0;1=4
P 5.17605 5.0381 6 P 0 0;1=4
P 5.13105 5.1231 6 P 0 0;1=4
P 5.08105 5.1231 6 P 0 0;1=4
P 4.99605 5.1631 6 P 0 0;1=4
P 4.99605 5.1231 6 P 0 0;1=4
P 4.99605 5.0381 6 P 0 0;1=4
P 4.99605 5.0831 6 P 0 0;1=4
P 4.99605 4.9931 6 P 0 0;1=4
P 5.03605 4.9531 6 P 0 0;1=4
P 5.03605 4.9131 6 P 0 0;1=4
P 5.21605 4.9531 6 P 0 0;1=4
P 5.17605 4.9531 6 P 0 0;1=4
P 5.13105 4.9531 6 P 0 0;1=4
P 5.08105 4.9531 6 P 0 0;1=4
P 5.21605 4.9131 6 P 0 0;1=4
P 5.17605 4.9131 6 P 0 0;1=4
P 5.08105 4.9131 6 P 0 0;1=4
P 5.13105 4.9131 6 P 0 0;1=4
P 4.99605 4.9531 6 P 0 0;1=4
P 4.99605 4.9131 6 P 0 0;1=4
P 6.34948996 5.03 6 P 0 0;1=4
P 2.74225 5.14 7 P 0 0;1=3
P 2.04606004 3.61615 7 P 0 0;1=3
P 2.14606004 3.46615 7 P 0 0;1=3
P 1.86111004 4.657 7 P 0 0;1=3
P 2.78225 5.14 7 P 0 0;1=3
P 2.04606004 3.66615 7 P 0 0;1=3
P 2.14606004 3.51615 7 P 0 0;1=3
P 1.90111004 4.657 7 P 0 0;1=3
P 1.93196998 5.0535 7 P 0 0;1=3
P 1.99606004 3.46615 7 P 0 0;1=3
P 4.58268002 2.56615 7 P 0 0;1=3
P 1.97196998 5.0535 7 P 0 0;1=3
P 1.99606004 3.51615 7 P 0 0;1=3
P 2.88086998 5.17001998 7 P 0 0;1=3
P 2.14606004 3.61615 7 P 0 0;1=3
P 2.34606004 3.66615 7 P 0 0;1=3
P 3.56176998 4.71973002 7 P 0 0;1=3
P 2.92086998 5.17001998 7 P 0 0;1=3
P 2.14606004 3.66615 7 P 0 0;1=3
P 2.34606004 3.71615 7 P 0 0;1=3
P 3.52176998 4.71973002 7 P 0 0;1=3
P 2.39606004 3.61615 7 P 0 0;1=3
P 3.49091004 4.587 7 P 0 0;1=3
P 2.39606004 3.66615 7 P 0 0;1=3
P 3.45091004 4.587 7 P 0 0;1=3
P 2.49606004 3.61615 7 P 0 0;1=3
P 3.56176998 5.14 7 P 0 0;1=3
P 2.49606004 3.66615 7 P 0 0;1=3
P 3.52176998 5.14 7 P 0 0;1=3
P 2.44606004 3.66615 7 P 0 0;1=3
P 3.42003996 4.78291998 7 P 0 0;1=3
P 4.30605 4.6631 6 P 0 0;1=4
P 4.34105 4.6431 6 P 0 0;1=4
P 4.38605 4.6431 6 P 0 0;1=4
P 4.42605 4.6631 6 P 0 0;1=4
P 4.46605 4.6631 6 P 0 0;1=4
P 4.30605 4.7031 6 P 0 0;1=4
P 4.42605 4.7031 6 P 0 0;1=4
P 4.46605 4.7031 6 P 0 0;1=4
P 4.26605 4.6631 6 P 0 0;1=4
P 4.26605 4.7031 6 P 0 0;1=4
P 4.65605 4.6631 6 P 0 0;1=4
P 4.69605 4.6631 6 P 0 0;1=4
P 4.65605 4.7031 6 P 0 0;1=4
P 4.69605 4.7031 6 P 0 0;1=4
P 4.73105 4.6431 6 P 0 0;1=4
P 4.81605 4.6631 6 P 0 0;1=4
P 4.85605 4.6631 6 P 0 0;1=4
P 4.81605 4.7031 6 P 0 0;1=4
P 4.85605 4.7031 6 P 0 0;1=4
P 4.77605 4.6431 6 P 0 0;1=4
P 5.17605 4.7131 6 P 0 0;1=4
P 5.17605 4.6731 6 P 0 0;1=4
P 5.08105 4.6731 6 P 0 0;1=4
P 5.13105 4.6731 6 P 0 0;1=4
P 5.03605 4.6731 6 P 0 0;1=4
P 5.03605 4.7131 6 P 0 0;1=4
P 4.30605 4.7481 6 P 0 0;1=4
P 4.30605 4.7931 6 P 0 0;1=4
P 4.30605 4.8381 6 P 0 0;1=4
P 4.38605 4.8381 6 P 0 0;1=4
P 4.34605 4.8381 6 P 0 0;1=4
P 4.46605 4.8381 6 P 0 0;1=4
P 4.42605 4.8381 6 P 0 0;1=4
P 4.42605 4.7931 6 P 0 0;1=4
P 4.42605 4.7481 6 P 0 0;1=4
P 4.46605 4.7931 6 P 0 0;1=4
P 4.46605 4.7481 6 P 0 0;1=4
P 4.26605 4.7481 6 P 0 0;1=4
P 4.26605 4.7931 6 P 0 0;1=4
P 4.26605 4.8381 6 P 0 0;1=4
P 4.65605 4.8381 6 P 0 0;1=4
P 4.65605 4.7931 6 P 0 0;1=4
P 4.65605 4.7481 6 P 0 0;1=4
P 4.69605 4.8381 6 P 0 0;1=4
P 4.69605 4.7931 6 P 0 0;1=4
P 4.69605 4.7481 6 P 0 0;1=4
P 4.73605 4.8381 6 P 0 0;1=4
P 4.81605 4.8381 6 P 0 0;1=4
P 4.81605 4.7931 6 P 0 0;1=4
P 4.81605 4.7481 6 P 0 0;1=4
P 4.85605 4.8381 6 P 0 0;1=4
P 4.85605 4.7931 6 P 0 0;1=4
P 4.85605 4.7481 6 P 0 0;1=4
P 4.77605 4.8381 6 P 0 0;1=4
P 5.08105 4.8431 6 P 0 0;1=4
P 5.13105 4.8431 6 P 0 0;1=4
P 5.17605 4.8431 6 P 0 0;1=4
P 5.17605 4.8031 6 P 0 0;1=4
P 5.17605 4.7581 6 P 0 0;1=4
P 5.03605 4.8431 6 P 0 0;1=4
P 5.03605 4.8031 6 P 0 0;1=4
P 5.03605 4.7581 6 P 0 0;1=4
P 4.58268002 2.96615 7 P 0 0;1=3
P 4.63268002 2.96615 7 P 0 0;1=3
P 4.63268002 3.11615 7 P 0 0;1=3
P 4.58268002 3.01615 7 P 0 0;1=3
P 4.58268002 3.11615 7 P 0 0;1=3
P 4.63268002 3.01615 7 P 0 0;1=3
P 4.63268002 3.31615 7 P 0 0;1=3
P 4.58268002 3.26615 7 P 0 0;1=3
P 4.58268002 3.31615 7 P 0 0;1=3
P 4.63268002 3.26615 7 P 0 0;1=3
P 4.63268002 3.16615 7 P 0 0;1=3
P 4.58268002 3.16615 7 P 0 0;1=3
P 4.58268002 3.46615 7 P 0 0;1=3
P 4.63268002 3.41615 7 P 0 0;1=3
P 4.63268002 3.46615 7 P 0 0;1=3
P 4.58268002 3.41615 7 P 0 0;1=3
P 4.58268002 3.61615 7 P 0 0;1=3
P 4.58268002 3.56615 7 P 0 0;1=3
P 4.63268002 3.61615 7 P 0 0;1=3
P 4.63268002 3.56615 7 P 0 0;1=3
P 4.58268002 3.71615 7 P 0 0;1=3
P 4.63268002 3.71615 7 P 0 0;1=3
P 4.58268002 3.76615 7 P 0 0;1=3
P 4.58268002 3.86615 7 P 0 0;1=3
P 4.63268002 3.76615 7 P 0 0;1=3
P 4.63268002 3.86615 7 P 0 0;1=3
P 4.68268002 2.96615 7 P 0 0;1=3
P 4.73268002 2.96615 7 P 0 0;1=3
P 4.78268002 2.96615 7 P 0 0;1=3
P 4.68268002 3.11615 7 P 0 0;1=3
P 4.68268002 3.01615 7 P 0 0;1=3
P 4.73268002 3.11615 7 P 0 0;1=3
P 4.73268002 3.01615 7 P 0 0;1=3
P 4.78268002 3.11615 7 P 0 0;1=3
P 4.78268002 3.01615 7 P 0 0;1=3
P 4.73268002 3.31615 7 P 0 0;1=3
P 4.73268002 3.26615 7 P 0 0;1=3
P 4.68268002 3.26615 7 P 0 0;1=3
P 4.68268002 3.31615 7 P 0 0;1=3
P 4.78268002 3.26615 7 P 0 0;1=3
P 4.78268002 3.31615 7 P 0 0;1=3
P 4.73268002 3.16615 7 P 0 0;1=3
P 4.68268002 3.16615 7 P 0 0;1=3
P 4.78268002 3.16615 7 P 0 0;1=3
P 4.73268002 3.41615 7 P 0 0;1=3
P 4.68268002 3.41615 7 P 0 0;1=3
P 4.68268002 3.46615 7 P 0 0;1=3
P 4.73268002 3.46615 7 P 0 0;1=3
P 4.78268002 3.46615 7 P 0 0;1=3
P 4.78268002 3.41615 7 P 0 0;1=3
P 4.73268002 3.56615 7 P 0 0;1=3
P 4.73268002 3.61615 7 P 0 0;1=3
P 4.68268002 3.56615 7 P 0 0;1=3
P 4.68268002 3.61615 7 P 0 0;1=3
P 4.78268002 3.61615 7 P 0 0;1=3
P 4.78268002 3.56615 7 P 0 0;1=3
P 4.73268002 3.71615 7 P 0 0;1=3
P 4.68268002 3.71615 7 P 0 0;1=3
P 4.78268002 3.71615 7 P 0 0;1=3
P 4.73268002 3.76615 7 P 0 0;1=3
P 4.73268002 3.86615 7 P 0 0;1=3
P 4.68268002 3.76615 7 P 0 0;1=3
P 4.68268002 3.86615 7 P 0 0;1=3
P 4.78268002 3.76615 7 P 0 0;1=3
P 4.78268002 3.86615 7 P 0 0;1=3
P 4.88268002 3.86615 7 P 0 0;1=3
P 4.83268002 3.86615 7 P 0 0;1=3
P 5.03268002 3.86615 7 P 0 0;1=3
P 4.93268002 3.86615 7 P 0 0;1=3
P 4.98268002 3.86615 7 P 0 0;1=3
P 4.88268002 3.76615 7 P 0 0;1=3
P 4.83268002 3.76615 7 P 0 0;1=3
P 5.03268002 3.76615 7 P 0 0;1=3
P 4.93268002 3.76615 7 P 0 0;1=3
P 4.98268002 3.76615 7 P 0 0;1=3
P 4.88268002 3.71615 7 P 0 0;1=3
P 4.83268002 3.71615 7 P 0 0;1=3
P 5.03268002 3.71615 7 P 0 0;1=3
P 4.93268002 3.71615 7 P 0 0;1=3
P 4.98268002 3.71615 7 P 0 0;1=3
P 4.88268002 3.61615 7 P 0 0;1=3
P 4.83268002 3.61615 7 P 0 0;1=3
P 5.03268002 3.61615 7 P 0 0;1=3
P 4.93268002 3.61615 7 P 0 0;1=3
P 4.98268002 3.61615 7 P 0 0;1=3
P 4.88268002 3.56615 7 P 0 0;1=3
P 4.83268002 3.56615 7 P 0 0;1=3
P 5.03268002 3.56615 7 P 0 0;1=3
P 4.93268002 3.56615 7 P 0 0;1=3
P 4.98268002 3.56615 7 P 0 0;1=3
P 4.88268002 3.46615 7 P 0 0;1=3
P 4.83268002 3.46615 7 P 0 0;1=3
P 5.03268002 3.46615 7 P 0 0;1=3
P 4.93268002 3.46615 7 P 0 0;1=3
P 4.98268002 3.46615 7 P 0 0;1=3
P 4.88268002 3.41615 7 P 0 0;1=3
P 4.83268002 3.41615 7 P 0 0;1=3
P 5.03268002 3.41615 7 P 0 0;1=3
P 4.93268002 3.41615 7 P 0 0;1=3
P 4.98268002 3.41615 7 P 0 0;1=3
P 4.88268002 3.31615 7 P 0 0;1=3
P 4.83268002 3.31615 7 P 0 0;1=3
P 5.03268002 3.31615 7 P 0 0;1=3
P 4.93268002 3.31615 7 P 0 0;1=3
P 4.98268002 3.31615 7 P 0 0;1=3
P 4.83268002 3.26615 7 P 0 0;1=3
P 4.88268002 3.26615 7 P 0 0;1=3
P 4.98268002 3.26615 7 P 0 0;1=3
P 4.93268002 3.26615 7 P 0 0;1=3
P 5.03268002 3.26615 7 P 0 0;1=3
P 4.83268002 3.16615 7 P 0 0;1=3
P 4.88268002 3.16615 7 P 0 0;1=3
P 4.98268002 3.16615 7 P 0 0;1=3
P 4.93268002 3.16615 7 P 0 0;1=3
P 5.03268002 3.16615 7 P 0 0;1=3
P 4.83268002 3.11615 7 P 0 0;1=3
P 4.88268002 3.11615 7 P 0 0;1=3
P 4.98268002 3.11615 7 P 0 0;1=3
P 4.93268002 3.11615 7 P 0 0;1=3
P 5.03268002 3.11615 7 P 0 0;1=3
P 4.83268002 3.01615 7 P 0 0;1=3
P 4.88268002 3.01615 7 P 0 0;1=3
P 4.98268002 3.01615 7 P 0 0;1=3
P 4.93268002 3.01615 7 P 0 0;1=3
P 5.03268002 3.01615 7 P 0 0;1=3
P 4.83268002 2.96615 7 P 0 0;1=3
P 4.88268002 2.96615 7 P 0 0;1=3
P 4.98268002 2.96615 7 P 0 0;1=3
P 4.93268002 2.96615 7 P 0 0;1=3
P 5.03268002 2.96615 7 P 0 0;1=3
P 2.44606004 3.71615 7 P 0 0;1=3
P 3.38003996 4.78291998 7 P 0 0;1=3
P 2.19606004 3.81615 7 P 0 0;1=3
P 3.02571004 4.667 7 P 0 0;1=3
P 2.19606004 3.86615 7 P 0 0;1=3
P 3.06571004 4.667 7 P 0 0;1=3
P 3.27831004 4.642 7 P 0 0;1=3
P 2.39606004 3.76615 7 P 0 0;1=3
P 4.73268002 2.66615 7 P 0 0;1=3
P 10.73661004 2.66615 7 P 0 0;1=3
P 3.23831004 4.642 7 P 0 0;1=3
P 2.39606004 3.81615 7 P 0 0;1=3
P 5.03268002 2.61615 7 P 0 0;1=3
P 3.34916998 5.1035 7 P 0 0;1=3
P 2.49606004 3.76615 7 P 0 0;1=3
P 3.30916998 5.1035 7 P 0 0;1=3
P 2.49606004 3.81615 7 P 0 0;1=3
P 11.03661004 2.61615 7 P 0 0;1=3
P 2.74225 4.667 7 P 0 0;1=3
P 2.09606004 3.66615 7 P 0 0;1=3
P 2.44606004 3.81615 7 P 0 0;1=3
P 3.20743996 4.78291998 7 P 0 0;1=3
P 2.78225 4.667 7 P 0 0;1=3
P 2.09606004 3.71615 7 P 0 0;1=3
P 2.44606004 3.86615 7 P 0 0;1=3
P 3.16743996 4.78291998 7 P 0 0;1=3
P 2.34606004 3.81615 7 P 0 0;1=3
P 3.27831004 5.22001998 7 P 0 0;1=3
P 2.34606004 3.86615 7 P 0 0;1=3
P 3.23831004 5.22001998 7 P 0 0;1=3
P 4.63268002 2.61615 7 P 0 0;1=3
P 10.98661004 2.61615 7 P 0 0;1=3
P 2.19606004 3.66615 7 P 0 0;1=3
P 2.81311004 4.78291998 7 P 0 0;1=3
P 10.98661004 2.56615 7 P 0 0;1=3
P 2.19606004 3.71615 7 P 0 0;1=3
P 2.85311004 4.78291998 7 P 0 0;1=3
P 0.64808996 1.655 6 P 0 0;1=4
P 5.76 2.66 6 P 0 0;1=0
P 10.63661004 2.61615 7 P 0 0;1=3
P 2.09606004 3.81615 7 P 0 0;1=3
P 3.09656998 5.0535 7 P 0 0;1=3
P 2.09606004 3.86615 7 P 0 0;1=3
P 3.13656998 5.0535 7 P 0 0;1=3
P 2.88708002 4.667 7 P 0 0;1=3
P 2.04606004 3.76615 7 P 0 0;1=3
P 10.73661004 2.61615 7 P 0 0;1=3
P 2.92708002 4.667 7 P 0 0;1=3
P 2.04606004 3.81615 7 P 0 0;1=3
P 10.68661004 2.61615 7 P 0 0;1=3
P 5.03268002 2.46615 7 P 0 0;1=3
P 5.03268002 2.51615 7 P 0 0;1=3
P 11.08661004 2.56615 7 P 0 0;1=3
P 10.68661004 2.56615 7 P 0 0;1=3
P 9.175 5.255 6 P 0 0;1=0
P 4.73268002 2.61615 7 P 0 0;1=3
P 9.11853996 5.255 6 P 0 0;1=0
P 5.08268002 2.41615 7 P 0 0;1=3
P 10.93661004 2.66615 7 P 0 0;1=3
P 10.58661004 2.61615 7 P 0 0;1=3
P 8.15 3.76615 7 P 0 0;1=3
P 9.02925 5.165 7 P 0 0;1=3
P 4.98268002 2.21615 7 P 0 0;1=3
P 10.58661004 2.56615 7 P 0 0;1=3
P 8.15 3.81615 7 P 0 0;1=3
P 9.06925 5.165 7 P 0 0;1=3
P 11.03661004 2.66615 7 P 0 0;1=3
P 4.98268002 2.26615 7 P 0 0;1=3
P 10.93661004 2.61615 7 P 0 0;1=3
P 5.03268002 2.26615 7 P 0 0;1=3
P 11.08661004 2.61615 7 P 0 0;1=3
P 5.03268002 2.31615 7 P 0 0;1=3
P 10.63661004 2.66615 7 P 0 0;1=3
P 3.775 5.295 6 P 0 0;1=0
P 0.73 5.78 6 P 0 0;1=4
P 8.07 5.29 6 P 0 0;1=0
P 3.8399 4.765 6 P 0 0;1=0
P 0.81 5.78 6 P 0 0;1=4
P 8.005 5.29 6 P 0 0;1=0
P 11.08661004 1.91615 7 P 0 0;1=3
P 4.98268002 1.91615 7 P 0 0;1=3
P 4.98268002 1.96615 7 P 0 0;1=3
P 4.93268002 1.86615 7 P 0 0;1=3
P 4.93268002 1.91615 7 P 0 0;1=3
P 5.03268002 1.86615 7 P 0 0;1=3
P 5.08268002 1.91615 7 P 0 0;1=3
P 5.08268002 2.56615 7 P 0 0;1=3
P 8.15 2.51615 7 P 0 0;1=3
P 4.98268002 2.61615 7 P 0 0;1=3
P 10.68661004 2.71615 7 P 0 0;1=3
P 10.98661004 2.71615 7 P 0 0;1=3
P 10.78661004 2.71615 7 P 0 0;1=3
P 4.93268002 2.66615 7 P 0 0;1=3
P 10.88661004 2.71615 7 P 0 0;1=3
P 10.68661004 2.76615 7 P 0 0;1=3
P 9.64 0.71 6 P 0 0;1=0
P 10.58661004 2.81615 7 P 0 0;1=3
P 9.43296004 0.49133002 6 P 0 0;1=0
P 9.43296004 0.73633002 6 P 0 0;1=0
P 10.63661004 2.81615 7 P 0 0;1=3
P 4.68268002 2.56615 7 P 0 0;1=3
P 10.68661004 2.81615 7 P 0 0;1=3
P 9.55795 0.36633002 6 P 0 0;1=0
P 10.73661004 2.81615 7 P 0 0;1=3
P 9.35796004 0.49133002 6 P 0 0;1=0
P 5.03268002 2.66615 7 P 0 0;1=3
P 10.78661004 2.81615 7 P 0 0;1=3
P 9.58296004 0.71133002 6 P 0 0;1=0
P 5.08268002 2.61615 7 P 0 0;1=3
P 11.08661004 1.96615 7 P 0 0;1=3
P 11.03661004 1.86615 7 P 0 0;1=3
P 11.03661004 1.91615 7 P 0 0;1=3
P 10.93661004 1.86615 7 P 0 0;1=3
P 10.93661004 1.91615 7 P 0 0;1=3
P 10.98661004 1.91615 7 P 0 0;1=3
P 10.98661004 1.96615 7 P 0 0;1=3
P 4.93268002 2.61615 7 P 0 0;1=3
P 11.03661004 2.01615 7 P 0 0;1=3
P 11.03661004 2.06615 7 P 0 0;1=3
P 10.93661004 2.01615 7 P 0 0;1=3
P 10.93661004 2.06615 7 P 0 0;1=3
P 10.98661004 2.06615 7 P 0 0;1=3
P 10.98661004 2.11615 7 P 0 0;1=3
P 11.08661004 2.06615 7 P 0 0;1=3
P 11.08661004 2.11615 7 P 0 0;1=3
P 3.115 5.255 6 P 0 0;1=0
P 4.63268002 2.66615 7 P 0 0;1=3
P 11.08661004 2.21615 7 P 0 0;1=3
P 4.98268002 2.56615 7 P 0 0;1=3
P 11.08661004 2.26615 7 P 0 0;1=3
P 11.03661004 2.26615 7 P 0 0;1=3
P 2.14606004 3.76615 7 P 0 0;1=3
P 3.02571004 5.165 7 P 0 0;1=3
P 11.03661004 2.31615 7 P 0 0;1=3
P 10.98661004 2.21615 7 P 0 0;1=3
P 10.98661004 2.26615 7 P 0 0;1=3
P 3.17146004 5.255 6 P 0 0;1=0
P 4.68268002 2.61615 7 P 0 0;1=3
P 10.93661004 2.26615 7 P 0 0;1=3
P 10.58661004 2.76615 7 P 0 0;1=3
P 4 5.29 6 P 0 0;1=0
P 10.93661004 2.31615 7 P 0 0;1=3
P 10.88661004 2.16615 7 P 0 0;1=3
P 10.73661004 1.91615 7 P 0 0;1=3
P 10.395 1.28555 7 P 0 0;1=3
P 12.81495 1.96456998 12 P 0 0;1=1
P 9.42358002 5.22001998 7 P 0 0;1=3
P 8.98115 2.825 7 P 0 0;1=3
P 4.58268002 2.61615 7 P 0 0;1=3
P 9.38358002 5.22001998 7 P 0 0;1=3
P 8.98115 2.865 7 P 0 0;1=3
P 2.14606004 3.81615 7 P 0 0;1=3
P 3.06571004 5.165 7 P 0 0;1=3
P 11.08661004 2.71615 7 P 0 0;1=3
P 3.985 4.88998996 6 P 0 0;1=0
P 11.73316004 2.652 7 P 0 0;1=3
P 12.55905 4.40551004 12 P 0 0;1=1
P 11.73316004 2.612 7 P 0 0;1=3
P 12.63778996 4.44488002 12 P 0 0;1=1
P 8.3 2.86615 7 P 0 0;1=3
P 4.83268002 2.16615 7 P 0 0;1=3
P 0.69348996 1.90611998 7 P 0 0;1=3
P 11.73316004 2.492 7 P 0 0;1=3
P 12.55905 4.24803002 12 P 0 0;1=1
P 4.88268002 2.16615 7 P 0 0;1=3
P 0.69348996 1.86611998 7 P 0 0;1=3
P 11.73316004 2.452 7 P 0 0;1=3
P 12.63778996 4.2874 12 P 0 0;1=1
P 8.25 2.86615 7 P 0 0;1=3
P 12.55905 3.93306998 12 P 0 0;1=1
P 11.73316004 2.332 7 P 0 0;1=3
P 12.63778996 3.97243996 12 P 0 0;1=1
P 11.73316004 2.292 7 P 0 0;1=3
P 10.83661004 2.16615 7 P 0 0;1=3
P 11.53316004 2.092 7 P 0 0;1=3
P 12.55905 3.77558996 12 P 0 0;1=1
P 11.53316004 2.052 7 P 0 0;1=3
P 12.63778996 3.81496004 12 P 0 0;1=1
P 12.81495 3.53936998 12 P 0 0;1=1
P 10.68661004 2.26615 7 P 0 0;1=3
P 9.975 2.3758 7 P 0 0;1=3
P 12.81495 3.38188996 12 P 0 0;1=1
P 10.73661004 2.31615 7 P 0 0;1=3
P 9.975 2.23955 7 P 0 0;1=3
P 12.81495 2.20078996 12 P 0 0;1=1
P 10.68661004 1.91615 7 P 0 0;1=3
P 10.42445 1.395 7 P 0 0;1=3
P 12.81495 2.75196998 12 P 0 0;1=1
P 10.73661004 2.01615 7 P 0 0;1=3
P 10.26025 1.82845 7 P 0 0;1=3
P 12.73621004 3.73621998 12 P 0 0;1=1
P 10.58661004 2.21615 7 P 0 0;1=3
P 10.09 2.26825 7 P 0 0;1=3
P 10.73661004 2.41615 7 P 0 0;1=3
P 10.09 2.69655 7 P 0 0;1=3
P 12.73621004 4.52361998 12 P 0 0;1=1
P 7.3426 4.69351004 6 P 0 0;1=0
P 11.73316004 1.532 7 P 0 0;1=3
P 12.55905 2.27953002 12 P 0 0;1=1
P 7.2926 4.69351004 6 P 0 0;1=0
P 12.73621004 3.57873996 12 P 0 0;1=1
P 10.68661004 2.21615 7 P 0 0;1=3
P 9.975 2.3358 7 P 0 0;1=3
P 12.73621004 3.42126004 12 P 0 0;1=1
P 10.73661004 2.26615 7 P 0 0;1=3
P 9.975 2.19955 7 P 0 0;1=3
P 11.73316004 2.172 7 P 0 0;1=3
P 12.55905 3.46063002 12 P 0 0;1=1
P 4.98268002 2.36615 7 P 0 0;1=3
P 10.73661004 1.86615 7 P 0 0;1=3
P 10.395 1.32555 7 P 0 0;1=3
P 12.73621004 2.00393996 12 P 0 0;1=1
P 11.73316004 2.132 7 P 0 0;1=3
P 12.63778996 3.5 12 P 0 0;1=1
P 3.38003996 5.22001998 7 P 0 0;1=3
P 2.97721004 2.865 7 P 0 0;1=3
P 4.98268002 2.41615 7 P 0 0;1=3
P 12.63778996 1.76771998 12 P 0 0;1=1
P 3.42003996 5.22001998 7 P 0 0;1=3
P 2.97721004 2.825 7 P 0 0;1=3
P 4.88268002 2.81615 7 P 0 0;1=3
P 4.93268002 2.81615 7 P 0 0;1=3
P 4.98268002 2.81615 7 P 0 0;1=3
P 5.03268002 2.81615 7 P 0 0;1=3
P 5.08268002 2.81615 7 P 0 0;1=3
P 11.03661004 2.81615 7 P 0 0;1=3
P 11.08661004 2.81615 7 P 0 0;1=3
P 10.98661004 2.81615 7 P 0 0;1=3
P 10.93661004 2.81615 7 P 0 0;1=3
P 10.88661004 2.81615 7 P 0 0;1=3
P 5.27886004 3.0214 6 P 0 0;1=4
P 5.27886004 3.0564 6 P 0 0;1=4
P 5.27886004 3.1014 6 P 0 0;1=4
P 5.27886004 3.1364 6 P 0 0;1=4
P 5.27886004 2.9764 6 P 0 0;1=4
P 5.27886004 2.9414 6 P 0 0;1=4
P 5.27886004 3.2614 6 P 0 0;1=4
P 5.27886004 3.2964 6 P 0 0;1=4
P 5.27886004 3.2164 6 P 0 0;1=4
P 5.27886004 3.1814 6 P 0 0;1=4
P 11.28278996 3.1814 6 P 0 0;1=4
P 11.28278996 3.2164 6 P 0 0;1=4
P 11.28278996 3.2964 6 P 0 0;1=4
P 11.28278996 3.2614 6 P 0 0;1=4
P 11.28278996 2.9414 6 P 0 0;1=4
P 11.28278996 2.9764 6 P 0 0;1=4
P 11.28278996 3.1364 6 P 0 0;1=4
P 11.28278996 3.1014 6 P 0 0;1=4
P 11.28278996 3.0564 6 P 0 0;1=4
P 11.28278996 3.0214 6 P 0 0;1=4
P 5.59708996 4.7302 6 P 0 0;1=4
P 5.57708996 4.6802 6 P 0 0;1=4
P 5.75708996 4.7302 6 P 0 0;1=4
P 5.83708996 4.7302 6 P 0 0;1=4
P 5.69708996 4.6802 6 P 0 0;1=4
P 5.73708996 4.6802 6 P 0 0;1=4
P 5.77708996 4.6802 6 P 0 0;1=4
P 5.81708996 4.6802 6 P 0 0;1=4
P 5.85708996 4.6802 6 P 0 0;1=4
P 5.67708996 4.7302 6 P 0 0;1=4
P 5.65708996 4.6802 6 P 0 0;1=4
P 5.61708996 4.6802 6 P 0 0;1=4
P 6.13708996 4.7602 6 P 0 0;1=4
P 6.09708996 4.6802 6 P 0 0;1=4
P 6.13708996 4.6402 6 P 0 0;1=4
P 6.13708996 4.6802 6 P 0 0;1=4
P 6.13708996 4.7202 6 P 0 0;1=4
P 5.91708996 4.7302 6 P 0 0;1=4
P 5.99708996 4.7302 6 P 0 0;1=4
P 6.07708996 4.7302 6 P 0 0;1=4
P 5.89708996 4.6802 6 P 0 0;1=4
P 5.93708996 4.6802 6 P 0 0;1=4
P 5.97708996 4.6802 6 P 0 0;1=4
P 6.01708996 4.6802 6 P 0 0;1=4
P 6.05708996 4.6802 6 P 0 0;1=4
P 5.59708996 4.7702 6 P 0 0;1=4
P 5.59708996 4.8102 6 P 0 0;1=4
P 5.75708996 4.8102 6 P 0 0;1=4
P 5.83708996 4.8102 6 P 0 0;1=4
P 5.75708996 4.7702 6 P 0 0;1=4
P 5.83708996 4.7702 6 P 0 0;1=4
P 5.67708996 4.8102 6 P 0 0;1=4
P 5.67708996 4.7702 6 P 0 0;1=4
P 6.13708996 4.9252 6 P 0 0;1=4
P 6.13708996 4.8402 6 P 0 0;1=4
P 6.13708996 4.8002 6 P 0 0;1=4
P 6.13708996 4.8852 6 P 0 0;1=4
P 5.91708996 4.8102 6 P 0 0;1=4
P 5.99708996 4.8102 6 P 0 0;1=4
P 5.91708996 4.7702 6 P 0 0;1=4
P 5.99708996 4.7702 6 P 0 0;1=4
P 6.07708996 4.8102 6 P 0 0;1=4
P 6.07708996 4.7702 6 P 0 0;1=4
P 4.93268002 2.26615 7 P 0 0;1=3
P 4.93268002 2.31615 7 P 0 0;1=3
P 5.08268002 2.36615 7 P 0 0;1=3
P 12.81495 3.22441004 12 P 0 0;1=1
P 10.68661004 2.06615 7 P 0 0;1=3
P 10.09 2.13095 7 P 0 0;1=3
P 10.63661004 2.31615 7 P 0 0;1=3
P 10.09 2.40335 7 P 0 0;1=3
P 12.81495 3.85433002 12 P 0 0;1=1
P 11.73316004 2.012 7 P 0 0;1=3
P 12.63778996 3.1063 12 P 0 0;1=1
P 11.73316004 1.972 7 P 0 0;1=3
P 12.55905 3.14566998 12 P 0 0;1=1
P 11.53316004 1.732 7 P 0 0;1=3
P 12.55905 2.98818996 12 P 0 0;1=1
P 12.81495 3.69685 12 P 0 0;1=1
P 10.58661004 2.26615 7 P 0 0;1=3
P 10.09 2.30825 7 P 0 0;1=3
P 11.53316004 1.772 7 P 0 0;1=3
P 12.63778996 2.94881998 12 P 0 0;1=1
P 12.81495 4.32676998 12 P 0 0;1=1
P 10.63661004 2.46615 7 P 0 0;1=3
P 9.975 2.62445 7 P 0 0;1=3
P 12.63778996 2.79133996 12 P 0 0;1=1
P 11.73316004 1.852 7 P 0 0;1=3
P 12.55905 2.83071004 12 P 0 0;1=1
P 11.73316004 1.812 7 P 0 0;1=3
P 10.73661004 2.46615 7 P 0 0;1=3
P 10.09 2.73655 7 P 0 0;1=3
P 12.81495 4.48425 12 P 0 0;1=1
P 10.63661004 2.26615 7 P 0 0;1=3
P 10.09 2.44335 7 P 0 0;1=3
P 12.73621004 3.8937 12 P 0 0;1=1
P 10.58661004 2.41615 7 P 0 0;1=3
P 9.975 2.5109 7 P 0 0;1=3
P 12.81495 4.16928996 12 P 0 0;1=1
P 1.025 -0.35 28 P 0 3;1=6
P 1.325 -0.35 28 P 0 3;1=6
P 1.175 -0.35 28 P 0 3;1=6
P 0.725 -0.35 28 P 0 3;1=6
P 0.875 -0.35 28 P 0 3;1=6
P 12.73621004 4.05118002 12 P 0 0;1=1
P 10.68661004 2.36615 7 P 0 0;1=3
P 10.09 2.53845 7 P 0 0;1=3
P 12.81495 2.35826998 12 P 0 0;1=1
P 10.63661004 1.86615 7 P 0 0;1=3
P 10.35543002 1.52156998 7 P 0 0;1=3
P 5.03268002 2.01615 7 P 0 0;1=3
P 5.08268002 2.21615 7 P 0 0;1=3
P 12.73621004 2.16141998 12 P 0 0;1=1
P 10.68661004 1.96615 7 P 0 0;1=3
P 10.46445 1.395 7 P 0 0;1=3
P 0.2 -0.293 20 P 0 0;1=14
P 12.27 0.29 20 P 0 0;1=14
P 0.66 0.29 20 P 0 0;1=14
P 0.2 5.82361998 20 P 0 0;1=14
P 12.81495 1.57086998 12 P 0 0;1=1
P 12.73621004 1.5315 12 P 0 0;1=1
P 12.63778996 2.7126 12 P 0 0;1=1
P 12.55905 2.67323002 12 P 0 0;1=1
P 12.55905 1.64961004 12 P 0 0;1=1
P 12.63778996 1.61023996 12 P 0 0;1=1
P 12.55905 1.57086998 12 P 0 0;1=1
P 12.63778996 1.5315 12 P 0 0;1=1
P 12.73621004 1.68898002 12 P 0 0;1=1
P 12.81495 1.64961004 12 P 0 0;1=1
P 12.63778996 1.68898002 12 P 0 0;1=1
P 12.55905 1.72835 12 P 0 0;1=1
P 12.81495 1.72835 12 P 0 0;1=1
P 12.73621004 1.45276004 12 P 0 0;1=1
P 12.81495 1.41338996 12 P 0 0;1=1
P 12.73621004 1.37401998 12 P 0 0;1=7
P 12.63778996 1.45276004 12 P 0 0;1=1
P 12.55905 1.41338996 12 P 0 0;1=1
P 0.35038996 1.5315 12 P 0 0;1=1
P 0.27165 1.49213002 12 P 0 0;1=1
P 0.17323002 2.67323002 12 P 0 0;1=1
P 0.09448996 2.63386004 12 P 0 0;1=1
P 0.09448996 1.61023996 12 P 0 0;1=1
P 0.17323002 1.57086998 12 P 0 0;1=1
P 0.09448996 1.5315 12 P 0 0;1=1
P 0.17323002 1.49213002 12 P 0 0;1=1
P 0.27165 1.64961004 12 P 0 0;1=1
P 0.35038996 1.61023996 12 P 0 0;1=1
P 0.17323002 1.64961004 12 P 0 0;1=1
P 0.09448996 1.68898002 12 P 0 0;1=1
P 0.35038996 1.68898002 12 P 0 0;1=1
P 0.27165 1.41338996 12 P 0 0;1=1
P 0.35038996 1.37401998 12 P 0 0;1=1
P 0.27165 1.33465 12 P 0 0;1=7
P 0.17323002 1.41338996 12 P 0 0;1=1
P 0.09448996 1.37401998 12 P 0 0;1=1
P 10.20866004 5.4441 25 P 0 0;1=15
P 5.78346004 5.4441 25 P 0 0;1=15
P 12.7252 6.31661998 20 P 0 0;1=14
P 0.2 6.31661998 20 P 0 0;1=14
P 12.7252 -0.293 20 P 0 0;1=14
P 0.22245 4.87401004 18 P 0 0;1=5
P 12.68701004 0.46063002 21 P 0 0;1=16
P 12.68701998 5.4252 21 P 0 0;1=16
P 0.22245 0.42126004 21 P 0 0;1=16
P 0.22255 5.38583002 21 P 0 0;1=16
P 7.17716998 5.7874 24 P 0 0;1=17
P 7.17716998 0.23621998 24 P 0 0;1=17
P 0.22245 0.68898002 23 P 0 0;1=18
P 0.22245 5.11811004 23 P 0 0;1=18
P 12.68701998 5.15748002 23 P 0 0;1=18
P 12.68701998 0.72835 23 P 0 0;1=18
P 6.11811004 1.52756004 23 P 0 0;1=18
P 6.11811004 4.20473002 23 P 0 0;1=18
P 4.83268002 4.22441004 23 P 0 0;1=18
P 2.24606004 4.22441004 23 P 0 0;1=18
P 0.96063002 4.20473002 23 P 0 0;1=18
P 0.96063002 1.52756004 23 P 0 0;1=18
P 2.24606004 1.50786998 23 P 0 0;1=18
P 4.83268002 1.50786998 23 P 0 0;1=18
P 6.04921004 2.58268002 22 P 0 0;1=19
P 1.05905 2.58268002 27 P 0 0;1=20
P 12.12205 1.52756004 23 P 0 0;1=18
P 12.12205 4.20473002 23 P 0 0;1=18
P 10.83661998 4.22441004 23 P 0 0;1=18
P 8.25 4.22441004 23 P 0 0;1=18
P 6.96456998 4.20473002 23 P 0 0;1=18
P 6.96456998 1.52756004 23 P 0 0;1=18
P 8.25 1.50786998 23 P 0 0;1=18
P 10.83661998 1.50786998 23 P 0 0;1=18
P 12.05315 2.58268002 22 P 0 0;1=19
P 7.06298996 2.58268002 27 P 0 0;1=20
P 12.33465 5.69528002 19 P 0 0;1=21
P 3.58311004 4.91851004 15 P 0 0;1=22
P 2.72091004 4.91851004 15 P 0 0;1=22
P 9.58665 4.91851004 15 P 0 0;1=22
P 8.72445 4.91851004 15 P 0 0;1=22
P 2.41851004 4.91851004 15 P 0 0;1=22
P 1.55631004 4.91851004 15 P 0 0;1=22
P 8.42205 4.91851004 15 P 0 0;1=22
P 7.55985 4.91851004 15 P 0 0;1=22
P 0.22243996 1.79331004 17 P 0 0;1=23
P 0.22243996 4.67323002 17 P 0 0;1=23
P 12.687 1.83268002 17 P 0 0;1=23
P 12.687 4.7126 17 P 0 0;1=23
P 0.7687 5.62008002 13 P 0 0;1=24
P 1.47736004 5.62008002 13 P 0 0;1=24
L 1.88908002 -1.91246004 1.89293002 -1.91246004 0 P 0 ;0
L 1.89126998 -1.91146004 1.89656998 -1.91146004 0 P 0 ;0
L 1.89393996 -1.91046004 1.9155 -1.91046004 0 P 0 ;0
L 1.91593996 -1.91246004 1.92048996 -1.91246004 0 P 0 ;0
L 1.9126 -1.91146004 1.9184 -1.91146004 0 P 0 ;0
L 1.89763002 -1.90946004 1.91016998 -1.90946004 0 P 0 ;0
L 1.89053002 -1.96001004 1.8974 -1.96001004 0 P 0 ;0
L 1.89053002 -1.95901004 1.8974 -1.95901004 0 P 0 ;0
L 1.89053002 -1.95801004 1.8974 -1.95801004 0 P 0 ;0
L 1.89053002 -1.95701004 1.8974 -1.95701004 0 P 0 ;0
L 1.89053002 -1.95601004 1.8974 -1.95601004 0 P 0 ;0
L 1.89053002 -1.95501004 1.8974 -1.95501004 0 P 0 ;0
L 1.89053002 -1.95401004 1.8974 -1.95401004 0 P 0 ;0
L 1.89053002 -1.95301004 1.89741004 -1.95301004 0 P 0 ;0
L 1.89053002 -1.95201004 1.89741998 -1.95201004 0 P 0 ;0
L 1.89053002 -1.95101004 1.89743996 -1.95101004 0 P 0 ;0
L 1.89053002 -1.95001004 1.89745 -1.95001004 0 P 0 ;0
L 1.89053002 -1.94901004 1.89746004 -1.94901004 0 P 0 ;0
L 1.89053002 -1.94801004 1.89753002 -1.94801004 0 P 0 ;0
L 1.89053002 -1.94701004 1.8977 -1.94701004 0 P 0 ;0
L 1.89053002 -1.94601004 1.89798002 -1.94601004 0 P 0 ;0
L 1.89053002 -1.94501004 1.89861004 -1.94501004 0 P 0 ;0
L 1.89053002 -1.94401004 1.90005 -1.94401004 0 P 0 ;0
L 1.89053002 -1.94301004 1.9113 -1.94301004 0 P 0 ;0
L 1.89053002 -1.94201004 1.91168002 -1.94201004 0 P 0 ;0
L 1.89053002 -1.94101004 1.91246998 -1.94101004 0 P 0 ;0
L 1.89053002 -1.94001004 1.90093996 -1.94001004 0 P 0 ;0
L 1.89053002 -1.93901004 1.89856004 -1.93901004 0 P 0 ;0
L 1.89053002 -1.93801004 1.89786998 -1.93801004 0 P 0 ;0
L 1.89053002 -1.93701004 1.89753996 -1.93701004 0 P 0 ;0
L 1.89053002 -1.93601004 1.89746998 -1.93601004 0 P 0 ;0
L 1.89053002 -1.93501004 1.89743996 -1.93501004 0 P 0 ;0
L 1.89053002 -1.93401004 1.89741998 -1.93401004 0 P 0 ;0
L 1.89053002 -1.93301004 1.8974 -1.93301004 0 P 0 ;0
L 1.89053002 -1.93201004 1.8974 -1.93201004 0 P 0 ;0
L 1.89053002 -1.93101004 1.8974 -1.93101004 0 P 0 ;0
L 1.89053002 -1.93001004 1.8974 -1.93001004 0 P 0 ;0
L 1.89053002 -1.92901004 1.8974 -1.92901004 0 P 0 ;0
L 1.89053002 -1.92801004 1.89753002 -1.92801004 0 P 0 ;0
L 1.89053002 -1.92701004 1.89793996 -1.92701004 0 P 0 ;0
L 1.89053002 -1.92601004 1.91713002 -1.92601004 0 P 0 ;0
L 1.89053002 -1.92501004 1.91628996 -1.92501004 0 P 0 ;0
L 1.89053002 -1.92401004 1.91513996 -1.92401004 0 P 0 ;0
L 1.89053002 -1.92301004 1.91321998 -1.92301004 0 P 0 ;0
L 1.89053002 -1.92201004 1.90551004 -1.92201004 0 P 0 ;0
L 1.89438996 -1.97246004 1.91331004 -1.97246004 0 P 0 ;0
L 1.89106998 -1.97146004 1.89973002 -1.97146004 0 P 0 ;0
L 1.88878002 -1.97046004 1.8949 -1.97046004 0 P 0 ;0
L 1.88698002 -1.96946004 1.89206998 -1.96946004 0 P 0 ;0
L 1.88546004 -1.96846004 1.88986998 -1.96846004 0 P 0 ;0
L 1.88416998 -1.96746004 1.88808996 -1.96746004 0 P 0 ;0
L 1.88288002 -1.96646004 1.88655 -1.96646004 0 P 0 ;0
L 1.88176998 -1.96546004 1.88518002 -1.96546004 0 P 0 ;0
L 1.88068996 -1.96446004 1.88393996 -1.96446004 0 P 0 ;0
L 1.87968996 -1.96346004 1.88286004 -1.96346004 0 P 0 ;0
L 1.87878002 -1.96246004 1.88186004 -1.96246004 0 P 0 ;0
L 1.8786 -1.92046004 1.88126998 -1.92046004 0 P 0 ;0
L 1.87946998 -1.91946004 1.88223002 -1.91946004 0 P 0 ;0
L 1.88048002 -1.91846004 1.88321004 -1.91846004 0 P 0 ;0
L 1.88153996 -1.91746004 1.88436998 -1.91746004 0 P 0 ;0
L 1.88273002 -1.91646004 1.88558996 -1.91646004 0 P 0 ;0
L 1.88406004 -1.91546004 1.88696998 -1.91546004 0 P 0 ;0
L 1.88548996 -1.91446004 1.88853002 -1.91446004 0 P 0 ;0
L 1.88718002 -1.91346004 1.89041998 -1.91346004 0 P 0 ;0
L 1.90896004 -1.92963996 1.90921998 -1.92991998 0 P 0 ;0
L 1.90921998 -1.92991998 1.90945 -1.93021998 0 P 0 ;0
L 1.90945 -1.93021998 1.90966004 -1.93053002 0 P 0 ;0
L 1.90966004 -1.93053002 1.90983002 -1.93086004 0 P 0 ;0
L 1.90983002 -1.93086004 1.90998002 -1.93121004 0 P 0 ;0
L 1.90998002 -1.93121004 1.9101 -1.93156998 0 P 0 ;0
L 1.9101 -1.93156998 1.91018996 -1.93193996 0 P 0 ;0
L 1.91018996 -1.93193996 1.91023996 -1.93231004 0 P 0 ;0
L 1.91023996 -1.93231004 1.91026998 -1.93265 0 P 0 ;0
L 1.91026998 -1.93265 1.91026004 -1.93298002 0 P 0 ;0
L 1.91026004 -1.93298002 1.91023002 -1.93331004 0 P 0 ;0
L 1.91023002 -1.93331004 1.91016998 -1.93363996 0 P 0 ;0
L 1.91016998 -1.93363996 1.91008996 -1.93396004 0 P 0 ;0
L 1.91008996 -1.93396004 1.90998002 -1.93428002 0 P 0 ;0
L 1.90998002 -1.93428002 1.90983996 -1.93458002 0 P 0 ;0
L 1.90983996 -1.93458002 1.90968996 -1.93486998 0 P 0 ;0
L 1.90968996 -1.93486998 1.90951004 -1.93516004 0 P 0 ;0
L 1.90951004 -1.93516004 1.90921004 -1.93556004 0 P 0 ;0
L 1.90921004 -1.93556004 1.90888002 -1.93593002 0 P 0 ;0
L 1.90888002 -1.93593002 1.90853002 -1.93626998 0 P 0 ;0
L 1.90853002 -1.93626998 1.90815 -1.93658996 0 P 0 ;0
L 1.90815 -1.93658996 1.90773996 -1.93686998 0 P 0 ;0
L 1.90773996 -1.93686998 1.90731998 -1.93711998 0 P 0 ;0
L 1.90731998 -1.93711998 1.90686998 -1.93733996 0 P 0 ;0
L 1.90686998 -1.93733996 1.90615 -1.93761004 0 P 0 ;0
L 1.90615 -1.93761004 1.90541998 -1.93783002 0 P 0 ;0
L 1.90541998 -1.93783002 1.90466004 -1.93798002 0 P 0 ;0
L 1.90466004 -1.93798002 1.9039 -1.93808002 0 P 0 ;0
L 1.9039 -1.93808002 1.90311998 -1.9381 0 P 0 ;0
L 1.90311998 -1.9381 1.90196004 -1.93808002 0 P 0 ;0
L 1.90196004 -1.93808002 1.90078996 -1.93798996 0 P 0 ;0
L 1.90078996 -1.93798996 1.90068002 -1.93798002 0 P 0 ;0
L 1.90068002 -1.93798002 1.90058002 -1.93795 0 P 0 ;0
L 1.90058002 -1.93795 1.90046998 -1.93791998 0 P 0 ;0
L 1.90046998 -1.93791998 1.90038002 -1.93788002 0 P 0 ;0
L 1.90038002 -1.93788002 1.90028002 -1.93783002 0 P 0 ;0
L 1.90028002 -1.93783002 1.90018996 -1.93778002 0 P 0 ;0
L 1.90018996 -1.93778002 1.9001 -1.93771004 0 P 0 ;0
L 1.9001 -1.93771004 1.90001998 -1.93763996 0 P 0 ;0
L 1.90001998 -1.93763996 1.89988002 -1.93748002 0 P 0 ;0
L 1.89988002 -1.93748002 1.89978002 -1.93733996 0 P 0 ;0
L 1.89978002 -1.93733996 1.89961998 -1.93703996 0 P 0 ;0
L 1.89961998 -1.93703996 1.89956998 -1.93688002 0 P 0 ;0
L 1.89956998 -1.93688002 1.89951998 -1.93671004 0 P 0 ;0
L 1.89951998 -1.93671004 1.89948996 -1.93655 0 P 0 ;0
L 1.89948996 -1.93655 1.89946998 -1.93636998 0 P 0 ;0
L 1.89946998 -1.93636998 1.8994 -1.93323002 0 P 0 ;0
L 1.8994 -1.93323002 1.8994 -1.92833002 0 P 0 ;0
L 1.8994 -1.92833002 1.90353996 -1.92833002 0 P 0 ;0
L 1.90353996 -1.92833002 1.90436998 -1.92835 0 P 0 ;0
L 1.90436998 -1.92835 1.9052 -1.92843002 0 P 0 ;0
L 1.9052 -1.92843002 1.90603002 -1.92853996 0 P 0 ;0
L 1.90603002 -1.92853996 1.90683996 -1.92871004 0 P 0 ;0
L 1.90683996 -1.92871004 1.90751004 -1.9289 0 P 0 ;0
L 1.90751004 -1.9289 1.90818002 -1.92913002 0 P 0 ;0
L 1.90818002 -1.92913002 1.90851998 -1.92928996 0 P 0 ;0
L 1.90851998 -1.92928996 1.90868002 -1.92938996 0 P 0 ;0
L 1.90868002 -1.92938996 1.90883002 -1.92951004 0 P 0 ;0
L 1.90883002 -1.92951004 1.90896004 -1.92963996 0 P 0 ;0
L 1.91188996 -1.96001004 1.91638996 -1.96001004 0 P 0 ;0
L 1.91156998 -1.95901004 1.91926998 -1.95901004 0 P 0 ;0
L 1.91125 -1.95801004 1.91891998 -1.95801004 0 P 0 ;0
L 1.91091998 -1.95701004 1.91853002 -1.95701004 0 P 0 ;0
L 1.9106 -1.95601004 1.91811004 -1.95601004 0 P 0 ;0
L 1.91025 -1.95501004 1.91765 -1.95501004 0 P 0 ;0
L 1.90988996 -1.95401004 1.91718996 -1.95401004 0 P 0 ;0
L 1.90953002 -1.95301004 1.91673002 -1.95301004 0 P 0 ;0
L 1.90918002 -1.95201004 1.91626998 -1.95201004 0 P 0 ;0
L 1.90881998 -1.95101004 1.91576004 -1.95101004 0 P 0 ;0
L 1.90841004 -1.95001004 1.91523996 -1.95001004 0 P 0 ;0
L 1.90793996 -1.94901004 1.91471004 -1.94901004 0 P 0 ;0
L 1.90738996 -1.94801004 1.91418002 -1.94801004 0 P 0 ;0
L 1.90676998 -1.94701004 1.9136 -1.94701004 0 P 0 ;0
L 1.90598996 -1.94601004 1.91261004 -1.94601004 0 P 0 ;0
L 1.90495 -1.94501004 1.91175 -1.94501004 0 P 0 ;0
L 1.90325 -1.94401004 1.91133002 -1.94401004 0 P 0 ;0
L 1.90456004 -1.94001004 1.91383002 -1.94001004 0 P 0 ;0
L 1.90801004 -1.93901004 1.91523002 -1.93901004 0 P 0 ;0
L 1.90956998 -1.93801004 1.91635 -1.93801004 0 P 0 ;0
L 1.9106 -1.93701004 1.91718002 -1.93701004 0 P 0 ;0
L 1.91133996 -1.93601004 1.91781004 -1.93601004 0 P 0 ;0
L 1.91183996 -1.93501004 1.91826004 -1.93501004 0 P 0 ;0
L 1.91213002 -1.93401004 1.9186 -1.93401004 0 P 0 ;0
L 1.91226004 -1.93301004 1.9188 -1.93301004 0 P 0 ;0
L 1.91221998 -1.93201004 1.9189 -1.93201004 0 P 0 ;0
L 1.91201998 -1.93101004 1.9189 -1.93101004 0 P 0 ;0
L 1.91163996 -1.93001004 1.91878996 -1.93001004 0 P 0 ;0
L 1.91105 -1.92901004 1.91856998 -1.92901004 0 P 0 ;0
L 1.91013996 -1.92801004 1.91823002 -1.92801004 0 P 0 ;0
L 1.90816998 -1.92701004 1.91776004 -1.92701004 0 P 0 ;0
L 1.90313996 -1.94011004 1.90316998 -1.9401 0 P 0 ;0
L 1.90316998 -1.9401 1.9032 -1.9401 0 P 0 ;0
L 1.9032 -1.9401 1.90398002 -1.94006998 0 P 0 ;0
L 1.90398002 -1.94006998 1.90406004 -1.94006998 0 P 0 ;0
L 1.90406004 -1.94006998 1.90413996 -1.94006004 0 P 0 ;0
L 1.90413996 -1.94006004 1.9049 -1.93996998 0 P 0 ;0
L 1.9049 -1.93996998 1.90493996 -1.93996004 0 P 0 ;0
L 1.90493996 -1.93996004 1.90498996 -1.93996004 0 P 0 ;0
L 1.90498996 -1.93996004 1.90506998 -1.93993996 0 P 0 ;0
L 1.90506998 -1.93993996 1.90581998 -1.93978002 0 P 0 ;0
L 1.90581998 -1.93978002 1.90586004 -1.93978002 0 P 0 ;0
L 1.90586004 -1.93978002 1.90593996 -1.93976004 0 P 0 ;0
L 1.90593996 -1.93976004 1.90596998 -1.93973996 0 P 0 ;0
L 1.90596998 -1.93973996 1.90671004 -1.93953002 0 P 0 ;0
L 1.90671004 -1.93953002 1.90678996 -1.93951004 0 P 0 ;0
L 1.90678996 -1.93951004 1.90758996 -1.93921004 0 P 0 ;0
L 1.90758996 -1.93921004 1.90766004 -1.93916998 0 P 0 ;0
L 1.90766004 -1.93916998 1.9077 -1.93915 0 P 0 ;0
L 1.9077 -1.93915 1.90773996 -1.93913996 0 P 0 ;0
L 1.90773996 -1.93913996 1.90818996 -1.93891998 0 P 0 ;0
L 1.90818996 -1.93891998 1.90821998 -1.9389 0 P 0 ;0
L 1.90821998 -1.9389 1.90826004 -1.93888996 0 P 0 ;0
L 1.90826004 -1.93888996 1.90828996 -1.93886998 0 P 0 ;0
L 1.90828996 -1.93886998 1.90833002 -1.93885 0 P 0 ;0
L 1.90833002 -1.93885 1.90875 -1.9386 0 P 0 ;0
L 1.90875 -1.9386 1.90883002 -1.93856004 0 P 0 ;0
L 1.90883002 -1.93856004 1.90888996 -1.93851004 0 P 0 ;0
L 1.90888996 -1.93851004 1.90928996 -1.93823002 0 P 0 ;0
L 1.90928996 -1.93823002 1.90933002 -1.9382 0 P 0 ;0
L 1.90933002 -1.9382 1.90936004 -1.93818002 0 P 0 ;0
L 1.90936004 -1.93818002 1.90938996 -1.93815 0 P 0 ;0
L 1.90938996 -1.93815 1.90941998 -1.93813002 0 P 0 ;0
L 1.90941998 -1.93813002 1.9098 -1.93781998 0 P 0 ;0
L 1.9098 -1.93781998 1.90986004 -1.93776004 0 P 0 ;0
L 1.90986004 -1.93776004 1.90988996 -1.93773996 0 P 0 ;0
L 1.90988996 -1.93773996 1.90991998 -1.93771004 0 P 0 ;0
L 1.90991998 -1.93771004 1.91028002 -1.93736004 0 P 0 ;0
L 1.91028002 -1.93736004 1.91038996 -1.93725 0 P 0 ;0
L 1.91038996 -1.93725 1.91071004 -1.93688002 0 P 0 ;0
L 1.91071004 -1.93688002 1.91073996 -1.93685 0 P 0 ;0
L 1.91073996 -1.93685 1.91116004 -1.9363 0 P 0 ;0
L 1.91116004 -1.9363 1.9112 -1.93623002 0 P 0 ;0
L 1.9112 -1.93623002 1.91138002 -1.93595 0 P 0 ;0
L 1.91138002 -1.93595 1.9114 -1.93591004 0 P 0 ;0
L 1.9114 -1.93591004 1.91143996 -1.93585 0 P 0 ;0
L 1.91143996 -1.93585 1.91146004 -1.93581004 0 P 0 ;0
L 1.91146004 -1.93581004 1.91161004 -1.93551998 0 P 0 ;0
L 1.91161004 -1.93551998 1.91163002 -1.93548996 0 P 0 ;0
L 1.91163002 -1.93548996 1.91165 -1.93545 0 P 0 ;0
L 1.91165 -1.93545 1.91166004 -1.93541004 0 P 0 ;0
L 1.91166004 -1.93541004 1.91168002 -1.93538002 0 P 0 ;0
L 1.91168002 -1.93538002 1.91181004 -1.93506998 0 P 0 ;0
L 1.91181004 -1.93506998 1.91183996 -1.935 0 P 0 ;0
L 1.91183996 -1.935 1.91186004 -1.93496004 0 P 0 ;0
L 1.91186004 -1.93496004 1.91186998 -1.93493002 0 P 0 ;0
L 1.91186998 -1.93493002 1.91198002 -1.93461004 0 P 0 ;0
L 1.91198002 -1.93461004 1.91198996 -1.93456998 0 P 0 ;0
L 1.91198996 -1.93456998 1.912 -1.93453996 0 P 0 ;0
L 1.912 -1.93453996 1.9121 -1.93413996 0 P 0 ;0
L 1.9121 -1.93413996 1.91211998 -1.9341 0 P 0 ;0
L 1.91211998 -1.9341 1.91211998 -1.93406004 0 P 0 ;0
L 1.91211998 -1.93406004 1.91213002 -1.93401998 0 P 0 ;0
L 1.91213002 -1.93401998 1.91213996 -1.93398996 0 P 0 ;0
L 1.91213996 -1.93398996 1.9122 -1.93366004 0 P 0 ;0
L 1.9122 -1.93366004 1.91221004 -1.93358002 0 P 0 ;0
L 1.91221004 -1.93358002 1.91221004 -1.93353996 0 P 0 ;0
L 1.91221004 -1.93353996 1.91221998 -1.9335 0 P 0 ;0
L 1.91221998 -1.9335 1.91225 -1.93316998 0 P 0 ;0
L 1.91225 -1.93316998 1.91226004 -1.93308996 0 P 0 ;0
L 1.91226004 -1.93308996 1.91226004 -1.93268002 0 P 0 ;0
L 1.91226004 -1.93268002 1.91226998 -1.93263996 0 P 0 ;0
L 1.91226998 -1.93263996 1.91226998 -1.9326 0 P 0 ;0
L 1.91226998 -1.9326 1.91226004 -1.93251998 0 P 0 ;0
L 1.91226004 -1.93251998 1.91223996 -1.93218996 0 P 0 ;0
L 1.91223996 -1.93218996 1.91223996 -1.93215 0 P 0 ;0
L 1.91223996 -1.93215 1.91223002 -1.9321 0 P 0 ;0
L 1.91223002 -1.9321 1.91223002 -1.93206004 0 P 0 ;0
L 1.91223002 -1.93206004 1.91221998 -1.93201998 0 P 0 ;0
L 1.91221998 -1.93201998 1.91216998 -1.93163996 0 P 0 ;0
L 1.91216998 -1.93163996 1.91216004 -1.9316 0 P 0 ;0
L 1.91216004 -1.9316 1.91213996 -1.93151004 0 P 0 ;0
L 1.91213996 -1.93151004 1.91213002 -1.93146998 0 P 0 ;0
L 1.91213002 -1.93146998 1.91205 -1.93111004 0 P 0 ;0
L 1.91205 -1.93111004 1.91203996 -1.93106004 0 P 0 ;0
L 1.91203996 -1.93106004 1.91203002 -1.93101998 0 P 0 ;0
L 1.91203002 -1.93101998 1.91201004 -1.93098002 0 P 0 ;0
L 1.91201004 -1.93098002 1.912 -1.93093996 0 P 0 ;0
L 1.912 -1.93093996 1.91188002 -1.93058002 0 P 0 ;0
L 1.91188002 -1.93058002 1.91186998 -1.93053996 0 P 0 ;0
L 1.91186998 -1.93053996 1.91185 -1.9305 0 P 0 ;0
L 1.91185 -1.9305 1.91183996 -1.93046004 0 P 0 ;0
L 1.91183996 -1.93046004 1.91181998 -1.93043002 0 P 0 ;0
L 1.91181998 -1.93043002 1.91166998 -1.93008002 0 P 0 ;0
L 1.91166998 -1.93008002 1.91166004 -1.93003996 0 P 0 ;0
L 1.91166004 -1.93003996 1.9116 -1.92991998 0 P 0 ;0
L 1.9116 -1.92991998 1.91141998 -1.92958996 0 P 0 ;0
L 1.91141998 -1.92958996 1.9114 -1.92955 0 P 0 ;0
L 1.9114 -1.92955 1.91138002 -1.92951998 0 P 0 ;0
L 1.91138002 -1.92951998 1.91133002 -1.92945 0 P 0 ;0
L 1.91133002 -1.92945 1.91113002 -1.92913002 0 P 0 ;0
L 1.91113002 -1.92913002 1.91111004 -1.92908996 0 P 0 ;0
L 1.91111004 -1.92908996 1.91108996 -1.92906004 0 P 0 ;0
L 1.91108996 -1.92906004 1.91106004 -1.92901998 0 P 0 ;0
L 1.91106004 -1.92901998 1.91103002 -1.92898996 0 P 0 ;0
L 1.91103002 -1.92898996 1.9108 -1.92868996 0 P 0 ;0
L 1.9108 -1.92868996 1.91076998 -1.92866004 0 P 0 ;0
L 1.91076998 -1.92866004 1.91075 -1.92861998 0 P 0 ;0
L 1.91075 -1.92861998 1.91068996 -1.92856004 0 P 0 ;0
L 1.91068996 -1.92856004 1.91043002 -1.92828002 0 P 0 ;0
L 1.91043002 -1.92828002 1.91035 -1.9282 0 P 0 ;0
L 1.91035 -1.9282 1.91033002 -1.92816998 0 P 0 ;0
L 1.91033002 -1.92816998 1.91018996 -1.92803996 0 P 0 ;0
L 1.91018996 -1.92803996 1.91018002 -1.92803996 0 P 0 ;0
L 1.91018002 -1.92803996 1.91016004 -1.92801998 0 P 0 ;0
L 1.91016004 -1.92801998 1.91011998 -1.92798996 0 P 0 ;0
L 1.91011998 -1.92798996 1.91006004 -1.92793002 0 P 0 ;0
L 1.91006004 -1.92793002 1.90991004 -1.92781998 0 P 0 ;0
L 1.90991004 -1.92781998 1.90988002 -1.9278 0 P 0 ;0
L 1.90988002 -1.9278 1.90983996 -1.92776998 0 P 0 ;0
L 1.90983996 -1.92776998 1.90976998 -1.92771998 0 P 0 ;0
L 1.90976998 -1.92771998 1.90961004 -1.92761998 0 P 0 ;0
L 1.90961004 -1.92761998 1.90953996 -1.92756998 0 P 0 ;0
L 1.90953996 -1.92756998 1.9095 -1.92755 0 P 0 ;0
L 1.9095 -1.92755 1.90946998 -1.92753002 0 P 0 ;0
L 1.90946998 -1.92753002 1.9093 -1.92743996 0 P 0 ;0
L 1.9093 -1.92743996 1.90926004 -1.92741998 0 P 0 ;0
L 1.90926004 -1.92741998 1.90923002 -1.9274 0 P 0 ;0
L 1.90923002 -1.9274 1.90915 -1.92736998 0 P 0 ;0
L 1.90915 -1.92736998 1.90896998 -1.92728996 0 P 0 ;0
L 1.90896998 -1.92728996 1.90893996 -1.92728002 0 P 0 ;0
L 1.90893996 -1.92728002 1.9089 -1.92726004 0 P 0 ;0
L 1.9089 -1.92726004 1.90886998 -1.92725 0 P 0 ;0
L 1.90886998 -1.92725 1.90883002 -1.92723996 0 P 0 ;0
L 1.90883002 -1.92723996 1.90816004 -1.92701004 0 P 0 ;0
L 1.90816004 -1.92701004 1.90813996 -1.927 0 P 0 ;0
L 1.90813996 -1.927 1.9081 -1.92698996 0 P 0 ;0
L 1.9081 -1.92698996 1.90803996 -1.92696998 0 P 0 ;0
L 1.90803996 -1.92696998 1.90736998 -1.92678002 0 P 0 ;0
L 1.90736998 -1.92678002 1.90723996 -1.92675 0 P 0 ;0
L 1.90723996 -1.92675 1.90643002 -1.92658996 0 P 0 ;0
L 1.90643002 -1.92658996 1.90636998 -1.92656998 0 P 0 ;0
L 1.90636998 -1.92656998 1.90633996 -1.92656998 0 P 0 ;0
L 1.90633996 -1.92656998 1.90631004 -1.92656004 0 P 0 ;0
L 1.90631004 -1.92656004 1.90548996 -1.92645 0 P 0 ;0
L 1.90548996 -1.92645 1.90543996 -1.92643996 0 P 0 ;0
L 1.90543996 -1.92643996 1.9054 -1.92643002 0 P 0 ;0
L 1.9054 -1.92643002 1.90538002 -1.92643002 0 P 0 ;0
L 1.90538002 -1.92643002 1.90455 -1.92636004 0 P 0 ;0
L 1.90455 -1.92636004 1.90443002 -1.92636004 0 P 0 ;0
L 1.90443002 -1.92636004 1.9036 -1.92633002 0 P 0 ;0
L 1.9036 -1.92633002 1.8994 -1.92633002 0 P 0 ;0
L 1.8994 -1.92633002 1.89798002 -1.92691004 0 P 0 ;0
L 1.89798002 -1.92691004 1.8974 -1.92833002 0 P 0 ;0
L 1.8974 -1.92833002 1.8974 -1.93328002 0 P 0 ;0
L 1.8974 -1.93328002 1.89748002 -1.93643002 0 P 0 ;0
L 1.89748002 -1.93643002 1.89748002 -1.93656004 0 P 0 ;0
L 1.89748002 -1.93656004 1.8975 -1.93673002 0 P 0 ;0
L 1.8975 -1.93673002 1.89751004 -1.93681004 0 P 0 ;0
L 1.89751004 -1.93681004 1.89751998 -1.9369 0 P 0 ;0
L 1.89751998 -1.9369 1.89755 -1.93706004 0 P 0 ;0
L 1.89755 -1.93706004 1.89758002 -1.93718996 0 P 0 ;0
L 1.89758002 -1.93718996 1.89758996 -1.93723002 0 P 0 ;0
L 1.89758996 -1.93723002 1.89763002 -1.9374 0 P 0 ;0
L 1.89763002 -1.9374 1.89763996 -1.93743996 0 P 0 ;0
L 1.89763996 -1.93743996 1.89766004 -1.93748002 0 P 0 ;0
L 1.89766004 -1.93748002 1.89768002 -1.93756004 0 P 0 ;0
L 1.89768002 -1.93756004 1.89773996 -1.93771998 0 P 0 ;0
L 1.89773996 -1.93771998 1.89776004 -1.93776004 0 P 0 ;0
L 1.89776004 -1.93776004 1.89776998 -1.9378 0 P 0 ;0
L 1.89776998 -1.9378 1.89781004 -1.93788002 0 P 0 ;0
L 1.89781004 -1.93788002 1.89788002 -1.93803996 0 P 0 ;0
L 1.89788002 -1.93803996 1.8979 -1.93808002 0 P 0 ;0
L 1.8979 -1.93808002 1.89791998 -1.93811004 0 P 0 ;0
L 1.89791998 -1.93811004 1.89796004 -1.93818996 0 P 0 ;0
L 1.89796004 -1.93818996 1.89803996 -1.93833996 0 P 0 ;0
L 1.89803996 -1.93833996 1.89813996 -1.93848002 0 P 0 ;0
L 1.89813996 -1.93848002 1.89823002 -1.93861998 0 P 0 ;0
L 1.89823002 -1.93861998 1.89828002 -1.93868996 0 P 0 ;0
L 1.89828002 -1.93868996 1.89831004 -1.93873002 0 P 0 ;0
L 1.89831004 -1.93873002 1.89833996 -1.93876004 0 P 0 ;0
L 1.89833996 -1.93876004 1.8984 -1.93883996 0 P 0 ;0
L 1.8984 -1.93883996 1.89848996 -1.93893002 0 P 0 ;0
L 1.89848996 -1.93893002 1.89851004 -1.93896004 0 P 0 ;0
L 1.89851004 -1.93896004 1.89868002 -1.93913002 0 P 0 ;0
L 1.89868002 -1.93913002 1.89871004 -1.93915 0 P 0 ;0
L 1.89871004 -1.93915 1.89878996 -1.93921998 0 P 0 ;0
L 1.89878996 -1.93921998 1.89885 -1.93928002 0 P 0 ;0
L 1.89885 -1.93928002 1.89888002 -1.9393 0 P 0 ;0
L 1.89888002 -1.9393 1.89891998 -1.93931998 0 P 0 ;0
L 1.89891998 -1.93931998 1.89901004 -1.93938996 0 P 0 ;0
L 1.89901004 -1.93938996 1.89903996 -1.93941004 0 P 0 ;0
L 1.89903996 -1.93941004 1.89906998 -1.93943996 0 P 0 ;0
L 1.89906998 -1.93943996 1.8991 -1.93946004 0 P 0 ;0
L 1.8991 -1.93946004 1.89913996 -1.93948002 0 P 0 ;0
L 1.89913996 -1.93948002 1.89923002 -1.93953996 0 P 0 ;0
L 1.89923002 -1.93953996 1.89926998 -1.93956004 0 P 0 ;0
L 1.89926998 -1.93956004 1.8993 -1.93958002 0 P 0 ;0
L 1.8993 -1.93958002 1.89933996 -1.9396 0 P 0 ;0
L 1.89933996 -1.9396 1.89936998 -1.93961004 0 P 0 ;0
L 1.89936998 -1.93961004 1.89938002 -1.93961004 0 P 0 ;0
L 1.89938002 -1.93961004 1.89946998 -1.93966004 0 P 0 ;0
L 1.89946998 -1.93966004 1.89953996 -1.9397 0 P 0 ;0
L 1.89953996 -1.9397 1.89971998 -1.93976998 0 P 0 ;0
L 1.89971998 -1.93976998 1.89975 -1.93978996 0 P 0 ;0
L 1.89975 -1.93978996 1.89978996 -1.9398 0 P 0 ;0
L 1.89978996 -1.9398 1.89986998 -1.93983002 0 P 0 ;0
L 1.89986998 -1.93983002 1.89996998 -1.93986004 0 P 0 ;0
L 1.89996998 -1.93986004 1.90001004 -1.93986998 0 P 0 ;0
L 1.90001004 -1.93986998 1.90005 -1.93988996 0 P 0 ;0
L 1.90005 -1.93988996 1.90013002 -1.9399 0 P 0 ;0
L 1.90013002 -1.9399 1.90023002 -1.93993002 0 P 0 ;0
L 1.90023002 -1.93993002 1.90023996 -1.93993002 0 P 0 ;0
L 1.90023996 -1.93993002 1.90028002 -1.93993996 0 P 0 ;0
L 1.90028002 -1.93993996 1.90031004 -1.93995 0 P 0 ;0
L 1.90031004 -1.93995 1.90036004 -1.93995 0 P 0 ;0
L 1.90036004 -1.93995 1.9004 -1.93996004 0 P 0 ;0
L 1.9004 -1.93996004 1.9005 -1.93996998 0 P 0 ;0
L 1.9005 -1.93996998 1.90061004 -1.93998996 0 P 0 ;0
L 1.90061004 -1.93998996 1.90063996 -1.93998996 0 P 0 ;0
L 1.90063996 -1.93998996 1.90181004 -1.94006998 0 P 0 ;0
L 1.90181004 -1.94006998 1.90183996 -1.94008002 0 P 0 ;0
L 1.90183996 -1.94008002 1.90191004 -1.94008002 0 P 0 ;0
L 1.90191004 -1.94008002 1.90308002 -1.9401 0 P 0 ;0
L 1.90308002 -1.9401 1.90311004 -1.9401 0 P 0 ;0
L 1.90311004 -1.9401 1.90313996 -1.94011004 0 P 0 ;0
L 1.90841004 -1.97146004 1.91683996 -1.97146004 0 P 0 ;0
L 1.9135 -1.97046004 1.91931004 -1.97046004 0 P 0 ;0
L 1.91655 -1.96946004 1.92131004 -1.96946004 0 P 0 ;0
L 1.91891998 -1.96846004 1.92301004 -1.96846004 0 P 0 ;0
L 1.92088996 -1.96746004 1.9245 -1.96746004 0 P 0 ;0
L 1.92251004 -1.96646004 1.9258 -1.96646004 0 P 0 ;0
L 1.92391004 -1.96546004 1.92696004 -1.96546004 0 P 0 ;0
L 1.92513002 -1.96446004 1.92803002 -1.96446004 0 P 0 ;0
L 1.9262 -1.96346004 1.92898996 -1.96346004 0 P 0 ;0
L 1.92713996 -1.96246004 1.92986004 -1.96246004 0 P 0 ;0
L 1.928 -1.96146004 1.93068996 -1.96146004 0 P 0 ;0
L 1.92878002 -1.96046004 1.93143002 -1.96046004 0 P 0 ;0
L 1.92951004 -1.95946004 1.93216004 -1.95946004 0 P 0 ;0
L 1.93016998 -1.95846004 1.93278996 -1.95846004 0 P 0 ;0
L 1.93078002 -1.95746004 1.93341004 -1.95746004 0 P 0 ;0
L 1.93133002 -1.95646004 1.93396004 -1.95646004 0 P 0 ;0
L 1.93185 -1.95546004 1.93448996 -1.95546004 0 P 0 ;0
L 1.93231004 -1.95446004 1.93495 -1.95446004 0 P 0 ;0
L 1.93275 -1.95346004 1.93541004 -1.95346004 0 P 0 ;0
L 1.93311998 -1.95246004 1.93586004 -1.95246004 0 P 0 ;0
L 1.93348002 -1.95146004 1.93628996 -1.95146004 0 P 0 ;0
L 1.93376998 -1.95046004 1.93666004 -1.95046004 0 P 0 ;0
L 1.93405 -1.94946004 1.93693002 -1.94946004 0 P 0 ;0
L 1.93428002 -1.94846004 1.93715 -1.94846004 0 P 0 ;0
L 1.93446998 -1.94746004 1.93733002 -1.94746004 0 P 0 ;0
L 1.93466004 -1.94646004 1.93743002 -1.94646004 0 P 0 ;0
L 1.93478996 -1.94546004 1.93748996 -1.94546004 0 P 0 ;0
L 1.9349 -1.94446998 1.93751998 -1.94446998 0 P 0 ;0
L 1.93496998 -1.94346004 1.93755 -1.94346004 0 P 0 ;0
L 1.93501998 -1.94246004 1.93758002 -1.94246004 0 P 0 ;0
L 1.93505 -1.94146998 1.93758996 -1.94146998 0 P 0 ;0
L 1.93503002 -1.94046004 1.93755 -1.94046004 0 P 0 ;0
L 1.935 -1.93946004 1.93751998 -1.93946004 0 P 0 ;0
L 1.93491998 -1.93846004 1.93748002 -1.93846004 0 P 0 ;0
L 1.93481004 -1.93746004 1.93738996 -1.93746004 0 P 0 ;0
L 1.93468996 -1.93646004 1.93726998 -1.93646004 0 P 0 ;0
L 1.93451004 -1.93546004 1.93716004 -1.93546004 0 P 0 ;0
L 1.93433002 -1.93446004 1.93703996 -1.93446004 0 P 0 ;0
L 1.93408996 -1.93346004 1.93685 -1.93346004 0 P 0 ;0
L 1.93383002 -1.93246004 1.93666004 -1.93246004 0 P 0 ;0
L 1.93353002 -1.93146004 1.93638996 -1.93146004 0 P 0 ;0
L 1.9332 -1.93046004 1.93611998 -1.93046004 0 P 0 ;0
L 1.93283996 -1.92946004 1.93576998 -1.92946004 0 P 0 ;0
L 1.93241004 -1.92846004 1.93541004 -1.92846004 0 P 0 ;0
L 1.93198996 -1.92746004 1.93498002 -1.92746004 0 P 0 ;0
L 1.93146998 -1.92646004 1.93451004 -1.92646004 0 P 0 ;0
L 1.93096004 -1.92546004 1.93398002 -1.92546004 0 P 0 ;0
L 1.93035 -1.92446998 1.93338002 -1.92446998 0 P 0 ;0
L 1.92973002 -1.92346004 1.93275 -1.92346004 0 P 0 ;0
L 1.92903002 -1.92246004 1.93201004 -1.92246004 0 P 0 ;0
L 1.92831004 -1.92146004 1.93125 -1.92146004 0 P 0 ;0
L 1.92746998 -1.92046004 1.93041004 -1.92046004 0 P 0 ;0
L 1.92661004 -1.91946004 1.92948996 -1.91946004 0 P 0 ;0
L 1.92558996 -1.91846004 1.92851004 -1.91846004 0 P 0 ;0
L 1.9245 -1.91746004 1.92741998 -1.91746004 0 P 0 ;0
L 1.92328996 -1.91646004 1.92621998 -1.91646004 0 P 0 ;0
L 1.92188002 -1.91546004 1.92491998 -1.91546004 0 P 0 ;0
L 1.92026004 -1.91446004 1.92358996 -1.91446004 0 P 0 ;0
L 1.91835 -1.91346004 1.92208002 -1.91346004 0 P 0 ;0
L 1.82446998 -2.08323996 1.87608002 -2.08323996 0 P 0 ;0
L 1.82403002 -2.08223996 1.87601004 -2.08223996 0 P 0 ;0
L 1.8234 -2.08123996 1.87591004 -2.08123996 0 P 0 ;0
L 1.82256004 -2.08023996 1.87578002 -2.08023996 0 P 0 ;0
L 1.82166004 -2.07923996 1.87558996 -2.07923996 0 P 0 ;0
L 1.82061998 -2.07823996 1.87533002 -2.07823996 0 P 0 ;0
L 1.81946004 -2.07723996 1.87498996 -2.07723996 0 P 0 ;0
L 1.81818002 -2.07623996 1.8746 -2.07623996 0 P 0 ;0
L 1.8168 -2.07523996 1.87416998 -2.07523996 0 P 0 ;0
L 1.81541998 -2.07423996 1.87371004 -2.07423996 0 P 0 ;0
L 1.81403002 -2.07323996 1.87316998 -2.07323996 0 P 0 ;0
L 1.81265 -2.07223996 1.87261004 -2.07223996 0 P 0 ;0
L 1.81126998 -2.07123996 1.87196004 -2.07123996 0 P 0 ;0
L 1.80986004 -2.07023996 1.87128002 -2.07023996 0 P 0 ;0
L 1.80843996 -2.06923996 1.87051998 -2.06923996 0 P 0 ;0
L 1.80703002 -2.06823996 1.8697 -2.06823996 0 P 0 ;0
L 1.80561004 -2.06723996 1.86883002 -2.06723996 0 P 0 ;0
L 1.8042 -2.06623996 1.86796004 -2.06623996 0 P 0 ;0
L 1.80278002 -2.06523996 1.86705 -2.06523996 0 P 0 ;0
L 1.80136004 -2.06423996 1.86608002 -2.06423996 0 P 0 ;0
L 1.79995 -2.06323996 1.8651 -2.06323996 0 P 0 ;0
L 1.79865 -2.06223996 1.86411004 -2.06223996 0 P 0 ;0
L 1.79735 -2.06123996 1.86301998 -2.06123996 0 P 0 ;0
L 1.79605 -2.06023996 1.86193002 -2.06023996 0 P 0 ;0
L 1.79475 -2.05923996 1.86083996 -2.05923996 0 P 0 ;0
L 1.79345 -2.05823996 1.85966998 -2.05823996 0 P 0 ;0
L 1.79215 -2.05723996 1.85846004 -2.05723996 0 P 0 ;0
L 1.79088002 -2.05623996 1.85726004 -2.05623996 0 P 0 ;0
L 1.78971998 -2.05523996 1.85598996 -2.05523996 0 P 0 ;0
L 1.78856004 -2.05423996 1.85461998 -2.05423996 0 P 0 ;0
L 1.7874 -2.05323996 1.85326004 -2.05323996 0 P 0 ;0
L 1.78623002 -2.05223996 1.8519 -2.05223996 0 P 0 ;0
L 1.78506998 -2.05123996 1.85053996 -2.05123996 0 P 0 ;0
L 1.78398002 -2.05023996 1.84918002 -2.05023996 0 P 0 ;0
L 1.783 -2.04923996 1.84781004 -2.04923996 0 P 0 ;0
L 1.87086004 -2.03023996 1.87535 -2.03023996 0 P 0 ;0
L 1.91633002 -1.91473002 1.9183 -1.91565 0 P 0 ;0
L 1.9183 -1.91565 1.92018996 -1.91673002 0 P 0 ;0
L 1.92018996 -1.91673002 1.92196998 -1.91796998 0 P 0 ;0
L 1.92196998 -1.91796998 1.92365 -1.91936004 0 P 0 ;0
L 1.92365 -1.91936004 1.9252 -1.92088002 0 P 0 ;0
L 1.9252 -1.92088002 1.92661004 -1.92253996 0 P 0 ;0
L 1.92661004 -1.92253996 1.92795 -1.92436998 0 P 0 ;0
L 1.92795 -1.92436998 1.92913996 -1.9263 0 P 0 ;0
L 1.92913996 -1.9263 1.93018002 -1.92831998 0 P 0 ;0
L 1.93018002 -1.92831998 1.93106998 -1.93041004 0 P 0 ;0
L 1.93106998 -1.93041004 1.93178996 -1.93256004 0 P 0 ;0
L 1.93178996 -1.93256004 1.93236004 -1.93476004 0 P 0 ;0
L 1.93236004 -1.93476004 1.93276004 -1.93703996 0 P 0 ;0
L 1.93276004 -1.93703996 1.93298996 -1.93933996 0 P 0 ;0
L 1.93298996 -1.93933996 1.93306004 -1.94165 0 P 0 ;0
L 1.93306004 -1.94165 1.93295 -1.94396998 0 P 0 ;0
L 1.93295 -1.94396998 1.93268002 -1.94626004 0 P 0 ;0
L 1.93268002 -1.94626004 1.93223002 -1.94853996 0 P 0 ;0
L 1.93223002 -1.94853996 1.93161998 -1.95071998 0 P 0 ;0
L 1.93161998 -1.95071998 1.93085 -1.95285 0 P 0 ;0
L 1.93085 -1.95285 1.92991004 -1.95491004 0 P 0 ;0
L 1.92991004 -1.95491004 1.92881004 -1.95688996 0 P 0 ;0
L 1.92881004 -1.95688996 1.92756004 -1.95878002 0 P 0 ;0
L 1.92756004 -1.95878002 1.92616004 -1.96056998 0 P 0 ;0
L 1.92616004 -1.96056998 1.92493996 -1.9619 0 P 0 ;0
L 1.92493996 -1.9619 1.92361998 -1.96313996 0 P 0 ;0
L 1.92361998 -1.96313996 1.9222 -1.96426004 0 P 0 ;0
L 1.9222 -1.96426004 1.9207 -1.96526998 0 P 0 ;0
L 1.9207 -1.96526998 1.91911004 -1.96616998 0 P 0 ;0
L 1.91911004 -1.96616998 1.91686998 -1.96721004 0 P 0 ;0
L 1.91686998 -1.96721004 1.91456004 -1.96806998 0 P 0 ;0
L 1.91456004 -1.96806998 1.91218996 -1.96876004 0 P 0 ;0
L 1.91218996 -1.96876004 1.90975 -1.96926998 0 P 0 ;0
L 1.90975 -1.96926998 1.90725 -1.9696 0 P 0 ;0
L 1.90725 -1.9696 1.90473002 -1.96973996 0 P 0 ;0
L 1.90473002 -1.96973996 1.9022 -1.96968996 0 P 0 ;0
L 1.9022 -1.96968996 1.89966998 -1.96945 0 P 0 ;0
L 1.89966998 -1.96945 1.89778002 -1.96913002 0 P 0 ;0
L 1.89778002 -1.96913002 1.89591998 -1.96868996 0 P 0 ;0
L 1.89591998 -1.96868996 1.8941 -1.96811004 0 P 0 ;0
L 1.8941 -1.96811004 1.89231004 -1.96741004 0 P 0 ;0
L 1.89231004 -1.96741004 1.89058002 -1.96658002 0 P 0 ;0
L 1.89058002 -1.96658002 1.88875 -1.96553996 0 P 0 ;0
L 1.88875 -1.96553996 1.88698996 -1.96435 0 P 0 ;0
L 1.88698996 -1.96435 1.88533996 -1.96303002 0 P 0 ;0
L 1.88533996 -1.96303002 1.88378996 -1.9616 0 P 0 ;0
L 1.88378996 -1.9616 1.88235 -1.96003996 0 P 0 ;0
L 1.88235 -1.96003996 1.88103002 -1.95838996 0 P 0 ;0
L 1.88103002 -1.95838996 1.87983996 -1.95663002 0 P 0 ;0
L 1.87983996 -1.95663002 1.87861998 -1.95446998 0 P 0 ;0
L 1.87861998 -1.95446998 1.87758002 -1.9522 0 P 0 ;0
L 1.87758002 -1.9522 1.87673996 -1.94986004 0 P 0 ;0
L 1.87673996 -1.94986004 1.8761 -1.94745 0 P 0 ;0
L 1.8761 -1.94745 1.87568002 -1.945 0 P 0 ;0
L 1.87568002 -1.945 1.87546004 -1.94248996 0 P 0 ;0
L 1.87546004 -1.94248996 1.87546004 -1.93998996 0 P 0 ;0
L 1.87546004 -1.93998996 1.87566998 -1.93748996 0 P 0 ;0
L 1.87566998 -1.93748996 1.87608996 -1.93501998 0 P 0 ;0
L 1.87608996 -1.93501998 1.87671998 -1.9326 0 P 0 ;0
L 1.87671998 -1.9326 1.87755 -1.93023002 0 P 0 ;0
L 1.87755 -1.93023002 1.8786 -1.92793002 0 P 0 ;0
L 1.8786 -1.92793002 1.87981998 -1.92575 0 P 0 ;0
L 1.87981998 -1.92575 1.88123002 -1.92368002 0 P 0 ;0
L 1.88123002 -1.92368002 1.88281004 -1.92175 0 P 0 ;0
L 1.88281004 -1.92175 1.88455 -1.91996004 0 P 0 ;0
L 1.88455 -1.91996004 1.88643002 -1.91831998 0 P 0 ;0
L 1.88643002 -1.91831998 1.88845 -1.91686004 0 P 0 ;0
L 1.88845 -1.91686004 1.88986998 -1.91598996 0 P 0 ;0
L 1.88986998 -1.91598996 1.89135 -1.91523002 0 P 0 ;0
L 1.89135 -1.91523002 1.89288002 -1.91458996 0 P 0 ;0
L 1.89288002 -1.91458996 1.89446998 -1.91406004 0 P 0 ;0
L 1.89446998 -1.91406004 1.89688996 -1.91343996 0 P 0 ;0
L 1.89688996 -1.91343996 1.89935 -1.91298996 0 P 0 ;0
L 1.89935 -1.91298996 1.90183996 -1.91271004 0 P 0 ;0
L 1.90183996 -1.91271004 1.9044 -1.91261004 0 P 0 ;0
L 1.9044 -1.91261004 1.90695 -1.91268002 0 P 0 ;0
L 1.90695 -1.91268002 1.90948996 -1.91291998 0 P 0 ;0
L 1.90948996 -1.91291998 1.91181998 -1.91331998 0 P 0 ;0
L 1.91181998 -1.91331998 1.91408996 -1.91393002 0 P 0 ;0
L 1.91408996 -1.91393002 1.91633002 -1.91473002 0 P 0 ;0
L 1.89498002 -1.90801998 1.8922 -1.90893002 0 P 0 ;0
L 1.8922 -1.90893002 1.88948002 -1.91003002 0 P 0 ;0
L 1.88948002 -1.91003002 1.88686004 -1.91133002 0 P 0 ;0
L 1.88686004 -1.91133002 1.88431004 -1.91283996 0 P 0 ;0
L 1.88431004 -1.91283996 1.88201004 -1.91446004 0 P 0 ;0
L 1.88201004 -1.91446004 1.87985 -1.91626998 0 P 0 ;0
L 1.87985 -1.91626998 1.87785 -1.91826004 0 P 0 ;0
L 1.87785 -1.91826004 1.87601998 -1.92041004 0 P 0 ;0
L 1.87601998 -1.92041004 1.87441004 -1.92266998 0 P 0 ;0
L 1.87441004 -1.92266998 1.87298996 -1.92505 0 P 0 ;0
L 1.87298996 -1.92505 1.87178002 -1.92756004 0 P 0 ;0
L 1.87178002 -1.92756004 1.87078996 -1.93015 0 P 0 ;0
L 1.87078996 -1.93015 1.87 -1.93286998 0 P 0 ;0
L 1.87 -1.93286998 1.86943996 -1.93563996 0 P 0 ;0
L 1.86943996 -1.93563996 1.86908996 -1.93845 0 P 0 ;0
L 1.86908996 -1.93845 1.86898002 -1.94128996 0 P 0 ;0
L 1.86898002 -1.94128996 1.86911998 -1.94485 0 P 0 ;0
L 1.86911998 -1.94485 1.86953996 -1.94841004 0 P 0 ;0
L 1.86953996 -1.94841004 1.86996004 -1.95048996 0 P 0 ;0
L 1.86996004 -1.95048996 1.87053002 -1.95251998 0 P 0 ;0
L 1.87053002 -1.95251998 1.87125 -1.95451998 0 P 0 ;0
L 1.87125 -1.95451998 1.87211004 -1.95643002 0 P 0 ;0
L 1.87211004 -1.95643002 1.8731 -1.95826004 0 P 0 ;0
L 1.8731 -1.95826004 1.87423996 -1.96001998 0 P 0 ;0
L 1.87423996 -1.96001998 1.87636998 -1.96278996 0 P 0 ;0
L 1.87636998 -1.96278996 1.87871998 -1.96536998 0 P 0 ;0
L 1.87871998 -1.96536998 1.88145 -1.96788002 0 P 0 ;0
L 1.88145 -1.96788002 1.88436998 -1.97015 0 P 0 ;0
L 1.88436998 -1.97015 1.88621004 -1.97135 0 P 0 ;0
L 1.88621004 -1.97135 1.88813002 -1.97238002 0 P 0 ;0
L 1.88813002 -1.97238002 1.89013002 -1.97326004 0 P 0 ;0
L 1.89013002 -1.97326004 1.89228002 -1.97398996 0 P 0 ;0
L 1.89228002 -1.97398996 1.89446998 -1.97455 0 P 0 ;0
L 1.89446998 -1.97455 1.89671004 -1.97493996 0 P 0 ;0
L 1.89671004 -1.97493996 1.90076998 -1.97533996 0 P 0 ;0
L 1.90076998 -1.97533996 1.90485 -1.97546998 0 P 0 ;0
L 1.90485 -1.97546998 1.90821004 -1.97531998 0 P 0 ;0
L 1.90821004 -1.97531998 1.91153996 -1.97488996 0 P 0 ;0
L 1.91153996 -1.97488996 1.91481998 -1.97418996 0 P 0 ;0
L 1.91481998 -1.97418996 1.9171 -1.9735 0 P 0 ;0
L 1.9171 -1.9735 1.91933002 -1.97266004 0 P 0 ;0
L 1.91933002 -1.97266004 1.92148002 -1.97166004 0 P 0 ;0
L 1.92148002 -1.97166004 1.92356998 -1.97048996 0 P 0 ;0
L 1.92356998 -1.97048996 1.92553996 -1.96918996 0 P 0 ;0
L 1.92553996 -1.96918996 1.92741004 -1.96773996 0 P 0 ;0
L 1.92741004 -1.96773996 1.92916004 -1.96616998 0 P 0 ;0
L 1.92916004 -1.96616998 1.93081004 -1.96446004 0 P 0 ;0
L 1.93081004 -1.96446004 1.93236998 -1.96256998 0 P 0 ;0
L 1.93236998 -1.96256998 1.93381004 -1.96058996 0 P 0 ;0
L 1.93381004 -1.96058996 1.93511998 -1.95851004 0 P 0 ;0
L 1.93511998 -1.95851004 1.93628996 -1.95633996 0 P 0 ;0
L 1.93628996 -1.95633996 1.93803996 -1.95251998 0 P 0 ;0
L 1.93803996 -1.95251998 1.93858002 -1.95101998 0 P 0 ;0
L 1.93858002 -1.95101998 1.93898996 -1.94948002 0 P 0 ;0
L 1.93898996 -1.94948002 1.93928996 -1.94786998 0 P 0 ;0
L 1.93928996 -1.94786998 1.93946004 -1.94625 0 P 0 ;0
L 1.93946004 -1.94625 1.9396 -1.94178002 0 P 0 ;0
L 1.9396 -1.94178002 1.93946004 -1.93803996 0 P 0 ;0
L 1.93946004 -1.93803996 1.93905 -1.9343 0 P 0 ;0
L 1.93905 -1.9343 1.93863996 -1.93213996 0 P 0 ;0
L 1.93863996 -1.93213996 1.93808002 -1.93001998 0 P 0 ;0
L 1.93808002 -1.93001998 1.93736004 -1.92795 0 P 0 ;0
L 1.93736004 -1.92795 1.93653002 -1.92601004 0 P 0 ;0
L 1.93653002 -1.92601004 1.93555 -1.92415 0 P 0 ;0
L 1.93555 -1.92415 1.93441998 -1.92236004 0 P 0 ;0
L 1.93441998 -1.92236004 1.9331 -1.92056004 0 P 0 ;0
L 1.9331 -1.92056004 1.93166998 -1.91885 0 P 0 ;0
L 1.93166998 -1.91885 1.93011998 -1.91723002 0 P 0 ;0
L 1.93011998 -1.91723002 1.92896004 -1.91615 0 P 0 ;0
L 1.92896004 -1.91615 1.92775 -1.91511004 0 P 0 ;0
L 1.92775 -1.91511004 1.92493002 -1.91295 0 P 0 ;0
L 1.92493002 -1.91295 1.9221 -1.91108002 0 P 0 ;0
L 1.9221 -1.91108002 1.92095 -1.91043002 0 P 0 ;0
L 1.92095 -1.91043002 1.91975 -1.90985 0 P 0 ;0
L 1.91975 -1.90985 1.91796004 -1.90913996 0 P 0 ;0
L 1.91796004 -1.90913996 1.91613002 -1.90856004 0 P 0 ;0
L 1.91613002 -1.90856004 1.91423996 -1.9081 0 P 0 ;0
L 1.91423996 -1.9081 1.91086004 -1.90751998 0 P 0 ;0
L 1.91086004 -1.90751998 1.90743002 -1.90716004 0 P 0 ;0
L 1.90743002 -1.90716004 1.90401004 -1.90701004 0 P 0 ;0
L 1.90401004 -1.90701004 1.90058002 -1.90708002 0 P 0 ;0
L 1.90058002 -1.90708002 1.8987 -1.90726004 0 P 0 ;0
L 1.8987 -1.90726004 1.89683002 -1.90756998 0 P 0 ;0
L 1.89683002 -1.90756998 1.89498002 -1.90801998 0 P 0 ;0
L 1.86643002 -2.02923996 1.87525 -2.02923996 0 P 0 ;0
L 1.86176998 -2.02823996 1.87515 -2.02823996 0 P 0 ;0
L 1.85588996 -2.02723996 1.87505 -2.02723996 0 P 0 ;0
L 1.78365 -2.00523996 1.87281004 -2.00523996 0 P 0 ;0
L 1.78451004 -2.00423996 1.87271004 -2.00423996 0 P 0 ;0
L 1.78546998 -2.00323996 1.87261004 -2.00323996 0 P 0 ;0
L 1.78655 -2.00223996 1.8725 -2.00223996 0 P 0 ;0
L 1.78776004 -2.00123996 1.8724 -2.00123996 0 P 0 ;0
L 1.78915 -2.00023996 1.8723 -2.00023996 0 P 0 ;0
L 1.79078996 -1.99923996 1.8722 -1.99923996 0 P 0 ;0
L 1.79263996 -1.99823996 1.87208996 -1.99823996 0 P 0 ;0
L 1.79458996 -1.99723996 1.87198996 -1.99723996 0 P 0 ;0
L 1.79686998 -1.99623996 1.87188002 -1.99623996 0 P 0 ;0
L 1.79946004 -1.99523996 1.87178002 -1.99523996 0 P 0 ;0
L 1.80231004 -1.99423996 1.86961998 -1.99423996 0 P 0 ;0
L 1.80596004 -1.99323996 1.86218002 -1.99323996 0 P 0 ;0
L 1.81051004 -1.99223996 1.85398002 -1.99223996 0 P 0 ;0
L 1.81676004 -1.99123996 1.84395 -1.99123996 0 P 0 ;0
L 1.87786998 -1.96146004 1.88093996 -1.96146004 0 P 0 ;0
L 1.8771 -1.96046004 1.88013002 -1.96046004 0 P 0 ;0
L 1.87633996 -1.95946004 1.87933996 -1.95946004 0 P 0 ;0
L 1.87561998 -1.95846004 1.87866998 -1.95846004 0 P 0 ;0
L 1.87496998 -1.95746004 1.87801998 -1.95746004 0 P 0 ;0
L 1.8744 -1.95646004 1.87745 -1.95646004 0 P 0 ;0
L 1.87386998 -1.95546004 1.87688002 -1.95546004 0 P 0 ;0
L 1.87341998 -1.95446004 1.87641998 -1.95446004 0 P 0 ;0
L 1.87298996 -1.95346004 1.87596004 -1.95346004 0 P 0 ;0
L 1.87263002 -1.95246004 1.87555 -1.95246004 0 P 0 ;0
L 1.87231004 -1.95146004 1.87518996 -1.95146004 0 P 0 ;0
L 1.87203002 -1.95046004 1.87483002 -1.95046004 0 P 0 ;0
L 1.87178996 -1.94946004 1.87456998 -1.94946004 0 P 0 ;0
L 1.87158996 -1.94846004 1.87431004 -1.94846004 0 P 0 ;0
L 1.87143996 -1.94746004 1.87408002 -1.94746004 0 P 0 ;0
L 1.87133002 -1.94646004 1.8739 -1.94646004 0 P 0 ;0
L 1.87121004 -1.94546004 1.87373002 -1.94546004 0 P 0 ;0
L 1.8711 -1.94446998 1.87361998 -1.94446998 0 P 0 ;0
L 1.87106998 -1.94346004 1.87353996 -1.94346004 0 P 0 ;0
L 1.87103002 -1.94246004 1.87346004 -1.94246004 0 P 0 ;0
L 1.87098996 -1.94146998 1.87346004 -1.94146998 0 P 0 ;0
L 1.87101004 -1.94046004 1.87346004 -1.94046004 0 P 0 ;0
L 1.87106004 -1.93946004 1.87348996 -1.93946004 0 P 0 ;0
L 1.87111004 -1.93846004 1.87358002 -1.93846004 0 P 0 ;0
L 1.87123002 -1.93746004 1.87366004 -1.93746004 0 P 0 ;0
L 1.87135 -1.93646004 1.87381998 -1.93646004 0 P 0 ;0
L 1.87151004 -1.93546004 1.87398996 -1.93546004 0 P 0 ;0
L 1.87171998 -1.93446004 1.87416998 -1.93446004 0 P 0 ;0
L 1.87191998 -1.93346004 1.87443002 -1.93346004 0 P 0 ;0
L 1.8722 -1.93246004 1.87468996 -1.93246004 0 P 0 ;0
L 1.87248996 -1.93146004 1.875 -1.93146004 0 P 0 ;0
L 1.87281004 -1.93046004 1.87535 -1.93046004 0 P 0 ;0
L 1.87318996 -1.92946004 1.87571004 -1.92946004 0 P 0 ;0
L 1.87356998 -1.92846004 1.87616004 -1.92846004 0 P 0 ;0
L 1.87405 -1.92746004 1.87661004 -1.92746004 0 P 0 ;0
L 1.87453002 -1.92646004 1.87711998 -1.92646004 0 P 0 ;0
L 1.87506998 -1.92546004 1.87768996 -1.92546004 0 P 0 ;0
L 1.87566004 -1.92446998 1.87826998 -1.92446998 0 P 0 ;0
L 1.87628996 -1.92346004 1.87896004 -1.92346004 0 P 0 ;0
L 1.87701004 -1.92246004 1.87963996 -1.92246004 0 P 0 ;0
L 1.87775 -1.92146004 1.88046004 -1.92146004 0 P 0 ;0
L 1.90483996 -1.97346004 1.9009 -1.97333996 0 P 0 ;0
L 1.9009 -1.97333996 1.89698002 -1.97295 0 P 0 ;0
L 1.89698002 -1.97295 1.89488996 -1.97258996 0 P 0 ;0
L 1.89488996 -1.97258996 1.89285 -1.97206998 0 P 0 ;0
L 1.89285 -1.97206998 1.89086004 -1.97138996 0 P 0 ;0
L 1.89086004 -1.97138996 1.889 -1.97058002 0 P 0 ;0
L 1.889 -1.97058002 1.88723002 -1.96961998 0 P 0 ;0
L 1.88723002 -1.96961998 1.88553002 -1.96851998 0 P 0 ;0
L 1.88553002 -1.96851998 1.88273996 -1.96636004 0 P 0 ;0
L 1.88273996 -1.96636004 1.88013996 -1.96396004 0 P 0 ;0
L 1.88013996 -1.96396004 1.8779 -1.9615 0 P 0 ;0
L 1.8779 -1.9615 1.87588002 -1.95886998 0 P 0 ;0
L 1.87588002 -1.95886998 1.87483002 -1.95723996 0 P 0 ;0
L 1.87483002 -1.95723996 1.8739 -1.95553996 0 P 0 ;0
L 1.8739 -1.95553996 1.87311004 -1.95376998 0 P 0 ;0
L 1.87311004 -1.95376998 1.87243002 -1.95191004 0 P 0 ;0
L 1.87243002 -1.95191004 1.8719 -1.95001998 0 P 0 ;0
L 1.8719 -1.95001998 1.87151998 -1.9481 0 P 0 ;0
L 1.87151998 -1.9481 1.87111004 -1.94468996 0 P 0 ;0
L 1.87111004 -1.94468996 1.87098002 -1.94128996 0 P 0 ;0
L 1.87098002 -1.94128996 1.87108996 -1.93861004 0 P 0 ;0
L 1.87108996 -1.93861004 1.87141004 -1.93596998 0 P 0 ;0
L 1.87141004 -1.93596998 1.87195 -1.93335 0 P 0 ;0
L 1.87195 -1.93335 1.87268996 -1.93078996 0 P 0 ;0
L 1.87268996 -1.93078996 1.87361998 -1.92835 0 P 0 ;0
L 1.87361998 -1.92835 1.87475 -1.926 0 P 0 ;0
L 1.87475 -1.926 1.87608996 -1.92376004 0 P 0 ;0
L 1.87608996 -1.92376004 1.8776 -1.92163996 0 P 0 ;0
L 1.8776 -1.92163996 1.87931998 -1.91961998 0 P 0 ;0
L 1.87931998 -1.91961998 1.8812 -1.91775 0 P 0 ;0
L 1.8812 -1.91775 1.88323002 -1.91605 0 P 0 ;0
L 1.88323002 -1.91605 1.8854 -1.91451998 0 P 0 ;0
L 1.8854 -1.91451998 1.88781004 -1.91308996 0 P 0 ;0
L 1.88781004 -1.91308996 1.89031004 -1.91186004 0 P 0 ;0
L 1.89031004 -1.91186004 1.89288002 -1.9108 0 P 0 ;0
L 1.89288002 -1.9108 1.89553002 -1.90995 0 P 0 ;0
L 1.89553002 -1.90995 1.89723002 -1.90953002 0 P 0 ;0
L 1.89723002 -1.90953002 1.89896004 -1.90923996 0 P 0 ;0
L 1.89896004 -1.90923996 1.90068996 -1.90908002 0 P 0 ;0
L 1.90068996 -1.90908002 1.90398996 -1.90901004 0 P 0 ;0
L 1.90398996 -1.90901004 1.90728002 -1.90915 0 P 0 ;0
L 1.90728002 -1.90915 1.91058996 -1.90951004 0 P 0 ;0
L 1.91058996 -1.90951004 1.91383996 -1.91006004 0 P 0 ;0
L 1.91383996 -1.91006004 1.91558996 -1.91048996 0 P 0 ;0
L 1.91558996 -1.91048996 1.91728996 -1.91101998 0 P 0 ;0
L 1.91728996 -1.91101998 1.91895 -1.91168002 0 P 0 ;0
L 1.91895 -1.91168002 1.92001998 -1.9122 0 P 0 ;0
L 1.92001998 -1.9122 1.92105 -1.91278996 0 P 0 ;0
L 1.92105 -1.91278996 1.92376998 -1.91458002 0 P 0 ;0
L 1.92376998 -1.91458002 1.92648996 -1.91666998 0 P 0 ;0
L 1.92648996 -1.91666998 1.92763002 -1.91763996 0 P 0 ;0
L 1.92763002 -1.91763996 1.92871004 -1.91865 0 P 0 ;0
L 1.92871004 -1.91865 1.93018002 -1.92018996 0 P 0 ;0
L 1.93018002 -1.92018996 1.93153002 -1.9218 0 P 0 ;0
L 1.93153002 -1.9218 1.93276998 -1.92348996 0 P 0 ;0
L 1.93276998 -1.92348996 1.93381004 -1.92515 0 P 0 ;0
L 1.93381004 -1.92515 1.93471998 -1.92686998 0 P 0 ;0
L 1.93471998 -1.92686998 1.9355 -1.92866998 0 P 0 ;0
L 1.9355 -1.92866998 1.93616998 -1.93061004 0 P 0 ;0
L 1.93616998 -1.93061004 1.93668996 -1.93258002 0 P 0 ;0
L 1.93668996 -1.93258002 1.93706998 -1.93458996 0 P 0 ;0
L 1.93706998 -1.93458996 1.93746998 -1.93818996 0 P 0 ;0
L 1.93746998 -1.93818996 1.9376 -1.94178996 0 P 0 ;0
L 1.9376 -1.94178996 1.93746004 -1.94611004 0 P 0 ;0
L 1.93746004 -1.94611004 1.93731004 -1.94758996 0 P 0 ;0
L 1.93731004 -1.94758996 1.93705 -1.94903996 0 P 0 ;0
L 1.93705 -1.94903996 1.93666998 -1.95041998 0 P 0 ;0
L 1.93666998 -1.95041998 1.93618002 -1.95176004 0 P 0 ;0
L 1.93618002 -1.95176004 1.9345 -1.95545 0 P 0 ;0
L 1.9345 -1.95545 1.93338996 -1.9575 0 P 0 ;0
L 1.93338996 -1.9575 1.93216004 -1.95946998 0 P 0 ;0
L 1.93216004 -1.95946998 1.93078996 -1.96133996 0 P 0 ;0
L 1.93078996 -1.96133996 1.92931004 -1.96311998 0 P 0 ;0
L 1.92931004 -1.96311998 1.92776998 -1.96473002 0 P 0 ;0
L 1.92776998 -1.96473002 1.92613002 -1.96621004 0 P 0 ;0
L 1.92613002 -1.96621004 1.92438002 -1.96756004 0 P 0 ;0
L 1.92438002 -1.96756004 1.92253002 -1.96878002 0 P 0 ;0
L 1.92253002 -1.96878002 1.92056998 -1.96986998 0 P 0 ;0
L 1.92056998 -1.96986998 1.91855 -1.97081998 0 P 0 ;0
L 1.91855 -1.97081998 1.91646004 -1.97161004 0 P 0 ;0
L 1.91646004 -1.97161004 1.91433002 -1.97223996 0 P 0 ;0
L 1.91433002 -1.97223996 1.9112 -1.97291004 0 P 0 ;0
L 1.9112 -1.97291004 1.90803996 -1.97331998 0 P 0 ;0
L 1.90803996 -1.97331998 1.90483996 -1.97346004 0 P 0 ;0
L 1.90476004 -1.97173996 1.9048 -1.97173996 0 P 0 ;0
L 1.9048 -1.97173996 1.90483996 -1.97173002 0 P 0 ;0
L 1.90483996 -1.97173002 1.90736004 -1.9716 0 P 0 ;0
L 1.90736004 -1.9716 1.9074 -1.97158996 0 P 0 ;0
L 1.9074 -1.97158996 1.90746998 -1.97158996 0 P 0 ;0
L 1.90746998 -1.97158996 1.90751004 -1.97158002 0 P 0 ;0
L 1.90751004 -1.97158002 1.91001004 -1.97126004 0 P 0 ;0
L 1.91001004 -1.97126004 1.91005 -1.97125 0 P 0 ;0
L 1.91005 -1.97125 1.91008002 -1.97123996 0 P 0 ;0
L 1.91008002 -1.97123996 1.91011998 -1.97123996 0 P 0 ;0
L 1.91011998 -1.97123996 1.91016004 -1.97123002 0 P 0 ;0
L 1.91016004 -1.97123002 1.9126 -1.97071998 0 P 0 ;0
L 1.9126 -1.97071998 1.9126 -1.97071004 0 P 0 ;0
L 1.9126 -1.97071004 1.91266998 -1.97071004 0 P 0 ;0
L 1.91266998 -1.97071004 1.91271004 -1.97068996 0 P 0 ;0
L 1.91271004 -1.97068996 1.91275 -1.97068002 0 P 0 ;0
L 1.91275 -1.97068002 1.91511998 -1.96998996 0 P 0 ;0
L 1.91511998 -1.96998996 1.91515 -1.96998996 0 P 0 ;0
L 1.91515 -1.96998996 1.91518996 -1.96996998 0 P 0 ;0
L 1.91518996 -1.96996998 1.91523002 -1.96996004 0 P 0 ;0
L 1.91523002 -1.96996004 1.91526004 -1.96995 0 P 0 ;0
L 1.91526004 -1.96995 1.91756998 -1.96908002 0 P 0 ;0
L 1.91756998 -1.96908002 1.91761004 -1.96906998 0 P 0 ;0
L 1.91761004 -1.96906998 1.91768002 -1.96903996 0 P 0 ;0
L 1.91768002 -1.96903996 1.91771004 -1.96901998 0 P 0 ;0
L 1.91771004 -1.96901998 1.91995 -1.96798002 0 P 0 ;0
L 1.91995 -1.96798002 1.92001998 -1.96795 0 P 0 ;0
L 1.92001998 -1.96795 1.92005 -1.96793002 0 P 0 ;0
L 1.92005 -1.96793002 1.92008996 -1.96791004 0 P 0 ;0
L 1.92008996 -1.96791004 1.92168002 -1.96701998 0 P 0 ;0
L 1.92168002 -1.96701998 1.92171998 -1.967 0 P 0 ;0
L 1.92171998 -1.967 1.92175 -1.96698002 0 P 0 ;0
L 1.92175 -1.96698002 1.92178996 -1.96695 0 P 0 ;0
L 1.92178996 -1.96695 1.92181998 -1.96693002 0 P 0 ;0
L 1.92181998 -1.96693002 1.92331998 -1.96591998 0 P 0 ;0
L 1.92331998 -1.96591998 1.92336004 -1.9659 0 P 0 ;0
L 1.92336004 -1.9659 1.92341998 -1.96586004 0 P 0 ;0
L 1.92341998 -1.96586004 1.92345 -1.96583002 0 P 0 ;0
L 1.92345 -1.96583002 1.92486004 -1.9647 0 P 0 ;0
L 1.92486004 -1.9647 1.92493002 -1.96465 0 P 0 ;0
L 1.92493002 -1.96465 1.92496004 -1.96463002 0 P 0 ;0
L 1.92496004 -1.96463002 1.92498996 -1.9646 0 P 0 ;0
L 1.92498996 -1.9646 1.92631004 -1.96336998 0 P 0 ;0
L 1.92631004 -1.96336998 1.9264 -1.96328002 0 P 0 ;0
L 1.9264 -1.96328002 1.92641998 -1.96325 0 P 0 ;0
L 1.92641998 -1.96325 1.92763996 -1.96191998 0 P 0 ;0
L 1.92763996 -1.96191998 1.92766998 -1.96188996 0 P 0 ;0
L 1.92766998 -1.96188996 1.92768996 -1.96186004 0 P 0 ;0
L 1.92768996 -1.96186004 1.92771998 -1.96183002 0 P 0 ;0
L 1.92771998 -1.96183002 1.92773996 -1.9618 0 P 0 ;0
L 1.92773996 -1.9618 1.92913996 -1.96001004 0 P 0 ;0
L 1.92913996 -1.96001004 1.92918996 -1.95995 0 P 0 ;0
L 1.92918996 -1.95995 1.92921004 -1.95991004 0 P 0 ;0
L 1.92921004 -1.95991004 1.92923002 -1.95988002 0 P 0 ;0
L 1.92923002 -1.95988002 1.93048002 -1.95798996 0 P 0 ;0
L 1.93048002 -1.95798996 1.93051998 -1.95793002 0 P 0 ;0
L 1.93051998 -1.95793002 1.93053996 -1.95788996 0 P 0 ;0
L 1.93053996 -1.95788996 1.93056004 -1.95786004 0 P 0 ;0
L 1.93056004 -1.95786004 1.93166004 -1.95588002 0 P 0 ;0
L 1.93166004 -1.95588002 1.93171004 -1.95576998 0 P 0 ;0
L 1.93171004 -1.95576998 1.93173002 -1.95573996 0 P 0 ;0
L 1.93173002 -1.95573996 1.93266998 -1.95366998 0 P 0 ;0
L 1.93266998 -1.95366998 1.93271004 -1.95356998 0 P 0 ;0
L 1.93271004 -1.95356998 1.93273002 -1.95353002 0 P 0 ;0
L 1.93273002 -1.95353002 1.9335 -1.9514 0 P 0 ;0
L 1.9335 -1.9514 1.93351004 -1.95136998 0 P 0 ;0
L 1.93351004 -1.95136998 1.93353002 -1.95133002 0 P 0 ;0
L 1.93353002 -1.95133002 1.93355 -1.95125 0 P 0 ;0
L 1.93355 -1.95125 1.93416004 -1.94906998 0 P 0 ;0
L 1.93416004 -1.94906998 1.93416998 -1.94903002 0 P 0 ;0
L 1.93416998 -1.94903002 1.93418002 -1.949 0 P 0 ;0
L 1.93418002 -1.949 1.93418002 -1.94896004 0 P 0 ;0
L 1.93418002 -1.94896004 1.93418996 -1.94891998 0 P 0 ;0
L 1.93418996 -1.94891998 1.93463996 -1.94665 0 P 0 ;0
L 1.93463996 -1.94665 1.93463996 -1.94661004 0 P 0 ;0
L 1.93463996 -1.94661004 1.93465 -1.94656998 0 P 0 ;0
L 1.93465 -1.94656998 1.93466004 -1.9465 0 P 0 ;0
L 1.93466004 -1.9465 1.93493996 -1.9442 0 P 0 ;0
L 1.93493996 -1.9442 1.93493996 -1.94413002 0 P 0 ;0
L 1.93493996 -1.94413002 1.93495 -1.94408996 0 P 0 ;0
L 1.93495 -1.94408996 1.93495 -1.94406004 0 P 0 ;0
L 1.93495 -1.94406004 1.93505 -1.94173996 0 P 0 ;0
L 1.93505 -1.94173996 1.93506004 -1.94171004 0 P 0 ;0
L 1.93506004 -1.94171004 1.93506004 -1.9416 0 P 0 ;0
L 1.93506004 -1.9416 1.93498996 -1.93928996 0 P 0 ;0
L 1.93498996 -1.93928996 1.93498996 -1.93921004 0 P 0 ;0
L 1.93498996 -1.93921004 1.93498002 -1.93913996 0 P 0 ;0
L 1.93498002 -1.93913996 1.93475 -1.93683996 0 P 0 ;0
L 1.93475 -1.93683996 1.93473996 -1.93676998 0 P 0 ;0
L 1.93473996 -1.93676998 1.93473002 -1.93673002 0 P 0 ;0
L 1.93473002 -1.93673002 1.93473002 -1.93668996 0 P 0 ;0
L 1.93473002 -1.93668996 1.93433002 -1.93441004 0 P 0 ;0
L 1.93433002 -1.93441004 1.93431998 -1.93436998 0 P 0 ;0
L 1.93431998 -1.93436998 1.93431004 -1.93433996 0 P 0 ;0
L 1.93431004 -1.93433996 1.93428996 -1.93426004 0 P 0 ;0
L 1.93428996 -1.93426004 1.93373002 -1.93206004 0 P 0 ;0
L 1.93373002 -1.93206004 1.93368996 -1.93191998 0 P 0 ;0
L 1.93368996 -1.93191998 1.93296004 -1.92976998 0 P 0 ;0
L 1.93296004 -1.92976998 1.93293996 -1.9297 0 P 0 ;0
L 1.93293996 -1.9297 1.93291004 -1.92963002 0 P 0 ;0
L 1.93291004 -1.92963002 1.93201998 -1.92753996 0 P 0 ;0
L 1.93201998 -1.92753996 1.93196998 -1.92743002 0 P 0 ;0
L 1.93196998 -1.92743002 1.93196004 -1.9274 0 P 0 ;0
L 1.93196004 -1.9274 1.93091998 -1.92538996 0 P 0 ;0
L 1.93091998 -1.92538996 1.9309 -1.92536004 0 P 0 ;0
L 1.9309 -1.92536004 1.93088002 -1.92531998 0 P 0 ;0
L 1.93088002 -1.92531998 1.93086004 -1.92528996 0 P 0 ;0
L 1.93086004 -1.92528996 1.93083996 -1.92525 0 P 0 ;0
L 1.93083996 -1.92525 1.92965 -1.92331998 0 P 0 ;0
L 1.92965 -1.92331998 1.92956998 -1.9232 0 P 0 ;0
L 1.92956998 -1.9232 1.92823002 -1.92136004 0 P 0 ;0
L 1.92823002 -1.92136004 1.92818002 -1.9213 0 P 0 ;0
L 1.92818002 -1.9213 1.92816004 -1.92126998 0 P 0 ;0
L 1.92816004 -1.92126998 1.92813002 -1.92123996 0 P 0 ;0
L 1.92813002 -1.92123996 1.92671998 -1.91958002 0 P 0 ;0
L 1.92671998 -1.91958002 1.9266 -1.91946004 0 P 0 ;0
L 1.9266 -1.91946004 1.92505 -1.91793002 0 P 0 ;0
L 1.92505 -1.91793002 1.92498996 -1.91786998 0 P 0 ;0
L 1.92498996 -1.91786998 1.92493002 -1.91781998 0 P 0 ;0
L 1.92493002 -1.91781998 1.92325 -1.91643002 0 P 0 ;0
L 1.92325 -1.91643002 1.92318996 -1.91636998 0 P 0 ;0
L 1.92318996 -1.91636998 1.92311998 -1.91631998 0 P 0 ;0
L 1.92311998 -1.91631998 1.92133002 -1.91508002 0 P 0 ;0
L 1.92133002 -1.91508002 1.92126004 -1.91503996 0 P 0 ;0
L 1.92126004 -1.91503996 1.92121998 -1.91501004 0 P 0 ;0
L 1.92121998 -1.91501004 1.92118002 -1.91498996 0 P 0 ;0
L 1.92118002 -1.91498996 1.91928996 -1.91391004 0 P 0 ;0
L 1.91928996 -1.91391004 1.91926004 -1.91388996 0 P 0 ;0
L 1.91926004 -1.91388996 1.91913996 -1.91383002 0 P 0 ;0
L 1.91913996 -1.91383002 1.91716998 -1.91291004 0 P 0 ;0
L 1.91716998 -1.91291004 1.91711998 -1.91288996 0 P 0 ;0
L 1.91711998 -1.91288996 1.91705 -1.91286004 0 P 0 ;0
L 1.91705 -1.91286004 1.917 -1.91285 0 P 0 ;0
L 1.917 -1.91285 1.91476998 -1.91203996 0 P 0 ;0
L 1.91476998 -1.91203996 1.91468996 -1.91201998 0 P 0 ;0
L 1.91468996 -1.91201998 1.91465 -1.912 0 P 0 ;0
L 1.91465 -1.912 1.9146 -1.91198996 0 P 0 ;0
L 1.9146 -1.91198996 1.91233002 -1.91138996 0 P 0 ;0
L 1.91233002 -1.91138996 1.91228002 -1.91138002 0 P 0 ;0
L 1.91228002 -1.91138002 1.91223996 -1.91136998 0 P 0 ;0
L 1.91223996 -1.91136998 1.91216004 -1.91136004 0 P 0 ;0
L 1.91216004 -1.91136004 1.90983002 -1.91095 0 P 0 ;0
L 1.90983002 -1.91095 1.9098 -1.91093996 0 P 0 ;0
L 1.9098 -1.91093996 1.90976004 -1.91093996 0 P 0 ;0
L 1.90976004 -1.91093996 1.90971998 -1.91093002 0 P 0 ;0
L 1.90971998 -1.91093002 1.90968002 -1.91093002 0 P 0 ;0
L 1.90968002 -1.91093002 1.90713996 -1.91068996 0 P 0 ;0
L 1.90713996 -1.91068996 1.9071 -1.91068002 0 P 0 ;0
L 1.9071 -1.91068002 1.907 -1.91068002 0 P 0 ;0
L 1.907 -1.91068002 1.90445 -1.91061004 0 P 0 ;0
L 1.90445 -1.91061004 1.90431004 -1.91061004 0 P 0 ;0
L 1.90431004 -1.91061004 1.90176004 -1.91071004 0 P 0 ;0
L 1.90176004 -1.91071004 1.90173002 -1.91071998 0 P 0 ;0
L 1.90173002 -1.91071998 1.90166004 -1.91071998 0 P 0 ;0
L 1.90166004 -1.91071998 1.90161998 -1.91073002 0 P 0 ;0
L 1.90161998 -1.91073002 1.89913002 -1.911 0 P 0 ;0
L 1.89913002 -1.911 1.89906004 -1.91101004 0 P 0 ;0
L 1.89906004 -1.91101004 1.89901998 -1.91101998 0 P 0 ;0
L 1.89901998 -1.91101998 1.89898996 -1.91101998 0 P 0 ;0
L 1.89898996 -1.91101998 1.89653002 -1.91146998 0 P 0 ;0
L 1.89653002 -1.91146998 1.8965 -1.91148002 0 P 0 ;0
L 1.8965 -1.91148002 1.89646004 -1.91148002 0 P 0 ;0
L 1.89646004 -1.91148002 1.8964 -1.9115 0 P 0 ;0
L 1.8964 -1.9115 1.89396998 -1.91211998 0 P 0 ;0
L 1.89396998 -1.91211998 1.89393996 -1.91213002 0 P 0 ;0
L 1.89393996 -1.91213002 1.89383002 -1.91216004 0 P 0 ;0
L 1.89383002 -1.91216004 1.89225 -1.91268996 0 P 0 ;0
L 1.89225 -1.91268996 1.89218002 -1.91271998 0 P 0 ;0
L 1.89218002 -1.91271998 1.89211004 -1.91273996 0 P 0 ;0
L 1.89211004 -1.91273996 1.8921 -1.91273996 0 P 0 ;0
L 1.8921 -1.91273996 1.89058002 -1.91338996 0 P 0 ;0
L 1.89058002 -1.91338996 1.89043996 -1.91345 0 P 0 ;0
L 1.89043996 -1.91345 1.88896004 -1.91421004 0 P 0 ;0
L 1.88896004 -1.91421004 1.88893002 -1.91423002 0 P 0 ;0
L 1.88893002 -1.91423002 1.8889 -1.91423996 0 P 0 ;0
L 1.8889 -1.91423996 1.88886004 -1.91426004 0 P 0 ;0
L 1.88886004 -1.91426004 1.88883002 -1.91428002 0 P 0 ;0
L 1.88883002 -1.91428002 1.88741004 -1.91515 0 P 0 ;0
L 1.88741004 -1.91515 1.88733996 -1.91518996 0 P 0 ;0
L 1.88733996 -1.91518996 1.88728002 -1.91523996 0 P 0 ;0
L 1.88728002 -1.91523996 1.88526004 -1.9167 0 P 0 ;0
L 1.88526004 -1.9167 1.88521998 -1.91673002 0 P 0 ;0
L 1.88521998 -1.91673002 1.88518996 -1.91675 0 P 0 ;0
L 1.88518996 -1.91675 1.88516004 -1.91678002 0 P 0 ;0
L 1.88516004 -1.91678002 1.88511998 -1.91681004 0 P 0 ;0
L 1.88511998 -1.91681004 1.88323002 -1.91845 0 P 0 ;0
L 1.88323002 -1.91845 1.8832 -1.91846998 0 P 0 ;0
L 1.8832 -1.91846998 1.88311004 -1.91856004 0 P 0 ;0
L 1.88311004 -1.91856004 1.88136998 -1.92036004 0 P 0 ;0
L 1.88136998 -1.92036004 1.88128002 -1.92045 0 P 0 ;0
L 1.88128002 -1.92045 1.88125 -1.92048996 0 P 0 ;0
L 1.88125 -1.92048996 1.87968002 -1.92241998 0 P 0 ;0
L 1.87968002 -1.92241998 1.87965 -1.92245 0 P 0 ;0
L 1.87965 -1.92245 1.87961998 -1.92248996 0 P 0 ;0
L 1.87961998 -1.92248996 1.87956998 -1.92256004 0 P 0 ;0
L 1.87956998 -1.92256004 1.87816998 -1.92461998 0 P 0 ;0
L 1.87816998 -1.92461998 1.8781 -1.92473002 0 P 0 ;0
L 1.8781 -1.92473002 1.87808002 -1.92476998 0 P 0 ;0
L 1.87808002 -1.92476998 1.87685 -1.92695 0 P 0 ;0
L 1.87685 -1.92695 1.87683002 -1.92698996 0 P 0 ;0
L 1.87683002 -1.92698996 1.87681004 -1.92701998 0 P 0 ;0
L 1.87681004 -1.92701998 1.87678996 -1.92706998 0 P 0 ;0
L 1.87678996 -1.92706998 1.87676998 -1.92711004 0 P 0 ;0
L 1.87676998 -1.92711004 1.87573002 -1.92941004 0 P 0 ;0
L 1.87573002 -1.92941004 1.87571004 -1.92945 0 P 0 ;0
L 1.87571004 -1.92945 1.8757 -1.92948996 0 P 0 ;0
L 1.8757 -1.92948996 1.87568002 -1.92951998 0 P 0 ;0
L 1.87568002 -1.92951998 1.87566998 -1.92956998 0 P 0 ;0
L 1.87566998 -1.92956998 1.87483996 -1.93193002 0 P 0 ;0
L 1.87483996 -1.93193002 1.87481004 -1.93201004 0 P 0 ;0
L 1.87481004 -1.93201004 1.87478996 -1.93208996 0 P 0 ;0
L 1.87478996 -1.93208996 1.87416004 -1.93451998 0 P 0 ;0
L 1.87416004 -1.93451998 1.87413996 -1.93456004 0 P 0 ;0
L 1.87413996 -1.93456004 1.87413002 -1.9346 0 P 0 ;0
L 1.87413002 -1.9346 1.87413002 -1.93463996 0 P 0 ;0
L 1.87413002 -1.93463996 1.87411998 -1.93468002 0 P 0 ;0
L 1.87411998 -1.93468002 1.8737 -1.93715 0 P 0 ;0
L 1.8737 -1.93715 1.87368996 -1.93718996 0 P 0 ;0
L 1.87368996 -1.93718996 1.87368002 -1.93723996 0 P 0 ;0
L 1.87368002 -1.93723996 1.87368002 -1.93731998 0 P 0 ;0
L 1.87368002 -1.93731998 1.87346998 -1.93981998 0 P 0 ;0
L 1.87346998 -1.93981998 1.87346004 -1.93986004 0 P 0 ;0
L 1.87346004 -1.93986004 1.87346004 -1.94258002 0 P 0 ;0
L 1.87346004 -1.94258002 1.87346998 -1.94266004 0 P 0 ;0
L 1.87346998 -1.94266004 1.87368002 -1.94516998 0 P 0 ;0
L 1.87368002 -1.94516998 1.87368996 -1.94521004 0 P 0 ;0
L 1.87368996 -1.94521004 1.87368996 -1.94525 0 P 0 ;0
L 1.87368996 -1.94525 1.87371004 -1.94533996 0 P 0 ;0
L 1.87371004 -1.94533996 1.87413996 -1.94778996 0 P 0 ;0
L 1.87413996 -1.94778996 1.87413996 -1.94783996 0 P 0 ;0
L 1.87413996 -1.94783996 1.87416998 -1.94796004 0 P 0 ;0
L 1.87416998 -1.94796004 1.87481004 -1.95036998 0 P 0 ;0
L 1.87481004 -1.95036998 1.87483996 -1.95048996 0 P 0 ;0
L 1.87483996 -1.95048996 1.87486004 -1.95053002 0 P 0 ;0
L 1.87486004 -1.95053002 1.8757 -1.95288002 0 P 0 ;0
L 1.8757 -1.95288002 1.87571004 -1.95291998 0 P 0 ;0
L 1.87571004 -1.95291998 1.87575 -1.953 0 P 0 ;0
L 1.87575 -1.953 1.87576004 -1.95303996 0 P 0 ;0
L 1.87576004 -1.95303996 1.8768 -1.9553 0 P 0 ;0
L 1.8768 -1.9553 1.87686004 -1.95541998 0 P 0 ;0
L 1.87686004 -1.95541998 1.87688002 -1.95545 0 P 0 ;0
L 1.87688002 -1.95545 1.8781 -1.95761004 0 P 0 ;0
L 1.8781 -1.95761004 1.87811998 -1.95761004 0 P 0 ;0
L 1.87811998 -1.95761004 1.8781 -1.95761998 0 P 0 ;0
L 1.8781 -1.95761998 1.87813996 -1.95768996 0 P 0 ;0
L 1.87813996 -1.95768996 1.87816998 -1.95771998 0 P 0 ;0
L 1.87816998 -1.95771998 1.87818996 -1.95775 0 P 0 ;0
L 1.87818996 -1.95775 1.87938002 -1.95951004 0 P 0 ;0
L 1.87938002 -1.95951004 1.87943996 -1.9596 0 P 0 ;0
L 1.87943996 -1.9596 1.87946998 -1.95963002 0 P 0 ;0
L 1.87946998 -1.95963002 1.88078002 -1.96128996 0 P 0 ;0
L 1.88078002 -1.96128996 1.88081004 -1.96131998 0 P 0 ;0
L 1.88081004 -1.96131998 1.88083002 -1.96135 0 P 0 ;0
L 1.88083002 -1.96135 1.88086004 -1.96136998 0 P 0 ;0
L 1.88086004 -1.96136998 1.88088002 -1.9614 0 P 0 ;0
L 1.88088002 -1.9614 1.88231998 -1.96295 0 P 0 ;0
L 1.88231998 -1.96295 1.88233996 -1.96298002 0 P 0 ;0
L 1.88233996 -1.96298002 1.8824 -1.96303996 0 P 0 ;0
L 1.8824 -1.96303996 1.88243002 -1.96306004 0 P 0 ;0
L 1.88243002 -1.96306004 1.88398002 -1.9645 0 P 0 ;0
L 1.88398002 -1.9645 1.88401004 -1.96451998 0 P 0 ;0
L 1.88401004 -1.96451998 1.88403002 -1.96455 0 P 0 ;0
L 1.88403002 -1.96455 1.88406998 -1.96458002 0 P 0 ;0
L 1.88406998 -1.96458002 1.88408996 -1.9646 0 P 0 ;0
L 1.88408996 -1.9646 1.88575 -1.96591004 0 P 0 ;0
L 1.88575 -1.96591004 1.88578002 -1.96593996 0 P 0 ;0
L 1.88578002 -1.96593996 1.88586998 -1.966 0 P 0 ;0
L 1.88586998 -1.966 1.88761998 -1.96718996 0 P 0 ;0
L 1.88761998 -1.96718996 1.88766004 -1.96721004 0 P 0 ;0
L 1.88766004 -1.96721004 1.88775 -1.96726998 0 P 0 ;0
L 1.88775 -1.96726998 1.88958996 -1.96831998 0 P 0 ;0
L 1.88958996 -1.96831998 1.88965 -1.96836004 0 P 0 ;0
L 1.88965 -1.96836004 1.88968002 -1.96836998 0 P 0 ;0
L 1.88968002 -1.96836998 1.88971998 -1.96838996 0 P 0 ;0
L 1.88971998 -1.96838996 1.89145 -1.96921998 0 P 0 ;0
L 1.89145 -1.96921998 1.89151004 -1.96925 0 P 0 ;0
L 1.89151004 -1.96925 1.89155 -1.96926004 0 P 0 ;0
L 1.89155 -1.96926004 1.89158002 -1.96926998 0 P 0 ;0
L 1.89158002 -1.96926998 1.89336004 -1.96996998 0 P 0 ;0
L 1.89336004 -1.96996998 1.89336004 -1.96998002 0 P 0 ;0
L 1.89336004 -1.96998002 1.89346004 -1.97001004 0 P 0 ;0
L 1.89346004 -1.97001004 1.89348996 -1.97001998 0 P 0 ;0
L 1.89348996 -1.97001998 1.89531998 -1.9706 0 P 0 ;0
L 1.89531998 -1.9706 1.89536004 -1.97061004 0 P 0 ;0
L 1.89536004 -1.97061004 1.89541998 -1.97063002 0 P 0 ;0
L 1.89541998 -1.97063002 1.89546004 -1.97063002 0 P 0 ;0
L 1.89546004 -1.97063002 1.89731998 -1.97108002 0 P 0 ;0
L 1.89731998 -1.97108002 1.89741998 -1.9711 0 P 0 ;0
L 1.89741998 -1.9711 1.89746004 -1.9711 0 P 0 ;0
L 1.89746004 -1.9711 1.89746004 -1.97111004 0 P 0 ;0
L 1.89746004 -1.97111004 1.89933996 -1.97141998 0 P 0 ;0
L 1.89933996 -1.97141998 1.89936998 -1.97143002 0 P 0 ;0
L 1.89936998 -1.97143002 1.89941004 -1.97143002 0 P 0 ;0
L 1.89941004 -1.97143002 1.89945 -1.97143996 0 P 0 ;0
L 1.89945 -1.97143996 1.89948002 -1.97143996 0 P 0 ;0
L 1.89948002 -1.97143996 1.90201004 -1.97168002 0 P 0 ;0
L 1.90201004 -1.97168002 1.90205 -1.97168002 0 P 0 ;0
L 1.90205 -1.97168002 1.90208996 -1.97168996 0 P 0 ;0
L 1.90208996 -1.97168996 1.90216004 -1.97168996 0 P 0 ;0
L 1.90216004 -1.97168996 1.90468996 -1.97173996 0 P 0 ;0
L 1.90468996 -1.97173996 1.90476004 -1.97173996 0 P 0 ;0
L 1.80616004 -2.12823996 1.83348996 -2.12823996 0 P 0 ;0
L 1.79591998 -2.12723996 1.8396 -2.12723996 0 P 0 ;0
L 1.78818002 -2.12623996 1.84465 -2.12623996 0 P 0 ;0
L 1.82003996 -2.09123996 1.87618996 -2.09123996 0 P 0 ;0
L 1.82198996 -2.09023996 1.8762 -2.09023996 0 P 0 ;0
L 1.82325 -2.08923996 1.8762 -2.08923996 0 P 0 ;0
L 1.82411998 -2.08823996 1.87618996 -2.08823996 0 P 0 ;0
L 1.82463002 -2.08723996 1.87616998 -2.08723996 0 P 0 ;0
L 1.82488002 -2.08623996 1.87615 -2.08623996 0 P 0 ;0
L 1.82493002 -2.08523996 1.87613002 -2.08523996 0 P 0 ;0
L 1.82476998 -2.08423996 1.87611004 -2.08423996 0 P 0 ;0
L 1.64846004 -2.08295 1.73316998 -2.08295 0 P 0 ;0
L 1.64811998 -2.08195 1.73356998 -2.08195 0 P 0 ;0
L 1.64776998 -2.08095 1.73398002 -2.08095 0 P 0 ;0
L 1.64743002 -2.07995 1.73438002 -2.07995 0 P 0 ;0
L 1.64708996 -2.07895 1.73478996 -2.07895 0 P 0 ;0
L 1.64673996 -2.07795 1.7352 -2.07795 0 P 0 ;0
L 1.6464 -2.07695 1.7356 -2.07695 0 P 0 ;0
L 1.64605 -2.07595 1.73601004 -2.07595 0 P 0 ;0
L 1.64571004 -2.07495 1.73641004 -2.07495 0 P 0 ;0
L 1.64536004 -2.07395 1.73681004 -2.07395 0 P 0 ;0
L 1.64501998 -2.07295 1.73721998 -2.07295 0 P 0 ;0
L 1.64466998 -2.07195 1.73761998 -2.07195 0 P 0 ;0
L 1.64433002 -2.07095 1.73803002 -2.07095 0 P 0 ;0
L 1.64398002 -2.06995 1.69251004 -2.06995 0 P 0 ;0
L 1.69583002 -2.06995 1.73843996 -2.06995 0 P 0 ;0
L 1.64363002 -2.06895 1.69168002 -2.06895 0 P 0 ;0
L 1.69671998 -2.06895 1.73883996 -2.06895 0 P 0 ;0
L 1.64328996 -2.06795 1.69136004 -2.06795 0 P 0 ;0
L 1.69708996 -2.06795 1.73925 -2.06795 0 P 0 ;0
L 1.64293996 -2.06695 1.69108002 -2.06695 0 P 0 ;0
L 1.69738002 -2.06695 1.73965 -2.06695 0 P 0 ;0
L 1.64258996 -2.06595 1.6908 -2.06595 0 P 0 ;0
L 1.69768002 -2.06595 1.74006004 -2.06595 0 P 0 ;0
L 1.64223996 -2.06495 1.69051998 -2.06495 0 P 0 ;0
L 1.69796998 -2.06495 1.74046004 -2.06495 0 P 0 ;0
L 1.6419 -2.06395 1.69023002 -2.06395 0 P 0 ;0
L 1.69826998 -2.06395 1.74086004 -2.06395 0 P 0 ;0
L 1.64155 -2.06295 1.68996004 -2.06295 0 P 0 ;0
L 1.69856004 -2.06295 1.74126998 -2.06295 0 P 0 ;0
L 1.6412 -2.06195 1.68966998 -2.06195 0 P 0 ;0
L 1.69886004 -2.06195 1.74168002 -2.06195 0 P 0 ;0
L 1.64085 -2.06095 1.68938996 -2.06095 0 P 0 ;0
L 1.69915 -2.06095 1.74208002 -2.06095 0 P 0 ;0
L 1.6405 -2.05995 1.68911004 -2.05995 0 P 0 ;0
L 1.69945 -2.05995 1.74248002 -2.05995 0 P 0 ;0
L 1.64016004 -2.05895 1.68883002 -2.05895 0 P 0 ;0
L 1.69973996 -2.05895 1.74288996 -2.05895 0 P 0 ;0
L 1.63981004 -2.05795 1.68855 -2.05795 0 P 0 ;0
L 1.70003996 -2.05795 1.74328996 -2.05795 0 P 0 ;0
L 1.63946004 -2.05695 1.68826998 -2.05695 0 P 0 ;0
L 1.70033002 -2.05695 1.7437 -2.05695 0 P 0 ;0
L 1.63911004 -2.05595 1.68798996 -2.05595 0 P 0 ;0
L 1.70063002 -2.05595 1.7441 -2.05595 0 P 0 ;0
L 1.63876998 -2.05495 1.68771004 -2.05495 0 P 0 ;0
L 1.70091998 -2.05495 1.74451004 -2.05495 0 P 0 ;0
L 1.63841998 -2.05395 1.68741998 -2.05395 0 P 0 ;0
L 1.70121998 -2.05395 1.74491004 -2.05395 0 P 0 ;0
L 1.63806998 -2.05295 1.68713996 -2.05295 0 P 0 ;0
L 1.70151004 -2.05295 1.74531004 -2.05295 0 P 0 ;0
L 1.63771998 -2.05195 1.68686004 -2.05195 0 P 0 ;0
L 1.70181004 -2.05195 1.74571998 -2.05195 0 P 0 ;0
L 1.63738002 -2.05095 1.68658002 -2.05095 0 P 0 ;0
L 1.7021 -2.05095 1.74611998 -2.05095 0 P 0 ;0
L 1.63703002 -2.04995 1.6863 -2.04995 0 P 0 ;0
L 1.7024 -2.04995 1.74653002 -2.04995 0 P 0 ;0
L 1.63668002 -2.04895 1.68601998 -2.04895 0 P 0 ;0
L 1.70268996 -2.04895 1.74693002 -2.04895 0 P 0 ;0
L 1.63633002 -2.04795 1.68573996 -2.04795 0 P 0 ;0
L 1.70298996 -2.04795 1.74733002 -2.04795 0 P 0 ;0
L 1.63598002 -2.04695 1.68546004 -2.04695 0 P 0 ;0
L 1.70328002 -2.04695 1.74773996 -2.04695 0 P 0 ;0
L 1.63563996 -2.04595 1.68518002 -2.04595 0 P 0 ;0
L 1.70358002 -2.04595 1.74813996 -2.04595 0 P 0 ;0
L 1.63528996 -2.04495 1.6849 -2.04495 0 P 0 ;0
L 1.70386998 -2.04495 1.74855 -2.04495 0 P 0 ;0
L 1.63493996 -2.04395 1.68461004 -2.04395 0 P 0 ;0
L 1.70416998 -2.04395 1.74895 -2.04395 0 P 0 ;0
L 1.63458996 -2.04295 1.68433002 -2.04295 0 P 0 ;0
L 1.70446004 -2.04295 1.74936004 -2.04295 0 P 0 ;0
L 1.63425 -2.04195 1.68405 -2.04195 0 P 0 ;0
L 1.70475 -2.04195 1.74976004 -2.04195 0 P 0 ;0
L 1.6339 -2.04095 1.68376998 -2.04095 0 P 0 ;0
L 1.70503002 -2.04095 1.75016004 -2.04095 0 P 0 ;0
L 1.63355 -2.03995 1.68348996 -2.03995 0 P 0 ;0
L 1.70531998 -2.03995 1.75056998 -2.03995 0 P 0 ;0
L 1.6332 -2.03895 1.68321004 -2.03895 0 P 0 ;0
L 1.7056 -2.03895 1.75096998 -2.03895 0 P 0 ;0
L 1.63286004 -2.03795 1.68293002 -2.03795 0 P 0 ;0
L 1.70588996 -2.03795 1.75138002 -2.03795 0 P 0 ;0
L 1.63251004 -2.03695 1.68266004 -2.03695 0 P 0 ;0
L 1.70618002 -2.03695 1.75178002 -2.03695 0 P 0 ;0
L 1.63216004 -2.03595 1.68238002 -2.03595 0 P 0 ;0
L 1.70646998 -2.03595 1.75218996 -2.03595 0 P 0 ;0
L 1.63181004 -2.03495 1.6821 -2.03495 0 P 0 ;0
L 1.70675 -2.03495 1.75258996 -2.03495 0 P 0 ;0
L 1.63146998 -2.03395 1.68183002 -2.03395 0 P 0 ;0
L 1.70703996 -2.03395 1.75298996 -2.03395 0 P 0 ;0
L 1.63111998 -2.03295 1.68155 -2.03295 0 P 0 ;0
L 1.70733002 -2.03295 1.7534 -2.03295 0 P 0 ;0
L 1.63076998 -2.03195 1.68126998 -2.03195 0 P 0 ;0
L 1.70761004 -2.03195 1.75381004 -2.03195 0 P 0 ;0
L 1.63041998 -2.03095 1.68098996 -2.03095 0 P 0 ;0
L 1.7079 -2.03095 1.75421004 -2.03095 0 P 0 ;0
L 1.63006998 -2.02995 1.68071004 -2.02995 0 P 0 ;0
L 1.70818996 -2.02995 1.75461004 -2.02995 0 P 0 ;0
L 1.62973002 -2.02895 1.68043996 -2.02895 0 P 0 ;0
L 1.70846998 -2.02895 1.75501998 -2.02895 0 P 0 ;0
L 1.62938002 -2.02795 1.68016004 -2.02795 0 P 0 ;0
L 1.70876004 -2.02795 1.75541998 -2.02795 0 P 0 ;0
L 1.62903002 -2.02695 1.67988002 -2.02695 0 P 0 ;0
L 1.70905 -2.02695 1.75583002 -2.02695 0 P 0 ;0
L 1.62868002 -2.02595 1.6796 -2.02595 0 P 0 ;0
L 1.70933996 -2.02595 1.75623002 -2.02595 0 P 0 ;0
L 1.62831004 -2.02495 1.67933002 -2.02495 0 P 0 ;0
L 1.70961998 -2.02495 1.75663996 -2.02495 0 P 0 ;0
L 1.62793996 -2.02395 1.67905 -2.02395 0 P 0 ;0
L 1.70991004 -2.02395 1.75703996 -2.02395 0 P 0 ;0
L 1.62756998 -2.02295 1.67876998 -2.02295 0 P 0 ;0
L 1.7102 -2.02295 1.75743996 -2.02295 0 P 0 ;0
L 1.6272 -2.02195 1.6785 -2.02195 0 P 0 ;0
L 1.71048002 -2.02195 1.75785 -2.02195 0 P 0 ;0
L 1.62683002 -2.02095 1.67821998 -2.02095 0 P 0 ;0
L 1.71076004 -2.02095 1.75825 -2.02095 0 P 0 ;0
L 1.62646998 -2.01995 1.67793996 -2.01995 0 P 0 ;0
L 1.71101004 -2.01995 1.75866004 -2.01995 0 P 0 ;0
L 1.6261 -2.01895 1.67766004 -2.01895 0 P 0 ;0
L 1.71126998 -2.01895 1.75906004 -2.01895 0 P 0 ;0
L 1.62573002 -2.01795 1.67738996 -2.01795 0 P 0 ;0
L 1.71151998 -2.01795 1.75946998 -2.01795 0 P 0 ;0
L 1.62536004 -2.01695 1.67711004 -2.01695 0 P 0 ;0
L 1.71176998 -2.01695 1.75986998 -2.01695 0 P 0 ;0
L 1.62498996 -2.01595 1.67683002 -2.01595 0 P 0 ;0
L 1.71203002 -2.01595 1.76026998 -2.01595 0 P 0 ;0
L 1.62461998 -2.01495 1.67656004 -2.01495 0 P 0 ;0
L 1.71228002 -2.01495 1.76068002 -2.01495 0 P 0 ;0
L 1.62425 -2.01395 1.67628002 -2.01395 0 P 0 ;0
L 1.71253996 -2.01395 1.76108002 -2.01395 0 P 0 ;0
L 1.62388002 -2.01295 1.67601998 -2.01295 0 P 0 ;0
L 1.71278996 -2.01295 1.76148996 -2.01295 0 P 0 ;0
L 1.62351004 -2.01195 1.67576998 -2.01195 0 P 0 ;0
L 1.71305 -2.01195 1.76188996 -2.01195 0 P 0 ;0
L 1.62313996 -2.01095 1.67551998 -2.01095 0 P 0 ;0
L 1.7133 -2.01095 1.76228996 -2.01095 0 P 0 ;0
L 1.62276998 -2.00995 1.67528002 -2.00995 0 P 0 ;0
L 1.71355 -2.00995 1.7627 -2.00995 0 P 0 ;0
L 1.6224 -2.00895 1.67503002 -2.00895 0 P 0 ;0
L 1.71381004 -2.00895 1.7631 -2.00895 0 P 0 ;0
L 1.62203002 -2.00795 1.67478996 -2.00795 0 P 0 ;0
L 1.71406004 -2.00795 1.76351004 -2.00795 0 P 0 ;0
L 1.62166004 -2.00695 1.67453996 -2.00695 0 P 0 ;0
L 1.71431004 -2.00695 1.76391004 -2.00695 0 P 0 ;0
L 1.62128996 -2.00595 1.67428996 -2.00595 0 P 0 ;0
L 1.71453996 -2.00595 1.76431998 -2.00595 0 P 0 ;0
L 1.62091004 -2.00495 1.67405 -2.00495 0 P 0 ;0
L 1.71476998 -2.00495 1.76471998 -2.00495 0 P 0 ;0
L 1.62051998 -2.00395 1.6738 -2.00395 0 P 0 ;0
L 1.715 -2.00395 1.76511998 -2.00395 0 P 0 ;0
L 1.62013002 -2.00295 1.67355 -2.00295 0 P 0 ;0
L 1.71523002 -2.00295 1.76553002 -2.00295 0 P 0 ;0
L 1.61973996 -2.00195 1.67331004 -2.00195 0 P 0 ;0
L 1.71546004 -2.00195 1.76593996 -2.00195 0 P 0 ;0
L 1.61935 -2.00095 1.67306004 -2.00095 0 P 0 ;0
L 1.71568996 -2.00095 1.76633996 -2.00095 0 P 0 ;0
L 1.61896004 -1.99995 1.67283996 -1.99995 0 P 0 ;0
L 1.71591998 -1.99995 1.76673996 -1.99995 0 P 0 ;0
L 1.61856998 -1.99895 1.67261998 -1.99895 0 P 0 ;0
L 1.71613996 -1.99895 1.76715 -1.99895 0 P 0 ;0
L 1.71638002 -1.99795 1.76755 -1.99795 0 P 0 ;0
L 1.7166 -1.99695 1.76796004 -1.99695 0 P 0 ;0
L 1.71683002 -1.99595 1.76836004 -1.99595 0 P 0 ;0
L 1.71866998 -1.99495 1.76876998 -1.99495 0 P 0 ;0
L 1.78213996 -2.04823996 1.84641998 -2.04823996 0 P 0 ;0
L 1.78138002 -2.04723996 1.84498996 -2.04723996 0 P 0 ;0
L 1.78071004 -2.04623996 1.84356004 -2.04623996 0 P 0 ;0
L 1.7801 -2.04523996 1.84213996 -2.04523996 0 P 0 ;0
L 1.77956004 -2.04423996 1.84071004 -2.04423996 0 P 0 ;0
L 1.77908996 -2.04323996 1.83928002 -2.04323996 0 P 0 ;0
L 1.77866004 -2.04223996 1.83786004 -2.04223996 0 P 0 ;0
L 1.77831004 -2.04123996 1.83658996 -2.04123996 0 P 0 ;0
L 1.77796004 -2.04023996 1.83536004 -2.04023996 0 P 0 ;0
L 1.77761004 -2.03923996 1.83428002 -2.03923996 0 P 0 ;0
L 1.77733996 -2.03823996 1.83321998 -2.03823996 0 P 0 ;0
L 1.77706998 -2.03723996 1.83236998 -2.03723996 0 P 0 ;0
L 1.7768 -2.03623996 1.83171004 -2.03623996 0 P 0 ;0
L 1.7766 -2.03523996 1.83121004 -2.03523996 0 P 0 ;0
L 1.77641004 -2.03423996 1.83085 -2.03423996 0 P 0 ;0
L 1.77621004 -2.03323996 1.83071004 -2.03323996 0 P 0 ;0
L 1.77608002 -2.03223996 1.83076998 -2.03223996 0 P 0 ;0
L 1.77596004 -2.03123996 1.83106004 -2.03123996 0 P 0 ;0
L 1.77583996 -2.03023996 1.83158996 -2.03023996 0 P 0 ;0
L 1.77576004 -2.02923996 1.83238002 -2.02923996 0 P 0 ;0
L 1.7757 -2.02823996 1.83356998 -2.02823996 0 P 0 ;0
L 1.7757 -2.02723996 1.83591998 -2.02723996 0 P 0 ;0
L 1.77571998 -2.02623996 1.87495 -2.02623996 0 P 0 ;0
L 1.7758 -2.02523996 1.87485 -2.02523996 0 P 0 ;0
L 1.77588996 -2.02423996 1.87475 -2.02423996 0 P 0 ;0
L 1.77605 -2.02323996 1.87465 -2.02323996 0 P 0 ;0
L 1.77621004 -2.02223996 1.87455 -2.02223996 0 P 0 ;0
L 1.7764 -2.02123996 1.87445 -2.02123996 0 P 0 ;0
L 1.77665 -2.02023996 1.87433996 -2.02023996 0 P 0 ;0
L 1.7769 -2.01923996 1.87425 -2.01923996 0 P 0 ;0
L 1.7772 -2.01823996 1.87413996 -2.01823996 0 P 0 ;0
L 1.77753002 -2.01723996 1.87405 -2.01723996 0 P 0 ;0
L 1.77786004 -2.01623996 1.87393996 -2.01623996 0 P 0 ;0
L 1.77823002 -2.01523996 1.87383996 -2.01523996 0 P 0 ;0
L 1.77863996 -2.01423996 1.87373996 -2.01423996 0 P 0 ;0
L 1.77903996 -2.01323996 1.87363996 -2.01323996 0 P 0 ;0
L 1.7795 -2.01223996 1.87353996 -2.01223996 0 P 0 ;0
L 1.77998996 -2.01123996 1.87343996 -2.01123996 0 P 0 ;0
L 1.78046998 -2.01023996 1.87333002 -2.01023996 0 P 0 ;0
L 1.78103996 -2.00923996 1.87323002 -2.00923996 0 P 0 ;0
L 1.78161004 -2.00823996 1.87311998 -2.00823996 0 P 0 ;0
L 1.78221004 -2.00723996 1.87301998 -2.00723996 0 P 0 ;0
L 1.78288002 -2.00623996 1.87291998 -2.00623996 0 P 0 ;0
L 1.64213996 -2.14795 1.70566004 -2.14795 0 P 0 ;0
L 1.64518996 -2.14695 1.7062 -2.14695 0 P 0 ;0
L 1.64728996 -2.14595 1.70673996 -2.14595 0 P 0 ;0
L 1.64906998 -2.14495 1.70728002 -2.14495 0 P 0 ;0
L 1.65058002 -2.14395 1.70783002 -2.14395 0 P 0 ;0
L 1.6519 -2.14295 1.70836998 -2.14295 0 P 0 ;0
L 1.65311998 -2.14195 1.70881998 -2.14195 0 P 0 ;0
L 1.65416998 -2.14095 1.70926998 -2.14095 0 P 0 ;0
L 1.65508996 -2.13995 1.70973002 -2.13995 0 P 0 ;0
L 1.65588002 -2.13895 1.71018002 -2.13895 0 P 0 ;0
L 1.65658002 -2.13795 1.71063002 -2.13795 0 P 0 ;0
L 1.65726998 -2.13695 1.71108996 -2.13695 0 P 0 ;0
L 1.65791998 -2.13595 1.71153996 -2.13595 0 P 0 ;0
L 1.65853002 -2.13495 1.71198996 -2.13495 0 P 0 ;0
L 1.65913002 -2.13395 1.71245 -2.13395 0 P 0 ;0
L 1.65968002 -2.13295 1.7129 -2.13295 0 P 0 ;0
L 1.66021998 -2.13195 1.71331004 -2.13195 0 P 0 ;0
L 1.66071998 -2.13095 1.71371998 -2.13095 0 P 0 ;0
L 1.66121004 -2.12995 1.71411998 -2.12995 0 P 0 ;0
L 1.66166998 -2.12895 1.71453002 -2.12895 0 P 0 ;0
L 1.66201004 -2.12795 1.71493996 -2.12795 0 P 0 ;0
L 1.66223996 -2.12695 1.71533996 -2.12695 0 P 0 ;0
L 1.66235 -2.12595 1.71575 -2.12595 0 P 0 ;0
L 1.66236004 -2.12495 1.71615 -2.12495 0 P 0 ;0
L 1.66228002 -2.12395 1.71656004 -2.12395 0 P 0 ;0
L 1.66211998 -2.12295 1.71696004 -2.12295 0 P 0 ;0
L 1.66188002 -2.12195 1.71736004 -2.12195 0 P 0 ;0
L 1.66156004 -2.12095 1.71776998 -2.12095 0 P 0 ;0
L 1.66121004 -2.11995 1.71818002 -2.11995 0 P 0 ;0
L 1.66086998 -2.11895 1.71858002 -2.11895 0 P 0 ;0
L 1.66053002 -2.11795 1.71898996 -2.11795 0 P 0 ;0
L 1.66018002 -2.11695 1.71938996 -2.11695 0 P 0 ;0
L 1.65983996 -2.11595 1.7198 -2.11595 0 P 0 ;0
L 1.65948996 -2.11495 1.7202 -2.11495 0 P 0 ;0
L 1.65913996 -2.11395 1.72061004 -2.11395 0 P 0 ;0
L 1.6588 -2.11295 1.72101004 -2.11295 0 P 0 ;0
L 1.65846004 -2.11195 1.72141998 -2.11195 0 P 0 ;0
L 1.65811004 -2.11095 1.72181998 -2.11095 0 P 0 ;0
L 1.65776998 -2.10995 1.72223002 -2.10995 0 P 0 ;0
L 1.65741998 -2.10895 1.72263002 -2.10895 0 P 0 ;0
L 1.65708002 -2.10795 1.72303996 -2.10795 0 P 0 ;0
L 1.65673002 -2.10695 1.72343996 -2.10695 0 P 0 ;0
L 1.65638996 -2.10595 1.72385 -2.10595 0 P 0 ;0
L 1.65605 -2.10495 1.72425 -2.10495 0 P 0 ;0
L 1.6557 -2.10395 1.72466004 -2.10395 0 P 0 ;0
L 1.65536004 -2.10295 1.72506998 -2.10295 0 P 0 ;0
L 1.65501004 -2.10195 1.72546998 -2.10195 0 P 0 ;0
L 1.65466998 -2.10095 1.72588002 -2.10095 0 P 0 ;0
L 1.65431998 -2.09995 1.72628002 -2.09995 0 P 0 ;0
L 1.65398002 -2.09895 1.72668996 -2.09895 0 P 0 ;0
L 1.65363002 -2.09795 1.72708996 -2.09795 0 P 0 ;0
L 1.65328996 -2.09695 1.72748996 -2.09695 0 P 0 ;0
L 1.65293996 -2.09595 1.7279 -2.09595 0 P 0 ;0
L 1.6526 -2.09495 1.72831004 -2.09495 0 P 0 ;0
L 1.65225 -2.09395 1.72871004 -2.09395 0 P 0 ;0
L 1.65191004 -2.09295 1.72911998 -2.09295 0 P 0 ;0
L 1.65156998 -2.09195 1.72951998 -2.09195 0 P 0 ;0
L 1.65121998 -2.09095 1.72993002 -2.09095 0 P 0 ;0
L 1.65088002 -2.08995 1.73033002 -2.08995 0 P 0 ;0
L 1.65053002 -2.08895 1.73073996 -2.08895 0 P 0 ;0
L 1.65018996 -2.08795 1.73113996 -2.08795 0 P 0 ;0
L 1.64983996 -2.08695 1.73155 -2.08695 0 P 0 ;0
L 1.6495 -2.08595 1.73195 -2.08595 0 P 0 ;0
L 1.64915 -2.08495 1.73236004 -2.08495 0 P 0 ;0
L 1.64881004 -2.08395 1.73276004 -2.08395 0 P 0 ;0
L 1.81726998 -1.98915 1.81196004 -1.9899 0 P 0 ;0
L 1.81196004 -1.9899 1.80668996 -1.99096998 0 P 0 ;0
L 1.80668996 -1.99096998 1.8019 -1.99226004 0 P 0 ;0
L 1.8019 -1.99226004 1.79718996 -1.99391004 0 P 0 ;0
L 1.79718996 -1.99391004 1.79316004 -1.99568002 0 P 0 ;0
L 1.79316004 -1.99568002 1.78926998 -1.99778002 0 P 0 ;0
L 1.78926998 -1.99778002 1.78771004 -1.99878002 0 P 0 ;0
L 1.78771004 -1.99878002 1.78623002 -1.99988002 0 P 0 ;0
L 1.78623002 -1.99988002 1.78481004 -2.00108002 0 P 0 ;0
L 1.78481004 -2.00108002 1.78346998 -2.00238996 0 P 0 ;0
L 1.78346998 -2.00238996 1.78228996 -2.00371998 0 P 0 ;0
L 1.78228996 -2.00371998 1.78121004 -2.00513002 0 P 0 ;0
L 1.78121004 -2.00513002 1.78023002 -2.00661004 0 P 0 ;0
L 1.78023002 -2.00661004 1.77868002 -2.00933996 0 P 0 ;0
L 1.77868002 -2.00933996 1.77731998 -2.01216998 0 P 0 ;0
L 1.77731998 -2.01216998 1.77611004 -2.01516004 0 P 0 ;0
L 1.77611004 -2.01516004 1.77508996 -2.01823002 0 P 0 ;0
L 1.77508996 -2.01823002 1.77436998 -2.02111004 0 P 0 ;0
L 1.77436998 -2.02111004 1.77388996 -2.02406004 0 P 0 ;0
L 1.77388996 -2.02406004 1.77371998 -2.02603996 0 P 0 ;0
L 1.77371998 -2.02603996 1.77368996 -2.02801998 0 P 0 ;0
L 1.77368996 -2.02801998 1.7738 -2.03001998 0 P 0 ;0
L 1.7738 -2.03001998 1.7742 -2.03338996 0 P 0 ;0
L 1.7742 -2.03338996 1.77485 -2.03671004 0 P 0 ;0
L 1.77485 -2.03671004 1.77573002 -2.03993996 0 P 0 ;0
L 1.77573002 -2.03993996 1.77683996 -2.04308002 0 P 0 ;0
L 1.77683996 -2.04308002 1.7776 -2.04481998 0 P 0 ;0
L 1.7776 -2.04481998 1.7785 -2.04648996 0 P 0 ;0
L 1.7785 -2.04648996 1.77953002 -2.04808996 0 P 0 ;0
L 1.77953002 -2.04808996 1.78061004 -2.04953996 0 P 0 ;0
L 1.78061004 -2.04953996 1.78181004 -2.05091004 0 P 0 ;0
L 1.78181004 -2.05091004 1.78311004 -2.05218996 0 P 0 ;0
L 1.78311004 -2.05218996 1.78988996 -2.05801998 0 P 0 ;0
L 1.78988996 -2.05801998 1.79883996 -2.06491004 0 P 0 ;0
L 1.79883996 -2.06491004 1.80976998 -2.07261004 0 P 0 ;0
L 1.80976998 -2.07261004 1.81753002 -2.07823002 0 P 0 ;0
L 1.81753002 -2.07823002 1.81896998 -2.07943002 0 P 0 ;0
L 1.81896998 -2.07943002 1.82033002 -2.08073002 0 P 0 ;0
L 1.82033002 -2.08073002 1.82156998 -2.08213996 0 P 0 ;0
L 1.82156998 -2.08213996 1.82186004 -2.08251004 0 P 0 ;0
L 1.82186004 -2.08251004 1.82211004 -2.0829 0 P 0 ;0
L 1.82211004 -2.0829 1.82233002 -2.08331004 0 P 0 ;0
L 1.82233002 -2.08331004 1.82253002 -2.08373996 0 P 0 ;0
L 1.82253002 -2.08373996 1.82268002 -2.08418002 0 P 0 ;0
L 1.82268002 -2.08418002 1.82281004 -2.08463002 0 P 0 ;0
L 1.82281004 -2.08463002 1.8229 -2.0851 0 P 0 ;0
L 1.8229 -2.0851 1.82293002 -2.08533996 0 P 0 ;0
L 1.82293002 -2.08533996 1.82293996 -2.08558996 0 P 0 ;0
L 1.82293996 -2.08558996 1.82291998 -2.08583996 0 P 0 ;0
L 1.82291998 -2.08583996 1.82288002 -2.08608002 0 P 0 ;0
L 1.82288002 -2.08608002 1.82283002 -2.08631998 0 P 0 ;0
L 1.82283002 -2.08631998 1.82275 -2.08656004 0 P 0 ;0
L 1.82275 -2.08656004 1.82265 -2.08678996 0 P 0 ;0
L 1.82265 -2.08678996 1.82253996 -2.087 0 P 0 ;0
L 1.82253996 -2.087 1.8224 -2.08721004 0 P 0 ;0
L 1.8224 -2.08721004 1.82225 -2.08741004 0 P 0 ;0
L 1.82225 -2.08741004 1.82208996 -2.08758996 0 P 0 ;0
L 1.82208996 -2.08758996 1.8216 -2.08803996 0 P 0 ;0
L 1.8216 -2.08803996 1.82106998 -2.08845 0 P 0 ;0
L 1.82106998 -2.08845 1.82051004 -2.08881004 0 P 0 ;0
L 1.82051004 -2.08881004 1.81991998 -2.08911998 0 P 0 ;0
L 1.81991998 -2.08911998 1.81931004 -2.08936998 0 P 0 ;0
L 1.81931004 -2.08936998 1.81868002 -2.08958002 0 P 0 ;0
L 1.81868002 -2.08958002 1.81803002 -2.08973002 0 P 0 ;0
L 1.81803002 -2.08973002 1.81736004 -2.08981998 0 P 0 ;0
L 1.81736004 -2.08981998 1.81293002 -2.09001998 0 P 0 ;0
L 1.81293002 -2.09001998 1.80846998 -2.08986004 0 P 0 ;0
L 1.80846998 -2.08986004 1.80256998 -2.08923002 0 P 0 ;0
L 1.80256998 -2.08923002 1.79668002 -2.08818996 0 P 0 ;0
L 1.79668002 -2.08818996 1.78223002 -2.08458002 0 P 0 ;0
L 1.78223002 -2.08458002 1.77788996 -2.08338002 0 P 0 ;0
L 1.77788996 -2.08338002 1.77415 -2.08246004 0 P 0 ;0
L 1.77415 -2.08246004 1.77095 -2.08175 0 P 0 ;0
L 1.77095 -2.08175 1.7709 -2.08173996 0 P 0 ;0
L 1.7709 -2.08173996 1.77076998 -2.08173996 0 P 0 ;0
L 1.77076998 -2.08173996 1.77068996 -2.08176004 0 P 0 ;0
L 1.77068996 -2.08176004 1.77053002 -2.08183996 0 P 0 ;0
L 1.77053002 -2.08183996 1.77043002 -2.08193996 0 P 0 ;0
L 1.77043002 -2.08193996 1.77036998 -2.08201998 0 P 0 ;0
L 1.77036998 -2.08201998 1.77031998 -2.08211998 0 P 0 ;0
L 1.77031998 -2.08211998 1.7703 -2.08216998 0 P 0 ;0
L 1.7703 -2.08216998 1.77028996 -2.08223002 0 P 0 ;0
L 1.77028996 -2.08223002 1.77028002 -2.08228002 0 P 0 ;0
L 1.77028002 -2.08228002 1.77028002 -2.08238996 0 P 0 ;0
L 1.77028002 -2.08238996 1.77056998 -2.08838996 0 P 0 ;0
L 1.77056998 -2.08838996 1.77096004 -2.09526004 0 P 0 ;0
L 1.77096004 -2.09526004 1.77153996 -2.1033 0 P 0 ;0
L 1.77153996 -2.1033 1.77236004 -2.11291004 0 P 0 ;0
L 1.77236004 -2.11291004 1.77311004 -2.1194 0 P 0 ;0
L 1.77311004 -2.1194 1.77383002 -2.12398002 0 P 0 ;0
L 1.77383002 -2.12398002 1.77386004 -2.12411004 0 P 0 ;0
L 1.77386004 -2.12411004 1.7739 -2.12423002 0 P 0 ;0
L 1.7739 -2.12423002 1.77395 -2.12436004 0 P 0 ;0
L 1.77395 -2.12436004 1.77401004 -2.12448002 0 P 0 ;0
L 1.77401004 -2.12448002 1.77408002 -2.12458996 0 P 0 ;0
L 1.77408002 -2.12458996 1.77416004 -2.1247 0 P 0 ;0
L 1.77416004 -2.1247 1.77425 -2.1248 0 P 0 ;0
L 1.77425 -2.1248 1.77435 -2.12488996 0 P 0 ;0
L 1.77435 -2.12488996 1.77445 -2.12496998 0 P 0 ;0
L 1.77445 -2.12496998 1.77456998 -2.12505 0 P 0 ;0
L 1.77456998 -2.12505 1.77571004 -2.12568996 0 P 0 ;0
L 1.77571004 -2.12568996 1.7769 -2.12623996 0 P 0 ;0
L 1.7769 -2.12623996 1.77813002 -2.12668996 0 P 0 ;0
L 1.77813002 -2.12668996 1.7794 -2.12703996 0 P 0 ;0
L 1.7794 -2.12703996 1.78068996 -2.12728996 0 P 0 ;0
L 1.78068996 -2.12728996 1.79791998 -2.12951004 0 P 0 ;0
L 1.79791998 -2.12951004 1.81536004 -2.13106004 0 P 0 ;0
L 1.81536004 -2.13106004 1.82125 -2.13123996 0 P 0 ;0
L 1.82125 -2.13123996 1.82716004 -2.13098996 0 P 0 ;0
L 1.82716004 -2.13098996 1.83583996 -2.12998002 0 P 0 ;0
L 1.83583996 -2.12998002 1.84445 -2.12836004 0 P 0 ;0
L 1.84445 -2.12836004 1.84911998 -2.12711004 0 P 0 ;0
L 1.84911998 -2.12711004 1.85366004 -2.12548002 0 P 0 ;0
L 1.85366004 -2.12548002 1.85806998 -2.12348002 0 P 0 ;0
L 1.85806998 -2.12348002 1.86078996 -2.12196998 0 P 0 ;0
L 1.86078996 -2.12196998 1.8634 -2.12026998 0 P 0 ;0
L 1.8634 -2.12026998 1.86586998 -2.11836998 0 P 0 ;0
L 1.86586998 -2.11836998 1.86821004 -2.11628002 0 P 0 ;0
L 1.86821004 -2.11628002 1.87026004 -2.11413002 0 P 0 ;0
L 1.87026004 -2.11413002 1.8721 -2.11181998 0 P 0 ;0
L 1.8721 -2.11181998 1.87375 -2.10936004 0 P 0 ;0
L 1.87375 -2.10936004 1.87516998 -2.10673996 0 P 0 ;0
L 1.87516998 -2.10673996 1.87605 -2.10483996 0 P 0 ;0
L 1.87605 -2.10483996 1.87683996 -2.10291004 0 P 0 ;0
L 1.87683996 -2.10291004 1.8772 -2.10188002 0 P 0 ;0
L 1.8772 -2.10188002 1.87748996 -2.10083002 0 P 0 ;0
L 1.87748996 -2.10083002 1.87771004 -2.09976998 0 P 0 ;0
L 1.87771004 -2.09976998 1.87798002 -2.09788996 0 P 0 ;0
L 1.87798002 -2.09788996 1.87811998 -2.09601004 0 P 0 ;0
L 1.87811998 -2.09601004 1.87821004 -2.08966998 0 P 0 ;0
L 1.87821004 -2.08966998 1.8781 -2.08353996 0 P 0 ;0
L 1.8781 -2.08353996 1.87798002 -2.08166004 0 P 0 ;0
L 1.87798002 -2.08166004 1.87773002 -2.07976998 0 P 0 ;0
L 1.87773002 -2.07976998 1.87753002 -2.07873996 0 P 0 ;0
L 1.87753002 -2.07873996 1.87726998 -2.07773996 0 P 0 ;0
L 1.87726998 -2.07773996 1.87695 -2.07673996 0 P 0 ;0
L 1.87695 -2.07673996 1.87628996 -2.07505 0 P 0 ;0
L 1.87628996 -2.07505 1.87553002 -2.07338002 0 P 0 ;0
L 1.87553002 -2.07338002 1.87441004 -2.07133996 0 P 0 ;0
L 1.87441004 -2.07133996 1.87313996 -2.06938002 0 P 0 ;0
L 1.87313996 -2.06938002 1.87171004 -2.06751004 0 P 0 ;0
L 1.87171004 -2.06751004 1.8688 -2.06416004 0 P 0 ;0
L 1.8688 -2.06416004 1.86566998 -2.06095 0 P 0 ;0
L 1.86566998 -2.06095 1.86181998 -2.05741998 0 P 0 ;0
L 1.86181998 -2.05741998 1.85778002 -2.05406998 0 P 0 ;0
L 1.85778002 -2.05406998 1.84833996 -2.04715 0 P 0 ;0
L 1.84833996 -2.04715 1.83913996 -2.0407 0 P 0 ;0
L 1.83913996 -2.0407 1.83686004 -2.0389 0 P 0 ;0
L 1.83686004 -2.0389 1.83471998 -2.03691998 0 P 0 ;0
L 1.83471998 -2.03691998 1.83428002 -2.03643002 0 P 0 ;0
L 1.83428002 -2.03643002 1.83386998 -2.0359 0 P 0 ;0
L 1.83386998 -2.0359 1.83351004 -2.03535 0 P 0 ;0
L 1.83351004 -2.03535 1.83318996 -2.03476004 0 P 0 ;0
L 1.83318996 -2.03476004 1.83291998 -2.03415 0 P 0 ;0
L 1.83291998 -2.03415 1.83283996 -2.03393996 0 P 0 ;0
L 1.83283996 -2.03393996 1.83278002 -2.03371004 0 P 0 ;0
L 1.83278002 -2.03371004 1.83273002 -2.03348996 0 P 0 ;0
L 1.83273002 -2.03348996 1.83271004 -2.03326004 0 P 0 ;0
L 1.83271004 -2.03326004 1.8327 -2.03303002 0 P 0 ;0
L 1.8327 -2.03303002 1.83271004 -2.0328 0 P 0 ;0
L 1.83271004 -2.0328 1.83275 -2.03258002 0 P 0 ;0
L 1.83275 -2.03258002 1.83278996 -2.03235 0 P 0 ;0
L 1.83278996 -2.03235 1.83286004 -2.03213002 0 P 0 ;0
L 1.83286004 -2.03213002 1.83293996 -2.03191998 0 P 0 ;0
L 1.83293996 -2.03191998 1.83305 -2.03171004 0 P 0 ;0
L 1.83305 -2.03171004 1.83325 -2.03135 0 P 0 ;0
L 1.83325 -2.03135 1.83348996 -2.03101998 0 P 0 ;0
L 1.83348996 -2.03101998 1.83375 -2.03071004 0 P 0 ;0
L 1.83375 -2.03071004 1.83403002 -2.03041004 0 P 0 ;0
L 1.83403002 -2.03041004 1.83433996 -2.03015 0 P 0 ;0
L 1.83433996 -2.03015 1.83466998 -2.02991004 0 P 0 ;0
L 1.83466998 -2.02991004 1.83501998 -2.02968996 0 P 0 ;0
L 1.83501998 -2.02968996 1.83538002 -2.02951004 0 P 0 ;0
L 1.83538002 -2.02951004 1.83576004 -2.02936004 0 P 0 ;0
L 1.83576004 -2.02936004 1.83615 -2.02923996 0 P 0 ;0
L 1.83615 -2.02923996 1.83655 -2.02915 0 P 0 ;0
L 1.83655 -2.02915 1.8392 -2.02873996 0 P 0 ;0
L 1.8392 -2.02873996 1.84188002 -2.0285 0 P 0 ;0
L 1.84188002 -2.0285 1.84458002 -2.02841004 0 P 0 ;0
L 1.84458002 -2.02841004 1.84993996 -2.02858002 0 P 0 ;0
L 1.84993996 -2.02858002 1.85526998 -2.02916004 0 P 0 ;0
L 1.85526998 -2.02916004 1.86155 -2.03023002 0 P 0 ;0
L 1.86155 -2.03023002 1.86778002 -2.03158002 0 P 0 ;0
L 1.86778002 -2.03158002 1.8713 -2.03238996 0 P 0 ;0
L 1.8713 -2.03238996 1.87428996 -2.03303002 0 P 0 ;0
L 1.87428996 -2.03303002 1.8769 -2.03356004 0 P 0 ;0
L 1.8769 -2.03356004 1.87691998 -2.03356998 0 P 0 ;0
L 1.87691998 -2.03356998 1.87696004 -2.03356998 0 P 0 ;0
L 1.87696004 -2.03356998 1.87696998 -2.03356004 0 P 0 ;0
L 1.87696998 -2.03356004 1.87701004 -2.03356004 0 P 0 ;0
L 1.87701004 -2.03356004 1.87703996 -2.03353996 0 P 0 ;0
L 1.87703996 -2.03353996 1.87706004 -2.03353002 0 P 0 ;0
L 1.87706004 -2.03353002 1.87706998 -2.03351998 0 P 0 ;0
L 1.87706998 -2.03351998 1.87708996 -2.03351004 0 P 0 ;0
L 1.87708996 -2.03351004 1.8771 -2.03348996 0 P 0 ;0
L 1.8771 -2.03348996 1.87711004 -2.03348002 0 P 0 ;0
L 1.87711004 -2.03348002 1.87721998 -2.0333 0 P 0 ;0
L 1.87721998 -2.0333 1.87731998 -2.0331 0 P 0 ;0
L 1.87731998 -2.0331 1.8774 -2.0329 0 P 0 ;0
L 1.8774 -2.0329 1.87746004 -2.03268996 0 P 0 ;0
L 1.87746004 -2.03268996 1.87751004 -2.03248002 0 P 0 ;0
L 1.87751004 -2.03248002 1.87753002 -2.03226998 0 P 0 ;0
L 1.87753002 -2.03226998 1.87753996 -2.03205 0 P 0 ;0
L 1.87753996 -2.03205 1.87753002 -2.03183002 0 P 0 ;0
L 1.87753002 -2.03183002 1.87565 -2.01323996 0 P 0 ;0
L 1.87565 -2.01323996 1.87371004 -1.99451998 0 P 0 ;0
L 1.87371004 -1.99451998 1.8737 -1.99438996 0 P 0 ;0
L 1.8737 -1.99438996 1.87366998 -1.99426998 0 P 0 ;0
L 1.87366998 -1.99426998 1.87363002 -1.99415 0 P 0 ;0
L 1.87363002 -1.99415 1.87358002 -1.99403002 0 P 0 ;0
L 1.87358002 -1.99403002 1.87351998 -1.99391004 0 P 0 ;0
L 1.87351998 -1.99391004 1.87346004 -1.9938 0 P 0 ;0
L 1.87346004 -1.9938 1.87338002 -1.9937 0 P 0 ;0
L 1.87338002 -1.9937 1.87328996 -1.9936 0 P 0 ;0
L 1.87328996 -1.9936 1.8732 -1.99351004 0 P 0 ;0
L 1.8732 -1.99351004 1.8731 -1.99343002 0 P 0 ;0
L 1.8731 -1.99343002 1.87298996 -1.99335 0 P 0 ;0
L 1.87298996 -1.99335 1.87248002 -1.99305 0 P 0 ;0
L 1.87248002 -1.99305 1.87193996 -1.99278002 0 P 0 ;0
L 1.87193996 -1.99278002 1.87136998 -1.99256998 0 P 0 ;0
L 1.87136998 -1.99256998 1.87078996 -1.99241004 0 P 0 ;0
L 1.87078996 -1.99241004 1.8702 -1.9923 0 P 0 ;0
L 1.8702 -1.9923 1.85876004 -1.99076004 0 P 0 ;0
L 1.85876004 -1.99076004 1.84691998 -1.98943002 0 P 0 ;0
L 1.84691998 -1.98943002 1.83693002 -1.98876004 0 P 0 ;0
L 1.83693002 -1.98876004 1.8318 -1.98863002 0 P 0 ;0
L 1.8318 -1.98863002 1.82623002 -1.98866998 0 P 0 ;0
L 1.82623002 -1.98866998 1.82106004 -1.98883996 0 P 0 ;0
L 1.82106004 -1.98883996 1.81726998 -1.98915 0 P 0 ;0
L 1.78061004 -2.12523996 1.84838002 -2.12523996 0 P 0 ;0
L 1.77733002 -2.12423996 1.85121004 -2.12423996 0 P 0 ;0
L 1.77573996 -2.12323996 1.85376998 -2.12323996 0 P 0 ;0
L 1.77558002 -2.12223996 1.85596998 -2.12223996 0 P 0 ;0
L 1.77541998 -2.12123996 1.85798996 -2.12123996 0 P 0 ;0
L 1.77526998 -2.12023996 1.85978996 -2.12023996 0 P 0 ;0
L 1.77511004 -2.11923996 1.86131998 -2.11923996 0 P 0 ;0
L 1.77498996 -2.11823996 1.86276004 -2.11823996 0 P 0 ;0
L 1.77486998 -2.11723996 1.86406998 -2.11723996 0 P 0 ;0
L 1.77475 -2.11623996 1.86526004 -2.11623996 0 P 0 ;0
L 1.77463996 -2.11523996 1.86638002 -2.11523996 0 P 0 ;0
L 1.77451998 -2.11423996 1.8674 -2.11423996 0 P 0 ;0
L 1.77441004 -2.11323996 1.86835 -2.11323996 0 P 0 ;0
L 1.77431004 -2.11223996 1.86921004 -2.11223996 0 P 0 ;0
L 1.77421998 -2.11123996 1.87001004 -2.11123996 0 P 0 ;0
L 1.77413996 -2.11023996 1.87075 -2.11023996 0 P 0 ;0
L 1.77405 -2.10923996 1.87141998 -2.10923996 0 P 0 ;0
L 1.77396998 -2.10823996 1.87208002 -2.10823996 0 P 0 ;0
L 1.77388002 -2.10723996 1.87261998 -2.10723996 0 P 0 ;0
L 1.7738 -2.10623996 1.87316998 -2.10623996 0 P 0 ;0
L 1.77371004 -2.10523996 1.87366004 -2.10523996 0 P 0 ;0
L 1.77363002 -2.10423996 1.87411998 -2.10423996 0 P 0 ;0
L 1.77353996 -2.10323996 1.87453996 -2.10323996 0 P 0 ;0
L 1.77346998 -2.10223996 1.87495 -2.10223996 0 P 0 ;0
L 1.7734 -2.10123996 1.8753 -2.10123996 0 P 0 ;0
L 1.77333002 -2.10023996 1.87556998 -2.10023996 0 P 0 ;0
L 1.77325 -2.09923996 1.87576998 -2.09923996 0 P 0 ;0
L 1.77318002 -2.09823996 1.87591998 -2.09823996 0 P 0 ;0
L 1.77311004 -2.09723996 1.87603002 -2.09723996 0 P 0 ;0
L 1.77303996 -2.09623996 1.8761 -2.09623996 0 P 0 ;0
L 1.77296998 -2.09523996 1.87613002 -2.09523996 0 P 0 ;0
L 1.77291004 -2.09423996 1.87613996 -2.09423996 0 P 0 ;0
L 1.77285 -2.09323996 1.87616004 -2.09323996 0 P 0 ;0
L 1.77278996 -2.09223996 1.87616998 -2.09223996 0 P 0 ;0
L 1.77273002 -2.09123996 1.80256998 -2.09123996 0 P 0 ;0
L 1.77268002 -2.09023996 1.7968 -2.09023996 0 P 0 ;0
L 1.77261998 -2.08923996 1.79263002 -2.08923996 0 P 0 ;0
L 1.77256004 -2.08823996 1.78861998 -2.08823996 0 P 0 ;0
L 1.77251004 -2.08723996 1.7846 -2.08723996 0 P 0 ;0
L 1.77246004 -2.08623996 1.7807 -2.08623996 0 P 0 ;0
L 1.77241998 -2.08523996 1.77705 -2.08523996 0 P 0 ;0
L 1.77236998 -2.08423996 1.77293996 -2.08423996 0 P 0 ;0
L 1.62463996 -2.18195 1.65948996 -2.18195 0 P 0 ;0
L 1.61963996 -2.18095 1.66483002 -2.18095 0 P 0 ;0
L 1.61818002 -1.99795 1.6724 -1.99795 0 P 0 ;0
L 1.61778996 -1.99695 1.67218002 -1.99695 0 P 0 ;0
L 1.6174 -1.99595 1.67196004 -1.99595 0 P 0 ;0
L 1.61701004 -1.99495 1.67173996 -1.99495 0 P 0 ;0
L 1.61391998 -2.15695 1.70026004 -2.15695 0 P 0 ;0
L 1.61386004 -2.15595 1.70088002 -2.15595 0 P 0 ;0
L 1.61381004 -2.15495 1.70151004 -2.15495 0 P 0 ;0
L 1.61375 -2.15395 1.70213996 -2.15395 0 P 0 ;0
L 1.6137 -2.15295 1.70276004 -2.15295 0 P 0 ;0
L 1.61365 -2.15195 1.70338996 -2.15195 0 P 0 ;0
L 1.6136 -2.15095 1.70401004 -2.15095 0 P 0 ;0
L 1.61355 -2.14995 1.70456998 -2.14995 0 P 0 ;0
L 1.61348996 -2.14895 1.70511998 -2.14895 0 P 0 ;0
L 1.61343996 -2.14795 1.61738002 -2.14795 0 P 0 ;0
L 1.55341004 -2.08286998 1.60538002 -2.08286998 0 P 0 ;0
L 1.55286004 -2.08186998 1.60526998 -2.08186998 0 P 0 ;0
L 1.5521 -2.08086998 1.6051 -2.08086998 0 P 0 ;0
L 1.55126998 -2.07986998 1.6049 -2.07986998 0 P 0 ;0
L 1.55033996 -2.07886998 1.60463996 -2.07886998 0 P 0 ;0
L 1.54928996 -2.07786998 1.60433002 -2.07786998 0 P 0 ;0
L 1.54806998 -2.07686998 1.60398996 -2.07686998 0 P 0 ;0
L 1.5467 -2.07586998 1.60356998 -2.07586998 0 P 0 ;0
L 1.54531004 -2.07486998 1.6031 -2.07486998 0 P 0 ;0
L 1.54391004 -2.07386998 1.60258996 -2.07386998 0 P 0 ;0
L 1.54251004 -2.07286998 1.60201004 -2.07286998 0 P 0 ;0
L 1.54111998 -2.07186998 1.60138002 -2.07186998 0 P 0 ;0
L 1.53971998 -2.07086998 1.60068002 -2.07086998 0 P 0 ;0
L 1.53833002 -2.06986998 1.59993002 -2.06986998 0 P 0 ;0
L 1.53693002 -2.06886998 1.59908002 -2.06886998 0 P 0 ;0
L 1.53556004 -2.06786998 1.59821004 -2.06786998 0 P 0 ;0
L 1.53418996 -2.06686998 1.59733996 -2.06686998 0 P 0 ;0
L 1.53281998 -2.06586998 1.59646998 -2.06586998 0 P 0 ;0
L 1.53145 -2.06486998 1.5955 -2.06486998 0 P 0 ;0
L 1.53008002 -2.06386998 1.59453002 -2.06386998 0 P 0 ;0
L 1.52871004 -2.06286998 1.59356004 -2.06286998 0 P 0 ;0
L 1.52733996 -2.06186998 1.59253002 -2.06186998 0 P 0 ;0
L 1.52596998 -2.06086998 1.59145 -2.06086998 0 P 0 ;0
L 1.5246 -2.05986998 1.59038002 -2.05986998 0 P 0 ;0
L 1.52323002 -2.05886998 1.5893 -2.05886998 0 P 0 ;0
L 1.52186004 -2.05786998 1.58813996 -2.05786998 0 P 0 ;0
L 1.52053996 -2.05686998 1.58696004 -2.05686998 0 P 0 ;0
L 1.51935 -2.05586998 1.58576998 -2.05586998 0 P 0 ;0
L 1.51816004 -2.05486998 1.58456998 -2.05486998 0 P 0 ;0
L 1.51706998 -2.05386998 1.58321004 -2.05386998 0 P 0 ;0
L 1.51603996 -2.05286998 1.58185 -2.05286998 0 P 0 ;0
L 1.51501998 -2.05186998 1.58048996 -2.05186998 0 P 0 ;0
L 1.51408996 -2.05086998 1.57913002 -2.05086998 0 P 0 ;0
L 1.5132 -2.04986998 1.57776998 -2.04986998 0 P 0 ;0
L 1.51231998 -2.04886998 1.57641998 -2.04886998 0 P 0 ;0
L 1.51151004 -2.04786998 1.57505 -2.04786998 0 P 0 ;0
L 1.51075 -2.04686998 1.57365 -2.04686998 0 P 0 ;0
L 1.51008002 -2.04586998 1.57223002 -2.04586998 0 P 0 ;0
L 1.50945 -2.04486998 1.57081004 -2.04486998 0 P 0 ;0
L 1.50888002 -2.04386998 1.56938996 -2.04386998 0 P 0 ;0
L 1.50836004 -2.04286998 1.56796998 -2.04286998 0 P 0 ;0
L 1.5079 -2.04186998 1.56655 -2.04186998 0 P 0 ;0
L 1.50748002 -2.04086998 1.56518996 -2.04086998 0 P 0 ;0
L 1.50708996 -2.03986998 1.564 -2.03986998 0 P 0 ;0
L 1.50676004 -2.03886998 1.56296998 -2.03886998 0 P 0 ;0
L 1.50641998 -2.03786998 1.56206004 -2.03786998 0 P 0 ;0
L 1.50616998 -2.03686998 1.56125 -2.03686998 0 P 0 ;0
L 1.50591004 -2.03586998 1.56066998 -2.03586998 0 P 0 ;0
L 1.5057 -2.03486998 1.56031998 -2.03486998 0 P 0 ;0
L 1.50551998 -2.03386998 1.56016004 -2.03386998 0 P 0 ;0
L 1.50533996 -2.03286998 1.56016998 -2.03286998 0 P 0 ;0
L 1.50523996 -2.03186998 1.56036004 -2.03186998 0 P 0 ;0
L 1.50513002 -2.03086998 1.56071998 -2.03086998 0 P 0 ;0
L 1.50506998 -2.02986998 1.56131004 -2.02986998 0 P 0 ;0
L 1.50503996 -2.02886998 1.5622 -2.02886998 0 P 0 ;0
L 1.50501004 -2.02786998 1.56355 -2.02786998 0 P 0 ;0
L 1.50501998 -2.02686998 1.5657 -2.02686998 0 P 0 ;0
L 1.50506998 -2.02586998 1.60378996 -2.02586998 0 P 0 ;0
L 1.50511998 -2.02486998 1.60371004 -2.02486998 0 P 0 ;0
L 1.50521004 -2.02386998 1.60363996 -2.02386998 0 P 0 ;0
L 1.50533996 -2.02286998 1.60356998 -2.02286998 0 P 0 ;0
L 1.50546998 -2.02186998 1.6035 -2.02186998 0 P 0 ;0
L 1.50563996 -2.02086998 1.60343002 -2.02086998 0 P 0 ;0
L 1.50585 -2.01986998 1.60336004 -2.01986998 0 P 0 ;0
L 1.50606004 -2.01886998 1.60328996 -2.01886998 0 P 0 ;0
L 1.50633002 -2.01786998 1.60321998 -2.01786998 0 P 0 ;0
L 1.50661998 -2.01686998 1.60315 -2.01686998 0 P 0 ;0
L 1.50691004 -2.01586998 1.60308002 -2.01586998 0 P 0 ;0
L 1.50726998 -2.01486998 1.603 -2.01486998 0 P 0 ;0
L 1.50766004 -2.01386998 1.60293002 -2.01386998 0 P 0 ;0
L 1.50808996 -2.01286998 1.60285 -2.01286998 0 P 0 ;0
L 1.50856998 -2.01186998 1.60278002 -2.01186998 0 P 0 ;0
L 1.50908996 -2.01086998 1.6027 -2.01086998 0 P 0 ;0
L 1.50966004 -2.00986998 1.60261998 -2.00986998 0 P 0 ;0
L 1.51028996 -2.00886998 1.60255 -2.00886998 0 P 0 ;0
L 1.51096998 -2.00786998 1.60246998 -2.00786998 0 P 0 ;0
L 1.51171998 -2.00686998 1.6024 -2.00686998 0 P 0 ;0
L 1.51253996 -2.00586998 1.60233002 -2.00586998 0 P 0 ;0
L 1.51343996 -2.00486998 1.60225 -2.00486998 0 P 0 ;0
L 1.5144 -2.00386998 1.60218002 -2.00386998 0 P 0 ;0
L 1.51551998 -2.00286998 1.6021 -2.00286998 0 P 0 ;0
L 1.51663996 -2.00186998 1.60203002 -2.00186998 0 P 0 ;0
L 1.51795 -2.00086998 1.60195 -2.00086998 0 P 0 ;0
L 1.51928996 -1.99986998 1.60183996 -1.99986998 0 P 0 ;0
L 1.52086998 -1.99886998 1.60173002 -1.99886998 0 P 0 ;0
L 1.52258996 -1.99786998 1.60156998 -1.99786998 0 P 0 ;0
L 1.52451004 -1.99686998 1.60138996 -1.99686998 0 P 0 ;0
L 1.52686998 -1.99586998 1.60106998 -1.99586998 0 P 0 ;0
L 1.52976004 -1.99486998 1.59943996 -1.99486998 0 P 0 ;0
L 1.53283002 -1.99386998 1.59543002 -1.99386998 0 P 0 ;0
L 1.53678996 -1.99286998 1.59003996 -1.99286998 0 P 0 ;0
L 1.54173996 -1.99186998 1.58073996 -1.99186998 0 P 0 ;0
L 1.55036998 -1.99086998 1.56493002 -1.99086998 0 P 0 ;0
L 1.6036 -2.03086998 1.60413996 -2.03086998 0 P 0 ;0
L 1.59891004 -2.02986998 1.60406998 -2.02986998 0 P 0 ;0
L 1.59435 -2.02886998 1.604 -2.02886998 0 P 0 ;0
L 1.58838996 -2.02786998 1.60393002 -2.02786998 0 P 0 ;0
L 1.57981004 -2.02686998 1.60386004 -2.02686998 0 P 0 ;0
L 1.54575 -1.98923996 1.53931998 -1.99021998 0 P 0 ;0
L 1.53931998 -1.99021998 1.53298996 -1.99171998 0 P 0 ;0
L 1.53298996 -1.99171998 1.52678996 -1.99373996 0 P 0 ;0
L 1.52678996 -1.99373996 1.52376998 -1.995 0 P 0 ;0
L 1.52376998 -1.995 1.52086998 -1.99651004 0 P 0 ;0
L 1.52086998 -1.99651004 1.5181 -1.99826004 0 P 0 ;0
L 1.5181 -1.99826004 1.51548002 -2.00023002 0 P 0 ;0
L 1.51548002 -2.00023002 1.51301004 -2.00243002 0 P 0 ;0
L 1.51301004 -2.00243002 1.51128996 -2.00423002 0 P 0 ;0
L 1.51128996 -2.00423002 1.50971998 -2.00616004 0 P 0 ;0
L 1.50971998 -2.00616004 1.50831004 -2.00821004 0 P 0 ;0
L 1.50831004 -2.00821004 1.50706998 -2.01036998 0 P 0 ;0
L 1.50706998 -2.01036998 1.50598996 -2.01261998 0 P 0 ;0
L 1.50598996 -2.01261998 1.50508996 -2.01496998 0 P 0 ;0
L 1.50508996 -2.01496998 1.5042 -2.01801004 0 P 0 ;0
L 1.5042 -2.01801004 1.50355 -2.02111004 0 P 0 ;0
L 1.50355 -2.02111004 1.50313996 -2.02426004 0 P 0 ;0
L 1.50313996 -2.02426004 1.50298996 -2.02743002 0 P 0 ;0
L 1.50298996 -2.02743002 1.50308996 -2.03063002 0 P 0 ;0
L 1.50308996 -2.03063002 1.50338002 -2.03326998 0 P 0 ;0
L 1.50338002 -2.03326998 1.50385 -2.03588002 0 P 0 ;0
L 1.50385 -2.03588002 1.50451004 -2.03845 0 P 0 ;0
L 1.50451004 -2.03845 1.50535 -2.04096998 0 P 0 ;0
L 1.50535 -2.04096998 1.50633002 -2.0433 0 P 0 ;0
L 1.50633002 -2.0433 1.5075 -2.04553002 0 P 0 ;0
L 1.5075 -2.04553002 1.50883996 -2.04766998 0 P 0 ;0
L 1.50883996 -2.04766998 1.51036998 -2.04968996 0 P 0 ;0
L 1.51036998 -2.04968996 1.51323002 -2.05291998 0 P 0 ;0
L 1.51323002 -2.05291998 1.51631998 -2.05593996 0 P 0 ;0
L 1.51631998 -2.05593996 1.51961998 -2.05871004 0 P 0 ;0
L 1.51961998 -2.05871004 1.53591004 -2.0706 0 P 0 ;0
L 1.53591004 -2.0706 1.54668002 -2.07831004 0 P 0 ;0
L 1.54668002 -2.07831004 1.54793996 -2.07933996 0 P 0 ;0
L 1.54793996 -2.07933996 1.54911998 -2.08046998 0 P 0 ;0
L 1.54911998 -2.08046998 1.55021004 -2.08168002 0 P 0 ;0
L 1.55021004 -2.08168002 1.5512 -2.08298996 0 P 0 ;0
L 1.5512 -2.08298996 1.55136004 -2.08323002 0 P 0 ;0
L 1.55136004 -2.08323002 1.5515 -2.08348002 0 P 0 ;0
L 1.5515 -2.08348002 1.55161004 -2.08373996 0 P 0 ;0
L 1.55161004 -2.08373996 1.5517 -2.08401998 0 P 0 ;0
L 1.5517 -2.08401998 1.55176998 -2.0843 0 P 0 ;0
L 1.55176998 -2.0843 1.55181004 -2.08458002 0 P 0 ;0
L 1.55181004 -2.08458002 1.55183002 -2.08486998 0 P 0 ;0
L 1.55183002 -2.08486998 1.55181998 -2.08516004 0 P 0 ;0
L 1.55181998 -2.08516004 1.55178996 -2.08545 0 P 0 ;0
L 1.55178996 -2.08545 1.55173996 -2.08573002 0 P 0 ;0
L 1.55173996 -2.08573002 1.55166004 -2.086 0 P 0 ;0
L 1.55166004 -2.086 1.55156004 -2.08628002 0 P 0 ;0
L 1.55156004 -2.08628002 1.55136998 -2.08666998 0 P 0 ;0
L 1.55136998 -2.08666998 1.55115 -2.08703996 0 P 0 ;0
L 1.55115 -2.08703996 1.5509 -2.08738996 0 P 0 ;0
L 1.5509 -2.08738996 1.55063002 -2.08771998 0 P 0 ;0
L 1.55063002 -2.08771998 1.55033002 -2.08803002 0 P 0 ;0
L 1.55033002 -2.08803002 1.55 -2.08831004 0 P 0 ;0
L 1.55 -2.08831004 1.54966004 -2.08856004 0 P 0 ;0
L 1.54966004 -2.08856004 1.54928996 -2.08878996 0 P 0 ;0
L 1.54928996 -2.08878996 1.5489 -2.08898996 0 P 0 ;0
L 1.5489 -2.08898996 1.54786004 -2.08941004 0 P 0 ;0
L 1.54786004 -2.08941004 1.54678996 -2.08973996 0 P 0 ;0
L 1.54678996 -2.08973996 1.54568002 -2.08998002 0 P 0 ;0
L 1.54568002 -2.08998002 1.54456998 -2.09011998 0 P 0 ;0
L 1.54456998 -2.09011998 1.54343996 -2.09016998 0 P 0 ;0
L 1.54343996 -2.09016998 1.53906998 -2.09003002 0 P 0 ;0
L 1.53906998 -2.09003002 1.53468002 -2.08961998 0 P 0 ;0
L 1.53468002 -2.08961998 1.52908996 -2.08878996 0 P 0 ;0
L 1.52908996 -2.08878996 1.52351004 -2.08766004 0 P 0 ;0
L 1.52351004 -2.08766004 1.51005 -2.08418996 0 P 0 ;0
L 1.51005 -2.08418996 1.50631004 -2.08318002 0 P 0 ;0
L 1.50631004 -2.08318002 1.50308002 -2.08238996 0 P 0 ;0
L 1.50308002 -2.08238996 1.50033996 -2.08183002 0 P 0 ;0
L 1.50033996 -2.08183002 1.5003 -2.08181998 0 P 0 ;0
L 1.5003 -2.08181998 1.50016004 -2.08181998 0 P 0 ;0
L 1.50016004 -2.08181998 1.50011998 -2.08183002 0 P 0 ;0
L 1.50011998 -2.08183002 1.50006998 -2.08183996 0 P 0 ;0
L 1.50006998 -2.08183996 1.50003002 -2.08186004 0 P 0 ;0
L 1.50003002 -2.08186004 1.49998996 -2.08186998 0 P 0 ;0
L 1.49998996 -2.08186998 1.49995 -2.08188996 0 P 0 ;0
L 1.49995 -2.08188996 1.49991004 -2.08191998 0 P 0 ;0
L 1.49991004 -2.08191998 1.49988002 -2.08195 0 P 0 ;0
L 1.49988002 -2.08195 1.49983996 -2.08198002 0 P 0 ;0
L 1.49983996 -2.08198002 1.4997 -2.08213996 0 P 0 ;0
L 1.4997 -2.08213996 1.49956004 -2.08231998 0 P 0 ;0
L 1.49956004 -2.08231998 1.49943996 -2.0825 0 P 0 ;0
L 1.49943996 -2.0825 1.49933996 -2.0827 0 P 0 ;0
L 1.49933996 -2.0827 1.49925 -2.0829 0 P 0 ;0
L 1.49925 -2.0829 1.49918996 -2.08311004 0 P 0 ;0
L 1.49918996 -2.08311004 1.49913996 -2.08333002 0 P 0 ;0
L 1.49913996 -2.08333002 1.49911004 -2.08355 0 P 0 ;0
L 1.49911004 -2.08355 1.4991 -2.08376998 0 P 0 ;0
L 1.4991 -2.08376998 1.49911004 -2.08398996 0 P 0 ;0
L 1.49911004 -2.08398996 1.50071004 -2.10395 0 P 0 ;0
L 1.50071004 -2.10395 1.5024 -2.12403996 0 P 0 ;0
L 1.5024 -2.12403996 1.50241998 -2.12418002 0 P 0 ;0
L 1.50241998 -2.12418002 1.50246004 -2.12431004 0 P 0 ;0
L 1.50246004 -2.12431004 1.50248996 -2.12445 0 P 0 ;0
L 1.50248996 -2.12445 1.50255 -2.12456998 0 P 0 ;0
L 1.50255 -2.12456998 1.50261004 -2.1247 0 P 0 ;0
L 1.50261004 -2.1247 1.50276998 -2.12491998 0 P 0 ;0
L 1.50276998 -2.12491998 1.50286004 -2.12501998 0 P 0 ;0
L 1.50286004 -2.12501998 1.50296998 -2.12511998 0 P 0 ;0
L 1.50296998 -2.12511998 1.50308002 -2.12521004 0 P 0 ;0
L 1.50308002 -2.12521004 1.50318996 -2.12528002 0 P 0 ;0
L 1.50318996 -2.12528002 1.50331998 -2.12535 0 P 0 ;0
L 1.50331998 -2.12535 1.50343996 -2.1254 0 P 0 ;0
L 1.50343996 -2.1254 1.50391998 -2.12556004 0 P 0 ;0
L 1.50391998 -2.12556004 1.5044 -2.12568996 0 P 0 ;0
L 1.5044 -2.12568996 1.50848002 -2.12648996 0 P 0 ;0
L 1.50848002 -2.12648996 1.51328996 -2.12738002 0 P 0 ;0
L 1.51328996 -2.12738002 1.51873996 -2.12833996 0 P 0 ;0
L 1.51873996 -2.12833996 1.52606004 -2.12945 0 P 0 ;0
L 1.52606004 -2.12945 1.53343996 -2.13023002 0 P 0 ;0
L 1.53343996 -2.13023002 1.54886998 -2.13086998 0 P 0 ;0
L 1.54886998 -2.13086998 1.56305 -2.1303 0 P 0 ;0
L 1.56305 -2.1303 1.56666004 -2.12988996 0 P 0 ;0
L 1.56666004 -2.12988996 1.57023002 -2.12926998 0 P 0 ;0
L 1.57023002 -2.12926998 1.5738 -2.12843002 0 P 0 ;0
L 1.5738 -2.12843002 1.57945 -2.12668996 0 P 0 ;0
L 1.57945 -2.12668996 1.58498002 -2.12456998 0 P 0 ;0
L 1.58498002 -2.12456998 1.58793996 -2.12318002 0 P 0 ;0
L 1.58793996 -2.12318002 1.59078996 -2.12156004 0 P 0 ;0
L 1.59078996 -2.12156004 1.59348996 -2.11971998 0 P 0 ;0
L 1.59348996 -2.11971998 1.59525 -2.11833002 0 P 0 ;0
L 1.59525 -2.11833002 1.5969 -2.11681998 0 P 0 ;0
L 1.5969 -2.11681998 1.59846004 -2.11521004 0 P 0 ;0
L 1.59846004 -2.11521004 1.59991004 -2.11348002 0 P 0 ;0
L 1.59991004 -2.11348002 1.60175 -2.11093996 0 P 0 ;0
L 1.60175 -2.11093996 1.60338002 -2.10826998 0 P 0 ;0
L 1.60338002 -2.10826998 1.60481004 -2.10548002 0 P 0 ;0
L 1.60481004 -2.10548002 1.60573002 -2.10321004 0 P 0 ;0
L 1.60573002 -2.10321004 1.60646004 -2.10088002 0 P 0 ;0
L 1.60646004 -2.10088002 1.60698002 -2.09848996 0 P 0 ;0
L 1.60698002 -2.09848996 1.60756004 -2.09421998 0 P 0 ;0
L 1.60756004 -2.09421998 1.6078 -2.08991004 0 P 0 ;0
L 1.6078 -2.08991004 1.60768996 -2.08565 0 P 0 ;0
L 1.60768996 -2.08565 1.60723002 -2.08141998 0 P 0 ;0
L 1.60723002 -2.08141998 1.60691998 -2.07968002 0 P 0 ;0
L 1.60691998 -2.07968002 1.60646998 -2.07796998 0 P 0 ;0
L 1.60646998 -2.07796998 1.60591998 -2.0763 0 P 0 ;0
L 1.60591998 -2.0763 1.60523002 -2.07466998 0 P 0 ;0
L 1.60523002 -2.07466998 1.60411998 -2.07246998 0 P 0 ;0
L 1.60411998 -2.07246998 1.60281004 -2.07038002 0 P 0 ;0
L 1.60281004 -2.07038002 1.60131998 -2.06838996 0 P 0 ;0
L 1.60131998 -2.06838996 1.59803996 -2.06461998 0 P 0 ;0
L 1.59803996 -2.06461998 1.59455 -2.06101998 0 P 0 ;0
L 1.59455 -2.06101998 1.59031998 -2.05708996 0 P 0 ;0
L 1.59031998 -2.05708996 1.58586004 -2.05333996 0 P 0 ;0
L 1.58586004 -2.05333996 1.57588002 -2.04598996 0 P 0 ;0
L 1.57588002 -2.04598996 1.56685 -2.03963996 0 P 0 ;0
L 1.56685 -2.03963996 1.56578002 -2.03878996 0 P 0 ;0
L 1.56578002 -2.03878996 1.56476998 -2.03786004 0 P 0 ;0
L 1.56476998 -2.03786004 1.56383002 -2.03686998 0 P 0 ;0
L 1.56383002 -2.03686998 1.56295 -2.0358 0 P 0 ;0
L 1.56295 -2.0358 1.56276998 -2.03555 0 P 0 ;0
L 1.56276998 -2.03555 1.56261004 -2.03528002 0 P 0 ;0
L 1.56261004 -2.03528002 1.56246998 -2.035 0 P 0 ;0
L 1.56246998 -2.035 1.56236004 -2.03471998 0 P 0 ;0
L 1.56236004 -2.03471998 1.56226998 -2.03441998 0 P 0 ;0
L 1.56226998 -2.03441998 1.5622 -2.03411998 0 P 0 ;0
L 1.5622 -2.03411998 1.56216004 -2.03381998 0 P 0 ;0
L 1.56216004 -2.03381998 1.56213996 -2.03351004 0 P 0 ;0
L 1.56213996 -2.03351004 1.56215 -2.0332 0 P 0 ;0
L 1.56215 -2.0332 1.56218002 -2.03288996 0 P 0 ;0
L 1.56218002 -2.03288996 1.56225 -2.03253996 0 P 0 ;0
L 1.56225 -2.03253996 1.56233996 -2.03221004 0 P 0 ;0
L 1.56233996 -2.03221004 1.56246004 -2.03186998 0 P 0 ;0
L 1.56246004 -2.03186998 1.56261004 -2.03156004 0 P 0 ;0
L 1.56261004 -2.03156004 1.56278996 -2.03125 0 P 0 ;0
L 1.56278996 -2.03125 1.56298002 -2.03096004 0 P 0 ;0
L 1.56298002 -2.03096004 1.56321004 -2.03068996 0 P 0 ;0
L 1.56321004 -2.03068996 1.56345 -2.03043996 0 P 0 ;0
L 1.56345 -2.03043996 1.56371004 -2.0302 0 P 0 ;0
L 1.56371004 -2.0302 1.56416004 -2.02986004 0 P 0 ;0
L 1.56416004 -2.02986004 1.56463002 -2.02955 0 P 0 ;0
L 1.56463002 -2.02955 1.56511998 -2.02928002 0 P 0 ;0
L 1.56511998 -2.02928002 1.56561998 -2.02903002 0 P 0 ;0
L 1.56561998 -2.02903002 1.56611998 -2.02883996 0 P 0 ;0
L 1.56611998 -2.02883996 1.56663996 -2.02866998 0 P 0 ;0
L 1.56663996 -2.02866998 1.56716004 -2.02855 0 P 0 ;0
L 1.56716004 -2.02855 1.5677 -2.02846998 0 P 0 ;0
L 1.5677 -2.02846998 1.56926998 -2.02835 0 P 0 ;0
L 1.56926998 -2.02835 1.57085 -2.02833996 0 P 0 ;0
L 1.57085 -2.02833996 1.57725 -2.02866998 0 P 0 ;0
L 1.57725 -2.02866998 1.58205 -2.02906004 0 P 0 ;0
L 1.58205 -2.02906004 1.58746998 -2.02975 0 P 0 ;0
L 1.58746998 -2.02975 1.59271004 -2.03056998 0 P 0 ;0
L 1.59271004 -2.03056998 1.59681004 -2.03143002 0 P 0 ;0
L 1.59681004 -2.03143002 1.60016004 -2.03221998 0 P 0 ;0
L 1.60016004 -2.03221998 1.60308002 -2.03281004 0 P 0 ;0
L 1.60308002 -2.03281004 1.60553996 -2.03323996 0 P 0 ;0
L 1.60553996 -2.03323996 1.60568996 -2.03323996 0 P 0 ;0
L 1.60568996 -2.03323996 1.60576998 -2.03321998 0 P 0 ;0
L 1.60576998 -2.03321998 1.60586004 -2.03316004 0 P 0 ;0
L 1.60586004 -2.03316004 1.6059 -2.03313996 0 P 0 ;0
L 1.6059 -2.03313996 1.60591998 -2.03311004 0 P 0 ;0
L 1.60591998 -2.03311004 1.60598996 -2.03303996 0 P 0 ;0
L 1.60598996 -2.03303996 1.60605 -2.03296998 0 P 0 ;0
L 1.60605 -2.03296998 1.6061 -2.03288996 0 P 0 ;0
L 1.6061 -2.03288996 1.60618002 -2.03273002 0 P 0 ;0
L 1.60618002 -2.03273002 1.60621004 -2.03263002 0 P 0 ;0
L 1.60621004 -2.03263002 1.60623002 -2.03253996 0 P 0 ;0
L 1.60623002 -2.03253996 1.60625 -2.03236004 0 P 0 ;0
L 1.60625 -2.03236004 1.60623996 -2.03226004 0 P 0 ;0
L 1.60623996 -2.03226004 1.60508002 -2.01578002 0 P 0 ;0
L 1.60508002 -2.01578002 1.60393996 -2.00068002 0 P 0 ;0
L 1.60393996 -2.00068002 1.60368002 -1.99833996 0 P 0 ;0
L 1.60368002 -1.99833996 1.60326998 -1.99601004 0 P 0 ;0
L 1.60326998 -1.99601004 1.60321004 -1.99576998 0 P 0 ;0
L 1.60321004 -1.99576998 1.60313996 -1.99553002 0 P 0 ;0
L 1.60313996 -1.99553002 1.60303996 -1.9953 0 P 0 ;0
L 1.60303996 -1.9953 1.60293002 -1.99508002 0 P 0 ;0
L 1.60293002 -1.99508002 1.60281004 -1.99486004 0 P 0 ;0
L 1.60281004 -1.99486004 1.60261998 -1.9946 0 P 0 ;0
L 1.60261998 -1.9946 1.60241004 -1.99435 0 P 0 ;0
L 1.60241004 -1.99435 1.60218002 -1.99411998 0 P 0 ;0
L 1.60218002 -1.99411998 1.60191998 -1.99391004 0 P 0 ;0
L 1.60191998 -1.99391004 1.60161004 -1.99368996 0 P 0 ;0
L 1.60161004 -1.99368996 1.60128996 -1.99348996 0 P 0 ;0
L 1.60128996 -1.99348996 1.60095 -1.99331998 0 P 0 ;0
L 1.60095 -1.99331998 1.6006 -1.99316004 0 P 0 ;0
L 1.6006 -1.99316004 1.59966004 -1.99283002 0 P 0 ;0
L 1.59966004 -1.99283002 1.59871004 -1.99255 0 P 0 ;0
L 1.59871004 -1.99255 1.5933 -1.99135 0 P 0 ;0
L 1.5933 -1.99135 1.5878 -1.9905 0 P 0 ;0
L 1.5878 -1.9905 1.57285 -1.98915 0 P 0 ;0
L 1.57285 -1.98915 1.55763996 -1.98861004 0 P 0 ;0
L 1.55763996 -1.98861004 1.55171004 -1.98876004 0 P 0 ;0
L 1.55171004 -1.98876004 1.54575 -1.98923996 0 P 0 ;0
L 1.53011998 -2.12786998 1.5666 -2.12786998 0 P 0 ;0
L 1.52236004 -2.12686998 1.57168002 -2.12686998 0 P 0 ;0
L 1.51621998 -2.12586998 1.5753 -2.12586998 0 P 0 ;0
L 1.51071004 -2.12486998 1.57856004 -2.12486998 0 P 0 ;0
L 1.50553002 -2.12386998 1.58121004 -2.12386998 0 P 0 ;0
L 1.50431004 -2.12286998 1.58381998 -2.12286998 0 P 0 ;0
L 1.50423002 -2.12186998 1.58601998 -2.12186998 0 P 0 ;0
L 1.50413996 -2.12086998 1.58796004 -2.12086998 0 P 0 ;0
L 1.50406004 -2.11986998 1.58971004 -2.11986998 0 P 0 ;0
L 1.50396998 -2.11886998 1.59118002 -2.11886998 0 P 0 ;0
L 1.50388996 -2.11786998 1.5926 -2.11786998 0 P 0 ;0
L 1.50381004 -2.11686998 1.59386004 -2.11686998 0 P 0 ;0
L 1.50371998 -2.11586998 1.59496998 -2.11586998 0 P 0 ;0
L 1.50363996 -2.11486998 1.59601004 -2.11486998 0 P 0 ;0
L 1.50355 -2.11386998 1.59696998 -2.11386998 0 P 0 ;0
L 1.50346998 -2.11286998 1.59781004 -2.11286998 0 P 0 ;0
L 1.50338002 -2.11186998 1.5986 -2.11186998 0 P 0 ;0
L 1.5033 -2.11086998 1.59933002 -2.11086998 0 P 0 ;0
L 1.50321004 -2.10986998 1.60005 -2.10986998 0 P 0 ;0
L 1.50313002 -2.10886998 1.60066998 -2.10886998 0 P 0 ;0
L 1.50305 -2.10786998 1.60128002 -2.10786998 0 P 0 ;0
L 1.50296004 -2.10686998 1.60185 -2.10686998 0 P 0 ;0
L 1.50288002 -2.10586998 1.60236004 -2.10586998 0 P 0 ;0
L 1.50278996 -2.10486998 1.60286998 -2.10486998 0 P 0 ;0
L 1.50271004 -2.10386998 1.6033 -2.10386998 0 P 0 ;0
L 1.50263002 -2.10286998 1.60371004 -2.10286998 0 P 0 ;0
L 1.50255 -2.10186998 1.60405 -2.10186998 0 P 0 ;0
L 1.50246998 -2.10086998 1.60436004 -2.10086998 0 P 0 ;0
L 1.50238996 -2.09986998 1.60463002 -2.09986998 0 P 0 ;0
L 1.50231004 -2.09886998 1.60485 -2.09886998 0 P 0 ;0
L 1.50223002 -2.09786998 1.60505 -2.09786998 0 P 0 ;0
L 1.50215 -2.09686998 1.60518002 -2.09686998 0 P 0 ;0
L 1.50206998 -2.09586998 1.60531998 -2.09586998 0 P 0 ;0
L 1.50198996 -2.09486998 1.60545 -2.09486998 0 P 0 ;0
L 1.50191004 -2.09386998 1.60558002 -2.09386998 0 P 0 ;0
L 1.50183002 -2.09286998 1.60563002 -2.09286998 0 P 0 ;0
L 1.50175 -2.09186998 1.53725 -2.09186998 0 P 0 ;0
L 1.54638996 -2.09186998 1.60568996 -2.09186998 0 P 0 ;0
L 1.50166998 -2.09086998 1.5295 -2.09086998 0 P 0 ;0
L 1.54956998 -2.09086998 1.60573996 -2.09086998 0 P 0 ;0
L 1.50158996 -2.08986998 1.52436004 -2.08986998 0 P 0 ;0
L 1.55125 -2.08986998 1.60578996 -2.08986998 0 P 0 ;0
L 1.50151004 -2.08886998 1.52021004 -2.08886998 0 P 0 ;0
L 1.55226998 -2.08886998 1.60576998 -2.08886998 0 P 0 ;0
L 1.50143002 -2.08786998 1.51633002 -2.08786998 0 P 0 ;0
L 1.55298002 -2.08786998 1.60573996 -2.08786998 0 P 0 ;0
L 1.50133996 -2.08686998 1.51246004 -2.08686998 0 P 0 ;0
L 1.55346998 -2.08686998 1.60571998 -2.08686998 0 P 0 ;0
L 1.50126998 -2.08586998 1.50861998 -2.08586998 0 P 0 ;0
L 1.55375 -2.08586998 1.60568996 -2.08586998 0 P 0 ;0
L 1.50118002 -2.08486998 1.50481004 -2.08486998 0 P 0 ;0
L 1.55383002 -2.08486998 1.60558996 -2.08486998 0 P 0 ;0
L 1.55371998 -2.08386998 1.60548996 -2.08386998 0 P 0 ;0
L 1.54886998 -2.12886998 1.53358996 -2.12823996 0 P 0 ;0
L 1.53358996 -2.12823996 1.52631998 -2.12746998 0 P 0 ;0
L 1.52631998 -2.12746998 1.51906004 -2.12636998 0 P 0 ;0
L 1.51906004 -2.12636998 1.51363002 -2.12541004 0 P 0 ;0
L 1.51363002 -2.12541004 1.50886998 -2.12451998 0 P 0 ;0
L 1.50886998 -2.12451998 1.50483996 -2.12373996 0 P 0 ;0
L 1.50483996 -2.12373996 1.50448996 -2.12365 0 P 0 ;0
L 1.50448996 -2.12365 1.50438002 -2.12361004 0 P 0 ;0
L 1.50438002 -2.12361004 1.5027 -2.10378002 0 P 0 ;0
L 1.5027 -2.10378002 1.50111998 -2.08403002 0 P 0 ;0
L 1.50111998 -2.08403002 1.50263996 -2.08433996 0 P 0 ;0
L 1.50263996 -2.08433996 1.50581004 -2.08511004 0 P 0 ;0
L 1.50581004 -2.08511004 1.50955 -2.08611998 0 P 0 ;0
L 1.50955 -2.08611998 1.52306004 -2.08961004 0 P 0 ;0
L 1.52306004 -2.08961004 1.52311004 -2.08961998 0 P 0 ;0
L 1.52311004 -2.08961998 1.52875 -2.09076004 0 P 0 ;0
L 1.52875 -2.09076004 1.5288 -2.09076004 0 P 0 ;0
L 1.5288 -2.09076004 1.53443996 -2.09161004 0 P 0 ;0
L 1.53443996 -2.09161004 1.53893996 -2.09203002 0 P 0 ;0
L 1.53893996 -2.09203002 1.54346004 -2.09216998 0 P 0 ;0
L 1.54346004 -2.09216998 1.54473996 -2.09211004 0 P 0 ;0
L 1.54473996 -2.09211004 1.54603002 -2.09195 0 P 0 ;0
L 1.54603002 -2.09195 1.54728996 -2.09166998 0 P 0 ;0
L 1.54728996 -2.09166998 1.54853002 -2.09128996 0 P 0 ;0
L 1.54853002 -2.09128996 1.54973002 -2.09081004 0 P 0 ;0
L 1.54973002 -2.09081004 1.55026998 -2.09053996 0 P 0 ;0
L 1.55026998 -2.09053996 1.55076998 -2.09023002 0 P 0 ;0
L 1.55076998 -2.09023002 1.55118002 -2.08991998 0 P 0 ;0
L 1.55118002 -2.08991998 1.55118002 -2.08991004 0 P 0 ;0
L 1.55118002 -2.08991004 1.5512 -2.08991004 0 P 0 ;0
L 1.5512 -2.08991004 1.55125 -2.08986998 0 P 0 ;0
L 1.55125 -2.08986998 1.55131004 -2.08981998 0 P 0 ;0
L 1.55131004 -2.08981998 1.55126998 -2.08978002 0 P 0 ;0
L 1.55126998 -2.08978002 1.55136004 -2.08978002 0 P 0 ;0
L 1.55136004 -2.08978002 1.5517 -2.08948996 0 P 0 ;0
L 1.5517 -2.08948996 1.55206004 -2.08911998 0 P 0 ;0
L 1.55206004 -2.08911998 1.55205 -2.08911004 0 P 0 ;0
L 1.55205 -2.08911004 1.55206004 -2.08911004 0 P 0 ;0
L 1.55206004 -2.08911004 1.55211998 -2.08906004 0 P 0 ;0
L 1.55211998 -2.08906004 1.55248996 -2.08861004 0 P 0 ;0
L 1.55248996 -2.08861004 1.55283996 -2.08811998 0 P 0 ;0
L 1.55283996 -2.08811998 1.55313996 -2.08761004 0 P 0 ;0
L 1.55313996 -2.08761004 1.5534 -2.08706998 0 P 0 ;0
L 1.5534 -2.08706998 1.55356004 -2.08663002 0 P 0 ;0
L 1.55356004 -2.08663002 1.55368996 -2.08618996 0 P 0 ;0
L 1.55368996 -2.08618996 1.55376998 -2.08573996 0 P 0 ;0
L 1.55376998 -2.08573996 1.55378002 -2.08565 0 P 0 ;0
L 1.55378002 -2.08565 1.55381998 -2.08528002 0 P 0 ;0
L 1.55381998 -2.08528002 1.55383002 -2.08481998 0 P 0 ;0
L 1.55383002 -2.08481998 1.5538 -2.08436998 0 P 0 ;0
L 1.5538 -2.08436998 1.55373002 -2.08391998 0 P 0 ;0
L 1.55373002 -2.08391998 1.55361998 -2.08346998 0 P 0 ;0
L 1.55361998 -2.08346998 1.55348002 -2.08303996 0 P 0 ;0
L 1.55348002 -2.08303996 1.5533 -2.08261004 0 P 0 ;0
L 1.5533 -2.08261004 1.55308996 -2.08221004 0 P 0 ;0
L 1.55308996 -2.08221004 1.55283996 -2.08183002 0 P 0 ;0
L 1.55283996 -2.08183002 1.55175 -2.0804 0 P 0 ;0
L 1.55175 -2.0804 1.55055 -2.07908002 0 P 0 ;0
L 1.55055 -2.07908002 1.54926004 -2.07783996 0 P 0 ;0
L 1.54926004 -2.07783996 1.54788996 -2.07671998 0 P 0 ;0
L 1.54788996 -2.07671998 1.53706998 -2.06898002 0 P 0 ;0
L 1.53706998 -2.06898002 1.52085 -2.05713996 0 P 0 ;0
L 1.52085 -2.05713996 1.51766004 -2.05445 0 P 0 ;0
L 1.51766004 -2.05445 1.51468002 -2.05153996 0 P 0 ;0
L 1.51468002 -2.05153996 1.51191998 -2.04841998 0 P 0 ;0
L 1.51191998 -2.04841998 1.51048996 -2.04651998 0 P 0 ;0
L 1.51048996 -2.04651998 1.50923002 -2.04453002 0 P 0 ;0
L 1.50923002 -2.04453002 1.50813996 -2.04245 0 P 0 ;0
L 1.50813996 -2.04245 1.50721998 -2.04026004 0 P 0 ;0
L 1.50721998 -2.04026004 1.50643002 -2.03788002 0 P 0 ;0
L 1.50643002 -2.03788002 1.50581004 -2.03545 0 P 0 ;0
L 1.50581004 -2.03545 1.50536004 -2.03298996 0 P 0 ;0
L 1.50536004 -2.03298996 1.50508996 -2.0305 0 P 0 ;0
L 1.50508996 -2.0305 1.50498996 -2.02745 0 P 0 ;0
L 1.50498996 -2.02745 1.50513996 -2.02443996 0 P 0 ;0
L 1.50513996 -2.02443996 1.50551998 -2.02145 0 P 0 ;0
L 1.50551998 -2.02145 1.50613996 -2.0185 0 P 0 ;0
L 1.50613996 -2.0185 1.50698996 -2.01561004 0 P 0 ;0
L 1.50698996 -2.01561004 1.50783002 -2.01341004 0 P 0 ;0
L 1.50783002 -2.01341004 1.50883002 -2.0113 0 P 0 ;0
L 1.50883002 -2.0113 1.51 -2.00928002 0 P 0 ;0
L 1.51 -2.00928002 1.51133002 -2.00736004 0 P 0 ;0
L 1.51133002 -2.00736004 1.5128 -2.00555 0 P 0 ;0
L 1.5128 -2.00555 1.5144 -2.00386004 0 P 0 ;0
L 1.5144 -2.00386004 1.51675 -2.00176998 0 P 0 ;0
L 1.51675 -2.00176998 1.51923002 -1.9999 0 P 0 ;0
L 1.51923002 -1.9999 1.52186004 -1.99823996 0 P 0 ;0
L 1.52186004 -1.99823996 1.52461998 -1.99681004 0 P 0 ;0
L 1.52461998 -1.99681004 1.52748996 -1.99561004 0 P 0 ;0
L 1.52748996 -1.99561004 1.53353002 -1.99363996 0 P 0 ;0
L 1.53353002 -1.99363996 1.5397 -1.99218002 0 P 0 ;0
L 1.5397 -1.99218002 1.54598002 -1.99123002 0 P 0 ;0
L 1.54598002 -1.99123002 1.55181004 -1.99075 0 P 0 ;0
L 1.55181004 -1.99075 1.55763002 -1.99061998 0 P 0 ;0
L 1.55763002 -1.99061998 1.57273002 -1.99113996 0 P 0 ;0
L 1.57273002 -1.99113996 1.58755 -1.99248996 0 P 0 ;0
L 1.58755 -1.99248996 1.59293002 -1.99331998 0 P 0 ;0
L 1.59293002 -1.99331998 1.59821004 -1.99448996 0 P 0 ;0
L 1.59821004 -1.99448996 1.59905 -1.99473002 0 P 0 ;0
L 1.59905 -1.99473002 1.59986004 -1.99501998 0 P 0 ;0
L 1.59986004 -1.99501998 1.60008002 -1.99511998 0 P 0 ;0
L 1.60008002 -1.99511998 1.6003 -1.99523002 0 P 0 ;0
L 1.6003 -1.99523002 1.60051004 -1.99536004 0 P 0 ;0
L 1.60051004 -1.99536004 1.60071004 -1.9955 0 P 0 ;0
L 1.60071004 -1.9955 1.60083002 -1.99561004 0 P 0 ;0
L 1.60083002 -1.99561004 1.60093996 -1.99571004 0 P 0 ;0
L 1.60093996 -1.99571004 1.60103996 -1.99583002 0 P 0 ;0
L 1.60103996 -1.99583002 1.60111998 -1.99595 0 P 0 ;0
L 1.60111998 -1.99595 1.60116998 -1.99601998 0 P 0 ;0
L 1.60116998 -1.99601998 1.60121004 -1.99611004 0 P 0 ;0
L 1.60121004 -1.99611004 1.60125 -1.99621004 0 P 0 ;0
L 1.60125 -1.99621004 1.60128002 -1.9963 0 P 0 ;0
L 1.60128002 -1.9963 1.60131004 -1.99641004 0 P 0 ;0
L 1.60131004 -1.99641004 1.6017 -1.99861998 0 P 0 ;0
L 1.6017 -1.99861998 1.60195 -2.00086998 0 P 0 ;0
L 1.60195 -2.00086998 1.60308002 -2.01593002 0 P 0 ;0
L 1.60308002 -2.01593002 1.60415 -2.03096998 0 P 0 ;0
L 1.60415 -2.03096998 1.60345 -2.03083996 0 P 0 ;0
L 1.60345 -2.03083996 1.60058996 -2.03026004 0 P 0 ;0
L 1.60058996 -2.03026004 1.59723002 -2.02948002 0 P 0 ;0
L 1.59723002 -2.02948002 1.59721998 -2.02948002 0 P 0 ;0
L 1.59721998 -2.02948002 1.59306998 -2.0286 0 P 0 ;0
L 1.59306998 -2.0286 1.58776004 -2.02776998 0 P 0 ;0
L 1.58776004 -2.02776998 1.58226004 -2.02708002 0 P 0 ;0
L 1.58226004 -2.02708002 1.57738002 -2.02666998 0 P 0 ;0
L 1.57738002 -2.02666998 1.5709 -2.02633996 0 P 0 ;0
L 1.5709 -2.02633996 1.56918996 -2.02635 0 P 0 ;0
L 1.56918996 -2.02635 1.56746998 -2.02648996 0 P 0 ;0
L 1.56746998 -2.02648996 1.56678996 -2.02658996 0 P 0 ;0
L 1.56678996 -2.02658996 1.56611998 -2.02673996 0 P 0 ;0
L 1.56611998 -2.02673996 1.56546004 -2.02695 0 P 0 ;0
L 1.56546004 -2.02695 1.56481998 -2.0272 0 P 0 ;0
L 1.56481998 -2.0272 1.56418996 -2.0275 0 P 0 ;0
L 1.56418996 -2.0275 1.56358002 -2.02785 0 P 0 ;0
L 1.56358002 -2.02785 1.563 -2.02823002 0 P 0 ;0
L 1.563 -2.02823002 1.56245 -2.02865 0 P 0 ;0
L 1.56245 -2.02865 1.56206998 -2.02898996 0 P 0 ;0
L 1.56206998 -2.02898996 1.56171004 -2.02936004 0 P 0 ;0
L 1.56171004 -2.02936004 1.56138002 -2.02976004 0 P 0 ;0
L 1.56138002 -2.02976004 1.56108996 -2.03018996 0 P 0 ;0
L 1.56108996 -2.03018996 1.56083002 -2.03063996 0 P 0 ;0
L 1.56083002 -2.03063996 1.56061998 -2.0311 0 P 0 ;0
L 1.56061998 -2.0311 1.56043996 -2.03158996 0 P 0 ;0
L 1.56043996 -2.03158996 1.5603 -2.03208002 0 P 0 ;0
L 1.5603 -2.03208002 1.5602 -2.0326 0 P 0 ;0
L 1.5602 -2.0326 1.56015 -2.03308002 0 P 0 ;0
L 1.56015 -2.03308002 1.56013996 -2.03353996 0 P 0 ;0
L 1.56013996 -2.03353996 1.56016004 -2.03391004 0 P 0 ;0
L 1.56016004 -2.03391004 1.56048002 -2.03391004 0 P 0 ;0
L 1.56048002 -2.03391004 1.56016004 -2.03393002 0 P 0 ;0
L 1.56016004 -2.03393002 1.56016998 -2.03401004 0 P 0 ;0
L 1.56016998 -2.03401004 1.56023002 -2.03448002 0 P 0 ;0
L 1.56023002 -2.03448002 1.56025 -2.03456004 0 P 0 ;0
L 1.56025 -2.03456004 1.56033002 -2.03493002 0 P 0 ;0
L 1.56033002 -2.03493002 1.56046998 -2.03538002 0 P 0 ;0
L 1.56046998 -2.03538002 1.56063996 -2.03581998 0 P 0 ;0
L 1.56063996 -2.03581998 1.56085 -2.03623996 0 P 0 ;0
L 1.56085 -2.03623996 1.56108996 -2.03663996 0 P 0 ;0
L 1.56108996 -2.03663996 1.56136004 -2.03701998 0 P 0 ;0
L 1.56136004 -2.03701998 1.56233002 -2.03818996 0 P 0 ;0
L 1.56233002 -2.03818996 1.56336998 -2.03928996 0 P 0 ;0
L 1.56336998 -2.03928996 1.56448002 -2.04031004 0 P 0 ;0
L 1.56448002 -2.04031004 1.56566004 -2.04123996 0 P 0 ;0
L 1.56566004 -2.04123996 1.57471004 -2.04761998 0 P 0 ;0
L 1.57471004 -2.04761998 1.58461998 -2.05491004 0 P 0 ;0
L 1.58461998 -2.05491004 1.58898996 -2.05858996 0 P 0 ;0
L 1.58898996 -2.05858996 1.59315 -2.06245 0 P 0 ;0
L 1.59315 -2.06245 1.59656998 -2.06596998 0 P 0 ;0
L 1.59656998 -2.06596998 1.59976004 -2.06965 0 P 0 ;0
L 1.59976004 -2.06965 1.60116004 -2.07151004 0 P 0 ;0
L 1.60116004 -2.07151004 1.60238002 -2.07346004 0 P 0 ;0
L 1.60238002 -2.07346004 1.60341998 -2.0755 0 P 0 ;0
L 1.60341998 -2.0755 1.60403996 -2.077 0 P 0 ;0
L 1.60403996 -2.077 1.60456004 -2.07853996 0 P 0 ;0
L 1.60456004 -2.07853996 1.60496004 -2.08011004 0 P 0 ;0
L 1.60496004 -2.08011004 1.60525 -2.0817 0 P 0 ;0
L 1.60525 -2.0817 1.60568996 -2.08578002 0 P 0 ;0
L 1.60568996 -2.08578002 1.60578996 -2.08988002 0 P 0 ;0
L 1.60578996 -2.08988002 1.60556998 -2.09403002 0 P 0 ;0
L 1.60556998 -2.09403002 1.60501004 -2.09813996 0 P 0 ;0
L 1.60501004 -2.09813996 1.60451998 -2.10036998 0 P 0 ;0
L 1.60451998 -2.10036998 1.60383996 -2.10253996 0 P 0 ;0
L 1.60383996 -2.10253996 1.60298996 -2.10465 0 P 0 ;0
L 1.60298996 -2.10465 1.60163996 -2.1073 0 P 0 ;0
L 1.60163996 -2.1073 1.60008002 -2.10983002 0 P 0 ;0
L 1.60008002 -2.10983002 1.59833002 -2.11225 0 P 0 ;0
L 1.59833002 -2.11225 1.59696998 -2.11386998 0 P 0 ;0
L 1.59696998 -2.11386998 1.59551004 -2.11538996 0 P 0 ;0
L 1.59551004 -2.11538996 1.59395 -2.1168 0 P 0 ;0
L 1.59395 -2.1168 1.59231004 -2.11811004 0 P 0 ;0
L 1.59231004 -2.11811004 1.58973002 -2.11986004 0 P 0 ;0
L 1.58973002 -2.11986004 1.58701998 -2.1214 0 P 0 ;0
L 1.58701998 -2.1214 1.5842 -2.12273002 0 P 0 ;0
L 1.5842 -2.12273002 1.5788 -2.1248 0 P 0 ;0
L 1.5788 -2.1248 1.57326998 -2.12648996 0 P 0 ;0
L 1.57326998 -2.12648996 1.56983002 -2.12731004 0 P 0 ;0
L 1.56983002 -2.12731004 1.56638002 -2.12791004 0 P 0 ;0
L 1.56638002 -2.12791004 1.56288996 -2.1283 0 P 0 ;0
L 1.56288996 -2.1283 1.54886998 -2.12886998 0 P 0 ;0
L 1.35851998 -2.06545 1.47866004 -2.06545 0 P 0 ;0
L 1.35936004 -2.06445 1.47871004 -2.06445 0 P 0 ;0
L 1.36041004 -2.06345 1.47875 -2.06345 0 P 0 ;0
L 1.36163996 -2.06245 1.4788 -2.06245 0 P 0 ;0
L 1.36293996 -2.06145 1.47883996 -2.06145 0 P 0 ;0
L 1.36436004 -2.06045 1.47888996 -2.06045 0 P 0 ;0
L 1.36598002 -2.05945 1.47893996 -2.05945 0 P 0 ;0
L 1.36776004 -2.05845 1.47898996 -2.05845 0 P 0 ;0
L 1.36971004 -2.05745 1.47903002 -2.05745 0 P 0 ;0
L 1.37166004 -2.05645 1.47908002 -2.05645 0 P 0 ;0
L 1.37391004 -2.05545 1.47911998 -2.05545 0 P 0 ;0
L 1.37616998 -2.05445 1.47916998 -2.05445 0 P 0 ;0
L 1.37873002 -2.05345 1.47921004 -2.05345 0 P 0 ;0
L 1.38136004 -2.05245 1.47926004 -2.05245 0 P 0 ;0
L 1.36875 -2.03345 1.37108996 -2.03345 0 P 0 ;0
L 1.36886004 -2.03245 1.37385 -2.03245 0 P 0 ;0
L 1.36896998 -2.03145 1.37678002 -2.03145 0 P 0 ;0
L 1.36908996 -2.03045 1.3797 -2.03045 0 P 0 ;0
L 1.36921004 -2.02945 1.38261998 -2.02945 0 P 0 ;0
L 1.36933002 -2.02845 1.38638996 -2.02845 0 P 0 ;0
L 1.36946004 -2.02745 1.39023996 -2.02745 0 P 0 ;0
L 1.36958002 -2.02645 1.39503002 -2.02645 0 P 0 ;0
L 1.3697 -2.02545 1.40068002 -2.02545 0 P 0 ;0
L 1.36981998 -2.02445 1.41053996 -2.02445 0 P 0 ;0
L 1.36993996 -2.02345 1.47993996 -2.02345 0 P 0 ;0
L 1.37008002 -2.02245 1.47988002 -2.02245 0 P 0 ;0
L 1.37021004 -2.02145 1.47978002 -2.02145 0 P 0 ;0
L 1.37033996 -2.02045 1.47968002 -2.02045 0 P 0 ;0
L 1.37046998 -2.01945 1.47953002 -2.01945 0 P 0 ;0
L 1.3706 -2.01845 1.47936004 -2.01845 0 P 0 ;0
L 1.37073002 -2.01745 1.47918002 -2.01745 0 P 0 ;0
L 1.37086004 -2.01645 1.47893002 -2.01645 0 P 0 ;0
L 1.37098996 -2.01545 1.47868002 -2.01545 0 P 0 ;0
L 1.37113002 -2.01445 1.4784 -2.01445 0 P 0 ;0
L 1.37126998 -2.01345 1.47806004 -2.01345 0 P 0 ;0
L 1.3714 -2.01245 1.47773002 -2.01245 0 P 0 ;0
L 1.37153996 -2.01145 1.47733002 -2.01145 0 P 0 ;0
L 1.37168002 -2.01045 1.47691004 -2.01045 0 P 0 ;0
L 1.37181004 -2.00945 1.47641004 -2.00945 0 P 0 ;0
L 1.37195 -2.00845 1.47588996 -2.00845 0 P 0 ;0
L 1.37208002 -2.00745 1.47528002 -2.00745 0 P 0 ;0
L 1.37221004 -2.00645 1.47463996 -2.00645 0 P 0 ;0
L 1.37235 -2.00545 1.47391998 -2.00545 0 P 0 ;0
L 1.37248996 -2.00445 1.47311004 -2.00445 0 P 0 ;0
L 1.37261998 -2.00345 1.47225 -2.00345 0 P 0 ;0
L 1.37276004 -2.00245 1.47126998 -2.00245 0 P 0 ;0
L 1.3729 -2.00145 1.4702 -2.00145 0 P 0 ;0
L 1.37303002 -2.00045 1.46903996 -2.00045 0 P 0 ;0
L 1.37316998 -1.99945 1.46775 -1.99945 0 P 0 ;0
L 1.3733 -1.99845 1.46625 -1.99845 0 P 0 ;0
L 1.37343996 -1.99745 1.46455 -1.99745 0 P 0 ;0
L 1.37356998 -1.99645 1.46253996 -1.99645 0 P 0 ;0
L 1.37753002 -1.99545 1.46041004 -1.99545 0 P 0 ;0
L 1.38218996 -1.99445 1.45781004 -1.99445 0 P 0 ;0
L 1.42925 -2.08345 1.47785 -2.08345 0 P 0 ;0
L 1.42931998 -2.08245 1.47788996 -2.08245 0 P 0 ;0
L 1.42938002 -2.08145 1.47793002 -2.08145 0 P 0 ;0
L 1.42945 -2.08045 1.47796998 -2.08045 0 P 0 ;0
L 1.42951004 -2.07945 1.47801004 -2.07945 0 P 0 ;0
L 1.42958002 -2.07845 1.47806004 -2.07845 0 P 0 ;0
L 1.42963996 -2.07745 1.4781 -2.07745 0 P 0 ;0
L 1.4297 -2.07645 1.47815 -2.07645 0 P 0 ;0
L 1.42976998 -2.07545 1.4782 -2.07545 0 P 0 ;0
L 1.42983002 -2.07445 1.47825 -2.07445 0 P 0 ;0
L 1.4299 -2.07345 1.47828996 -2.07345 0 P 0 ;0
L 1.42963996 -2.07245 1.47833996 -2.07245 0 P 0 ;0
L 1.42918996 -2.07145 1.47838002 -2.07145 0 P 0 ;0
L 1.38425 -2.05145 1.47931004 -2.05145 0 P 0 ;0
L 1.38731998 -2.05045 1.47933996 -2.05045 0 P 0 ;0
L 1.39088002 -2.04945 1.47938002 -2.04945 0 P 0 ;0
L 1.3947 -2.04845 1.47941004 -2.04845 0 P 0 ;0
L 1.39851004 -2.04745 1.47945 -2.04745 0 P 0 ;0
L 1.40233002 -2.04645 1.47948002 -2.04645 0 P 0 ;0
L 1.40608002 -2.04545 1.47951004 -2.04545 0 P 0 ;0
L 1.40983002 -2.04445 1.47955 -2.04445 0 P 0 ;0
L 1.41306998 -2.04345 1.47958996 -2.04345 0 P 0 ;0
L 1.41591998 -2.04245 1.47961998 -2.04245 0 P 0 ;0
L 1.41876998 -2.04145 1.47965 -2.04145 0 P 0 ;0
L 1.42133996 -2.04045 1.47968996 -2.04045 0 P 0 ;0
L 1.42361998 -2.03945 1.47971998 -2.03945 0 P 0 ;0
L 1.42591004 -2.03845 1.47975 -2.03845 0 P 0 ;0
L 1.42805 -2.03745 1.47978002 -2.03745 0 P 0 ;0
L 1.42936004 -2.03645 1.47981004 -2.03645 0 P 0 ;0
L 1.43003002 -2.03545 1.47983002 -2.03545 0 P 0 ;0
L 1.43081998 -2.03445 1.47986004 -2.03445 0 P 0 ;0
L 1.43121004 -2.03345 1.47988002 -2.03345 0 P 0 ;0
L 1.43141998 -2.03245 1.4799 -2.03245 0 P 0 ;0
L 1.43146998 -2.03145 1.47993002 -2.03145 0 P 0 ;0
L 1.43136004 -2.03045 1.47996004 -2.03045 0 P 0 ;0
L 1.43108002 -2.02945 1.47998002 -2.02945 0 P 0 ;0
L 1.4306 -2.02845 1.48001004 -2.02845 0 P 0 ;0
L 1.42986998 -2.02745 1.48001004 -2.02745 0 P 0 ;0
L 1.42875 -2.02645 1.47998996 -2.02645 0 P 0 ;0
L 1.42658996 -2.02545 1.47996998 -2.02545 0 P 0 ;0
L 1.42203996 -2.02445 1.47996004 -2.02445 0 P 0 ;0
L 1.38748002 -1.99345 1.45483002 -1.99345 0 P 0 ;0
L 1.39331998 -1.99245 1.45108996 -1.99245 0 P 0 ;0
L 1.40051004 -1.99145 1.44503002 -1.99145 0 P 0 ;0
L 1.38096998 -2.12745 1.4051 -2.12745 0 P 0 ;0
L 1.37671004 -2.12645 1.41113996 -2.12645 0 P 0 ;0
L 1.3736 -2.12545 1.41238996 -2.12545 0 P 0 ;0
L 1.37096998 -2.12445 1.41268002 -2.12445 0 P 0 ;0
L 1.36876998 -2.12345 1.41296998 -2.12345 0 P 0 ;0
L 1.36685 -2.12245 1.41326998 -2.12245 0 P 0 ;0
L 1.36516004 -2.12145 1.41356004 -2.12145 0 P 0 ;0
L 1.36366004 -2.12045 1.41385 -2.12045 0 P 0 ;0
L 1.36225 -2.11945 1.41413996 -2.11945 0 P 0 ;0
L 1.361 -2.11845 1.41443002 -2.11845 0 P 0 ;0
L 1.35983002 -2.11745 1.41471998 -2.11745 0 P 0 ;0
L 1.35876004 -2.11645 1.41501004 -2.11645 0 P 0 ;0
L 1.42661998 -2.12445 1.47693002 -2.12445 0 P 0 ;0
L 1.42665 -2.12345 1.47693002 -2.12345 0 P 0 ;0
L 1.4267 -2.12245 1.47693002 -2.12245 0 P 0 ;0
L 1.42675 -2.12145 1.47693002 -2.12145 0 P 0 ;0
L 1.42681004 -2.12045 1.47693002 -2.12045 0 P 0 ;0
L 1.42686998 -2.11945 1.47693002 -2.11945 0 P 0 ;0
L 1.42691998 -2.11845 1.47693002 -2.11845 0 P 0 ;0
L 1.42698996 -2.11745 1.47693002 -2.11745 0 P 0 ;0
L 1.42705 -2.11645 1.47693002 -2.11645 0 P 0 ;0
L 1.42711004 -2.11545 1.47693002 -2.11545 0 P 0 ;0
L 1.42716998 -2.11445 1.47693002 -2.11445 0 P 0 ;0
L 1.42723002 -2.11345 1.47693996 -2.11345 0 P 0 ;0
L 1.4273 -2.11245 1.47695 -2.11245 0 P 0 ;0
L 1.42736998 -2.11145 1.47696004 -2.11145 0 P 0 ;0
L 1.42743996 -2.11045 1.47698002 -2.11045 0 P 0 ;0
L 1.42751004 -2.10945 1.47698996 -2.10945 0 P 0 ;0
L 1.42758002 -2.10845 1.47701004 -2.10845 0 P 0 ;0
L 1.42765 -2.10745 1.47703002 -2.10745 0 P 0 ;0
L 1.42771004 -2.10645 1.47703996 -2.10645 0 P 0 ;0
L 1.42778002 -2.10545 1.47706998 -2.10545 0 P 0 ;0
L 1.42783996 -2.10445 1.4771 -2.10445 0 P 0 ;0
L 1.42791004 -2.10345 1.47713002 -2.10345 0 P 0 ;0
L 1.42798002 -2.10245 1.47716004 -2.10245 0 P 0 ;0
L 1.42805 -2.10145 1.4772 -2.10145 0 P 0 ;0
L 1.42811004 -2.10045 1.47723002 -2.10045 0 P 0 ;0
L 1.40953002 -2.09945 1.41973002 -2.09945 0 P 0 ;0
L 1.42818002 -2.09945 1.47726004 -2.09945 0 P 0 ;0
L 1.41618002 -2.09845 1.41996998 -2.09845 0 P 0 ;0
L 1.42825 -2.09845 1.47728996 -2.09845 0 P 0 ;0
L 1.42831998 -2.09745 1.47733002 -2.09745 0 P 0 ;0
L 1.42838996 -2.09645 1.47736004 -2.09645 0 P 0 ;0
L 1.42846004 -2.09545 1.47738996 -2.09545 0 P 0 ;0
L 1.42851998 -2.09445 1.47741998 -2.09445 0 P 0 ;0
L 1.42858996 -2.09345 1.47746004 -2.09345 0 P 0 ;0
L 1.42866004 -2.09245 1.4775 -2.09245 0 P 0 ;0
L 1.42873002 -2.09145 1.47753996 -2.09145 0 P 0 ;0
L 1.42878996 -2.09045 1.47758002 -2.09045 0 P 0 ;0
L 1.42886004 -2.08945 1.47761998 -2.08945 0 P 0 ;0
L 1.42893002 -2.08845 1.47766004 -2.08845 0 P 0 ;0
L 1.42898996 -2.08745 1.4777 -2.08745 0 P 0 ;0
L 1.42906004 -2.08645 1.47773002 -2.08645 0 P 0 ;0
L 1.42911998 -2.08545 1.47776998 -2.08545 0 P 0 ;0
L 1.42918996 -2.08445 1.47781004 -2.08445 0 P 0 ;0
L 1.61686004 -2.17995 1.66846004 -2.17995 0 P 0 ;0
L 1.61591004 -2.17895 1.67158996 -2.17895 0 P 0 ;0
L 1.61553996 -2.17795 1.67431998 -2.17795 0 P 0 ;0
L 1.61526998 -2.17695 1.67675 -2.17695 0 P 0 ;0
L 1.61508002 -2.17595 1.67903996 -2.17595 0 P 0 ;0
L 1.61496998 -2.17495 1.68108002 -2.17495 0 P 0 ;0
L 1.61491004 -2.17395 1.68295 -2.17395 0 P 0 ;0
L 1.61485 -2.17295 1.68458996 -2.17295 0 P 0 ;0
L 1.61478996 -2.17195 1.6861 -2.17195 0 P 0 ;0
L 1.61473002 -2.17095 1.6875 -2.17095 0 P 0 ;0
L 1.61466998 -2.16995 1.68876998 -2.16995 0 P 0 ;0
L 1.61461004 -2.16895 1.68998002 -2.16895 0 P 0 ;0
L 1.61455 -2.16795 1.69108002 -2.16795 0 P 0 ;0
L 1.61448996 -2.16695 1.69211998 -2.16695 0 P 0 ;0
L 1.61443002 -2.16595 1.69316004 -2.16595 0 P 0 ;0
L 1.61436998 -2.16495 1.69411998 -2.16495 0 P 0 ;0
L 1.61431004 -2.16395 1.69498996 -2.16395 0 P 0 ;0
L 1.61425 -2.16295 1.69586004 -2.16295 0 P 0 ;0
L 1.61418996 -2.16195 1.69673002 -2.16195 0 P 0 ;0
L 1.61413002 -2.16095 1.69746998 -2.16095 0 P 0 ;0
L 1.61406998 -2.15995 1.6982 -2.15995 0 P 0 ;0
L 1.61401998 -2.15895 1.69893996 -2.15895 0 P 0 ;0
L 1.61396998 -2.15795 1.69963002 -2.15795 0 P 0 ;0
L 1.64433002 -2.18295 1.63151004 -2.18271004 0 P 0 ;0
L 1.63151004 -2.18271004 1.62658002 -2.18226998 0 P 0 ;0
L 1.62658002 -2.18226998 1.62168996 -2.18146998 0 P 0 ;0
L 1.62168996 -2.18146998 1.6201 -2.1811 0 P 0 ;0
L 1.6201 -2.1811 1.61853996 -2.18061004 0 P 0 ;0
L 1.61853996 -2.18061004 1.61701004 -2.18001998 0 P 0 ;0
L 1.61701004 -2.18001998 1.61686004 -2.17995 0 P 0 ;0
L 1.61686004 -2.17995 1.61671004 -2.17986998 0 P 0 ;0
L 1.61671004 -2.17986998 1.61656998 -2.17976998 0 P 0 ;0
L 1.61656998 -2.17976998 1.61643996 -2.17966998 0 P 0 ;0
L 1.61643996 -2.17966998 1.61631998 -2.17955 0 P 0 ;0
L 1.61631998 -2.17955 1.61621004 -2.17943002 0 P 0 ;0
L 1.61621004 -2.17943002 1.6161 -2.1793 0 P 0 ;0
L 1.6161 -2.1793 1.61601004 -2.17915 0 P 0 ;0
L 1.61601004 -2.17915 1.61593002 -2.179 0 P 0 ;0
L 1.61593002 -2.179 1.61586004 -2.17885 0 P 0 ;0
L 1.61586004 -2.17885 1.61553002 -2.17791004 0 P 0 ;0
L 1.61553002 -2.17791004 1.61526998 -2.17696004 0 P 0 ;0
L 1.61526998 -2.17696004 1.61508996 -2.17598996 0 P 0 ;0
L 1.61508996 -2.17598996 1.61496998 -2.17496998 0 P 0 ;0
L 1.61496998 -2.17496998 1.61408002 -2.16011004 0 P 0 ;0
L 1.61408002 -2.16011004 1.61341998 -2.14758996 0 P 0 ;0
L 1.61341998 -2.14758996 1.6202 -2.14821004 0 P 0 ;0
L 1.6202 -2.14821004 1.62023002 -2.14821004 0 P 0 ;0
L 1.62023002 -2.14821004 1.63216998 -2.14893996 0 P 0 ;0
L 1.63216998 -2.14893996 1.6349 -2.14893002 0 P 0 ;0
L 1.6349 -2.14893002 1.63761998 -2.14873002 0 P 0 ;0
L 1.63761998 -2.14873002 1.64031998 -2.14835 0 P 0 ;0
L 1.64031998 -2.14835 1.64198996 -2.14798996 0 P 0 ;0
L 1.64198996 -2.14798996 1.64363002 -2.14751998 0 P 0 ;0
L 1.64363002 -2.14751998 1.64523002 -2.14693002 0 P 0 ;0
L 1.64523002 -2.14693002 1.64678996 -2.14623002 0 P 0 ;0
L 1.64678996 -2.14623002 1.64888002 -2.14506998 0 P 0 ;0
L 1.64888002 -2.14506998 1.65086998 -2.14376004 0 P 0 ;0
L 1.65086998 -2.14376004 1.65093996 -2.14371004 0 P 0 ;0
L 1.65093996 -2.14371004 1.65275 -2.14228996 0 P 0 ;0
L 1.65275 -2.14228996 1.6539 -2.14123996 0 P 0 ;0
L 1.6539 -2.14123996 1.65496004 -2.14011004 0 P 0 ;0
L 1.65496004 -2.14011004 1.65591998 -2.13891004 0 P 0 ;0
L 1.65591998 -2.13891004 1.65755 -2.13653996 0 P 0 ;0
L 1.65755 -2.13653996 1.65901998 -2.13415 0 P 0 ;0
L 1.65901998 -2.13415 1.65903002 -2.13413002 0 P 0 ;0
L 1.65903002 -2.13413002 1.66035 -2.13171998 0 P 0 ;0
L 1.66035 -2.13171998 1.66155 -2.12925 0 P 0 ;0
L 1.66155 -2.12925 1.66183996 -2.12851998 0 P 0 ;0
L 1.66183996 -2.12851998 1.66206998 -2.12776004 0 P 0 ;0
L 1.66206998 -2.12776004 1.66223996 -2.12696998 0 P 0 ;0
L 1.66223996 -2.12696998 1.66233996 -2.12618002 0 P 0 ;0
L 1.66233996 -2.12618002 1.66236998 -2.12538996 0 P 0 ;0
L 1.66236998 -2.12538996 1.66233002 -2.12436004 0 P 0 ;0
L 1.66233002 -2.12436004 1.66221004 -2.12335 0 P 0 ;0
L 1.66221004 -2.12335 1.662 -2.12235 0 P 0 ;0
L 1.662 -2.12235 1.66171004 -2.12141004 0 P 0 ;0
L 1.66171004 -2.12141004 1.64438996 -2.07113002 0 P 0 ;0
L 1.64438996 -2.07113002 1.62871998 -2.02606004 0 P 0 ;0
L 1.62871998 -2.02606004 1.62116004 -2.00558996 0 P 0 ;0
L 1.62116004 -2.00558996 1.62116004 -2.00556998 0 P 0 ;0
L 1.62116004 -2.00556998 1.61681004 -1.99443996 0 P 0 ;0
L 1.61681004 -1.99443996 1.67163002 -1.99443996 0 P 0 ;0
L 1.67163002 -1.99443996 1.67301004 -2.00076004 0 P 0 ;0
L 1.67301004 -2.00076004 1.67613002 -2.01341998 0 P 0 ;0
L 1.67613002 -2.01341998 1.68331004 -2.03931998 0 P 0 ;0
L 1.68331004 -2.03931998 1.69153002 -2.06856998 0 P 0 ;0
L 1.69153002 -2.06856998 1.6916 -2.06876004 0 P 0 ;0
L 1.6916 -2.06876004 1.69168996 -2.06896998 0 P 0 ;0
L 1.69168996 -2.06896998 1.69181004 -2.06918002 0 P 0 ;0
L 1.69181004 -2.06918002 1.69193002 -2.06936998 0 P 0 ;0
L 1.69193002 -2.06936998 1.69208002 -2.06956004 0 P 0 ;0
L 1.69208002 -2.06956004 1.69223996 -2.06973002 0 P 0 ;0
L 1.69223996 -2.06973002 1.69241998 -2.06988002 0 P 0 ;0
L 1.69241998 -2.06988002 1.6926 -2.07001998 0 P 0 ;0
L 1.6926 -2.07001998 1.6928 -2.07015 0 P 0 ;0
L 1.6928 -2.07015 1.69301004 -2.07025 0 P 0 ;0
L 1.69301004 -2.07025 1.69323002 -2.07033996 0 P 0 ;0
L 1.69323002 -2.07033996 1.69346004 -2.07041004 0 P 0 ;0
L 1.69346004 -2.07041004 1.69368002 -2.07045 0 P 0 ;0
L 1.69368002 -2.07045 1.69391998 -2.07048002 0 P 0 ;0
L 1.69391998 -2.07048002 1.69413996 -2.07048996 0 P 0 ;0
L 1.69413996 -2.07048996 1.6944 -2.07048002 0 P 0 ;0
L 1.6944 -2.07048002 1.69465 -2.07045 0 P 0 ;0
L 1.69465 -2.07045 1.69488996 -2.07038996 0 P 0 ;0
L 1.69488996 -2.07038996 1.69513996 -2.07031998 0 P 0 ;0
L 1.69513996 -2.07031998 1.69536998 -2.07021998 0 P 0 ;0
L 1.69536998 -2.07021998 1.69558996 -2.0701 0 P 0 ;0
L 1.69558996 -2.0701 1.69581004 -2.06996998 0 P 0 ;0
L 1.69581004 -2.06996998 1.69601004 -2.06981998 0 P 0 ;0
L 1.69601004 -2.06981998 1.6962 -2.06965 0 P 0 ;0
L 1.6962 -2.06965 1.69636998 -2.06946004 0 P 0 ;0
L 1.69636998 -2.06946004 1.69653002 -2.06926004 0 P 0 ;0
L 1.69653002 -2.06926004 1.69666004 -2.06905 0 P 0 ;0
L 1.69666004 -2.06905 1.69678996 -2.06883002 0 P 0 ;0
L 1.69678996 -2.06883002 1.69688002 -2.0686 0 P 0 ;0
L 1.69688002 -2.0686 1.69695 -2.0684 0 P 0 ;0
L 1.69695 -2.0684 1.70426004 -2.04365 0 P 0 ;0
L 1.70426004 -2.04365 1.70426004 -2.04363002 0 P 0 ;0
L 1.70426004 -2.04363002 1.71066998 -2.0213 0 P 0 ;0
L 1.71066998 -2.0213 1.71068002 -2.02126004 0 P 0 ;0
L 1.71068002 -2.02126004 1.71431998 -2.00693996 0 P 0 ;0
L 1.71431998 -2.00693996 1.71706004 -1.99496998 0 P 0 ;0
L 1.71706004 -1.99496998 1.74335 -1.9947 0 P 0 ;0
L 1.74335 -1.9947 1.75403002 -1.99461004 0 P 0 ;0
L 1.75403002 -1.99461004 1.76301004 -1.99465 0 P 0 ;0
L 1.76301004 -1.99465 1.76886004 -1.99471004 0 P 0 ;0
L 1.76886004 -1.99471004 1.76883996 -1.99476004 0 P 0 ;0
L 1.76883996 -1.99476004 1.74021004 -2.06556004 0 P 0 ;0
L 1.74021004 -2.06556004 1.71298002 -2.13276998 0 P 0 ;0
L 1.71298002 -2.13276998 1.70836998 -2.14293996 0 P 0 ;0
L 1.70836998 -2.14293996 1.70413996 -2.15076004 0 P 0 ;0
L 1.70413996 -2.15076004 1.69941998 -2.15828996 0 P 0 ;0
L 1.69941998 -2.15828996 1.6967 -2.16198996 0 P 0 ;0
L 1.6967 -2.16198996 1.6937 -2.16541998 0 P 0 ;0
L 1.6937 -2.16541998 1.69041998 -2.1686 0 P 0 ;0
L 1.69041998 -2.1686 1.68793996 -2.17063002 0 P 0 ;0
L 1.68793996 -2.17063002 1.68535 -2.17248002 0 P 0 ;0
L 1.68535 -2.17248002 1.68263996 -2.17413996 0 P 0 ;0
L 1.68263996 -2.17413996 1.67981004 -2.17561004 0 P 0 ;0
L 1.67981004 -2.17561004 1.67525 -2.17761004 0 P 0 ;0
L 1.67525 -2.17761004 1.6706 -2.17931998 0 P 0 ;0
L 1.6706 -2.17931998 1.66586004 -2.18073002 0 P 0 ;0
L 1.66586004 -2.18073002 1.66141998 -2.1817 0 P 0 ;0
L 1.66141998 -2.1817 1.65691998 -2.18228996 0 P 0 ;0
L 1.65691998 -2.18228996 1.64433002 -2.18295 0 P 0 ;0
L 1.61928996 -2.00628002 1.62683996 -2.02673002 0 P 0 ;0
L 1.62683996 -2.02673002 1.6425 -2.07178002 0 P 0 ;0
L 1.6425 -2.07178002 1.65981004 -2.12201998 0 P 0 ;0
L 1.65981004 -2.12201998 1.66006004 -2.12283996 0 P 0 ;0
L 1.66006004 -2.12283996 1.66023002 -2.12368002 0 P 0 ;0
L 1.66023002 -2.12368002 1.66033996 -2.12451998 0 P 0 ;0
L 1.66033996 -2.12451998 1.66036998 -2.12538002 0 P 0 ;0
L 1.66036998 -2.12538002 1.66033996 -2.12601004 0 P 0 ;0
L 1.66033996 -2.12601004 1.66026998 -2.12663996 0 P 0 ;0
L 1.66026998 -2.12663996 1.66013996 -2.12725 0 P 0 ;0
L 1.66013996 -2.12725 1.65995 -2.12786004 0 P 0 ;0
L 1.65995 -2.12786004 1.65971004 -2.12843996 0 P 0 ;0
L 1.65971004 -2.12843996 1.65856998 -2.1308 0 P 0 ;0
L 1.65856998 -2.1308 1.6573 -2.13313002 0 P 0 ;0
L 1.6573 -2.13313002 1.65586998 -2.13545 0 P 0 ;0
L 1.65586998 -2.13545 1.65431004 -2.13771998 0 P 0 ;0
L 1.65431004 -2.13771998 1.65343996 -2.1388 0 P 0 ;0
L 1.65343996 -2.1388 1.65248996 -2.13981998 0 P 0 ;0
L 1.65248996 -2.13981998 1.65146004 -2.14076004 0 P 0 ;0
L 1.65146004 -2.14076004 1.64971004 -2.14213002 0 P 0 ;0
L 1.64971004 -2.14213002 1.64785 -2.14336004 0 P 0 ;0
L 1.64785 -2.14336004 1.64588996 -2.14443996 0 P 0 ;0
L 1.64588996 -2.14443996 1.64446998 -2.14508002 0 P 0 ;0
L 1.64446998 -2.14508002 1.64301004 -2.14561998 0 P 0 ;0
L 1.64301004 -2.14561998 1.64151004 -2.14605 0 P 0 ;0
L 1.64151004 -2.14605 1.63996998 -2.14636998 0 P 0 ;0
L 1.63996998 -2.14636998 1.63741004 -2.14673996 0 P 0 ;0
L 1.63741004 -2.14673996 1.63483002 -2.14693002 0 P 0 ;0
L 1.63483002 -2.14693002 1.63223002 -2.14693996 0 P 0 ;0
L 1.63223002 -2.14693996 1.62036004 -2.14621998 0 P 0 ;0
L 1.62036004 -2.14621998 1.6113 -2.14538002 0 P 0 ;0
L 1.6113 -2.14538002 1.61208996 -2.16023002 0 P 0 ;0
L 1.61208996 -2.16023002 1.61298002 -2.17515 0 P 0 ;0
L 1.61298002 -2.17515 1.6131 -2.17628002 0 P 0 ;0
L 1.6131 -2.17628002 1.61331998 -2.17741004 0 P 0 ;0
L 1.61331998 -2.17741004 1.61361998 -2.17851004 0 P 0 ;0
L 1.61361998 -2.17851004 1.614 -2.17958996 0 P 0 ;0
L 1.614 -2.17958996 1.61413996 -2.17988996 0 P 0 ;0
L 1.61413996 -2.17988996 1.61428996 -2.18018002 0 P 0 ;0
L 1.61428996 -2.18018002 1.61446998 -2.18045 0 P 0 ;0
L 1.61446998 -2.18045 1.61466998 -2.18071004 0 P 0 ;0
L 1.61466998 -2.18071004 1.61488996 -2.18095 0 P 0 ;0
L 1.61488996 -2.18095 1.61511998 -2.18116998 0 P 0 ;0
L 1.61511998 -2.18116998 1.61538002 -2.18138002 0 P 0 ;0
L 1.61538002 -2.18138002 1.61565 -2.18156004 0 P 0 ;0
L 1.61565 -2.18156004 1.61593002 -2.18173002 0 P 0 ;0
L 1.61593002 -2.18173002 1.61623002 -2.18186004 0 P 0 ;0
L 1.61623002 -2.18186004 1.61788002 -2.1825 0 P 0 ;0
L 1.61788002 -2.1825 1.61956998 -2.18301998 0 P 0 ;0
L 1.61956998 -2.18301998 1.6213 -2.18343002 0 P 0 ;0
L 1.6213 -2.18343002 1.62633002 -2.18426004 0 P 0 ;0
L 1.62633002 -2.18426004 1.6314 -2.18471004 0 P 0 ;0
L 1.6314 -2.18471004 1.64436004 -2.18495 0 P 0 ;0
L 1.64436004 -2.18495 1.65711004 -2.18428002 0 P 0 ;0
L 1.65711004 -2.18428002 1.66176998 -2.18366998 0 P 0 ;0
L 1.66176998 -2.18366998 1.66636004 -2.18266998 0 P 0 ;0
L 1.66636004 -2.18266998 1.67123002 -2.18121004 0 P 0 ;0
L 1.67123002 -2.18121004 1.676 -2.17946998 0 P 0 ;0
L 1.676 -2.17946998 1.68068002 -2.17741998 0 P 0 ;0
L 1.68068002 -2.17741998 1.68361998 -2.17588002 0 P 0 ;0
L 1.68361998 -2.17588002 1.68646004 -2.17415 0 P 0 ;0
L 1.68646004 -2.17415 1.68916004 -2.17221998 0 P 0 ;0
L 1.68916004 -2.17221998 1.69175 -2.17008996 0 P 0 ;0
L 1.69175 -2.17008996 1.69515 -2.1668 0 P 0 ;0
L 1.69515 -2.1668 1.69826004 -2.16323996 0 P 0 ;0
L 1.69826004 -2.16323996 1.70108002 -2.15941998 0 P 0 ;0
L 1.70108002 -2.15941998 1.70586004 -2.15176998 0 P 0 ;0
L 1.70586004 -2.15176998 1.71016004 -2.14383002 0 P 0 ;0
L 1.71016004 -2.14383002 1.71481998 -2.13356004 0 P 0 ;0
L 1.71481998 -2.13356004 1.74206998 -2.06631004 0 P 0 ;0
L 1.74206998 -2.06631004 1.77071004 -1.99548002 0 P 0 ;0
L 1.77071004 -1.99548002 1.77088002 -1.99498996 0 P 0 ;0
L 1.77088002 -1.99498996 1.77101998 -1.99448996 0 P 0 ;0
L 1.77101998 -1.99448996 1.77111998 -1.99398996 0 P 0 ;0
L 1.77111998 -1.99398996 1.77118002 -1.99346998 0 P 0 ;0
L 1.77118002 -1.99346998 1.7712 -1.99295 0 P 0 ;0
L 1.7712 -1.99295 1.7712 -1.99293002 0 P 0 ;0
L 1.7712 -1.99293002 1.77118996 -1.99286998 0 P 0 ;0
L 1.77118996 -1.99286998 1.77118002 -1.99286004 0 P 0 ;0
L 1.77118002 -1.99286004 1.77118002 -1.99283996 0 P 0 ;0
L 1.77118002 -1.99283996 1.77111004 -1.99276998 0 P 0 ;0
L 1.77111004 -1.99276998 1.77106998 -1.99275 0 P 0 ;0
L 1.77106998 -1.99275 1.77106004 -1.99273996 0 P 0 ;0
L 1.77106004 -1.99273996 1.771 -1.99273002 0 P 0 ;0
L 1.771 -1.99273002 1.77098002 -1.99273002 0 P 0 ;0
L 1.77098002 -1.99273002 1.76301004 -1.99265 0 P 0 ;0
L 1.76301004 -1.99265 1.75401998 -1.99261004 0 P 0 ;0
L 1.75401998 -1.99261004 1.74333002 -1.9927 0 P 0 ;0
L 1.74333002 -1.9927 1.71546004 -1.99298996 0 P 0 ;0
L 1.71546004 -1.99298996 1.71236998 -2.00646998 0 P 0 ;0
L 1.71236998 -2.00646998 1.70873996 -2.02078002 0 P 0 ;0
L 1.70873996 -2.02078002 1.70233996 -2.04308002 0 P 0 ;0
L 1.70233996 -2.04308002 1.69505 -2.0678 0 P 0 ;0
L 1.69505 -2.0678 1.69501998 -2.06788002 0 P 0 ;0
L 1.69501998 -2.06788002 1.69498996 -2.06795 0 P 0 ;0
L 1.69498996 -2.06795 1.69495 -2.06801998 0 P 0 ;0
L 1.69495 -2.06801998 1.69485 -2.06816004 0 P 0 ;0
L 1.69485 -2.06816004 1.69478996 -2.06821998 0 P 0 ;0
L 1.69478996 -2.06821998 1.69466998 -2.06831998 0 P 0 ;0
L 1.69466998 -2.06831998 1.69453002 -2.0684 0 P 0 ;0
L 1.69453002 -2.0684 1.69445 -2.06843002 0 P 0 ;0
L 1.69445 -2.06843002 1.69438002 -2.06846004 0 P 0 ;0
L 1.69438002 -2.06846004 1.69428996 -2.06846998 0 P 0 ;0
L 1.69428996 -2.06846998 1.69421004 -2.06848996 0 P 0 ;0
L 1.69421004 -2.06848996 1.69406998 -2.06848996 0 P 0 ;0
L 1.69406998 -2.06848996 1.69395 -2.06846998 0 P 0 ;0
L 1.69395 -2.06846998 1.69383002 -2.06843002 0 P 0 ;0
L 1.69383002 -2.06843002 1.69373002 -2.06836998 0 P 0 ;0
L 1.69373002 -2.06836998 1.69363002 -2.06828996 0 P 0 ;0
L 1.69363002 -2.06828996 1.69358996 -2.06823996 0 P 0 ;0
L 1.69358996 -2.06823996 1.69355 -2.0682 0 P 0 ;0
L 1.69355 -2.0682 1.69351998 -2.06815 0 P 0 ;0
L 1.69351998 -2.06815 1.69346004 -2.06803996 0 P 0 ;0
L 1.69346004 -2.06803996 1.69343996 -2.06798002 0 P 0 ;0
L 1.69343996 -2.06798002 1.68523002 -2.03878002 0 P 0 ;0
L 1.68523002 -2.03878002 1.67806998 -2.01291998 0 P 0 ;0
L 1.67806998 -2.01291998 1.67496004 -2.00031004 0 P 0 ;0
L 1.67496004 -2.00031004 1.67323002 -1.99243996 0 P 0 ;0
L 1.67323002 -1.99243996 1.61388002 -1.99243996 0 P 0 ;0
L 1.61388002 -1.99243996 1.61928996 -2.00628002 0 P 0 ;0
L 1.35018002 -2.08345 1.39488996 -2.08345 0 P 0 ;0
L 1.35026004 -2.08245 1.39586004 -2.08245 0 P 0 ;0
L 1.35041004 -2.08145 1.39708996 -2.08145 0 P 0 ;0
L 1.35058996 -2.08045 1.39853002 -2.08045 0 P 0 ;0
L 1.35083996 -2.07945 1.40031998 -2.07945 0 P 0 ;0
L 1.35116998 -2.07845 1.40271004 -2.07845 0 P 0 ;0
L 1.35158002 -2.07745 1.40561998 -2.07745 0 P 0 ;0
L 1.35203002 -2.07645 1.4092 -2.07645 0 P 0 ;0
L 1.35248002 -2.07545 1.41288996 -2.07545 0 P 0 ;0
L 1.35293002 -2.07445 1.4164 -2.07445 0 P 0 ;0
L 1.35338996 -2.07345 1.41975 -2.07345 0 P 0 ;0
L 1.35393996 -2.07245 1.42293996 -2.07245 0 P 0 ;0
L 1.35448996 -2.07145 1.42606998 -2.07145 0 P 0 ;0
L 1.35505 -2.07045 1.47843002 -2.07045 0 P 0 ;0
L 1.3557 -2.06945 1.47846998 -2.06945 0 P 0 ;0
L 1.35635 -2.06845 1.47851998 -2.06845 0 P 0 ;0
L 1.35701998 -2.06745 1.47856998 -2.06745 0 P 0 ;0
L 1.35776998 -2.06645 1.47861004 -2.06645 0 P 0 ;0
L 1.29346998 -2.00516004 1.33388996 -2.00516004 0 P 0 ;0
L 1.29448996 -2.00416004 1.33385 -2.00416004 0 P 0 ;0
L 1.29551004 -2.00316004 1.33381004 -2.00316004 0 P 0 ;0
L 1.29653996 -2.00216004 1.33376004 -2.00216004 0 P 0 ;0
L 1.29756004 -2.00116004 1.33371004 -2.00116004 0 P 0 ;0
L 1.29861998 -2.00016004 1.33366004 -2.00016004 0 P 0 ;0
L 1.29973002 -1.99916004 1.3336 -1.99916004 0 P 0 ;0
L 1.30101004 -1.99816004 1.33355 -1.99816004 0 P 0 ;0
L 1.30238996 -1.99716004 1.3335 -1.99716004 0 P 0 ;0
L 1.30393996 -1.99616004 1.33345 -1.99616004 0 P 0 ;0
L 1.30571004 -1.99516004 1.33338996 -1.99516004 0 P 0 ;0
L 1.3077 -1.99416004 1.33333002 -1.99416004 0 P 0 ;0
L 1.31001004 -1.99316004 1.33328002 -1.99316004 0 P 0 ;0
L 1.31288002 -1.99216004 1.33321998 -1.99216004 0 P 0 ;0
L 1.31688996 -1.99116004 1.33316004 -1.99116004 0 P 0 ;0
L 1.39798996 -1.98971998 1.39326998 -1.99043002 0 P 0 ;0
L 1.39326998 -1.99043002 1.38806998 -1.9913 0 P 0 ;0
L 1.38806998 -1.9913 1.38316004 -1.9922 0 P 0 ;0
L 1.38316004 -1.9922 1.37946004 -1.99296998 0 P 0 ;0
L 1.37946004 -1.99296998 1.3718 -1.99466998 0 P 0 ;0
L 1.3718 -1.99466998 1.36896004 -2.01553996 0 P 0 ;0
L 1.36896004 -2.01553996 1.36791004 -2.02358996 0 P 0 ;0
L 1.36791004 -2.02358996 1.36708002 -2.03043002 0 P 0 ;0
L 1.36708002 -2.03043002 1.36638996 -2.03646004 0 P 0 ;0
L 1.36638996 -2.03646004 1.36638002 -2.03648996 0 P 0 ;0
L 1.36638002 -2.03648996 1.36638996 -2.03653002 0 P 0 ;0
L 1.36638996 -2.03653002 1.36638996 -2.03656998 0 P 0 ;0
L 1.36638996 -2.03656998 1.3664 -2.03663996 0 P 0 ;0
L 1.3664 -2.03663996 1.36641998 -2.03666998 0 P 0 ;0
L 1.36641998 -2.03666998 1.36643002 -2.03671004 0 P 0 ;0
L 1.36643002 -2.03671004 1.36648996 -2.0368 0 P 0 ;0
L 1.36648996 -2.0368 1.36656004 -2.03686004 0 P 0 ;0
L 1.36656004 -2.03686004 1.3666 -2.03688996 0 P 0 ;0
L 1.3666 -2.03688996 1.36663002 -2.03691004 0 P 0 ;0
L 1.36663002 -2.03691004 1.36666004 -2.03691004 0 P 0 ;0
L 1.36666004 -2.03691004 1.36671004 -2.03693002 0 P 0 ;0
L 1.36671004 -2.03693002 1.36676998 -2.03693002 0 P 0 ;0
L 1.36676998 -2.03693002 1.36685 -2.03691998 0 P 0 ;0
L 1.36685 -2.03691998 1.36895 -2.03628002 0 P 0 ;0
L 1.36895 -2.03628002 1.37143002 -2.03545 0 P 0 ;0
L 1.37143002 -2.03545 1.37428996 -2.03441004 0 P 0 ;0
L 1.37428996 -2.03441004 1.38346004 -2.03126998 0 P 0 ;0
L 1.38346004 -2.03126998 1.39251998 -2.02891998 0 P 0 ;0
L 1.39251998 -2.02891998 1.40156004 -2.02731998 0 P 0 ;0
L 1.40156004 -2.02731998 1.41068002 -2.02643996 0 P 0 ;0
L 1.41068002 -2.02643996 1.41566998 -2.02628002 0 P 0 ;0
L 1.41566998 -2.02628002 1.42066004 -2.02633996 0 P 0 ;0
L 1.42066004 -2.02633996 1.42221004 -2.02646998 0 P 0 ;0
L 1.42221004 -2.02646998 1.42375 -2.02671998 0 P 0 ;0
L 1.42375 -2.02671998 1.42525 -2.0271 0 P 0 ;0
L 1.42525 -2.0271 1.42671998 -2.02761004 0 P 0 ;0
L 1.42671998 -2.02761004 1.42706004 -2.02776004 0 P 0 ;0
L 1.42706004 -2.02776004 1.42738002 -2.02793002 0 P 0 ;0
L 1.42738002 -2.02793002 1.42768002 -2.02813996 0 P 0 ;0
L 1.42768002 -2.02813996 1.42796998 -2.02836004 0 P 0 ;0
L 1.42796998 -2.02836004 1.42823002 -2.02861004 0 P 0 ;0
L 1.42823002 -2.02861004 1.42848002 -2.02888996 0 P 0 ;0
L 1.42848002 -2.02888996 1.4287 -2.02918002 0 P 0 ;0
L 1.4287 -2.02918002 1.42888996 -2.02948996 0 P 0 ;0
L 1.42888996 -2.02948996 1.42906004 -2.02981004 0 P 0 ;0
L 1.42906004 -2.02981004 1.4292 -2.03015 0 P 0 ;0
L 1.4292 -2.03015 1.42931998 -2.0305 0 P 0 ;0
L 1.42931998 -2.0305 1.4294 -2.03086004 0 P 0 ;0
L 1.4294 -2.03086004 1.42945 -2.03121998 0 P 0 ;0
L 1.42945 -2.03121998 1.42946998 -2.03158002 0 P 0 ;0
L 1.42946998 -2.03158002 1.42946004 -2.03195 0 P 0 ;0
L 1.42946004 -2.03195 1.42941998 -2.03231004 0 P 0 ;0
L 1.42941998 -2.03231004 1.42935 -2.03266998 0 P 0 ;0
L 1.42935 -2.03266998 1.42925 -2.03301998 0 P 0 ;0
L 1.42925 -2.03301998 1.42911998 -2.03336004 0 P 0 ;0
L 1.42911998 -2.03336004 1.42896004 -2.03368996 0 P 0 ;0
L 1.42896004 -2.03368996 1.42875 -2.03405 0 P 0 ;0
L 1.42875 -2.03405 1.42851004 -2.03438996 0 P 0 ;0
L 1.42851004 -2.03438996 1.42825 -2.03471004 0 P 0 ;0
L 1.42825 -2.03471004 1.42796004 -2.03501004 0 P 0 ;0
L 1.42796004 -2.03501004 1.42765 -2.03528996 0 P 0 ;0
L 1.42765 -2.03528996 1.42731998 -2.03553996 0 P 0 ;0
L 1.42731998 -2.03553996 1.42696998 -2.03576004 0 P 0 ;0
L 1.42696998 -2.03576004 1.4266 -2.03596004 0 P 0 ;0
L 1.4266 -2.03596004 1.41951004 -2.03906004 0 P 0 ;0
L 1.41951004 -2.03906004 1.4109 -2.04208996 0 P 0 ;0
L 1.4109 -2.04208996 1.40178002 -2.04451998 0 P 0 ;0
L 1.40178002 -2.04451998 1.3878 -2.04818996 0 P 0 ;0
L 1.3878 -2.04818996 1.38176998 -2.05015 0 P 0 ;0
L 1.38176998 -2.05015 1.3758 -2.05243002 0 P 0 ;0
L 1.3758 -2.05243002 1.37086998 -2.0546 0 P 0 ;0
L 1.37086998 -2.0546 1.36603996 -2.05708002 0 P 0 ;0
L 1.36603996 -2.05708002 1.36356004 -2.05856004 0 P 0 ;0
L 1.36356004 -2.05856004 1.36118996 -2.06023002 0 P 0 ;0
L 1.36118996 -2.06023002 1.35895 -2.06206004 0 P 0 ;0
L 1.35895 -2.06206004 1.35805 -2.06291004 0 P 0 ;0
L 1.35805 -2.06291004 1.35721998 -2.06385 0 P 0 ;0
L 1.35721998 -2.06385 1.35518996 -2.06655 0 P 0 ;0
L 1.35518996 -2.06655 1.3532 -2.06961998 0 P 0 ;0
L 1.3532 -2.06961998 1.35156004 -2.07263002 0 P 0 ;0
L 1.35156004 -2.07263002 1.34951004 -2.07718002 0 P 0 ;0
L 1.34951004 -2.07718002 1.34911004 -2.07825 0 P 0 ;0
L 1.34911004 -2.07825 1.34878996 -2.07935 0 P 0 ;0
L 1.34878996 -2.07935 1.34853002 -2.08046998 0 P 0 ;0
L 1.34853002 -2.08046998 1.34825 -2.08238002 0 P 0 ;0
L 1.34825 -2.08238002 1.34811998 -2.08431004 0 P 0 ;0
L 1.34811998 -2.08431004 1.348 -2.09128996 0 P 0 ;0
L 1.348 -2.09128996 1.3481 -2.09761004 0 P 0 ;0
L 1.3481 -2.09761004 1.34823002 -2.09961004 0 P 0 ;0
L 1.34823002 -2.09961004 1.34846998 -2.10161004 0 P 0 ;0
L 1.34846998 -2.10161004 1.34876998 -2.10321998 0 P 0 ;0
L 1.34876998 -2.10321998 1.3492 -2.10478996 0 P 0 ;0
L 1.3492 -2.10478996 1.3498 -2.10648996 0 P 0 ;0
L 1.3498 -2.10648996 1.3505 -2.10815 0 P 0 ;0
L 1.3505 -2.10815 1.35178996 -2.11066004 0 P 0 ;0
L 1.35178996 -2.11066004 1.35328002 -2.11305 0 P 0 ;0
L 1.35328002 -2.11305 1.35496998 -2.1153 0 P 0 ;0
L 1.35496998 -2.1153 1.35685 -2.1174 0 P 0 ;0
L 1.35685 -2.1174 1.35891998 -2.11933996 0 P 0 ;0
L 1.35891998 -2.11933996 1.36126998 -2.12121998 0 P 0 ;0
L 1.36126998 -2.12121998 1.36373996 -2.12293002 0 P 0 ;0
L 1.36373996 -2.12293002 1.36633002 -2.12446004 0 P 0 ;0
L 1.36633002 -2.12446004 1.36901004 -2.1258 0 P 0 ;0
L 1.36901004 -2.1258 1.3718 -2.12695 0 P 0 ;0
L 1.3718 -2.12695 1.37578996 -2.12828002 0 P 0 ;0
L 1.37578996 -2.12828002 1.37986998 -2.12928996 0 P 0 ;0
L 1.37986998 -2.12928996 1.38401998 -2.12998996 0 P 0 ;0
L 1.38401998 -2.12998996 1.3882 -2.13036004 0 P 0 ;0
L 1.3882 -2.13036004 1.39443002 -2.13045 0 P 0 ;0
L 1.39443002 -2.13045 1.40066004 -2.13006998 0 P 0 ;0
L 1.40066004 -2.13006998 1.40685 -2.12923002 0 P 0 ;0
L 1.40685 -2.12923002 1.41371004 -2.12801998 0 P 0 ;0
L 1.41371004 -2.12801998 1.41583002 -2.12081004 0 P 0 ;0
L 1.41583002 -2.12081004 1.41953996 -2.10798996 0 P 0 ;0
L 1.41953996 -2.10798996 1.42135 -2.10126998 0 P 0 ;0
L 1.42135 -2.10126998 1.42236998 -2.097 0 P 0 ;0
L 1.42236998 -2.097 1.42238996 -2.09691004 0 P 0 ;0
L 1.42238996 -2.09691004 1.4224 -2.09681998 0 P 0 ;0
L 1.4224 -2.09681998 1.4224 -2.09673996 0 P 0 ;0
L 1.4224 -2.09673996 1.42238002 -2.09656004 0 P 0 ;0
L 1.42238002 -2.09656004 1.42235 -2.09648002 0 P 0 ;0
L 1.42235 -2.09648002 1.42233002 -2.09638996 0 P 0 ;0
L 1.42233002 -2.09638996 1.42225 -2.09623002 0 P 0 ;0
L 1.42225 -2.09623002 1.4222 -2.09616004 0 P 0 ;0
L 1.4222 -2.09616004 1.42213996 -2.09608996 0 P 0 ;0
L 1.42213996 -2.09608996 1.42208996 -2.09601998 0 P 0 ;0
L 1.42208996 -2.09601998 1.42203996 -2.09598996 0 P 0 ;0
L 1.42203996 -2.09598996 1.42198996 -2.09595 0 P 0 ;0
L 1.42198996 -2.09595 1.42188996 -2.09588996 0 P 0 ;0
L 1.42188996 -2.09588996 1.42183002 -2.09586004 0 P 0 ;0
L 1.42183002 -2.09586004 1.42178002 -2.09585 0 P 0 ;0
L 1.42178002 -2.09585 1.42171998 -2.09583002 0 P 0 ;0
L 1.42171998 -2.09583002 1.42166004 -2.09581998 0 P 0 ;0
L 1.42166004 -2.09581998 1.42153996 -2.09581998 0 P 0 ;0
L 1.42153996 -2.09581998 1.41978002 -2.09591004 0 P 0 ;0
L 1.41978002 -2.09591004 1.41763996 -2.09615 0 P 0 ;0
L 1.41763996 -2.09615 1.41521998 -2.09658002 0 P 0 ;0
L 1.41521998 -2.09658002 1.4107 -2.09733002 0 P 0 ;0
L 1.4107 -2.09733002 1.40613002 -2.09775 0 P 0 ;0
L 1.40613002 -2.09775 1.40481004 -2.09778002 0 P 0 ;0
L 1.40481004 -2.09778002 1.40348996 -2.09771998 0 P 0 ;0
L 1.40348996 -2.09771998 1.40216998 -2.09756004 0 P 0 ;0
L 1.40216998 -2.09756004 1.40086998 -2.0973 0 P 0 ;0
L 1.40086998 -2.0973 1.39958996 -2.09695 0 P 0 ;0
L 1.39958996 -2.09695 1.39895 -2.09671998 0 P 0 ;0
L 1.39895 -2.09671998 1.39831998 -2.09643002 0 P 0 ;0
L 1.39831998 -2.09643002 1.39773002 -2.0961 0 P 0 ;0
L 1.39773002 -2.0961 1.39716004 -2.09571004 0 P 0 ;0
L 1.39716004 -2.09571004 1.39663002 -2.09528002 0 P 0 ;0
L 1.39663002 -2.09528002 1.39613996 -2.0948 0 P 0 ;0
L 1.39613996 -2.0948 1.39568002 -2.09428002 0 P 0 ;0
L 1.39568002 -2.09428002 1.39533996 -2.09381998 0 P 0 ;0
L 1.39533996 -2.09381998 1.39505 -2.09333996 0 P 0 ;0
L 1.39505 -2.09333996 1.39478996 -2.09281998 0 P 0 ;0
L 1.39478996 -2.09281998 1.39456998 -2.09228996 0 P 0 ;0
L 1.39456998 -2.09228996 1.3944 -2.09173996 0 P 0 ;0
L 1.3944 -2.09173996 1.39428002 -2.09118996 0 P 0 ;0
L 1.39428002 -2.09118996 1.39421004 -2.09061998 0 P 0 ;0
L 1.39421004 -2.09061998 1.39418002 -2.09003996 0 P 0 ;0
L 1.39418002 -2.09003996 1.39421004 -2.08943002 0 P 0 ;0
L 1.39421004 -2.08943002 1.39428002 -2.08883002 0 P 0 ;0
L 1.39428002 -2.08883002 1.39441004 -2.08823002 0 P 0 ;0
L 1.39441004 -2.08823002 1.3946 -2.08765 0 P 0 ;0
L 1.3946 -2.08765 1.39483002 -2.08708002 0 P 0 ;0
L 1.39483002 -2.08708002 1.39511004 -2.08653996 0 P 0 ;0
L 1.39511004 -2.08653996 1.39555 -2.08583996 0 P 0 ;0
L 1.39555 -2.08583996 1.39603996 -2.08518002 0 P 0 ;0
L 1.39603996 -2.08518002 1.39658002 -2.08456004 0 P 0 ;0
L 1.39658002 -2.08456004 1.39716004 -2.08396998 0 P 0 ;0
L 1.39716004 -2.08396998 1.39778002 -2.08343002 0 P 0 ;0
L 1.39778002 -2.08343002 1.39878996 -2.08266998 0 P 0 ;0
L 1.39878996 -2.08266998 1.39985 -2.08196998 0 P 0 ;0
L 1.39985 -2.08196998 1.40096004 -2.08135 0 P 0 ;0
L 1.40096004 -2.08135 1.40211998 -2.08081004 0 P 0 ;0
L 1.40211998 -2.08081004 1.40503002 -2.07971004 0 P 0 ;0
L 1.40503002 -2.07971004 1.40801998 -2.07881998 0 P 0 ;0
L 1.40801998 -2.07881998 1.41128996 -2.07796004 0 P 0 ;0
L 1.41128996 -2.07796004 1.41506004 -2.07691998 0 P 0 ;0
L 1.41506004 -2.07691998 1.41871998 -2.07585 0 P 0 ;0
L 1.41871998 -2.07585 1.42165 -2.07495 0 P 0 ;0
L 1.42165 -2.07495 1.42791998 -2.07295 0 P 0 ;0
L 1.42791998 -2.07295 1.42731998 -2.08241004 0 P 0 ;0
L 1.42731998 -2.08241004 1.42701004 -2.08708002 0 P 0 ;0
L 1.42701004 -2.08708002 1.42658002 -2.09353996 0 P 0 ;0
L 1.42658002 -2.09353996 1.4261 -2.10055 0 P 0 ;0
L 1.4261 -2.10055 1.42566998 -2.10706004 0 P 0 ;0
L 1.42566998 -2.10706004 1.42525 -2.11306004 0 P 0 ;0
L 1.42525 -2.11306004 1.42491998 -2.11851998 0 P 0 ;0
L 1.42491998 -2.11851998 1.42466004 -2.1231 0 P 0 ;0
L 1.42466004 -2.1231 1.42461004 -2.12471004 0 P 0 ;0
L 1.42461004 -2.12471004 1.4246 -2.12716004 0 P 0 ;0
L 1.4246 -2.12716004 1.47893002 -2.12716004 0 P 0 ;0
L 1.47893002 -2.12716004 1.47893002 -2.11358002 0 P 0 ;0
L 1.47893002 -2.11358002 1.47905 -2.10616998 0 P 0 ;0
L 1.47905 -2.10616998 1.47943996 -2.09385 0 P 0 ;0
L 1.47943996 -2.09385 1.48 -2.07968996 0 P 0 ;0
L 1.48 -2.07968996 1.48066004 -2.0655 0 P 0 ;0
L 1.48066004 -2.0655 1.4813 -2.05168996 0 P 0 ;0
L 1.4813 -2.05168996 1.48175 -2.03873996 0 P 0 ;0
L 1.48175 -2.03873996 1.48201998 -2.02785 0 P 0 ;0
L 1.48201998 -2.02785 1.48191998 -2.02286004 0 P 0 ;0
L 1.48191998 -2.02286004 1.48165 -2.01995 0 P 0 ;0
L 1.48165 -2.01995 1.48115 -2.01708002 0 P 0 ;0
L 1.48115 -2.01708002 1.48043996 -2.01425 0 P 0 ;0
L 1.48043996 -2.01425 1.47951004 -2.01146998 0 P 0 ;0
L 1.47951004 -2.01146998 1.47866998 -2.00946998 0 P 0 ;0
L 1.47866998 -2.00946998 1.47768002 -2.00753996 0 P 0 ;0
L 1.47768002 -2.00753996 1.47655 -2.00568002 0 P 0 ;0
L 1.47655 -2.00568002 1.47528002 -2.00391998 0 P 0 ;0
L 1.47528002 -2.00391998 1.47388002 -2.00225 0 P 0 ;0
L 1.47388002 -2.00225 1.47228996 -2.00063002 0 P 0 ;0
L 1.47228996 -2.00063002 1.4706 -1.99911998 0 P 0 ;0
L 1.4706 -1.99911998 1.4688 -1.99773002 0 P 0 ;0
L 1.4688 -1.99773002 1.46691004 -1.99648002 0 P 0 ;0
L 1.46691004 -1.99648002 1.46491998 -1.99535 0 P 0 ;0
L 1.46491998 -1.99535 1.46098996 -1.99351004 0 P 0 ;0
L 1.46098996 -1.99351004 1.45693002 -1.99196998 0 P 0 ;0
L 1.45693002 -1.99196998 1.45276004 -1.99076004 0 P 0 ;0
L 1.45276004 -1.99076004 1.44953996 -1.99006004 0 P 0 ;0
L 1.44953996 -1.99006004 1.44628996 -1.98956004 0 P 0 ;0
L 1.44628996 -1.98956004 1.44298002 -1.98923996 0 P 0 ;0
L 1.44298002 -1.98923996 1.42695 -1.98856998 0 P 0 ;0
L 1.42695 -1.98856998 1.41038996 -1.98865 0 P 0 ;0
L 1.41038996 -1.98865 1.4042 -1.98901004 0 P 0 ;0
L 1.4042 -1.98901004 1.39798996 -1.98971998 0 P 0 ;0
L 1.35778996 -2.11545 1.4153 -2.11545 0 P 0 ;0
L 1.35688996 -2.11445 1.41558996 -2.11445 0 P 0 ;0
L 1.35608002 -2.11345 1.41588002 -2.11345 0 P 0 ;0
L 1.35533002 -2.11245 1.41616998 -2.11245 0 P 0 ;0
L 1.35463996 -2.11145 1.41646004 -2.11145 0 P 0 ;0
L 1.35401004 -2.11045 1.41675 -2.11045 0 P 0 ;0
L 1.35341004 -2.10945 1.41703996 -2.10945 0 P 0 ;0
L 1.3529 -2.10845 1.41733002 -2.10845 0 P 0 ;0
L 1.35238002 -2.10745 1.41761998 -2.10745 0 P 0 ;0
L 1.35195 -2.10645 1.41788002 -2.10645 0 P 0 ;0
L 1.35155 -2.10545 1.41816004 -2.10545 0 P 0 ;0
L 1.3512 -2.10445 1.41841998 -2.10445 0 P 0 ;0
L 1.35091004 -2.10345 1.41868996 -2.10345 0 P 0 ;0
L 1.35066004 -2.10245 1.41896004 -2.10245 0 P 0 ;0
L 1.35046998 -2.10145 1.41923002 -2.10145 0 P 0 ;0
L 1.35033996 -2.10045 1.41948996 -2.10045 0 P 0 ;0
L 1.35021998 -2.09945 1.40141004 -2.09945 0 P 0 ;0
L 1.35016004 -2.09845 1.39791004 -2.09845 0 P 0 ;0
L 1.3501 -2.09745 1.39616004 -2.09745 0 P 0 ;0
L 1.35008002 -2.09645 1.39496004 -2.09645 0 P 0 ;0
L 1.35006998 -2.09545 1.39406004 -2.09545 0 P 0 ;0
L 1.35005 -2.09445 1.39338002 -2.09445 0 P 0 ;0
L 1.35003996 -2.09345 1.39288002 -2.09345 0 P 0 ;0
L 1.35001998 -2.09245 1.39253002 -2.09245 0 P 0 ;0
L 1.35001004 -2.09145 1.3923 -2.09145 0 P 0 ;0
L 1.35001998 -2.09045 1.3922 -2.09045 0 P 0 ;0
L 1.35003002 -2.08945 1.3922 -2.08945 0 P 0 ;0
L 1.35005 -2.08845 1.39231998 -2.08845 0 P 0 ;0
L 1.35006998 -2.08745 1.39256004 -2.08745 0 P 0 ;0
L 1.35008002 -2.08645 1.39293002 -2.08645 0 P 0 ;0
L 1.3501 -2.08545 1.39343002 -2.08545 0 P 0 ;0
L 1.35011004 -2.08445 1.39408996 -2.08445 0 P 0 ;0
L 1.39438002 -2.12845 1.3883 -2.12836004 0 P 0 ;0
L 1.3883 -2.12836004 1.38426998 -2.128 0 P 0 ;0
L 1.38426998 -2.128 1.38028002 -2.12733002 0 P 0 ;0
L 1.38028002 -2.12733002 1.37635 -2.12636004 0 P 0 ;0
L 1.37635 -2.12636004 1.37248996 -2.12508002 0 P 0 ;0
L 1.37248996 -2.12508002 1.36983996 -2.12398002 0 P 0 ;0
L 1.36983996 -2.12398002 1.36728996 -2.1227 0 P 0 ;0
L 1.36728996 -2.1227 1.36481998 -2.12123996 0 P 0 ;0
L 1.36481998 -2.12123996 1.36246004 -2.11961004 0 P 0 ;0
L 1.36246004 -2.11961004 1.36023002 -2.11781998 0 P 0 ;0
L 1.36023002 -2.11781998 1.35828996 -2.116 0 P 0 ;0
L 1.35828996 -2.116 1.35651998 -2.11403002 0 P 0 ;0
L 1.35651998 -2.11403002 1.35493002 -2.11191004 0 P 0 ;0
L 1.35493002 -2.11191004 1.35353002 -2.10966998 0 P 0 ;0
L 1.35353002 -2.10966998 1.35231004 -2.10731004 0 P 0 ;0
L 1.35231004 -2.10731004 1.35166998 -2.10576998 0 P 0 ;0
L 1.35166998 -2.10576998 1.35111004 -2.1042 0 P 0 ;0
L 1.35111004 -2.1042 1.35071998 -2.10276004 0 P 0 ;0
L 1.35071998 -2.10276004 1.35045 -2.1013 0 P 0 ;0
L 1.35045 -2.1013 1.35021998 -2.09943002 0 P 0 ;0
L 1.35021998 -2.09943002 1.3501 -2.09753002 0 P 0 ;0
L 1.3501 -2.09753002 1.35001004 -2.09128002 0 P 0 ;0
L 1.35001004 -2.09128002 1.35011998 -2.0844 0 P 0 ;0
L 1.35011998 -2.0844 1.35023996 -2.08258996 0 P 0 ;0
L 1.35023996 -2.08258996 1.3505 -2.08083996 0 P 0 ;0
L 1.3505 -2.08083996 1.35071998 -2.07985 0 P 0 ;0
L 1.35071998 -2.07985 1.35101004 -2.07888002 0 P 0 ;0
L 1.35101004 -2.07888002 1.35136004 -2.07793002 0 P 0 ;0
L 1.35136004 -2.07793002 1.35335 -2.07351998 0 P 0 ;0
L 1.35335 -2.07351998 1.35491998 -2.07065 0 P 0 ;0
L 1.35491998 -2.07065 1.35683002 -2.0677 0 P 0 ;0
L 1.35683002 -2.0677 1.35876998 -2.06511004 0 P 0 ;0
L 1.35876998 -2.06511004 1.35948996 -2.0643 0 P 0 ;0
L 1.35948996 -2.0643 1.36026998 -2.06356004 0 P 0 ;0
L 1.36026998 -2.06356004 1.3624 -2.06181998 0 P 0 ;0
L 1.3624 -2.06181998 1.36465 -2.06023996 0 P 0 ;0
L 1.36465 -2.06023996 1.36701004 -2.05883002 0 P 0 ;0
L 1.36701004 -2.05883002 1.37173002 -2.05641004 0 P 0 ;0
L 1.37173002 -2.05641004 1.37656004 -2.05426998 0 P 0 ;0
L 1.37656004 -2.05426998 1.38243002 -2.05203996 0 P 0 ;0
L 1.38243002 -2.05203996 1.38836004 -2.0501 0 P 0 ;0
L 1.38836004 -2.0501 1.4023 -2.04645 0 P 0 ;0
L 1.4023 -2.04645 1.41148996 -2.044 0 P 0 ;0
L 1.41148996 -2.044 1.42016998 -2.04095 0 P 0 ;0
L 1.42016998 -2.04095 1.42016998 -2.04093996 0 P 0 ;0
L 1.42016998 -2.04093996 1.42021004 -2.04093996 0 P 0 ;0
L 1.42021004 -2.04093996 1.42023996 -2.04093002 0 P 0 ;0
L 1.42023996 -2.04093002 1.42746998 -2.03776004 0 P 0 ;0
L 1.42746998 -2.03776004 1.42753002 -2.03773002 0 P 0 ;0
L 1.42753002 -2.03773002 1.42796998 -2.03748996 0 P 0 ;0
L 1.42796998 -2.03748996 1.42846004 -2.03718996 0 P 0 ;0
L 1.42846004 -2.03718996 1.42891998 -2.03683996 0 P 0 ;0
L 1.42891998 -2.03683996 1.42935 -2.03646004 0 P 0 ;0
L 1.42935 -2.03646004 1.42975 -2.03603996 0 P 0 ;0
L 1.42975 -2.03603996 1.43011004 -2.0356 0 P 0 ;0
L 1.43011004 -2.0356 1.43016004 -2.03553002 0 P 0 ;0
L 1.43016004 -2.03553002 1.4299 -2.03535 0 P 0 ;0
L 1.4299 -2.03535 1.43028002 -2.03535 0 P 0 ;0
L 1.43028002 -2.03535 1.43043996 -2.03513002 0 P 0 ;0
L 1.43043996 -2.03513002 1.43048002 -2.03506004 0 P 0 ;0
L 1.43048002 -2.03506004 1.43041998 -2.03501998 0 P 0 ;0
L 1.43041998 -2.03501998 1.4305 -2.03501998 0 P 0 ;0
L 1.4305 -2.03501998 1.43073002 -2.03463002 0 P 0 ;0
L 1.43073002 -2.03463002 1.43096004 -2.03415 0 P 0 ;0
L 1.43096004 -2.03415 1.43115 -2.03365 0 P 0 ;0
L 1.43115 -2.03365 1.4313 -2.03313002 0 P 0 ;0
L 1.4313 -2.03313002 1.4314 -2.03261004 0 P 0 ;0
L 1.4314 -2.03261004 1.43146004 -2.03208002 0 P 0 ;0
L 1.43146004 -2.03208002 1.43146998 -2.03155 0 P 0 ;0
L 1.43146998 -2.03155 1.43143996 -2.03101004 0 P 0 ;0
L 1.43143996 -2.03101004 1.43143002 -2.03093002 0 P 0 ;0
L 1.43143002 -2.03093002 1.43136004 -2.03048996 0 P 0 ;0
L 1.43136004 -2.03048996 1.43125 -2.02996998 0 P 0 ;0
L 1.43125 -2.02996998 1.43108002 -2.02946004 0 P 0 ;0
L 1.43108002 -2.02946004 1.43086998 -2.02896004 0 P 0 ;0
L 1.43086998 -2.02896004 1.43063002 -2.02848996 0 P 0 ;0
L 1.43063002 -2.02848996 1.43033996 -2.02803996 0 P 0 ;0
L 1.43033996 -2.02803996 1.43001998 -2.02761004 0 P 0 ;0
L 1.43001998 -2.02761004 1.42966004 -2.02721004 0 P 0 ;0
L 1.42966004 -2.02721004 1.42928002 -2.02685 0 P 0 ;0
L 1.42928002 -2.02685 1.42886004 -2.02651998 0 P 0 ;0
L 1.42886004 -2.02651998 1.42841998 -2.02623002 0 P 0 ;0
L 1.42841998 -2.02623002 1.42795 -2.02596998 0 P 0 ;0
L 1.42795 -2.02596998 1.42746004 -2.02575 0 P 0 ;0
L 1.42746004 -2.02575 1.42583002 -2.02518002 0 P 0 ;0
L 1.42583002 -2.02518002 1.42416004 -2.02476004 0 P 0 ;0
L 1.42416004 -2.02476004 1.42245 -2.02448002 0 P 0 ;0
L 1.42245 -2.02448002 1.42075 -2.02435 0 P 0 ;0
L 1.42075 -2.02435 1.41565 -2.02428002 0 P 0 ;0
L 1.41565 -2.02428002 1.4156 -2.02428002 0 P 0 ;0
L 1.4156 -2.02428002 1.41055 -2.02445 0 P 0 ;0
L 1.41055 -2.02445 1.41048002 -2.02445 0 P 0 ;0
L 1.41048002 -2.02445 1.40128996 -2.02533996 0 P 0 ;0
L 1.40128996 -2.02533996 1.39208996 -2.02696998 0 P 0 ;0
L 1.39208996 -2.02696998 1.38288002 -2.02936004 0 P 0 ;0
L 1.38288002 -2.02936004 1.37363002 -2.03251998 0 P 0 ;0
L 1.37363002 -2.03251998 1.37076998 -2.03356004 0 P 0 ;0
L 1.37076998 -2.03356004 1.36865 -2.03426998 0 P 0 ;0
L 1.36865 -2.03426998 1.36906004 -2.03066998 0 P 0 ;0
L 1.36906004 -2.03066998 1.36988996 -2.02383996 0 P 0 ;0
L 1.36988996 -2.02383996 1.37095 -2.01581004 0 P 0 ;0
L 1.37095 -2.01581004 1.37358996 -1.99631998 0 P 0 ;0
L 1.37358996 -1.99631998 1.37988002 -1.99491998 0 P 0 ;0
L 1.37988002 -1.99491998 1.38353996 -1.99416998 0 P 0 ;0
L 1.38353996 -1.99416998 1.38841998 -1.99326998 0 P 0 ;0
L 1.38841998 -1.99326998 1.39358002 -1.9924 0 P 0 ;0
L 1.39358002 -1.9924 1.39825 -1.9917 0 P 0 ;0
L 1.39825 -1.9917 1.40436998 -1.991 0 P 0 ;0
L 1.40436998 -1.991 1.41045 -1.99065 0 P 0 ;0
L 1.41045 -1.99065 1.42691004 -1.99056998 0 P 0 ;0
L 1.42691004 -1.99056998 1.44283996 -1.99123996 0 P 0 ;0
L 1.44283996 -1.99123996 1.44603996 -1.99153996 0 P 0 ;0
L 1.44603996 -1.99153996 1.44918002 -1.99203002 0 P 0 ;0
L 1.44918002 -1.99203002 1.45226004 -1.9927 0 P 0 ;0
L 1.45226004 -1.9927 1.4563 -1.99386998 0 P 0 ;0
L 1.4563 -1.99386998 1.46021004 -1.99535 0 P 0 ;0
L 1.46021004 -1.99535 1.464 -1.99713002 0 P 0 ;0
L 1.464 -1.99713002 1.46586004 -1.99818996 0 P 0 ;0
L 1.46586004 -1.99818996 1.46763996 -1.99936004 0 P 0 ;0
L 1.46763996 -1.99936004 1.46931998 -2.00066004 0 P 0 ;0
L 1.46931998 -2.00066004 1.47091004 -2.00206998 0 P 0 ;0
L 1.47091004 -2.00206998 1.47238996 -2.00358996 0 P 0 ;0
L 1.47238996 -2.00358996 1.4737 -2.00515 0 P 0 ;0
L 1.4737 -2.00515 1.47488002 -2.00678996 0 P 0 ;0
L 1.47488002 -2.00678996 1.47593996 -2.00851004 0 P 0 ;0
L 1.47593996 -2.00851004 1.47686004 -2.01031004 0 P 0 ;0
L 1.47686004 -2.01031004 1.47763996 -2.01216998 0 P 0 ;0
L 1.47763996 -2.01216998 1.47851998 -2.01481004 0 P 0 ;0
L 1.47851998 -2.01481004 1.47918996 -2.01748996 0 P 0 ;0
L 1.47918996 -2.01748996 1.47966004 -2.02021998 0 P 0 ;0
L 1.47966004 -2.02021998 1.47993002 -2.02296998 0 P 0 ;0
L 1.47993002 -2.02296998 1.48001998 -2.02783996 0 P 0 ;0
L 1.48001998 -2.02783996 1.47975 -2.03868996 0 P 0 ;0
L 1.47975 -2.03868996 1.4793 -2.05161004 0 P 0 ;0
L 1.4793 -2.05161004 1.47866004 -2.06543002 0 P 0 ;0
L 1.47866004 -2.06543002 1.47801004 -2.07961004 0 P 0 ;0
L 1.47801004 -2.07961004 1.47743996 -2.09378996 0 P 0 ;0
L 1.47743996 -2.09378996 1.47705 -2.10613002 0 P 0 ;0
L 1.47705 -2.10613002 1.47693002 -2.11356004 0 P 0 ;0
L 1.47693002 -2.11356004 1.47693002 -2.12516004 0 P 0 ;0
L 1.47693002 -2.12516004 1.42661004 -2.12516004 0 P 0 ;0
L 1.42661004 -2.12516004 1.42661004 -2.12473996 0 P 0 ;0
L 1.42661004 -2.12473996 1.42666004 -2.12318002 0 P 0 ;0
L 1.42666004 -2.12318002 1.42691004 -2.11863996 0 P 0 ;0
L 1.42691004 -2.11863996 1.42725 -2.1132 0 P 0 ;0
L 1.42725 -2.1132 1.42766004 -2.1072 0 P 0 ;0
L 1.42766004 -2.1072 1.42766004 -2.10718996 0 P 0 ;0
L 1.42766004 -2.10718996 1.4281 -2.10068996 0 P 0 ;0
L 1.4281 -2.10068996 1.42858002 -2.09368002 0 P 0 ;0
L 1.42858002 -2.09368002 1.42901004 -2.08721004 0 P 0 ;0
L 1.42901004 -2.08721004 1.42901004 -2.0872 0 P 0 ;0
L 1.42901004 -2.0872 1.42931004 -2.08256004 0 P 0 ;0
L 1.42931004 -2.08256004 1.42991998 -2.07308002 0 P 0 ;0
L 1.42991998 -2.07308002 1.42916004 -2.07136998 0 P 0 ;0
L 1.42916004 -2.07136998 1.42731998 -2.07105 0 P 0 ;0
L 1.42731998 -2.07105 1.42105 -2.07303996 0 P 0 ;0
L 1.42105 -2.07303996 1.41815 -2.07393002 0 P 0 ;0
L 1.41815 -2.07393002 1.41451004 -2.075 0 P 0 ;0
L 1.41451004 -2.075 1.41076004 -2.07603002 0 P 0 ;0
L 1.41076004 -2.07603002 1.40748002 -2.0769 0 P 0 ;0
L 1.40748002 -2.0769 1.40438996 -2.07781004 0 P 0 ;0
L 1.40438996 -2.07781004 1.40431998 -2.07783996 0 P 0 ;0
L 1.40431998 -2.07783996 1.40133996 -2.07896998 0 P 0 ;0
L 1.40133996 -2.07896998 1.40005 -2.07956998 0 P 0 ;0
L 1.40005 -2.07956998 1.39881998 -2.08026004 0 P 0 ;0
L 1.39881998 -2.08026004 1.39763996 -2.08103002 0 P 0 ;0
L 1.39763996 -2.08103002 1.39651998 -2.08188002 0 P 0 ;0
L 1.39651998 -2.08188002 1.39578996 -2.08251004 0 P 0 ;0
L 1.39578996 -2.08251004 1.39573996 -2.08256004 0 P 0 ;0
L 1.39573996 -2.08256004 1.3951 -2.08318996 0 P 0 ;0
L 1.3951 -2.08318996 1.39446998 -2.08393002 0 P 0 ;0
L 1.39446998 -2.08393002 1.3939 -2.08471004 0 P 0 ;0
L 1.3939 -2.08471004 1.39336998 -2.08553996 0 P 0 ;0
L 1.39336998 -2.08553996 1.39301004 -2.08623996 0 P 0 ;0
L 1.39301004 -2.08623996 1.39271004 -2.08696998 0 P 0 ;0
L 1.39271004 -2.08696998 1.39248002 -2.08771998 0 P 0 ;0
L 1.39248002 -2.08771998 1.39231004 -2.08848996 0 P 0 ;0
L 1.39231004 -2.08848996 1.39221004 -2.08926004 0 P 0 ;0
L 1.39221004 -2.08926004 1.39218002 -2.09003996 0 P 0 ;0
L 1.39218002 -2.09003996 1.39221004 -2.0908 0 P 0 ;0
L 1.39221004 -2.0908 1.39231004 -2.09153002 0 P 0 ;0
L 1.39231004 -2.09153002 1.39246998 -2.09226004 0 P 0 ;0
L 1.39246998 -2.09226004 1.39268996 -2.09296998 0 P 0 ;0
L 1.39268996 -2.09296998 1.39296004 -2.09365 0 P 0 ;0
L 1.39296004 -2.09365 1.3933 -2.09431004 0 P 0 ;0
L 1.3933 -2.09431004 1.39368996 -2.09493996 0 P 0 ;0
L 1.39368996 -2.09493996 1.39411998 -2.09553996 0 P 0 ;0
L 1.39411998 -2.09553996 1.39468996 -2.09618002 0 P 0 ;0
L 1.39468996 -2.09618002 1.3953 -2.09678002 0 P 0 ;0
L 1.3953 -2.09678002 1.39596004 -2.09731998 0 P 0 ;0
L 1.39596004 -2.09731998 1.39666998 -2.0978 0 P 0 ;0
L 1.39666998 -2.0978 1.39673996 -2.09783996 0 P 0 ;0
L 1.39673996 -2.09783996 1.39741004 -2.09821998 0 P 0 ;0
L 1.39741004 -2.09821998 1.39748996 -2.09825 0 P 0 ;0
L 1.39748996 -2.09825 1.39818996 -2.09856998 0 P 0 ;0
L 1.39818996 -2.09856998 1.39898996 -2.09886004 0 P 0 ;0
L 1.39898996 -2.09886004 1.39906998 -2.09888002 0 P 0 ;0
L 1.39906998 -2.09888002 1.40043996 -2.09888002 0 P 0 ;0
L 1.40043996 -2.09888002 1.40033996 -2.09923002 0 P 0 ;0
L 1.40033996 -2.09923002 1.40041998 -2.09925 0 P 0 ;0
L 1.40041998 -2.09925 1.40186004 -2.09953002 0 P 0 ;0
L 1.40186004 -2.09953002 1.40331004 -2.09971004 0 P 0 ;0
L 1.40331004 -2.09971004 1.40478002 -2.09978002 0 P 0 ;0
L 1.40478002 -2.09978002 1.40625 -2.09975 0 P 0 ;0
L 1.40625 -2.09975 1.41096004 -2.09931004 0 P 0 ;0
L 1.41096004 -2.09931004 1.41556998 -2.09855 0 P 0 ;0
L 1.41556998 -2.09855 1.41791998 -2.09813002 0 P 0 ;0
L 1.41791998 -2.09813002 1.41995 -2.09791004 0 P 0 ;0
L 1.41995 -2.09791004 1.4201 -2.0979 0 P 0 ;0
L 1.4201 -2.0979 1.41941004 -2.10078002 0 P 0 ;0
L 1.41941004 -2.10078002 1.41761004 -2.10745 0 P 0 ;0
L 1.41761004 -2.10745 1.41391004 -2.12025 0 P 0 ;0
L 1.41391004 -2.12025 1.41215 -2.12626998 0 P 0 ;0
L 1.41215 -2.12626998 1.40655 -2.12725 0 P 0 ;0
L 1.40655 -2.12725 1.40046004 -2.12808002 0 P 0 ;0
L 1.40046004 -2.12808002 1.39438002 -2.12845 0 P 0 ;0
L 1.15303002 -2.08283002 1.20788996 -2.08283002 0 P 0 ;0
L 1.15398996 -2.08183002 1.20795 -2.08183002 0 P 0 ;0
L 1.15483002 -2.08083002 1.208 -2.08083002 0 P 0 ;0
L 1.15555 -2.07983002 1.20805 -2.07983002 0 P 0 ;0
L 1.15621998 -2.07883002 1.2081 -2.07883002 0 P 0 ;0
L 1.15681998 -2.07783002 1.20816004 -2.07783002 0 P 0 ;0
L 1.15733002 -2.07683002 1.20821004 -2.07683002 0 P 0 ;0
L 1.15778996 -2.07583002 1.20826004 -2.07583002 0 P 0 ;0
L 1.15818002 -2.07483002 1.20831004 -2.07483002 0 P 0 ;0
L 1.15853996 -2.07383002 1.20836998 -2.07383002 0 P 0 ;0
L 1.15881998 -2.07283002 1.20841998 -2.07283002 0 P 0 ;0
L 1.1591 -2.07183002 1.20846998 -2.07183002 0 P 0 ;0
L 1.15938002 -2.07083002 1.20853002 -2.07083002 0 P 0 ;0
L 1.1596 -2.06983002 1.20858002 -2.06983002 0 P 0 ;0
L 1.15981004 -2.06883002 1.20863996 -2.06883002 0 P 0 ;0
L 1.16001004 -2.06783002 1.20868996 -2.06783002 0 P 0 ;0
L 1.1602 -2.06683002 1.20875 -2.06683002 0 P 0 ;0
L 1.16033996 -2.06583002 1.2088 -2.06583002 0 P 0 ;0
L 1.16048996 -2.06483002 1.20886004 -2.06483002 0 P 0 ;0
L 1.16063996 -2.06383002 1.20891998 -2.06383002 0 P 0 ;0
L 1.16078002 -2.06283002 1.20896998 -2.06283002 0 P 0 ;0
L 1.16088996 -2.06183002 1.20903002 -2.06183002 0 P 0 ;0
L 1.16098996 -2.06083002 1.20908002 -2.06083002 0 P 0 ;0
L 1.16108996 -2.05983002 1.20913996 -2.05983002 0 P 0 ;0
L 1.16118002 -2.05883002 1.20918996 -2.05883002 0 P 0 ;0
L 1.16128002 -2.05783002 1.20925 -2.05783002 0 P 0 ;0
L 1.16133996 -2.05683002 1.2093 -2.05683002 0 P 0 ;0
L 1.1614 -2.05583002 1.20936004 -2.05583002 0 P 0 ;0
L 1.16146004 -2.05483002 1.20941004 -2.05483002 0 P 0 ;0
L 1.16151998 -2.05383002 1.20946998 -2.05383002 0 P 0 ;0
L 1.16158002 -2.05283002 1.20951998 -2.05283002 0 P 0 ;0
L 1.16163996 -2.05183002 1.20958002 -2.05183002 0 P 0 ;0
L 1.1617 -2.05083002 1.20963996 -2.05083002 0 P 0 ;0
L 1.16175 -2.04983002 1.2097 -2.04983002 0 P 0 ;0
L 1.16181004 -2.04883002 1.20975 -2.04883002 0 P 0 ;0
L 1.16186998 -2.04783002 1.20981004 -2.04783002 0 P 0 ;0
L 1.16193002 -2.04683002 1.20986998 -2.04683002 0 P 0 ;0
L 1.16198996 -2.04583002 1.20993002 -2.04583002 0 P 0 ;0
L 1.16205 -2.04483002 1.20998996 -2.04483002 0 P 0 ;0
L 1.16211004 -2.04383002 1.21005 -2.04383002 0 P 0 ;0
L 1.16215 -2.04283002 1.2101 -2.04283002 0 P 0 ;0
L 1.1622 -2.04183002 1.21016004 -2.04183002 0 P 0 ;0
L 1.16225 -2.04083002 1.21021998 -2.04083002 0 P 0 ;0
L 1.16228996 -2.03983002 1.21028002 -2.03983002 0 P 0 ;0
L 1.16233996 -2.03883002 1.21033996 -2.03883002 0 P 0 ;0
L 1.16238002 -2.03783002 1.2104 -2.03783002 0 P 0 ;0
L 1.16243002 -2.03683002 1.21046004 -2.03683002 0 P 0 ;0
L 1.16246998 -2.03583002 1.21051004 -2.03583002 0 P 0 ;0
L 1.16251998 -2.03483002 1.21056998 -2.03483002 0 P 0 ;0
L 1.16256998 -2.03383002 1.21063996 -2.03383002 0 P 0 ;0
L 1.16261004 -2.03283002 1.2107 -2.03283002 0 P 0 ;0
L 1.16266004 -2.03183002 1.21076004 -2.03183002 0 P 0 ;0
L 1.1627 -2.03083002 1.21083002 -2.03083002 0 P 0 ;0
L 1.16015 -1.97631004 1.17066004 -1.97631004 0 P 0 ;0
L 1.15961998 -1.97531004 1.17026004 -1.97531004 0 P 0 ;0
L 1.1591 -1.97431004 1.16986998 -1.97431004 0 P 0 ;0
L 1.15856998 -1.97331004 1.16946998 -1.97331004 0 P 0 ;0
L 1.15803996 -1.97231004 1.16903002 -1.97231004 0 P 0 ;0
L 1.15746998 -1.97131004 1.16858996 -1.97131004 0 P 0 ;0
L 1.1569 -1.97031004 1.16815 -1.97031004 0 P 0 ;0
L 1.15631998 -1.96931004 1.16771004 -1.96931004 0 P 0 ;0
L 1.15573996 -1.96831004 1.16726998 -1.96831004 0 P 0 ;0
L 1.15516004 -1.96731004 1.16681998 -1.96731004 0 P 0 ;0
L 1.15458996 -1.96631004 1.16638002 -1.96631004 0 P 0 ;0
L 1.15398002 -1.96531004 1.16593996 -1.96531004 0 P 0 ;0
L 1.1533 -1.96431004 1.16548996 -1.96431004 0 P 0 ;0
L 1.15261998 -1.96331004 1.16503002 -1.96331004 0 P 0 ;0
L 1.15193996 -1.96231004 1.16448002 -1.96231004 0 P 0 ;0
L 1.15126004 -1.96131004 1.16393002 -1.96131004 0 P 0 ;0
L 1.15058002 -1.96031004 1.16338002 -1.96031004 0 P 0 ;0
L 1.1499 -1.95931004 1.16283002 -1.95931004 0 P 0 ;0
L 1.1491 -1.95831004 1.16228996 -1.95831004 0 P 0 ;0
L 1.14831004 -1.95731004 1.16173996 -1.95731004 0 P 0 ;0
L 1.14751004 -1.95631004 1.16118996 -1.95631004 0 P 0 ;0
L 1.14671004 -1.95531004 1.16063996 -1.95531004 0 P 0 ;0
L 1.14591998 -1.95431004 1.16008996 -1.95431004 0 P 0 ;0
L 1.14511998 -1.95331004 1.15943996 -1.95331004 0 P 0 ;0
L 1.1442 -1.95231004 1.15878002 -1.95231004 0 P 0 ;0
L 1.14326998 -1.95131004 1.15811004 -1.95131004 0 P 0 ;0
L 1.14233996 -1.95031004 1.15745 -1.95031004 0 P 0 ;0
L 1.14141004 -1.94931004 1.15678002 -1.94931004 0 P 0 ;0
L 1.14048996 -1.94831004 1.15611998 -1.94831004 0 P 0 ;0
L 1.1395 -1.94731004 1.15545 -1.94731004 0 P 0 ;0
L 1.13843002 -1.94631004 1.15478996 -1.94631004 0 P 0 ;0
L 1.13736004 -1.94531004 1.15411998 -1.94531004 0 P 0 ;0
L 1.13628996 -1.94431004 1.15333002 -1.94431004 0 P 0 ;0
L 1.13521004 -1.94331004 1.15253002 -1.94331004 0 P 0 ;0
L 1.13413996 -1.94231004 1.15173996 -1.94231004 0 P 0 ;0
L 1.13306998 -1.94131004 1.15093996 -1.94131004 0 P 0 ;0
L 1.132 -1.94031004 1.15013996 -1.94031004 0 P 0 ;0
L 1.13081004 -1.93931004 1.14935 -1.93931004 0 P 0 ;0
L 1.12958002 -1.93831004 1.14855 -1.93831004 0 P 0 ;0
L 1.12833996 -1.93731004 1.14775 -1.93731004 0 P 0 ;0
L 1.1271 -1.93631004 1.14688996 -1.93631004 0 P 0 ;0
L 1.12586004 -1.93531004 1.14593996 -1.93531004 0 P 0 ;0
L 1.12461998 -1.93431004 1.14498996 -1.93431004 0 P 0 ;0
L 1.12338002 -1.93331004 1.14405 -1.93331004 0 P 0 ;0
L 1.12203002 -1.93231004 1.1431 -1.93231004 0 P 0 ;0
L 1.1206 -1.93131004 1.14216004 -1.93131004 0 P 0 ;0
L 1.11916004 -1.93031004 1.14121004 -1.93031004 0 P 0 ;0
L 1.11771998 -1.92931004 1.14026998 -1.92931004 0 P 0 ;0
L 1.11628996 -1.92831004 1.13931998 -1.92831004 0 P 0 ;0
L 1.11483996 -1.92731004 1.13838002 -1.92731004 0 P 0 ;0
L 1.11338996 -1.92631004 1.13743002 -1.92631004 0 P 0 ;0
L 1.11171998 -1.92531004 1.13648996 -1.92531004 0 P 0 ;0
L 1.11005 -1.92431004 1.13538002 -1.92431004 0 P 0 ;0
L 1.10838002 -1.92331004 1.13426998 -1.92331004 0 P 0 ;0
L 1.1067 -1.92231004 1.13315 -1.92231004 0 P 0 ;0
L 1.10503002 -1.92131004 1.13203002 -1.92131004 0 P 0 ;0
L 1.10336004 -1.92031004 1.13091998 -1.92031004 0 P 0 ;0
L 1.1015 -1.91931004 1.1298 -1.91931004 0 P 0 ;0
L 1.09955 -1.91831004 1.12868002 -1.91831004 0 P 0 ;0
L 1.16275 -2.02983002 1.21088996 -2.02983002 0 P 0 ;0
L 1.16278996 -2.02883002 1.21095 -2.02883002 0 P 0 ;0
L 1.16283996 -2.02783002 1.21101004 -2.02783002 0 P 0 ;0
L 1.16226998 -2.02683002 1.21108002 -2.02683002 0 P 0 ;0
L 1.16153996 -2.02583002 1.21113996 -2.02583002 0 P 0 ;0
L 1.15846004 -2.02483002 1.2112 -2.02483002 0 P 0 ;0
L 1.10036004 -2.00383002 1.21255 -2.00383002 0 P 0 ;0
L 1.10226004 -2.00283002 1.2126 -2.00283002 0 P 0 ;0
L 1.10433996 -2.00183002 1.21266998 -2.00183002 0 P 0 ;0
L 1.1065 -2.00083002 1.21273002 -2.00083002 0 P 0 ;0
L 1.10886998 -1.99983002 1.21278996 -1.99983002 0 P 0 ;0
L 1.11138002 -1.99883002 1.21285 -1.99883002 0 P 0 ;0
L 1.11436998 -1.99783002 1.21288002 -1.99783002 0 P 0 ;0
L 1.11748996 -1.99683002 1.21255 -1.99683002 0 P 0 ;0
L 1.12061998 -1.99583002 1.2089 -1.99583002 0 P 0 ;0
L 1.12433996 -1.99483002 1.2036 -1.99483002 0 P 0 ;0
L 1.12863996 -1.99383002 1.19728002 -1.99383002 0 P 0 ;0
L 1.13295 -1.99283002 1.19096998 -1.99283002 0 P 0 ;0
L 1.13985 -1.99183002 1.18111998 -1.99183002 0 P 0 ;0
L 1.14948002 -1.99083002 1.1651 -1.99083002 0 P 0 ;0
L 1.24218002 -2.08316004 1.29143996 -2.08316004 0 P 0 ;0
L 1.24223002 -2.08216004 1.29151004 -2.08216004 0 P 0 ;0
L 1.24228002 -2.08116004 1.29158996 -2.08116004 0 P 0 ;0
L 1.24233996 -2.08016004 1.29166004 -2.08016004 0 P 0 ;0
L 1.24238996 -2.07916004 1.29173002 -2.07916004 0 P 0 ;0
L 1.24245 -2.07816004 1.29181004 -2.07816004 0 P 0 ;0
L 1.2425 -2.07716004 1.29188002 -2.07716004 0 P 0 ;0
L 1.24256004 -2.07616004 1.29195 -2.07616004 0 P 0 ;0
L 1.24261004 -2.07516004 1.29203002 -2.07516004 0 P 0 ;0
L 1.24266998 -2.07416004 1.2921 -2.07416004 0 P 0 ;0
L 1.24271998 -2.07316004 1.29216998 -2.07316004 0 P 0 ;0
L 1.24278002 -2.07216004 1.29223996 -2.07216004 0 P 0 ;0
L 1.24283002 -2.07116004 1.29231998 -2.07116004 0 P 0 ;0
L 1.24288002 -2.07016004 1.29238996 -2.07016004 0 P 0 ;0
L 1.24293002 -2.06916004 1.29246004 -2.06916004 0 P 0 ;0
L 1.24296998 -2.06816004 1.29253002 -2.06816004 0 P 0 ;0
L 1.24301998 -2.06716004 1.29261004 -2.06716004 0 P 0 ;0
L 1.24306004 -2.06616004 1.2927 -2.06616004 0 P 0 ;0
L 1.24311004 -2.06516004 1.29281004 -2.06516004 0 P 0 ;0
L 1.24315 -2.06416004 1.29291998 -2.06416004 0 P 0 ;0
L 1.2432 -2.06316004 1.29303002 -2.06316004 0 P 0 ;0
L 1.24323996 -2.06216004 1.29315 -2.06216004 0 P 0 ;0
L 1.24328996 -2.06116004 1.29331998 -2.06116004 0 P 0 ;0
L 1.24333002 -2.06016004 1.2935 -2.06016004 0 P 0 ;0
L 1.24338002 -2.05916004 1.29366998 -2.05916004 0 P 0 ;0
L 1.24341998 -2.05816004 1.29385 -2.05816004 0 P 0 ;0
L 1.24346998 -2.05716004 1.29408996 -2.05716004 0 P 0 ;0
L 1.24351004 -2.05616004 1.29433996 -2.05616004 0 P 0 ;0
L 1.24355 -2.05516004 1.29458996 -2.05516004 0 P 0 ;0
L 1.2436 -2.05416004 1.29485 -2.05416004 0 P 0 ;0
L 1.24363996 -2.05316004 1.29516998 -2.05316004 0 P 0 ;0
L 1.24368996 -2.05216004 1.29551998 -2.05216004 0 P 0 ;0
L 1.24373002 -2.05116004 1.29586004 -2.05116004 0 P 0 ;0
L 1.24378002 -2.05016004 1.29621004 -2.05016004 0 P 0 ;0
L 1.24383002 -2.04916004 1.29663996 -2.04916004 0 P 0 ;0
L 1.24386998 -2.04816004 1.29708002 -2.04816004 0 P 0 ;0
L 1.24391004 -2.04716004 1.29753002 -2.04716004 0 P 0 ;0
L 1.24396004 -2.04616004 1.29796998 -2.04616004 0 P 0 ;0
L 1.244 -2.04516004 1.29851004 -2.04516004 0 P 0 ;0
L 1.24405 -2.04416004 1.2991 -2.04416004 0 P 0 ;0
L 1.24408996 -2.04316004 1.29975 -2.04316004 0 P 0 ;0
L 1.24413996 -2.04216004 1.3005 -2.04216004 0 P 0 ;0
L 1.24418002 -2.04116004 1.30131998 -2.04116004 0 P 0 ;0
L 1.24423002 -2.04016004 1.30223002 -2.04016004 0 P 0 ;0
L 1.24426998 -2.03916004 1.30326998 -2.03916004 0 P 0 ;0
L 1.24431998 -2.03816004 1.30446004 -2.03816004 0 P 0 ;0
L 1.24436004 -2.03716004 1.30581998 -2.03716004 0 P 0 ;0
L 1.24441004 -2.03616004 1.30738002 -2.03616004 0 P 0 ;0
L 1.24445 -2.03516004 1.30923002 -2.03516004 0 P 0 ;0
L 1.24448996 -2.03416004 1.31156004 -2.03416004 0 P 0 ;0
L 1.24453996 -2.03316004 1.31478996 -2.03316004 0 P 0 ;0
L 1.24458996 -2.03216004 1.32013002 -2.03216004 0 P 0 ;0
L 1.24461998 -2.03116004 1.33481004 -2.03116004 0 P 0 ;0
L 1.24463996 -2.03016004 1.33478002 -2.03016004 0 P 0 ;0
L 1.24466004 -2.02916004 1.33473996 -2.02916004 0 P 0 ;0
L 1.24468002 -2.02816004 1.33471004 -2.02816004 0 P 0 ;0
L 1.2447 -2.02716004 1.33468002 -2.02716004 0 P 0 ;0
L 1.24471998 -2.02616004 1.33463996 -2.02616004 0 P 0 ;0
L 1.24473996 -2.02516004 1.3346 -2.02516004 0 P 0 ;0
L 1.24476004 -2.02416004 1.33456998 -2.02416004 0 P 0 ;0
L 1.24478002 -2.02316004 1.33453002 -2.02316004 0 P 0 ;0
L 1.2448 -2.02216004 1.3345 -2.02216004 0 P 0 ;0
L 1.24481998 -2.02116004 1.33446998 -2.02116004 0 P 0 ;0
L 1.24483996 -2.02016004 1.33443002 -2.02016004 0 P 0 ;0
L 1.24486004 -2.01916004 1.3344 -2.01916004 0 P 0 ;0
L 1.24488002 -2.01816004 1.33436004 -2.01816004 0 P 0 ;0
L 1.2449 -2.01716004 1.33433002 -2.01716004 0 P 0 ;0
L 1.24491998 -2.01616004 1.33428996 -2.01616004 0 P 0 ;0
L 1.24493996 -2.01516004 1.33426004 -2.01516004 0 P 0 ;0
L 1.24496004 -2.01416004 1.33421998 -2.01416004 0 P 0 ;0
L 1.24498002 -2.01316004 1.33418996 -2.01316004 0 P 0 ;0
L 1.245 -2.01216004 1.33415 -2.01216004 0 P 0 ;0
L 1.24501998 -2.01116004 1.33411998 -2.01116004 0 P 0 ;0
L 1.24503996 -2.01016004 1.33408002 -2.01016004 0 P 0 ;0
L 1.24506004 -2.00916004 1.33403996 -2.00916004 0 P 0 ;0
L 1.24508002 -2.00816004 1.334 -2.00816004 0 P 0 ;0
L 1.2451 -2.00716004 1.33396004 -2.00716004 0 P 0 ;0
L 1.24511998 -2.00616004 1.33393002 -2.00616004 0 P 0 ;0
L 1.24513996 -2.00516004 1.29098996 -2.00516004 0 P 0 ;0
L 1.24513996 -2.00416004 1.29033002 -2.00416004 0 P 0 ;0
L 1.24513996 -2.00316004 1.29005 -2.00316004 0 P 0 ;0
L 1.24513996 -2.00216004 1.29005 -2.00216004 0 P 0 ;0
L 1.24513996 -2.00116004 1.29005 -2.00116004 0 P 0 ;0
L 1.24515 -2.00016004 1.29005 -2.00016004 0 P 0 ;0
L 1.24515 -1.99916004 1.29005 -1.99916004 0 P 0 ;0
L 1.24515 -1.99816004 1.29005 -1.99816004 0 P 0 ;0
L 1.24515 -1.99716004 1.29005 -1.99716004 0 P 0 ;0
L 1.24515 -1.99616004 1.29005 -1.99616004 0 P 0 ;0
L 1.24515 -1.99516004 1.29005 -1.99516004 0 P 0 ;0
L 1.16085 -2.02753002 1.1601 -2.04393002 0 P 0 ;0
L 1.1601 -2.04393002 1.15928996 -2.05771998 0 P 0 ;0
L 1.15928996 -2.05771998 1.15883996 -2.06228002 0 P 0 ;0
L 1.15883996 -2.06228002 1.15818002 -2.06681998 0 P 0 ;0
L 1.15818002 -2.06681998 1.15751004 -2.07006998 0 P 0 ;0
L 1.15751004 -2.07006998 1.15661004 -2.07328996 0 P 0 ;0
L 1.15661004 -2.07328996 1.15616004 -2.07453996 0 P 0 ;0
L 1.15616004 -2.07453996 1.15563002 -2.07576998 0 P 0 ;0
L 1.15563002 -2.07576998 1.15501998 -2.07696004 0 P 0 ;0
L 1.15501998 -2.07696004 1.15433002 -2.0781 0 P 0 ;0
L 1.15433002 -2.0781 1.1534 -2.07941998 0 P 0 ;0
L 1.1534 -2.07941998 1.15236004 -2.08066004 0 P 0 ;0
L 1.15236004 -2.08066004 1.15123002 -2.08181998 0 P 0 ;0
L 1.15123002 -2.08181998 1.15001004 -2.08286998 0 P 0 ;0
L 1.15001004 -2.08286998 1.14871004 -2.08383002 0 P 0 ;0
L 1.14871004 -2.08383002 1.14733002 -2.08468002 0 P 0 ;0
L 1.14733002 -2.08468002 1.14591004 -2.0854 0 P 0 ;0
L 1.14591004 -2.0854 1.14443996 -2.086 0 P 0 ;0
L 1.14443996 -2.086 1.14291004 -2.08648002 0 P 0 ;0
L 1.14291004 -2.08648002 1.14136004 -2.08683002 0 P 0 ;0
L 1.14136004 -2.08683002 1.13976998 -2.08703996 0 P 0 ;0
L 1.13976998 -2.08703996 1.13816004 -2.08713002 0 P 0 ;0
L 1.13816004 -2.08713002 1.13656998 -2.08708002 0 P 0 ;0
L 1.13656998 -2.08708002 1.13498996 -2.0869 0 P 0 ;0
L 1.13498996 -2.0869 1.13341998 -2.08658996 0 P 0 ;0
L 1.13341998 -2.08658996 1.13188996 -2.08615 0 P 0 ;0
L 1.13188996 -2.08615 1.1304 -2.08558996 0 P 0 ;0
L 1.1304 -2.08558996 1.12895 -2.08488996 0 P 0 ;0
L 1.12895 -2.08488996 1.12756998 -2.08408002 0 P 0 ;0
L 1.12756998 -2.08408002 1.12625 -2.08315 0 P 0 ;0
L 1.12625 -2.08315 1.12501004 -2.08211998 0 P 0 ;0
L 1.12501004 -2.08211998 1.12386004 -2.081 0 P 0 ;0
L 1.12386004 -2.081 1.12281004 -2.07978002 0 P 0 ;0
L 1.12281004 -2.07978002 1.12183996 -2.07846998 0 P 0 ;0
L 1.12183996 -2.07846998 1.1211 -2.07726004 0 P 0 ;0
L 1.1211 -2.07726004 1.12046998 -2.07598996 0 P 0 ;0
L 1.12046998 -2.07598996 1.11996004 -2.07466998 0 P 0 ;0
L 1.11996004 -2.07466998 1.11955 -2.07331004 0 P 0 ;0
L 1.11955 -2.07331004 1.11926998 -2.07191004 0 P 0 ;0
L 1.11926998 -2.07191004 1.11868002 -2.06693996 0 P 0 ;0
L 1.11868002 -2.06693996 1.11848002 -2.06191004 0 P 0 ;0
L 1.11848002 -2.06191004 1.11871004 -2.05668002 0 P 0 ;0
L 1.11871004 -2.05668002 1.11936004 -2.05148002 0 P 0 ;0
L 1.11936004 -2.05148002 1.11978996 -2.04936998 0 P 0 ;0
L 1.11978996 -2.04936998 1.12036998 -2.0473 0 P 0 ;0
L 1.12036998 -2.0473 1.12108996 -2.04528002 0 P 0 ;0
L 1.12108996 -2.04528002 1.12196004 -2.04331998 0 P 0 ;0
L 1.12196004 -2.04331998 1.1229 -2.04153996 0 P 0 ;0
L 1.1229 -2.04153996 1.12396998 -2.03985 0 P 0 ;0
L 1.12396998 -2.03985 1.12516998 -2.03823002 0 P 0 ;0
L 1.12516998 -2.03823002 1.12735 -2.03573996 0 P 0 ;0
L 1.12735 -2.03573996 1.12973002 -2.03345 0 P 0 ;0
L 1.12973002 -2.03345 1.13223996 -2.03141998 0 P 0 ;0
L 1.13223996 -2.03141998 1.13491998 -2.02961004 0 P 0 ;0
L 1.13491998 -2.02961004 1.13611004 -2.02893002 0 P 0 ;0
L 1.13611004 -2.02893002 1.13735 -2.02833996 0 P 0 ;0
L 1.13735 -2.02833996 1.13861998 -2.02781998 0 P 0 ;0
L 1.13861998 -2.02781998 1.13993996 -2.0274 0 P 0 ;0
L 1.13993996 -2.0274 1.14191004 -2.02693002 0 P 0 ;0
L 1.14191004 -2.02693002 1.14391004 -2.02663002 0 P 0 ;0
L 1.14391004 -2.02663002 1.14935 -2.02626004 0 P 0 ;0
L 1.14935 -2.02626004 1.15471004 -2.0263 0 P 0 ;0
L 1.15471004 -2.0263 1.15591004 -2.02638996 0 P 0 ;0
L 1.15591004 -2.02638996 1.1571 -2.02656998 0 P 0 ;0
L 1.1571 -2.02656998 1.15828002 -2.02683996 0 P 0 ;0
L 1.15828002 -2.02683996 1.16085 -2.02753002 0 P 0 ;0
L 1.13876998 -2.14783002 1.20233002 -2.14783002 0 P 0 ;0
L 1.14236998 -2.14683002 1.20266004 -2.14683002 0 P 0 ;0
L 1.14481004 -2.14583002 1.20296004 -2.14583002 0 P 0 ;0
L 1.1467 -2.14483002 1.20325 -2.14483002 0 P 0 ;0
L 1.14826004 -2.14383002 1.20353002 -2.14383002 0 P 0 ;0
L 1.1496 -2.14283002 1.20373996 -2.14283002 0 P 0 ;0
L 1.15078996 -2.14183002 1.20395 -2.14183002 0 P 0 ;0
L 1.15186004 -2.14083002 1.20415 -2.14083002 0 P 0 ;0
L 1.15278996 -2.13983002 1.20431998 -2.13983002 0 P 0 ;0
L 1.15361998 -2.13883002 1.20446004 -2.13883002 0 P 0 ;0
L 1.15436004 -2.13783002 1.20458002 -2.13783002 0 P 0 ;0
L 1.155 -2.13683002 1.20466998 -2.13683002 0 P 0 ;0
L 1.15556998 -2.13583002 1.20475 -2.13583002 0 P 0 ;0
L 1.15608996 -2.13483002 1.20481998 -2.13483002 0 P 0 ;0
L 1.15653996 -2.13383002 1.20488996 -2.13383002 0 P 0 ;0
L 1.15691004 -2.13283002 1.20496004 -2.13283002 0 P 0 ;0
L 1.15723996 -2.13183002 1.20503002 -2.13183002 0 P 0 ;0
L 1.15751998 -2.13083002 1.2051 -2.13083002 0 P 0 ;0
L 1.15773002 -2.12983002 1.20516004 -2.12983002 0 P 0 ;0
L 1.15793002 -2.12883002 1.20523002 -2.12883002 0 P 0 ;0
L 1.15806004 -2.12783002 1.2053 -2.12783002 0 P 0 ;0
L 1.15816998 -2.12683002 1.20536998 -2.12683002 0 P 0 ;0
L 1.15821004 -2.12583002 1.20543996 -2.12583002 0 P 0 ;0
L 1.11716004 -2.12483002 1.12726004 -2.12483002 0 P 0 ;0
L 1.15823996 -2.12483002 1.20551004 -2.12483002 0 P 0 ;0
L 1.10911998 -2.12383002 1.1352 -2.12383002 0 P 0 ;0
L 1.15821998 -2.12383002 1.20556998 -2.12383002 0 P 0 ;0
L 1.10468996 -2.12283002 1.14018996 -2.12283002 0 P 0 ;0
L 1.1582 -2.12283002 1.20563996 -2.12283002 0 P 0 ;0
L 1.10131004 -2.12183002 1.14366998 -2.12183002 0 P 0 ;0
L 1.15818002 -2.12183002 1.2057 -2.12183002 0 P 0 ;0
L 1.15808996 -2.12083002 1.20576004 -2.12083002 0 P 0 ;0
L 1.15781004 -2.11983002 1.20583002 -2.11983002 0 P 0 ;0
L 1.15721004 -2.11883002 1.20588002 -2.11883002 0 P 0 ;0
L 1.14146004 -2.08883002 1.20758002 -2.08883002 0 P 0 ;0
L 1.14525 -2.08783002 1.20763002 -2.08783002 0 P 0 ;0
L 1.14751004 -2.08683002 1.20768002 -2.08683002 0 P 0 ;0
L 1.14928002 -2.08583002 1.20773002 -2.08583002 0 P 0 ;0
L 1.15073002 -2.08483002 1.20778996 -2.08483002 0 P 0 ;0
L 1.15196004 -2.08383002 1.20783996 -2.08383002 0 P 0 ;0
L 1.13818996 -2.08913002 1.13826998 -2.08913002 0 P 0 ;0
L 1.13826998 -2.08913002 1.13988002 -2.08903996 0 P 0 ;0
L 1.13988002 -2.08903996 1.13996004 -2.08903996 0 P 0 ;0
L 1.13996004 -2.08903996 1.14001004 -2.08903002 0 P 0 ;0
L 1.14001004 -2.08903002 1.14005 -2.08901998 0 P 0 ;0
L 1.14005 -2.08901998 1.14163002 -2.08881004 0 P 0 ;0
L 1.14163002 -2.08881004 1.14166998 -2.0888 0 P 0 ;0
L 1.14166998 -2.0888 1.14171004 -2.0888 0 P 0 ;0
L 1.14171004 -2.0888 1.14178996 -2.08878002 0 P 0 ;0
L 1.14178996 -2.08878002 1.14335 -2.08843002 0 P 0 ;0
L 1.14335 -2.08843002 1.14351004 -2.08838996 0 P 0 ;0
L 1.14351004 -2.08838996 1.14503002 -2.08791004 0 P 0 ;0
L 1.14503002 -2.08791004 1.14511004 -2.08788996 0 P 0 ;0
L 1.14511004 -2.08788996 1.14515 -2.08786998 0 P 0 ;0
L 1.14515 -2.08786998 1.14518996 -2.08786004 0 P 0 ;0
L 1.14518996 -2.08786004 1.14666004 -2.08725 0 P 0 ;0
L 1.14666004 -2.08725 1.14673996 -2.08721998 0 P 0 ;0
L 1.14673996 -2.08721998 1.14678002 -2.0872 0 P 0 ;0
L 1.14678002 -2.0872 1.14681998 -2.08718996 0 P 0 ;0
L 1.14681998 -2.08718996 1.14823996 -2.08646998 0 P 0 ;0
L 1.14823996 -2.08646998 1.14826998 -2.08645 0 P 0 ;0
L 1.14826998 -2.08645 1.14835 -2.08641004 0 P 0 ;0
L 1.14835 -2.08641004 1.14838002 -2.08638002 0 P 0 ;0
L 1.14838002 -2.08638002 1.14976004 -2.08553002 0 P 0 ;0
L 1.14976004 -2.08553002 1.14978996 -2.08551004 0 P 0 ;0
L 1.14978996 -2.08551004 1.14983002 -2.08548996 0 P 0 ;0
L 1.14983002 -2.08548996 1.14988996 -2.08543996 0 P 0 ;0
L 1.14988996 -2.08543996 1.1512 -2.08448996 0 P 0 ;0
L 1.1512 -2.08448996 1.15126004 -2.08443996 0 P 0 ;0
L 1.15126004 -2.08443996 1.15128996 -2.08441004 0 P 0 ;0
L 1.15128996 -2.08441004 1.15131998 -2.08438996 0 P 0 ;0
L 1.15131998 -2.08438996 1.15253996 -2.08333002 0 P 0 ;0
L 1.15253996 -2.08333002 1.15256998 -2.0833 0 P 0 ;0
L 1.15256998 -2.0833 1.1526 -2.08328002 0 P 0 ;0
L 1.1526 -2.08328002 1.15263002 -2.08323996 0 P 0 ;0
L 1.15263002 -2.08323996 1.15266004 -2.08321998 0 P 0 ;0
L 1.15266004 -2.08321998 1.15378996 -2.08206004 0 P 0 ;0
L 1.15378996 -2.08206004 1.15376004 -2.08203996 0 P 0 ;0
L 1.15376004 -2.08203996 1.15381998 -2.08203996 0 P 0 ;0
L 1.15381998 -2.08203996 1.15383996 -2.082 0 P 0 ;0
L 1.15383996 -2.082 1.15386998 -2.08196998 0 P 0 ;0
L 1.15386998 -2.08196998 1.1539 -2.08195 0 P 0 ;0
L 1.1539 -2.08195 1.15493002 -2.08071004 0 P 0 ;0
L 1.15493002 -2.08071004 1.15493002 -2.0807 0 P 0 ;0
L 1.15493002 -2.0807 1.15496004 -2.08066998 0 P 0 ;0
L 1.15496004 -2.08066998 1.15498002 -2.08063996 0 P 0 ;0
L 1.15498002 -2.08063996 1.15501004 -2.08061004 0 P 0 ;0
L 1.15501004 -2.08061004 1.15503002 -2.08058002 0 P 0 ;0
L 1.15503002 -2.08058002 1.15596004 -2.07926004 0 P 0 ;0
L 1.15596004 -2.07926004 1.15603996 -2.07913996 0 P 0 ;0
L 1.15603996 -2.07913996 1.15673002 -2.07798996 0 P 0 ;0
L 1.15673002 -2.07798996 1.15676998 -2.07793002 0 P 0 ;0
L 1.15676998 -2.07793002 1.15678996 -2.07786998 0 P 0 ;0
L 1.15678996 -2.07786998 1.15741004 -2.07668996 0 P 0 ;0
L 1.15741004 -2.07668996 1.15743996 -2.07663002 0 P 0 ;0
L 1.15743996 -2.07663002 1.15746004 -2.07656998 0 P 0 ;0
L 1.15746004 -2.07656998 1.15746998 -2.07656998 0 P 0 ;0
L 1.15746998 -2.07656998 1.158 -2.07533996 0 P 0 ;0
L 1.158 -2.07533996 1.15801004 -2.07531004 0 P 0 ;0
L 1.15801004 -2.07531004 1.15803002 -2.07528002 0 P 0 ;0
L 1.15803002 -2.07528002 1.15805 -2.07521998 0 P 0 ;0
L 1.15805 -2.07521998 1.15848996 -2.07396004 0 P 0 ;0
L 1.15848996 -2.07396004 1.15841004 -2.07393002 0 P 0 ;0
L 1.15841004 -2.07393002 1.15851004 -2.07393002 0 P 0 ;0
L 1.15851004 -2.07393002 1.15851998 -2.0739 0 P 0 ;0
L 1.15851998 -2.0739 1.15853002 -2.07386004 0 P 0 ;0
L 1.15853002 -2.07386004 1.15853996 -2.07383002 0 P 0 ;0
L 1.15853996 -2.07383002 1.15943996 -2.07061004 0 P 0 ;0
L 1.15943996 -2.07061004 1.15945 -2.07058002 0 P 0 ;0
L 1.15945 -2.07058002 1.15946004 -2.07053996 0 P 0 ;0
L 1.15946004 -2.07053996 1.15946998 -2.07051004 0 P 0 ;0
L 1.15946998 -2.07051004 1.15946998 -2.07046998 0 P 0 ;0
L 1.15946998 -2.07046998 1.16013996 -2.06723002 0 P 0 ;0
L 1.16013996 -2.06723002 1.16013996 -2.0672 0 P 0 ;0
L 1.16013996 -2.0672 1.16016004 -2.06713996 0 P 0 ;0
L 1.16016004 -2.06713996 1.16016004 -2.06711004 0 P 0 ;0
L 1.16016004 -2.06711004 1.16081998 -2.06256004 0 P 0 ;0
L 1.16081998 -2.06256004 1.16081998 -2.06253996 0 P 0 ;0
L 1.16081998 -2.06253996 1.16083002 -2.0625 0 P 0 ;0
L 1.16083002 -2.0625 1.16083002 -2.06246998 0 P 0 ;0
L 1.16083002 -2.06246998 1.16126998 -2.05791004 0 P 0 ;0
L 1.16126998 -2.05791004 1.16128002 -2.0579 0 P 0 ;0
L 1.16128002 -2.0579 1.16128002 -2.05783996 0 P 0 ;0
L 1.16128002 -2.05783996 1.1621 -2.04405 0 P 0 ;0
L 1.1621 -2.04405 1.1621 -2.04401998 0 P 0 ;0
L 1.1621 -2.04401998 1.16285 -2.02761998 0 P 0 ;0
L 1.16285 -2.02761998 1.16136998 -2.0256 0 P 0 ;0
L 1.16136998 -2.0256 1.15878996 -2.02491004 0 P 0 ;0
L 1.15878996 -2.02491004 1.15878002 -2.0249 0 P 0 ;0
L 1.15878002 -2.0249 1.15871998 -2.02488996 0 P 0 ;0
L 1.15871998 -2.02488996 1.15755 -2.02461998 0 P 0 ;0
L 1.15755 -2.02461998 1.15746998 -2.0246 0 P 0 ;0
L 1.15746998 -2.0246 1.1574 -2.0246 0 P 0 ;0
L 1.1574 -2.0246 1.15621004 -2.02441004 0 P 0 ;0
L 1.15621004 -2.02441004 1.15616998 -2.02441004 0 P 0 ;0
L 1.15616998 -2.02441004 1.1561 -2.0244 0 P 0 ;0
L 1.1561 -2.0244 1.15606004 -2.02438996 0 P 0 ;0
L 1.15606004 -2.02438996 1.15486004 -2.0243 0 P 0 ;0
L 1.15486004 -2.0243 1.15471998 -2.0243 0 P 0 ;0
L 1.15471998 -2.0243 1.14936004 -2.02426004 0 P 0 ;0
L 1.14936004 -2.02426004 1.14928996 -2.02426004 0 P 0 ;0
L 1.14928996 -2.02426004 1.14925 -2.02426998 0 P 0 ;0
L 1.14925 -2.02426998 1.14921004 -2.02426998 0 P 0 ;0
L 1.14921004 -2.02426998 1.14376998 -2.02463996 0 P 0 ;0
L 1.14376998 -2.02463996 1.1437 -2.02463996 0 P 0 ;0
L 1.1437 -2.02463996 1.14365 -2.02465 0 P 0 ;0
L 1.14365 -2.02465 1.14361004 -2.02465 0 P 0 ;0
L 1.14361004 -2.02465 1.14161998 -2.02495 0 P 0 ;0
L 1.14161998 -2.02495 1.14161004 -2.02495 0 P 0 ;0
L 1.14161004 -2.02495 1.14153002 -2.02496998 0 P 0 ;0
L 1.14153002 -2.02496998 1.14148996 -2.02496998 0 P 0 ;0
L 1.14148996 -2.02496998 1.14143996 -2.02498996 0 P 0 ;0
L 1.14143996 -2.02498996 1.13946998 -2.02545 0 P 0 ;0
L 1.13946998 -2.02545 1.13943996 -2.02546998 0 P 0 ;0
L 1.13943996 -2.02546998 1.1394 -2.02546998 0 P 0 ;0
L 1.1394 -2.02546998 1.13933002 -2.0255 0 P 0 ;0
L 1.13933002 -2.0255 1.13801004 -2.02591998 0 P 0 ;0
L 1.13801004 -2.02591998 1.13798002 -2.02593002 0 P 0 ;0
L 1.13798002 -2.02593002 1.13793996 -2.02593996 0 P 0 ;0
L 1.13793996 -2.02593996 1.13788002 -2.02596998 0 P 0 ;0
L 1.13788002 -2.02596998 1.1366 -2.02648002 0 P 0 ;0
L 1.1366 -2.02648002 1.13653996 -2.0265 0 P 0 ;0
L 1.13653996 -2.0265 1.13648002 -2.02653002 0 P 0 ;0
L 1.13648002 -2.02653002 1.13523996 -2.02713002 0 P 0 ;0
L 1.13523996 -2.02713002 1.13518002 -2.02716004 0 P 0 ;0
L 1.13518002 -2.02716004 1.13515 -2.02716998 0 P 0 ;0
L 1.13515 -2.02716998 1.13511998 -2.02718996 0 P 0 ;0
L 1.13511998 -2.02718996 1.13393002 -2.02786998 0 P 0 ;0
L 1.13393002 -2.02786998 1.13388996 -2.02788996 0 P 0 ;0
L 1.13388996 -2.02788996 1.1338 -2.02795 0 P 0 ;0
L 1.1338 -2.02795 1.13111998 -2.02976004 0 P 0 ;0
L 1.13111998 -2.02976004 1.13105 -2.02981004 0 P 0 ;0
L 1.13105 -2.02981004 1.13101004 -2.02983996 0 P 0 ;0
L 1.13101004 -2.02983996 1.13098002 -2.02986004 0 P 0 ;0
L 1.13098002 -2.02986004 1.12846998 -2.03188996 0 P 0 ;0
L 1.12846998 -2.03188996 1.12838002 -2.03198002 0 P 0 ;0
L 1.12838002 -2.03198002 1.12833996 -2.03201004 0 P 0 ;0
L 1.12833996 -2.03201004 1.12596004 -2.0343 0 P 0 ;0
L 1.12596004 -2.0343 1.12593996 -2.03433002 0 P 0 ;0
L 1.12593996 -2.03433002 1.1259 -2.03436004 0 P 0 ;0
L 1.1259 -2.03436004 1.12588002 -2.03438996 0 P 0 ;0
L 1.12588002 -2.03438996 1.12585 -2.03443002 0 P 0 ;0
L 1.12585 -2.03443002 1.12366998 -2.03691004 0 P 0 ;0
L 1.12366998 -2.03691004 1.12363996 -2.03695 0 P 0 ;0
L 1.12363996 -2.03695 1.12361998 -2.03698002 0 P 0 ;0
L 1.12361998 -2.03698002 1.12358996 -2.03701004 0 P 0 ;0
L 1.12358996 -2.03701004 1.12356998 -2.03703996 0 P 0 ;0
L 1.12356998 -2.03703996 1.12236998 -2.03865 0 P 0 ;0
L 1.12236998 -2.03865 1.12233996 -2.03868996 0 P 0 ;0
L 1.12233996 -2.03868996 1.12233002 -2.03871004 0 P 0 ;0
L 1.12233002 -2.03871004 1.12228996 -2.03878002 0 P 0 ;0
L 1.12228996 -2.03878002 1.12121004 -2.04046998 0 P 0 ;0
L 1.12121004 -2.04046998 1.12118996 -2.0405 0 P 0 ;0
L 1.12118996 -2.0405 1.12116998 -2.04053996 0 P 0 ;0
L 1.12116998 -2.04053996 1.12115 -2.04056998 0 P 0 ;0
L 1.12115 -2.04056998 1.12113996 -2.04061004 0 P 0 ;0
L 1.12113996 -2.04061004 1.12018996 -2.04238002 0 P 0 ;0
L 1.12018996 -2.04238002 1.12016004 -2.04245 0 P 0 ;0
L 1.12016004 -2.04245 1.12013996 -2.04248002 0 P 0 ;0
L 1.12013996 -2.04248002 1.12013002 -2.04251004 0 P 0 ;0
L 1.12013002 -2.04251004 1.11926004 -2.04446998 0 P 0 ;0
L 1.11926004 -2.04446998 1.11925 -2.0445 0 P 0 ;0
L 1.11925 -2.0445 1.11923002 -2.04453996 0 P 0 ;0
L 1.11923002 -2.04453996 1.11921998 -2.04458002 0 P 0 ;0
L 1.11921998 -2.04458002 1.11921004 -2.04461004 0 P 0 ;0
L 1.11921004 -2.04461004 1.11848002 -2.04663002 0 P 0 ;0
L 1.11848002 -2.04663002 1.11846998 -2.04666004 0 P 0 ;0
L 1.11846998 -2.04666004 1.11846004 -2.0467 0 P 0 ;0
L 1.11846004 -2.0467 1.11843996 -2.04676998 0 P 0 ;0
L 1.11843996 -2.04676998 1.11786004 -2.04883996 0 P 0 ;0
L 1.11786004 -2.04883996 1.11785 -2.04886998 0 P 0 ;0
L 1.11785 -2.04886998 1.11783996 -2.04891004 0 P 0 ;0
L 1.11783996 -2.04891004 1.11783996 -2.04893996 0 P 0 ;0
L 1.11783996 -2.04893996 1.11783002 -2.04896998 0 P 0 ;0
L 1.11783002 -2.04896998 1.11783002 -2.04898002 0 P 0 ;0
L 1.11783002 -2.04898002 1.1174 -2.05108002 0 P 0 ;0
L 1.1174 -2.05108002 1.1174 -2.05111998 0 P 0 ;0
L 1.1174 -2.05111998 1.11738996 -2.05116004 0 P 0 ;0
L 1.11738996 -2.05116004 1.11738002 -2.05118996 0 P 0 ;0
L 1.11738002 -2.05118996 1.11738002 -2.05123002 0 P 0 ;0
L 1.11738002 -2.05123002 1.11673002 -2.05643002 0 P 0 ;0
L 1.11673002 -2.05643002 1.11671998 -2.05646998 0 P 0 ;0
L 1.11671998 -2.05646998 1.11671998 -2.05655 0 P 0 ;0
L 1.11671998 -2.05655 1.11671004 -2.05658996 0 P 0 ;0
L 1.11671004 -2.05658996 1.11648996 -2.06181998 0 P 0 ;0
L 1.11648996 -2.06181998 1.11648002 -2.06186998 0 P 0 ;0
L 1.11648002 -2.06186998 1.11648002 -2.06195 0 P 0 ;0
L 1.11648002 -2.06195 1.11648996 -2.06198996 0 P 0 ;0
L 1.11648996 -2.06198996 1.11668002 -2.06696998 0 P 0 ;0
L 1.11668002 -2.06696998 1.11768002 -2.06696998 0 P 0 ;0
L 1.11768002 -2.06696998 1.11668002 -2.06701004 0 P 0 ;0
L 1.11668002 -2.06701004 1.11668002 -2.06713002 0 P 0 ;0
L 1.11668002 -2.06713002 1.11668996 -2.06716998 0 P 0 ;0
L 1.11668996 -2.06716998 1.11728002 -2.07215 0 P 0 ;0
L 1.11728002 -2.07215 1.11728996 -2.07218996 0 P 0 ;0
L 1.11728996 -2.07218996 1.11728996 -2.07223002 0 P 0 ;0
L 1.11728996 -2.07223002 1.11731004 -2.07231004 0 P 0 ;0
L 1.11731004 -2.07231004 1.11758996 -2.07371004 0 P 0 ;0
L 1.11758996 -2.07371004 1.1176 -2.07375 0 P 0 ;0
L 1.1176 -2.07375 1.11761004 -2.0738 0 P 0 ;0
L 1.11761004 -2.0738 1.11761998 -2.07383996 0 P 0 ;0
L 1.11761998 -2.07383996 1.11763996 -2.07388002 0 P 0 ;0
L 1.11763996 -2.07388002 1.11803996 -2.07523996 0 P 0 ;0
L 1.11803996 -2.07523996 1.11806004 -2.07531998 0 P 0 ;0
L 1.11806004 -2.07531998 1.11808002 -2.07536004 0 P 0 ;0
L 1.11808002 -2.07536004 1.11808996 -2.07541004 0 P 0 ;0
L 1.11808996 -2.07541004 1.11861004 -2.07673002 0 P 0 ;0
L 1.11861004 -2.07673002 1.11863996 -2.07681004 0 P 0 ;0
L 1.11863996 -2.07681004 1.11866004 -2.07683996 0 P 0 ;0
L 1.11866004 -2.07683996 1.11868002 -2.07688002 0 P 0 ;0
L 1.11868002 -2.07688002 1.11931004 -2.07815 0 P 0 ;0
L 1.11931004 -2.07815 1.11935 -2.07823002 0 P 0 ;0
L 1.11935 -2.07823002 1.1194 -2.0783 0 P 0 ;0
L 1.1194 -2.0783 1.12013996 -2.07951998 0 P 0 ;0
L 1.12013996 -2.07951998 1.12021004 -2.07961998 0 P 0 ;0
L 1.12021004 -2.07961998 1.12023002 -2.07965 0 P 0 ;0
L 1.12023002 -2.07965 1.12023002 -2.07966004 0 P 0 ;0
L 1.12023002 -2.07966004 1.1212 -2.08096998 0 P 0 ;0
L 1.1212 -2.08096998 1.12123996 -2.08103002 0 P 0 ;0
L 1.12123996 -2.08103002 1.12126998 -2.08106004 0 P 0 ;0
L 1.12126998 -2.08106004 1.12128996 -2.08108996 0 P 0 ;0
L 1.12128996 -2.08108996 1.12235 -2.08231004 0 P 0 ;0
L 1.12235 -2.08231004 1.12238002 -2.08233996 0 P 0 ;0
L 1.12238002 -2.08233996 1.1224 -2.08236998 0 P 0 ;0
L 1.1224 -2.08236998 1.12246004 -2.08243002 0 P 0 ;0
L 1.12246004 -2.08243002 1.12361004 -2.08355 0 P 0 ;0
L 1.12361004 -2.08355 1.12366998 -2.08361004 0 P 0 ;0
L 1.12366998 -2.08361004 1.1237 -2.08363002 0 P 0 ;0
L 1.1237 -2.08363002 1.12373002 -2.08366004 0 P 0 ;0
L 1.12373002 -2.08366004 1.12496998 -2.08468996 0 P 0 ;0
L 1.12496998 -2.08468996 1.125 -2.08471004 0 P 0 ;0
L 1.125 -2.08471004 1.12503002 -2.08473996 0 P 0 ;0
L 1.12503002 -2.08473996 1.12506998 -2.08476004 0 P 0 ;0
L 1.12506998 -2.08476004 1.1251 -2.08478996 0 P 0 ;0
L 1.1251 -2.08478996 1.12641998 -2.08571004 0 P 0 ;0
L 1.12641998 -2.08571004 1.12645 -2.08573002 0 P 0 ;0
L 1.12645 -2.08573002 1.12648002 -2.08576004 0 P 0 ;0
L 1.12648002 -2.08576004 1.12651004 -2.08578002 0 P 0 ;0
L 1.12651004 -2.08578002 1.12655 -2.0858 0 P 0 ;0
L 1.12655 -2.0858 1.12793996 -2.08661004 0 P 0 ;0
L 1.12793996 -2.08661004 1.12801004 -2.08665 0 P 0 ;0
L 1.12801004 -2.08665 1.12805 -2.08666998 0 P 0 ;0
L 1.12805 -2.08666998 1.12808002 -2.08668996 0 P 0 ;0
L 1.12808002 -2.08668996 1.12808996 -2.08668996 0 P 0 ;0
L 1.12808996 -2.08668996 1.12953996 -2.08738996 0 P 0 ;0
L 1.12953996 -2.08738996 1.12961998 -2.08743002 0 P 0 ;0
L 1.12961998 -2.08743002 1.12965 -2.08743996 0 P 0 ;0
L 1.12965 -2.08743996 1.1297 -2.08746004 0 P 0 ;0
L 1.1297 -2.08746004 1.13118002 -2.08801998 0 P 0 ;0
L 1.13118002 -2.08801998 1.13133996 -2.08808002 0 P 0 ;0
L 1.13133996 -2.08808002 1.13286998 -2.08851004 0 P 0 ;0
L 1.13286998 -2.08851004 1.13295 -2.08853996 0 P 0 ;0
L 1.13295 -2.08853996 1.13303996 -2.08855 0 P 0 ;0
L 1.13303996 -2.08855 1.1346 -2.08886004 0 P 0 ;0
L 1.1346 -2.08886004 1.13471998 -2.08888996 0 P 0 ;0
L 1.13471998 -2.08888996 1.13476004 -2.08888996 0 P 0 ;0
L 1.13476004 -2.08888996 1.13633996 -2.08906998 0 P 0 ;0
L 1.13633996 -2.08906998 1.13638996 -2.08908002 0 P 0 ;0
L 1.13638996 -2.08908002 1.13651004 -2.08908002 0 P 0 ;0
L 1.13651004 -2.08908002 1.1381 -2.08913002 0 P 0 ;0
L 1.1381 -2.08913002 1.13818996 -2.08913002 0 P 0 ;0
L 1.31623996 -1.98923996 1.3135 -1.98988002 0 P 0 ;0
L 1.3135 -1.98988002 1.31078996 -1.99071004 0 P 0 ;0
L 1.31078996 -1.99071004 1.30813002 -1.99175 0 P 0 ;0
L 1.30813002 -1.99175 1.30553996 -1.99296998 0 P 0 ;0
L 1.30553996 -1.99296998 1.30308996 -1.99431998 0 P 0 ;0
L 1.30308996 -1.99431998 1.30073996 -1.99585 0 P 0 ;0
L 1.30073996 -1.99585 1.29863996 -1.99746004 0 P 0 ;0
L 1.29863996 -1.99746004 1.29666004 -1.99923996 0 P 0 ;0
L 1.29666004 -1.99923996 1.29205 -2.00375 0 P 0 ;0
L 1.29205 -2.00375 1.29205 -1.99243996 0 P 0 ;0
L 1.29205 -1.99243996 1.24316004 -1.99243996 0 P 0 ;0
L 1.24316004 -1.99243996 1.24313996 -2.00521004 0 P 0 ;0
L 1.24313996 -2.00521004 1.24261004 -2.03151004 0 P 0 ;0
L 1.24261004 -2.03151004 1.24086998 -2.07046004 0 P 0 ;0
L 1.24086998 -2.07046004 1.23873996 -2.10921004 0 P 0 ;0
L 1.23873996 -2.10921004 1.23811998 -2.11641998 0 P 0 ;0
L 1.23811998 -2.11641998 1.23711998 -2.12361998 0 P 0 ;0
L 1.23711998 -2.12361998 1.23655 -2.12716004 0 P 0 ;0
L 1.23655 -2.12716004 1.29205 -2.12716004 0 P 0 ;0
L 1.29205 -2.12716004 1.29206998 -2.11766004 0 P 0 ;0
L 1.29206998 -2.11766004 1.29238996 -2.10283996 0 P 0 ;0
L 1.29238996 -2.10283996 1.29336004 -2.08431004 0 P 0 ;0
L 1.29336004 -2.08431004 1.29463996 -2.06673002 0 P 0 ;0
L 1.29463996 -2.06673002 1.29511004 -2.06253002 0 P 0 ;0
L 1.29511004 -2.06253002 1.29583996 -2.05836004 0 P 0 ;0
L 1.29583996 -2.05836004 1.29683002 -2.05446998 0 P 0 ;0
L 1.29683002 -2.05446998 1.29813996 -2.05068996 0 P 0 ;0
L 1.29813996 -2.05068996 1.29978002 -2.04701998 0 P 0 ;0
L 1.29978002 -2.04701998 1.30056998 -2.04556998 0 P 0 ;0
L 1.30056998 -2.04556998 1.30146998 -2.04418996 0 P 0 ;0
L 1.30146998 -2.04418996 1.30246998 -2.04288002 0 P 0 ;0
L 1.30246998 -2.04288002 1.30356998 -2.04165 0 P 0 ;0
L 1.30356998 -2.04165 1.30475 -2.0405 0 P 0 ;0
L 1.30475 -2.0405 1.30603996 -2.03945 0 P 0 ;0
L 1.30603996 -2.03945 1.30773996 -2.03826004 0 P 0 ;0
L 1.30773996 -2.03826004 1.30953002 -2.03723002 0 P 0 ;0
L 1.30953002 -2.03723002 1.31141004 -2.03635 0 P 0 ;0
L 1.31141004 -2.03635 1.31335 -2.03563002 0 P 0 ;0
L 1.31335 -2.03563002 1.31535 -2.03508002 0 P 0 ;0
L 1.31535 -2.03508002 1.31973996 -2.03423002 0 P 0 ;0
L 1.31973996 -2.03423002 1.32416004 -2.03366998 0 P 0 ;0
L 1.32416004 -2.03366998 1.32863002 -2.0334 0 P 0 ;0
L 1.32863002 -2.0334 1.33688002 -2.03318002 0 P 0 ;0
L 1.33688002 -2.03318002 1.33613002 -2.01151004 0 P 0 ;0
L 1.33613002 -2.01151004 1.33581004 -2.00315 0 P 0 ;0
L 1.33581004 -2.00315 1.33543996 -1.99596004 0 P 0 ;0
L 1.33543996 -1.99596004 1.33508002 -1.98971004 0 P 0 ;0
L 1.33508002 -1.98971004 1.33503996 -1.98945 0 P 0 ;0
L 1.33503996 -1.98945 1.335 -1.98931998 0 P 0 ;0
L 1.335 -1.98931998 1.33496004 -1.9892 0 P 0 ;0
L 1.33496004 -1.9892 1.3349 -1.98908002 0 P 0 ;0
L 1.3349 -1.98908002 1.33483996 -1.98896998 0 P 0 ;0
L 1.33483996 -1.98896998 1.33476998 -1.98886004 0 P 0 ;0
L 1.33476998 -1.98886004 1.33468996 -1.98876004 0 P 0 ;0
L 1.33468996 -1.98876004 1.3346 -1.98866998 0 P 0 ;0
L 1.3346 -1.98866998 1.33451004 -1.98858996 0 P 0 ;0
L 1.33451004 -1.98858996 1.3344 -1.98851998 0 P 0 ;0
L 1.3344 -1.98851998 1.3343 -1.98845 0 P 0 ;0
L 1.3343 -1.98845 1.33418002 -1.98838996 0 P 0 ;0
L 1.33418002 -1.98838996 1.33406998 -1.98833996 0 P 0 ;0
L 1.33406998 -1.98833996 1.33395 -1.9883 0 P 0 ;0
L 1.33395 -1.9883 1.33383002 -1.98828002 0 P 0 ;0
L 1.33383002 -1.98828002 1.3337 -1.98826004 0 P 0 ;0
L 1.3337 -1.98826004 1.33356998 -1.98825 0 P 0 ;0
L 1.33356998 -1.98825 1.32756998 -1.98823002 0 P 0 ;0
L 1.32756998 -1.98823002 1.32135 -1.98853996 0 P 0 ;0
L 1.32135 -1.98853996 1.31878996 -1.98881998 0 P 0 ;0
L 1.31878996 -1.98881998 1.31623996 -1.98923996 0 P 0 ;0
L 1.2389 -2.12516004 1.29006004 -2.12516004 0 P 0 ;0
L 1.23906998 -2.12416004 1.29006004 -2.12416004 0 P 0 ;0
L 1.23921004 -2.12316004 1.29006004 -2.12316004 0 P 0 ;0
L 1.23933996 -2.12216004 1.29006004 -2.12216004 0 P 0 ;0
L 1.23948996 -2.12116004 1.29006004 -2.12116004 0 P 0 ;0
L 1.23961998 -2.12016004 1.29006998 -2.12016004 0 P 0 ;0
L 1.23976004 -2.11916004 1.29006998 -2.11916004 0 P 0 ;0
L 1.2399 -2.11816004 1.29006998 -2.11816004 0 P 0 ;0
L 1.24003996 -2.11716004 1.29008002 -2.11716004 0 P 0 ;0
L 1.24015 -2.11616004 1.2901 -2.11616004 0 P 0 ;0
L 1.24023996 -2.11516004 1.29011998 -2.11516004 0 P 0 ;0
L 1.24033002 -2.11416004 1.29013996 -2.11416004 0 P 0 ;0
L 1.24041004 -2.11316004 1.29016004 -2.11316004 0 P 0 ;0
L 1.24048996 -2.11216004 1.29018996 -2.11216004 0 P 0 ;0
L 1.24058002 -2.11116004 1.29021004 -2.11116004 0 P 0 ;0
L 1.24066998 -2.11016004 1.29023002 -2.11016004 0 P 0 ;0
L 1.24075 -2.10916004 1.29025 -2.10916004 0 P 0 ;0
L 1.2408 -2.10816004 1.29026998 -2.10816004 0 P 0 ;0
L 1.24086004 -2.10716004 1.29028996 -2.10716004 0 P 0 ;0
L 1.24091004 -2.10616004 1.29031998 -2.10616004 0 P 0 ;0
L 1.24096998 -2.10516004 1.29033996 -2.10516004 0 P 0 ;0
L 1.24101998 -2.10416004 1.29036004 -2.10416004 0 P 0 ;0
L 1.24108002 -2.10316004 1.29038002 -2.10316004 0 P 0 ;0
L 1.24113002 -2.10216004 1.29041998 -2.10216004 0 P 0 ;0
L 1.24118002 -2.10116004 1.29046998 -2.10116004 0 P 0 ;0
L 1.24123996 -2.10016004 1.29053002 -2.10016004 0 P 0 ;0
L 1.24128996 -2.09916004 1.29058002 -2.09916004 0 P 0 ;0
L 1.24135 -2.09816004 1.29063002 -2.09816004 0 P 0 ;0
L 1.2414 -2.09716004 1.29068002 -2.09716004 0 P 0 ;0
L 1.24146004 -2.09616004 1.29073996 -2.09616004 0 P 0 ;0
L 1.24151004 -2.09516004 1.29078996 -2.09516004 0 P 0 ;0
L 1.24156998 -2.09416004 1.29083996 -2.09416004 0 P 0 ;0
L 1.24161998 -2.09316004 1.2909 -2.09316004 0 P 0 ;0
L 1.24168002 -2.09216004 1.29095 -2.09216004 0 P 0 ;0
L 1.24173002 -2.09116004 1.291 -2.09116004 0 P 0 ;0
L 1.24178996 -2.09016004 1.29105 -2.09016004 0 P 0 ;0
L 1.24183996 -2.08916004 1.2911 -2.08916004 0 P 0 ;0
L 1.2419 -2.08816004 1.29116004 -2.08816004 0 P 0 ;0
L 1.24196004 -2.08716004 1.29121004 -2.08716004 0 P 0 ;0
L 1.24201004 -2.08616004 1.29126998 -2.08616004 0 P 0 ;0
L 1.24206998 -2.08516004 1.29131998 -2.08516004 0 P 0 ;0
L 1.24211998 -2.08416004 1.29136998 -2.08416004 0 P 0 ;0
L 1.2389 -2.12516004 1.2391 -2.12393002 0 P 0 ;0
L 1.2391 -2.12393002 1.2391 -2.1239 0 P 0 ;0
L 1.2391 -2.1239 1.24011004 -2.11665 0 P 0 ;0
L 1.24011004 -2.11665 1.24073002 -2.10935 0 P 0 ;0
L 1.24073002 -2.10935 1.24073996 -2.10931998 0 P 0 ;0
L 1.24073996 -2.10931998 1.24286004 -2.07056004 0 P 0 ;0
L 1.24286004 -2.07056004 1.24461004 -2.03158002 0 P 0 ;0
L 1.24461004 -2.03158002 1.24513996 -2.00523002 0 P 0 ;0
L 1.24513996 -2.00523002 1.24515 -1.99443996 0 P 0 ;0
L 1.24515 -1.99443996 1.29005 -1.99443996 0 P 0 ;0
L 1.29005 -1.99443996 1.29005 -2.00375 0 P 0 ;0
L 1.29005 -2.00375 1.29128002 -2.0056 0 P 0 ;0
L 1.29128002 -2.0056 1.29345 -2.00518002 0 P 0 ;0
L 1.29345 -2.00518002 1.29803002 -2.0007 0 P 0 ;0
L 1.29803002 -2.0007 1.29991998 -1.999 0 P 0 ;0
L 1.29991998 -1.999 1.30188996 -1.99748996 0 P 0 ;0
L 1.30188996 -1.99748996 1.30411998 -1.99603996 0 P 0 ;0
L 1.30411998 -1.99603996 1.30645 -1.99475 0 P 0 ;0
L 1.30645 -1.99475 1.30891998 -1.99358996 0 P 0 ;0
L 1.30891998 -1.99358996 1.31145 -1.9926 0 P 0 ;0
L 1.31145 -1.9926 1.31401998 -1.99181004 0 P 0 ;0
L 1.31401998 -1.99181004 1.31663996 -1.9912 0 P 0 ;0
L 1.31663996 -1.9912 1.31906004 -1.9908 0 P 0 ;0
L 1.31906004 -1.9908 1.32151004 -1.99053002 0 P 0 ;0
L 1.32151004 -1.99053002 1.32761998 -1.99023002 0 P 0 ;0
L 1.32761998 -1.99023002 1.3331 -1.99025 0 P 0 ;0
L 1.3331 -1.99025 1.33345 -1.99608002 0 P 0 ;0
L 1.33345 -1.99608002 1.33381004 -2.00323002 0 P 0 ;0
L 1.33381004 -2.00323002 1.33413002 -2.01158996 0 P 0 ;0
L 1.33413002 -2.01158996 1.33413002 -2.0116 0 P 0 ;0
L 1.33413002 -2.0116 1.33481998 -2.03123002 0 P 0 ;0
L 1.33481998 -2.03123002 1.32853996 -2.0314 0 P 0 ;0
L 1.32853996 -2.0314 1.32398002 -2.03166998 0 P 0 ;0
L 1.32398002 -2.03166998 1.31941998 -2.03225 0 P 0 ;0
L 1.31941998 -2.03225 1.31488996 -2.03313002 0 P 0 ;0
L 1.31488996 -2.03313002 1.31273996 -2.03373002 0 P 0 ;0
L 1.31273996 -2.03373002 1.31063996 -2.0345 0 P 0 ;0
L 1.31063996 -2.0345 1.3086 -2.03545 0 P 0 ;0
L 1.3086 -2.03545 1.30666004 -2.03656998 0 P 0 ;0
L 1.30666004 -2.03656998 1.30658996 -2.03661998 0 P 0 ;0
L 1.30658996 -2.03661998 1.30483002 -2.03786004 0 P 0 ;0
L 1.30483002 -2.03786004 1.30341998 -2.03901004 0 P 0 ;0
L 1.30341998 -2.03901004 1.30336998 -2.03906004 0 P 0 ;0
L 1.30336998 -2.03906004 1.30211998 -2.04026004 0 P 0 ;0
L 1.30211998 -2.04026004 1.30093002 -2.0416 0 P 0 ;0
L 1.30093002 -2.0416 1.29983002 -2.04303996 0 P 0 ;0
L 1.29983002 -2.04303996 1.29978996 -2.0431 0 P 0 ;0
L 1.29978996 -2.0431 1.29885 -2.04453996 0 P 0 ;0
L 1.29885 -2.04453996 1.29798996 -2.04613002 0 P 0 ;0
L 1.29798996 -2.04613002 1.29631998 -2.04986998 0 P 0 ;0
L 1.29631998 -2.04986998 1.29628002 -2.04995 0 P 0 ;0
L 1.29628002 -2.04995 1.29625 -2.05003002 0 P 0 ;0
L 1.29625 -2.05003002 1.29491998 -2.0539 0 P 0 ;0
L 1.29491998 -2.0539 1.29388996 -2.05793996 0 P 0 ;0
L 1.29388996 -2.05793996 1.29386998 -2.05801998 0 P 0 ;0
L 1.29386998 -2.05801998 1.29313996 -2.06221004 0 P 0 ;0
L 1.29313996 -2.06221004 1.29313002 -2.06223996 0 P 0 ;0
L 1.29313002 -2.06223996 1.29311998 -2.0623 0 P 0 ;0
L 1.29311998 -2.0623 1.29265 -2.06655 0 P 0 ;0
L 1.29265 -2.06655 1.29136998 -2.08418996 0 P 0 ;0
L 1.29136998 -2.08418996 1.29038996 -2.10276998 0 P 0 ;0
L 1.29038996 -2.10276998 1.29006998 -2.11763002 0 P 0 ;0
L 1.29006998 -2.11763002 1.29006004 -2.12516004 0 P 0 ;0
L 1.29006004 -2.12516004 1.2389 -2.12516004 0 P 0 ;0
L 1.09846998 -2.00483002 1.21248002 -2.00483002 0 P 0 ;0
L 1.09838002 -2.12083002 1.14708002 -2.12083002 0 P 0 ;0
L 1.11933002 -2.18283002 1.15161998 -2.18283002 0 P 0 ;0
L 1.11001998 -2.18183002 1.15838002 -2.18183002 0 P 0 ;0
L 1.10246998 -2.18083002 1.16333996 -2.18083002 0 P 0 ;0
L 1.04061004 -1.89731004 1.09978002 -1.89731004 0 P 0 ;0
L 1.03565 -1.89631004 1.09821004 -1.89631004 0 P 0 ;0
L 1.03068996 -1.89531004 1.09661004 -1.89531004 0 P 0 ;0
L 1.02573002 -1.89431004 1.09475 -1.89431004 0 P 0 ;0
L 1.019 -1.89331004 1.09288002 -1.89331004 0 P 0 ;0
L 1.01163996 -1.89231004 1.09101998 -1.89231004 0 P 0 ;0
L 0.99518996 -1.89131004 1.08916004 -1.89131004 0 P 0 ;0
L 0.87011998 -1.88331004 1.07278996 -1.88331004 0 P 0 ;0
L 0.86963996 -1.88231004 1.07053002 -1.88231004 0 P 0 ;0
L 0.86916004 -1.88131004 1.06828002 -1.88131004 0 P 0 ;0
L 0.86863002 -1.88031004 1.06603002 -1.88031004 0 P 0 ;0
L 0.86806998 -1.87931004 1.06351004 -1.87931004 0 P 0 ;0
L 0.8675 -1.87831004 1.06076998 -1.87831004 0 P 0 ;0
L 0.86693002 -1.87731004 1.05803996 -1.87731004 0 P 0 ;0
L 0.86631004 -1.87631004 1.05531004 -1.87631004 0 P 0 ;0
L 0.86563996 -1.87531004 1.05256998 -1.87531004 0 P 0 ;0
L 0.86498002 -1.87431004 1.04983996 -1.87431004 0 P 0 ;0
L 0.86431998 -1.87331004 1.0471 -1.87331004 0 P 0 ;0
L 0.86356004 -1.87231004 1.04376004 -1.87231004 0 P 0 ;0
L 0.86278996 -1.87131004 1.04041998 -1.87131004 0 P 0 ;0
L 0.86203002 -1.87031004 1.03708002 -1.87031004 0 P 0 ;0
L 0.86118996 -1.86931004 1.03373996 -1.86931004 0 P 0 ;0
L 0.8603 -1.86831004 1.0304 -1.86831004 0 P 0 ;0
L 0.85941004 -1.86731004 1.02656998 -1.86731004 0 P 0 ;0
L 0.8585 -1.86631004 1.02231998 -1.86631004 0 P 0 ;0
L 0.85756998 -1.86531004 1.01806998 -1.86531004 0 P 0 ;0
L 0.85663002 -1.86431004 1.01381998 -1.86431004 0 P 0 ;0
L 0.85568996 -1.86331004 1.00931998 -1.86331004 0 P 0 ;0
L 0.85481004 -1.86231004 1.00335 -1.86231004 0 P 0 ;0
L 0.85916998 -1.86131004 0.99738002 -1.86131004 0 P 0 ;0
L 0.86716998 -1.86031004 0.99141998 -1.86031004 0 P 0 ;0
L 0.87476998 -1.89731004 0.89943002 -1.89731004 0 P 0 ;0
L 0.87453996 -1.89631004 0.90426004 -1.89631004 0 P 0 ;0
L 0.87431004 -1.89531004 0.9097 -1.89531004 0 P 0 ;0
L 0.87406998 -1.89431004 0.91608002 -1.89431004 0 P 0 ;0
L 0.87383002 -1.89331004 0.92246004 -1.89331004 0 P 0 ;0
L 0.87355 -1.89231004 0.93086004 -1.89231004 0 P 0 ;0
L 0.87323002 -1.89131004 0.95553002 -1.89131004 0 P 0 ;0
L 0.87291004 -1.89031004 1.08728996 -1.89031004 0 P 0 ;0
L 0.87258996 -1.88931004 1.08543002 -1.88931004 0 P 0 ;0
L 0.87223002 -1.88831004 1.08356998 -1.88831004 0 P 0 ;0
L 0.87183002 -1.88731004 1.0817 -1.88731004 0 P 0 ;0
L 0.87143002 -1.88631004 1.07955 -1.88631004 0 P 0 ;0
L 0.87103002 -1.88531004 1.07728996 -1.88531004 0 P 0 ;0
L 0.8706 -1.88431004 1.07503996 -1.88431004 0 P 0 ;0
L 0.87525 -1.85931004 0.98545 -1.85931004 0 P 0 ;0
L 0.88421004 -1.85831004 0.97621004 -1.85831004 0 P 0 ;0
L 0.89393002 -1.85731004 0.96606998 -1.85731004 0 P 0 ;0
L 0.9106 -1.85631004 0.95203002 -1.85631004 0 P 0 ;0
L 1.08716004 -1.91231004 1.12151004 -1.91231004 0 P 0 ;0
L 1.08486004 -1.91131004 1.12018996 -1.91131004 0 P 0 ;0
L 1.08256004 -1.91031004 1.11886004 -1.91031004 0 P 0 ;0
L 1.08023002 -1.90931004 1.11753996 -1.90931004 0 P 0 ;0
L 1.07738002 -1.90831004 1.11621004 -1.90831004 0 P 0 ;0
L 1.07453002 -1.90731004 1.11488996 -1.90731004 0 P 0 ;0
L 1.07168996 -1.90631004 1.11356998 -1.90631004 0 P 0 ;0
L 1.06883996 -1.90531004 1.11223996 -1.90531004 0 P 0 ;0
L 1.066 -1.90431004 1.11076998 -1.90431004 0 P 0 ;0
L 1.06315 -1.90331004 1.1092 -1.90331004 0 P 0 ;0
L 1.0599 -1.90231004 1.10763002 -1.90231004 0 P 0 ;0
L 1.05611998 -1.90131004 1.10606004 -1.90131004 0 P 0 ;0
L 1.05235 -1.90031004 1.10448996 -1.90031004 0 P 0 ;0
L 1.04856998 -1.89931004 1.10291998 -1.89931004 0 P 0 ;0
L 1.04478996 -1.89831004 1.10135 -1.89831004 0 P 0 ;0
L 0.98815 -2.08316004 1.03726998 -2.08316004 0 P 0 ;0
L 0.98818002 -2.08216004 1.03731004 -2.08216004 0 P 0 ;0
L 0.98821998 -2.08116004 1.03735 -2.08116004 0 P 0 ;0
L 0.98825 -2.08016004 1.03738996 -2.08016004 0 P 0 ;0
L 0.98828002 -2.07916004 1.03743002 -2.07916004 0 P 0 ;0
L 0.98831998 -2.07816004 1.03746998 -2.07816004 0 P 0 ;0
L 0.98835 -2.07716004 1.03751004 -2.07716004 0 P 0 ;0
L 0.98838002 -2.07616004 1.03755 -2.07616004 0 P 0 ;0
L 0.98841998 -2.07516004 1.03758002 -2.07516004 0 P 0 ;0
L 0.98845 -2.07416004 1.03761004 -2.07416004 0 P 0 ;0
L 0.98848002 -2.07316004 1.03763996 -2.07316004 0 P 0 ;0
L 0.98851004 -2.07216004 1.03768002 -2.07216004 0 P 0 ;0
L 0.98855 -2.07116004 1.03771004 -2.07116004 0 P 0 ;0
L 0.98858002 -2.07016004 1.03773996 -2.07016004 0 P 0 ;0
L 0.98858996 -2.06916004 1.03776998 -2.06916004 0 P 0 ;0
L 0.98858996 -2.06816004 1.0378 -2.06816004 0 P 0 ;0
L 0.98858996 -2.06716004 1.03783002 -2.06716004 0 P 0 ;0
L 0.98858002 -2.06616004 1.03786004 -2.06616004 0 P 0 ;0
L 0.98856998 -2.06516004 1.0379 -2.06516004 0 P 0 ;0
L 0.98856998 -2.06416004 1.03793002 -2.06416004 0 P 0 ;0
L 0.98856998 -2.06316004 1.03796004 -2.06316004 0 P 0 ;0
L 0.98856004 -2.06216004 1.03798996 -2.06216004 0 P 0 ;0
L 0.98855 -2.06116004 1.03801998 -2.06116004 0 P 0 ;0
L 0.98855 -2.06016004 1.03805 -2.06016004 0 P 0 ;0
L 0.98853996 -2.05916004 1.03808002 -2.05916004 0 P 0 ;0
L 0.98853996 -2.05816004 1.0381 -2.05816004 0 P 0 ;0
L 0.98853002 -2.05716004 1.03811998 -2.05716004 0 P 0 ;0
L 0.98848002 -2.05616004 1.03815 -2.05616004 0 P 0 ;0
L 0.98841004 -2.05516004 1.03818002 -2.05516004 0 P 0 ;0
L 0.98835 -2.05416004 1.0382 -2.05416004 0 P 0 ;0
L 0.98828002 -2.05316004 1.03821998 -2.05316004 0 P 0 ;0
L 0.98821004 -2.05216004 1.03825 -2.05216004 0 P 0 ;0
L 0.98815 -2.05116004 1.03826998 -2.05116004 0 P 0 ;0
L 0.98808996 -2.05016004 1.03828996 -2.05016004 0 P 0 ;0
L 0.98801998 -2.04916004 1.03831998 -2.04916004 0 P 0 ;0
L 0.98796004 -2.04816004 1.03833996 -2.04816004 0 P 0 ;0
L 0.98788996 -2.04716004 1.03836004 -2.04716004 0 P 0 ;0
L 0.98783002 -2.04616004 1.03838996 -2.04616004 0 P 0 ;0
L 0.98768996 -2.04516004 1.0384 -2.04516004 0 P 0 ;0
L 0.98756004 -2.04416004 1.03841004 -2.04416004 0 P 0 ;0
L 0.98738002 -2.04316004 1.03841998 -2.04316004 0 P 0 ;0
L 0.98716004 -2.04216004 1.03843002 -2.04216004 0 P 0 ;0
L 0.98691998 -2.04116004 1.03843996 -2.04116004 0 P 0 ;0
L 0.98661998 -2.04016004 1.03845 -2.04016004 0 P 0 ;0
L 0.98631998 -2.03916004 1.03846004 -2.03916004 0 P 0 ;0
L 0.98593996 -2.03816004 1.03846998 -2.03816004 0 P 0 ;0
L 0.98546998 -2.03716004 1.03848002 -2.03716004 0 P 0 ;0
L 0.98491004 -2.03616004 1.03846998 -2.03616004 0 P 0 ;0
L 0.98425 -2.03516004 1.03846004 -2.03516004 0 P 0 ;0
L 0.98346004 -2.03416004 1.03846004 -2.03416004 0 P 0 ;0
L 0.98251998 -2.03316004 1.03843996 -2.03316004 0 P 0 ;0
L 0.98138002 -2.03216004 1.03843002 -2.03216004 0 P 0 ;0
L 0.97998996 -2.03116004 1.03841998 -2.03116004 0 P 0 ;0
L 0.97813996 -2.03016004 1.03841004 -2.03016004 0 P 0 ;0
L 0.97491004 -2.02916004 1.0384 -2.02916004 0 P 0 ;0
L 0.94763996 -2.00716004 1.03293996 -2.00716004 0 P 0 ;0
L 0.94978996 -2.00616004 1.03231998 -2.00616004 0 P 0 ;0
L 0.95081004 -2.00516004 1.0317 -2.00516004 0 P 0 ;0
L 0.95183002 -2.00416004 1.03098002 -2.00416004 0 P 0 ;0
L 0.95285 -2.00316004 1.03023002 -2.00316004 0 P 0 ;0
L 0.95388996 -2.00216004 1.02936004 -2.00216004 0 P 0 ;0
L 0.95498002 -2.00116004 1.02841998 -2.00116004 0 P 0 ;0
L 0.95621998 -2.00016004 1.02738996 -2.00016004 0 P 0 ;0
L 0.95761998 -1.99916004 1.0262 -1.99916004 0 P 0 ;0
L 0.9592 -1.99816004 1.02486004 -1.99816004 0 P 0 ;0
L 0.96083996 -1.99716004 1.02335 -1.99716004 0 P 0 ;0
L 0.9627 -1.99616004 1.02161004 -1.99616004 0 P 0 ;0
L 0.96468996 -1.99516004 1.01951998 -1.99516004 0 P 0 ;0
L 0.96685 -1.99416004 1.01683002 -1.99416004 0 P 0 ;0
L 0.96936998 -1.99316004 1.01378002 -1.99316004 0 P 0 ;0
L 0.97236998 -1.99216004 1.00981004 -1.99216004 0 P 0 ;0
L 0.97676004 -1.99116004 1.00456998 -1.99116004 0 P 0 ;0
L 1.06713996 -2.08283002 1.12288002 -2.08283002 0 P 0 ;0
L 1.06698996 -2.08183002 1.12193996 -2.08183002 0 P 0 ;0
L 1.06686004 -2.08083002 1.12108996 -2.08083002 0 P 0 ;0
L 1.06673996 -2.07983002 1.12036004 -2.07983002 0 P 0 ;0
L 1.06661998 -2.07883002 1.11971998 -2.07883002 0 P 0 ;0
L 1.06653002 -2.07783002 1.11916004 -2.07783002 0 P 0 ;0
L 1.06648002 -2.07683002 1.11866004 -2.07683002 0 P 0 ;0
L 1.06641998 -2.07583002 1.11826004 -2.07583002 0 P 0 ;0
L 1.06636998 -2.07483002 1.11791998 -2.07483002 0 P 0 ;0
L 1.06631998 -2.07383002 1.11761998 -2.07383002 0 P 0 ;0
L 1.06626004 -2.07283002 1.11741998 -2.07283002 0 P 0 ;0
L 1.06621004 -2.07183002 1.11723996 -2.07183002 0 P 0 ;0
L 1.06616004 -2.07083002 1.11711998 -2.07083002 0 P 0 ;0
L 1.06616004 -2.06983002 1.11701004 -2.06983002 0 P 0 ;0
L 1.06616004 -2.06883002 1.11688996 -2.06883002 0 P 0 ;0
L 1.06616998 -2.06783002 1.11676998 -2.06783002 0 P 0 ;0
L 1.06618002 -2.06683002 1.11666998 -2.06683002 0 P 0 ;0
L 1.06618996 -2.06583002 1.11663002 -2.06583002 0 P 0 ;0
L 1.0662 -2.06483002 1.11658996 -2.06483002 0 P 0 ;0
L 1.06621004 -2.06383002 1.11656004 -2.06383002 0 P 0 ;0
L 1.06623002 -2.06283002 1.11651998 -2.06283002 0 P 0 ;0
L 1.06631004 -2.06183002 1.11648996 -2.06183002 0 P 0 ;0
L 1.06638002 -2.06083002 1.11653002 -2.06083002 0 P 0 ;0
L 1.06645 -2.05983002 1.11656998 -2.05983002 0 P 0 ;0
L 1.06651998 -2.05883002 1.11661998 -2.05883002 0 P 0 ;0
L 1.06658996 -2.05783002 1.11666004 -2.05783002 0 P 0 ;0
L 1.06666998 -2.05683002 1.11671004 -2.05683002 0 P 0 ;0
L 1.06673996 -2.05583002 1.11681004 -2.05583002 0 P 0 ;0
L 1.06686004 -2.05483002 1.11693002 -2.05483002 0 P 0 ;0
L 1.067 -2.05383002 1.11705 -2.05383002 0 P 0 ;0
L 1.06713996 -2.05283002 1.11718002 -2.05283002 0 P 0 ;0
L 1.06728002 -2.05183002 1.11731004 -2.05183002 0 P 0 ;0
L 1.06741998 -2.05083002 1.11746004 -2.05083002 0 P 0 ;0
L 1.06756004 -2.04983002 1.11766004 -2.04983002 0 P 0 ;0
L 1.0677 -2.04883002 1.11786004 -2.04883002 0 P 0 ;0
L 1.06786004 -2.04783002 1.11813996 -2.04783002 0 P 0 ;0
L 1.06806998 -2.04683002 1.11841998 -2.04683002 0 P 0 ;0
L 1.06828002 -2.04583002 1.11876998 -2.04583002 0 P 0 ;0
L 1.06848996 -2.04483002 1.11913002 -2.04483002 0 P 0 ;0
L 1.06871004 -2.04383002 1.11955 -2.04383002 0 P 0 ;0
L 1.06898996 -2.04283002 1.11998996 -2.04283002 0 P 0 ;0
L 1.06928002 -2.04183002 1.12048002 -2.04183002 0 P 0 ;0
L 1.06956004 -2.04083002 1.12101004 -2.04083002 0 P 0 ;0
L 1.06985 -2.03983002 1.12161998 -2.03983002 0 P 0 ;0
L 1.07021004 -2.03883002 1.12225 -2.03883002 0 P 0 ;0
L 1.07056998 -2.03783002 1.12298002 -2.03783002 0 P 0 ;0
L 1.07093002 -2.03683002 1.12373996 -2.03683002 0 P 0 ;0
L 1.07128996 -2.03583002 1.12461998 -2.03583002 0 P 0 ;0
L 1.07173002 -2.03483002 1.12548996 -2.03483002 0 P 0 ;0
L 1.07216998 -2.03383002 1.12646004 -2.03383002 0 P 0 ;0
L 1.07261998 -2.03283002 1.12748996 -2.03283002 0 P 0 ;0
L 1.07308002 -2.03183002 1.12855 -2.03183002 0 P 0 ;0
L 1.07361998 -2.03083002 1.12978996 -2.03083002 0 P 0 ;0
L 1.09761004 -1.91731004 1.12756998 -1.91731004 0 P 0 ;0
L 1.09566004 -1.91631004 1.12645 -1.91631004 0 P 0 ;0
L 1.09371004 -1.91531004 1.12533002 -1.91531004 0 P 0 ;0
L 1.09176004 -1.91431004 1.12416004 -1.91431004 0 P 0 ;0
L 1.08946004 -1.91331004 1.12283996 -1.91331004 0 P 0 ;0
L 1.07415 -2.02983002 1.13101998 -2.02983002 0 P 0 ;0
L 1.07468996 -2.02883002 1.13248996 -2.02883002 0 P 0 ;0
L 1.07528996 -2.02783002 1.134 -2.02783002 0 P 0 ;0
L 1.07591998 -2.02683002 1.13586004 -2.02683002 0 P 0 ;0
L 1.07656004 -2.02583002 1.13828996 -2.02583002 0 P 0 ;0
L 1.07721004 -2.02483002 1.14243002 -2.02483002 0 P 0 ;0
L 1.07795 -2.02383002 1.21126998 -2.02383002 0 P 0 ;0
L 1.07868002 -2.02283002 1.21133002 -2.02283002 0 P 0 ;0
L 1.07941998 -2.02183002 1.2114 -2.02183002 0 P 0 ;0
L 1.08021004 -2.02083002 1.21146004 -2.02083002 0 P 0 ;0
L 1.08103996 -2.01983002 1.21153002 -2.01983002 0 P 0 ;0
L 1.08186998 -2.01883002 1.2116 -2.01883002 0 P 0 ;0
L 1.08273002 -2.01783002 1.21166004 -2.01783002 0 P 0 ;0
L 1.08366998 -2.01683002 1.21173002 -2.01683002 0 P 0 ;0
L 1.0846 -2.01583002 1.2118 -2.01583002 0 P 0 ;0
L 1.08555 -2.01483002 1.21186004 -2.01483002 0 P 0 ;0
L 1.08661004 -2.01383002 1.21193002 -2.01383002 0 P 0 ;0
L 1.08766998 -2.01283002 1.21198996 -2.01283002 0 P 0 ;0
L 1.08873002 -2.01183002 1.21205 -2.01183002 0 P 0 ;0
L 1.0898 -2.01083002 1.21211998 -2.01083002 0 P 0 ;0
L 1.09098996 -2.00983002 1.21218002 -2.00983002 0 P 0 ;0
L 1.09225 -2.00883002 1.21223996 -2.00883002 0 P 0 ;0
L 1.09358996 -2.00783002 1.2123 -2.00783002 0 P 0 ;0
L 1.09506998 -2.00683002 1.21236004 -2.00683002 0 P 0 ;0
L 1.09668996 -2.00583002 1.21241998 -2.00583002 0 P 0 ;0
L 0.98546998 -2.12516004 1.03548996 -2.12516004 0 P 0 ;0
L 0.98558996 -2.12416004 1.03553996 -2.12416004 0 P 0 ;0
L 0.9857 -2.12316004 1.03558002 -2.12316004 0 P 0 ;0
L 0.98581004 -2.12216004 1.03561998 -2.12216004 0 P 0 ;0
L 0.98591004 -2.12116004 1.03566998 -2.12116004 0 P 0 ;0
L 0.98598996 -2.12016004 1.03571004 -2.12016004 0 P 0 ;0
L 0.98608002 -2.11916004 1.03575 -2.11916004 0 P 0 ;0
L 0.98616998 -2.11816004 1.0358 -2.11816004 0 P 0 ;0
L 0.98625 -2.11716004 1.03583996 -2.11716004 0 P 0 ;0
L 0.98633996 -2.11616004 1.03588002 -2.11616004 0 P 0 ;0
L 0.98641998 -2.11516004 1.03593002 -2.11516004 0 P 0 ;0
L 0.98651004 -2.11416004 1.03596998 -2.11416004 0 P 0 ;0
L 0.9866 -2.11316004 1.03601004 -2.11316004 0 P 0 ;0
L 0.98668002 -2.11216004 1.03605 -2.11216004 0 P 0 ;0
L 0.98676998 -2.11116004 1.0361 -2.11116004 0 P 0 ;0
L 0.98685 -2.11016004 1.03613996 -2.11016004 0 P 0 ;0
L 0.98693996 -2.10916004 1.03618002 -2.10916004 0 P 0 ;0
L 0.987 -2.10816004 1.03623002 -2.10816004 0 P 0 ;0
L 0.98705 -2.10716004 1.03626998 -2.10716004 0 P 0 ;0
L 0.9871 -2.10616004 1.03631004 -2.10616004 0 P 0 ;0
L 0.98716004 -2.10516004 1.03636004 -2.10516004 0 P 0 ;0
L 0.9872 -2.10416004 1.0364 -2.10416004 0 P 0 ;0
L 0.98725 -2.10316004 1.03643996 -2.10316004 0 P 0 ;0
L 0.98731004 -2.10216004 1.03648002 -2.10216004 0 P 0 ;0
L 0.98735 -2.10116004 1.03653002 -2.10116004 0 P 0 ;0
L 0.9874 -2.10016004 1.03656998 -2.10016004 0 P 0 ;0
L 0.98746004 -2.09916004 1.03661004 -2.09916004 0 P 0 ;0
L 0.98751004 -2.09816004 1.03666004 -2.09816004 0 P 0 ;0
L 0.98755 -2.09716004 1.0367 -2.09716004 0 P 0 ;0
L 0.9876 -2.09616004 1.03673996 -2.09616004 0 P 0 ;0
L 0.98766004 -2.09516004 1.03678996 -2.09516004 0 P 0 ;0
L 0.9877 -2.09416004 1.03683002 -2.09416004 0 P 0 ;0
L 0.98775 -2.09316004 1.03686998 -2.09316004 0 P 0 ;0
L 0.98781004 -2.09216004 1.03691998 -2.09216004 0 P 0 ;0
L 0.98785 -2.09116004 1.03696004 -2.09116004 0 P 0 ;0
L 0.9879 -2.09016004 1.037 -2.09016004 0 P 0 ;0
L 0.98796004 -2.08916004 1.03703996 -2.08916004 0 P 0 ;0
L 0.98798996 -2.08816004 1.03706998 -2.08816004 0 P 0 ;0
L 0.98801998 -2.08716004 1.03711004 -2.08716004 0 P 0 ;0
L 0.98805 -2.08616004 1.03715 -2.08616004 0 P 0 ;0
L 0.98808996 -2.08516004 1.03718996 -2.08516004 0 P 0 ;0
L 0.98811998 -2.08416004 1.03723002 -2.08416004 0 P 0 ;0
L 1.08216998 -2.15683002 1.19803996 -2.15683002 0 P 0 ;0
L 1.0821 -2.15583002 1.19861004 -2.15583002 0 P 0 ;0
L 1.08201998 -2.15483002 1.19918002 -2.15483002 0 P 0 ;0
L 1.08195 -2.15383002 1.1997 -2.15383002 0 P 0 ;0
L 1.08188996 -2.15283002 1.20018002 -2.15283002 0 P 0 ;0
L 1.08183002 -2.15183002 1.20066004 -2.15183002 0 P 0 ;0
L 1.08176998 -2.15083002 1.20113996 -2.15083002 0 P 0 ;0
L 1.08171998 -2.14983002 1.20153996 -2.14983002 0 P 0 ;0
L 1.08166004 -2.14883002 1.20193002 -2.14883002 0 P 0 ;0
L 1.0816 -2.14783002 1.11538996 -2.14783002 0 P 0 ;0
L 1.08155 -2.14683002 1.10903002 -2.14683002 0 P 0 ;0
L 1.0815 -2.14583002 1.10415 -2.14583002 0 P 0 ;0
L 1.08146004 -2.14483002 1.09953002 -2.14483002 0 P 0 ;0
L 1.08141004 -2.14383002 1.09563996 -2.14383002 0 P 0 ;0
L 1.08136004 -2.14283002 1.09183996 -2.14283002 0 P 0 ;0
L 1.08131004 -2.14183002 1.08821004 -2.14183002 0 P 0 ;0
L 1.08133002 -2.14083002 1.08471998 -2.14083002 0 P 0 ;0
L 1.09586998 -2.11983002 1.14965 -2.11983002 0 P 0 ;0
L 1.09361998 -2.11883002 1.15221998 -2.11883002 0 P 0 ;0
L 1.09158996 -2.11783002 1.20595 -2.11783002 0 P 0 ;0
L 1.08988002 -2.11683002 1.20601004 -2.11683002 0 P 0 ;0
L 1.08823996 -2.11583002 1.20606998 -2.11583002 0 P 0 ;0
L 1.08678996 -2.11483002 1.20613002 -2.11483002 0 P 0 ;0
L 1.08541004 -2.11383002 1.20618996 -2.11383002 0 P 0 ;0
L 1.08416998 -2.11283002 1.20625 -2.11283002 0 P 0 ;0
L 1.08295 -2.11183002 1.20631004 -2.11183002 0 P 0 ;0
L 1.08188002 -2.11083002 1.20638002 -2.11083002 0 P 0 ;0
L 1.08081998 -2.10983002 1.20643996 -2.10983002 0 P 0 ;0
L 1.07986004 -2.10883002 1.2065 -2.10883002 0 P 0 ;0
L 1.07895 -2.10783002 1.20656004 -2.10783002 0 P 0 ;0
L 1.07803002 -2.10683002 1.20661998 -2.10683002 0 P 0 ;0
L 1.07723996 -2.10583002 1.20666998 -2.10583002 0 P 0 ;0
L 1.07646004 -2.10483002 1.20671998 -2.10483002 0 P 0 ;0
L 1.07568002 -2.10383002 1.20678002 -2.10383002 0 P 0 ;0
L 1.075 -2.10283002 1.20683002 -2.10283002 0 P 0 ;0
L 1.07433002 -2.10183002 1.20688002 -2.10183002 0 P 0 ;0
L 1.07366998 -2.10083002 1.20693996 -2.10083002 0 P 0 ;0
L 1.07308996 -2.09983002 1.20698996 -2.09983002 0 P 0 ;0
L 1.07253002 -2.09883002 1.20705 -2.09883002 0 P 0 ;0
L 1.07198002 -2.09783002 1.2071 -2.09783002 0 P 0 ;0
L 1.07146998 -2.09683002 1.20715 -2.09683002 0 P 0 ;0
L 1.07101998 -2.09583002 1.2072 -2.09583002 0 P 0 ;0
L 1.07056998 -2.09483002 1.20726004 -2.09483002 0 P 0 ;0
L 1.07013002 -2.09383002 1.20731004 -2.09383002 0 P 0 ;0
L 1.06976998 -2.09283002 1.20736004 -2.09283002 0 P 0 ;0
L 1.06941998 -2.09183002 1.20741998 -2.09183002 0 P 0 ;0
L 1.06906004 -2.09083002 1.20746998 -2.09083002 0 P 0 ;0
L 1.06876004 -2.08983002 1.20753002 -2.08983002 0 P 0 ;0
L 1.06848996 -2.08883002 1.13443002 -2.08883002 0 P 0 ;0
L 1.06821998 -2.08783002 1.13068002 -2.08783002 0 P 0 ;0
L 1.06795 -2.08683002 1.12836998 -2.08683002 0 P 0 ;0
L 1.06771998 -2.08583002 1.1266 -2.08583002 0 P 0 ;0
L 1.06753002 -2.08483002 1.12516004 -2.08483002 0 P 0 ;0
L 1.06733002 -2.08383002 1.12393996 -2.08383002 0 P 0 ;0
L 0.90273996 -1.85456998 0.89068996 -1.85558002 0 P 0 ;0
L 0.89068996 -1.85558002 0.87421004 -1.85741998 0 P 0 ;0
L 0.87421004 -1.85741998 0.85783002 -1.85946998 0 P 0 ;0
L 0.85783002 -1.85946998 0.85526998 -1.8599 0 P 0 ;0
L 0.85526998 -1.8599 0.85276004 -1.86055 0 P 0 ;0
L 0.85276004 -1.86055 0.85255 -1.86063996 0 P 0 ;0
L 0.85255 -1.86063996 0.85248996 -1.86068996 0 P 0 ;0
L 0.85248996 -1.86068996 0.85243002 -1.86073002 0 P 0 ;0
L 0.85243002 -1.86073002 0.85238002 -1.86078002 0 P 0 ;0
L 0.85238002 -1.86078002 0.85233002 -1.86083996 0 P 0 ;0
L 0.85233002 -1.86083996 0.85225 -1.86096004 0 P 0 ;0
L 0.85225 -1.86096004 0.85218002 -1.8611 0 P 0 ;0
L 0.85218002 -1.8611 0.85216004 -1.86116998 0 P 0 ;0
L 0.85216004 -1.86116998 0.85215 -1.86123996 0 P 0 ;0
L 0.85215 -1.86123996 0.85213996 -1.86136998 0 P 0 ;0
L 0.85213996 -1.86136998 0.85213002 -1.86148996 0 P 0 ;0
L 0.85213002 -1.86148996 0.85213996 -1.86161998 0 P 0 ;0
L 0.85213996 -1.86161998 0.85215 -1.86173996 0 P 0 ;0
L 0.85215 -1.86173996 0.85218002 -1.86186998 0 P 0 ;0
L 0.85218002 -1.86186998 0.85221004 -1.86198996 0 P 0 ;0
L 0.85221004 -1.86198996 0.85225 -1.8621 0 P 0 ;0
L 0.85225 -1.8621 0.85231004 -1.86221998 0 P 0 ;0
L 0.85231004 -1.86221998 0.85236998 -1.86233002 0 P 0 ;0
L 0.85236998 -1.86233002 0.85281998 -1.863 0 P 0 ;0
L 0.85281998 -1.863 0.8533 -1.86363996 0 P 0 ;0
L 0.8533 -1.86363996 0.85383002 -1.86425 0 P 0 ;0
L 0.85383002 -1.86425 0.85736004 -1.86801998 0 P 0 ;0
L 0.85736004 -1.86801998 0.86013002 -1.87113002 0 P 0 ;0
L 0.86013002 -1.87113002 0.86266004 -1.87443002 0 P 0 ;0
L 0.86266004 -1.87443002 0.86501004 -1.87798996 0 P 0 ;0
L 0.86501004 -1.87798996 0.86711998 -1.88171004 0 P 0 ;0
L 0.86711998 -1.88171004 0.86896998 -1.88553996 0 P 0 ;0
L 0.86896998 -1.88553996 0.87055 -1.8895 0 P 0 ;0
L 0.87055 -1.8895 0.8718 -1.89343002 0 P 0 ;0
L 0.8718 -1.89343002 0.87276004 -1.89745 0 P 0 ;0
L 0.87276004 -1.89745 0.87371004 -1.90195 0 P 0 ;0
L 0.87371004 -1.90195 0.87383002 -1.90236004 0 P 0 ;0
L 0.87383002 -1.90236004 0.87396998 -1.90276004 0 P 0 ;0
L 0.87396998 -1.90276004 0.87416004 -1.90313996 0 P 0 ;0
L 0.87416004 -1.90313996 0.87436998 -1.90351004 0 P 0 ;0
L 0.87436998 -1.90351004 0.87443002 -1.9036 0 P 0 ;0
L 0.87443002 -1.9036 0.87456998 -1.90376004 0 P 0 ;0
L 0.87456998 -1.90376004 0.87465 -1.90381998 0 P 0 ;0
L 0.87465 -1.90381998 0.87473002 -1.90388996 0 P 0 ;0
L 0.87473002 -1.90388996 0.87481998 -1.90393996 0 P 0 ;0
L 0.87481998 -1.90393996 0.87491998 -1.90398996 0 P 0 ;0
L 0.87491998 -1.90398996 0.87501004 -1.90403002 0 P 0 ;0
L 0.87501004 -1.90403002 0.87521004 -1.90408996 0 P 0 ;0
L 0.87521004 -1.90408996 0.87531998 -1.9041 0 P 0 ;0
L 0.87531998 -1.9041 0.87573002 -1.90413002 0 P 0 ;0
L 0.87573002 -1.90413002 0.87613996 -1.90411998 0 P 0 ;0
L 0.87613996 -1.90411998 0.87653996 -1.90408002 0 P 0 ;0
L 0.87653996 -1.90408002 0.87695 -1.90401004 0 P 0 ;0
L 0.87695 -1.90401004 0.90756004 -1.89766998 0 P 0 ;0
L 0.90756004 -1.89766998 0.92603996 -1.89478002 0 P 0 ;0
L 0.92603996 -1.89478002 0.93486004 -1.89393996 0 P 0 ;0
L 0.93486004 -1.89393996 0.94371004 -1.8935 0 P 0 ;0
L 0.94371004 -1.8935 0.97045 -1.89308002 0 P 0 ;0
L 0.97045 -1.89308002 0.99468996 -1.89328996 0 P 0 ;0
L 0.99468996 -1.89328996 1.01021004 -1.89413996 0 P 0 ;0
L 1.01021004 -1.89413996 1.0241 -1.89601998 0 P 0 ;0
L 1.0241 -1.89601998 1.04188002 -1.89961004 0 P 0 ;0
L 1.04188002 -1.89961004 1.06095 -1.90466004 0 P 0 ;0
L 1.06095 -1.90466004 1.07963996 -1.91123002 0 P 0 ;0
L 1.07963996 -1.91123002 1.09093996 -1.91613002 0 P 0 ;0
L 1.09093996 -1.91613002 1.10186998 -1.92175 0 P 0 ;0
L 1.10186998 -1.92175 1.11243996 -1.92806998 0 P 0 ;0
L 1.11243996 -1.92806998 1.12163002 -1.93446998 0 P 0 ;0
L 1.12163002 -1.93446998 1.13033002 -1.94148996 0 P 0 ;0
L 1.13033002 -1.94148996 1.1385 -1.94911004 0 P 0 ;0
L 1.1385 -1.94911004 1.14358996 -1.9546 0 P 0 ;0
L 1.14358996 -1.9546 1.14825 -1.96045 0 P 0 ;0
L 1.14825 -1.96045 1.15246998 -1.96663002 0 P 0 ;0
L 1.15246998 -1.96663002 1.15623002 -1.97316004 0 P 0 ;0
L 1.15623002 -1.97316004 1.15895 -1.97831004 0 P 0 ;0
L 1.15895 -1.97831004 1.17358996 -1.97831004 0 P 0 ;0
L 1.17358996 -1.97831004 1.17135 -1.9726 0 P 0 ;0
L 1.17135 -1.9726 1.16696004 -1.96266998 0 P 0 ;0
L 1.16696004 -1.96266998 1.16171998 -1.95313002 0 P 0 ;0
L 1.16171998 -1.95313002 1.1557 -1.94406998 0 P 0 ;0
L 1.1557 -1.94406998 1.14885 -1.93548002 0 P 0 ;0
L 1.14885 -1.93548002 1.13778996 -1.92378002 0 P 0 ;0
L 1.13778996 -1.92378002 1.12576998 -1.91301998 0 P 0 ;0
L 1.12576998 -1.91301998 1.11283996 -1.90326004 0 P 0 ;0
L 1.11283996 -1.90326004 1.09783002 -1.89368996 0 P 0 ;0
L 1.09783002 -1.89368996 1.08213002 -1.88526998 0 P 0 ;0
L 1.08213002 -1.88526998 1.06576998 -1.87801004 0 P 0 ;0
L 1.06576998 -1.87801004 1.04776004 -1.87141998 0 P 0 ;0
L 1.04776004 -1.87141998 1.02938002 -1.86591998 0 P 0 ;0
L 1.02938002 -1.86591998 1.01058002 -1.8615 0 P 0 ;0
L 1.01058002 -1.8615 0.98441998 -1.85711004 0 P 0 ;0
L 0.98441998 -1.85711004 0.95781004 -1.85448996 0 P 0 ;0
L 0.95781004 -1.85448996 0.93061004 -1.85366004 0 P 0 ;0
L 0.93061004 -1.85366004 0.90273996 -1.85456998 0 P 0 ;0
L 1.16015 -1.97631004 1.15798002 -1.97218996 0 P 0 ;0
L 1.15798002 -1.97218996 1.15796004 -1.97216004 0 P 0 ;0
L 1.15796004 -1.97216004 1.15416004 -1.96556998 0 P 0 ;0
L 1.15416004 -1.96556998 1.15411998 -1.96551004 0 P 0 ;0
L 1.15411998 -1.96551004 1.14986004 -1.95926004 0 P 0 ;0
L 1.14986004 -1.95926004 1.14981998 -1.95921004 0 P 0 ;0
L 1.14981998 -1.95921004 1.14511004 -1.9533 0 P 0 ;0
L 1.14511004 -1.9533 1.13991998 -1.9477 0 P 0 ;0
L 1.13991998 -1.9477 1.13986004 -1.94765 0 P 0 ;0
L 1.13986004 -1.94765 1.13163996 -1.93998002 0 P 0 ;0
L 1.13163996 -1.93998002 1.12283002 -1.93286004 0 P 0 ;0
L 1.12283002 -1.93286004 1.11351998 -1.92638996 0 P 0 ;0
L 1.11351998 -1.92638996 1.10283996 -1.92 0 P 0 ;0
L 1.10283996 -1.92 1.0918 -1.91433002 0 P 0 ;0
L 1.0918 -1.91433002 1.08036998 -1.90936004 0 P 0 ;0
L 1.08036998 -1.90936004 1.06153002 -1.90273996 0 P 0 ;0
L 1.06153002 -1.90273996 1.06146004 -1.90273002 0 P 0 ;0
L 1.06146004 -1.90273002 1.04233002 -1.89766004 0 P 0 ;0
L 1.04233002 -1.89766004 1.02443002 -1.89405 0 P 0 ;0
L 1.02443002 -1.89405 1.0104 -1.89213996 0 P 0 ;0
L 1.0104 -1.89213996 0.99475 -1.89128996 0 P 0 ;0
L 0.99475 -1.89128996 0.97045 -1.89108002 0 P 0 ;0
L 0.97045 -1.89108002 0.94365 -1.8915 0 P 0 ;0
L 0.94365 -1.8915 0.94361998 -1.8915 0 P 0 ;0
L 0.94361998 -1.8915 0.93471998 -1.89195 0 P 0 ;0
L 0.93471998 -1.89195 0.92578996 -1.89278996 0 P 0 ;0
L 0.92578996 -1.89278996 0.9072 -1.89571004 0 P 0 ;0
L 0.9072 -1.89571004 0.87656998 -1.90203996 0 P 0 ;0
L 0.87656998 -1.90203996 0.87626998 -1.9021 0 P 0 ;0
L 0.87626998 -1.9021 0.87601998 -1.90211998 0 P 0 ;0
L 0.87601998 -1.90211998 0.87588996 -1.90213002 0 P 0 ;0
L 0.87588996 -1.90213002 0.87583002 -1.90198996 0 P 0 ;0
L 0.87583002 -1.90198996 0.87573002 -1.90175 0 P 0 ;0
L 0.87573002 -1.90175 0.87566004 -1.90146998 0 P 0 ;0
L 0.87566004 -1.90146998 0.87471004 -1.89701004 0 P 0 ;0
L 0.87471004 -1.89701004 0.8747 -1.89698996 0 P 0 ;0
L 0.8747 -1.89698996 0.87373002 -1.89288996 0 P 0 ;0
L 0.87373002 -1.89288996 0.87243002 -1.88881998 0 P 0 ;0
L 0.87243002 -1.88881998 0.8724 -1.88876004 0 P 0 ;0
L 0.8724 -1.88876004 0.8708 -1.88473996 0 P 0 ;0
L 0.8708 -1.88473996 0.8689 -1.88078002 0 P 0 ;0
L 0.8689 -1.88078002 0.86671998 -1.87693996 0 P 0 ;0
L 0.86671998 -1.87693996 0.86428996 -1.87326004 0 P 0 ;0
L 0.86428996 -1.87326004 0.86166998 -1.86985 0 P 0 ;0
L 0.86166998 -1.86985 0.85883996 -1.86668002 0 P 0 ;0
L 0.85883996 -1.86668002 0.85883002 -1.86666004 0 P 0 ;0
L 0.85883002 -1.86666004 0.85531998 -1.86291004 0 P 0 ;0
L 0.85531998 -1.86291004 0.85486004 -1.86238002 0 P 0 ;0
L 0.85486004 -1.86238002 0.85466004 -1.86211998 0 P 0 ;0
L 0.85466004 -1.86211998 0.8557 -1.86186004 0 P 0 ;0
L 0.8557 -1.86186004 0.85811998 -1.86145 0 P 0 ;0
L 0.85811998 -1.86145 0.87443996 -1.85941004 0 P 0 ;0
L 0.87443996 -1.85941004 0.89088996 -1.85756998 0 P 0 ;0
L 0.89088996 -1.85756998 0.90286004 -1.85656998 0 P 0 ;0
L 0.90286004 -1.85656998 0.93061004 -1.85566004 0 P 0 ;0
L 0.93061004 -1.85566004 0.95768002 -1.85648996 0 P 0 ;0
L 0.95768002 -1.85648996 0.98416004 -1.8591 0 P 0 ;0
L 0.98416004 -1.8591 1.01018996 -1.86346004 0 P 0 ;0
L 1.01018996 -1.86346004 1.02886004 -1.86785 0 P 0 ;0
L 1.02886004 -1.86785 1.04711998 -1.87331998 0 P 0 ;0
L 1.04711998 -1.87331998 1.06501004 -1.87986004 0 P 0 ;0
L 1.06501004 -1.87986004 1.08125 -1.88706998 0 P 0 ;0
L 1.08125 -1.88706998 1.09681004 -1.89541998 0 P 0 ;0
L 1.09681004 -1.89541998 1.1117 -1.9049 0 P 0 ;0
L 1.1117 -1.9049 1.1245 -1.91456998 0 P 0 ;0
L 1.1245 -1.91456998 1.13638996 -1.92521004 0 P 0 ;0
L 1.13638996 -1.92521004 1.14733996 -1.93678996 0 P 0 ;0
L 1.14733996 -1.93678996 1.15408002 -1.94525 0 P 0 ;0
L 1.15408002 -1.94525 1.16001004 -1.95416998 0 P 0 ;0
L 1.16001004 -1.95416998 1.16516004 -1.96355 0 P 0 ;0
L 1.16516004 -1.96355 1.1695 -1.97336998 0 P 0 ;0
L 1.1695 -1.97336998 1.17066004 -1.97631004 0 P 0 ;0
L 1.17066004 -1.97631004 1.16015 -1.97631004 0 P 0 ;0
L 0.87563002 -1.90131004 0.8801 -1.90131004 0 P 0 ;0
L 0.87541004 -1.90031004 0.88493996 -1.90031004 0 P 0 ;0
L 0.8752 -1.89931004 0.88976998 -1.89931004 0 P 0 ;0
L 0.87498996 -1.89831004 0.8946 -1.89831004 0 P 0 ;0
L 0.89423002 -2.08316004 0.94355 -2.08316004 0 P 0 ;0
L 0.89428996 -2.08216004 0.9436 -2.08216004 0 P 0 ;0
L 0.89435 -2.08116004 0.94365 -2.08116004 0 P 0 ;0
L 0.89441004 -2.08016004 0.9437 -2.08016004 0 P 0 ;0
L 0.89446004 -2.07916004 0.94375 -2.07916004 0 P 0 ;0
L 0.89451998 -2.07816004 0.94378996 -2.07816004 0 P 0 ;0
L 0.89458002 -2.07716004 0.94383996 -2.07716004 0 P 0 ;0
L 0.89463996 -2.07616004 0.94388996 -2.07616004 0 P 0 ;0
L 0.8947 -2.07516004 0.94393996 -2.07516004 0 P 0 ;0
L 0.89475 -2.07416004 0.94398002 -2.07416004 0 P 0 ;0
L 0.89481004 -2.07316004 0.94403002 -2.07316004 0 P 0 ;0
L 0.89486998 -2.07216004 0.94408002 -2.07216004 0 P 0 ;0
L 0.89493002 -2.07116004 0.94415 -2.07116004 0 P 0 ;0
L 0.89498996 -2.07016004 0.94426004 -2.07016004 0 P 0 ;0
L 0.89505 -2.06916004 0.94436998 -2.06916004 0 P 0 ;0
L 0.8951 -2.06816004 0.94448002 -2.06816004 0 P 0 ;0
L 0.89516004 -2.06716004 0.94458996 -2.06716004 0 P 0 ;0
L 0.89521998 -2.06616004 0.9447 -2.06616004 0 P 0 ;0
L 0.89526998 -2.06516004 0.94481004 -2.06516004 0 P 0 ;0
L 0.89531004 -2.06416004 0.94491998 -2.06416004 0 P 0 ;0
L 0.89535 -2.06316004 0.94503002 -2.06316004 0 P 0 ;0
L 0.8954 -2.06216004 0.94513996 -2.06216004 0 P 0 ;0
L 0.89543996 -2.06116004 0.94531998 -2.06116004 0 P 0 ;0
L 0.89548996 -2.06016004 0.94551004 -2.06016004 0 P 0 ;0
L 0.89553002 -2.05916004 0.9457 -2.05916004 0 P 0 ;0
L 0.89558002 -2.05816004 0.94588996 -2.05816004 0 P 0 ;0
L 0.89561998 -2.05716004 0.94608002 -2.05716004 0 P 0 ;0
L 0.89566998 -2.05616004 0.94626998 -2.05616004 0 P 0 ;0
L 0.89571004 -2.05516004 0.94646998 -2.05516004 0 P 0 ;0
L 0.89575 -2.05416004 0.94666004 -2.05416004 0 P 0 ;0
L 0.8958 -2.05316004 0.94685 -2.05316004 0 P 0 ;0
L 0.89583996 -2.05216004 0.94708002 -2.05216004 0 P 0 ;0
L 0.89588996 -2.05116004 0.94735 -2.05116004 0 P 0 ;0
L 0.89593996 -2.05016004 0.94761998 -2.05016004 0 P 0 ;0
L 0.89598002 -2.04916004 0.9479 -2.04916004 0 P 0 ;0
L 0.89601998 -2.04816004 0.94825 -2.04816004 0 P 0 ;0
L 0.89606998 -2.04716004 0.94858996 -2.04716004 0 P 0 ;0
L 0.89611004 -2.04616004 0.94893002 -2.04616004 0 P 0 ;0
L 0.89616004 -2.04516004 0.94935 -2.04516004 0 P 0 ;0
L 0.8962 -2.04416004 0.94976998 -2.04416004 0 P 0 ;0
L 0.89625 -2.04316004 0.9502 -2.04316004 0 P 0 ;0
L 0.89628002 -2.04216004 0.95068996 -2.04216004 0 P 0 ;0
L 0.89631004 -2.04116004 0.95118996 -2.04116004 0 P 0 ;0
L 0.89633996 -2.04016004 0.95168996 -2.04016004 0 P 0 ;0
L 0.89638002 -2.03916004 0.95228002 -2.03916004 0 P 0 ;0
L 0.89641004 -2.03816004 0.95291004 -2.03816004 0 P 0 ;0
L 0.89643996 -2.03716004 0.95363002 -2.03716004 0 P 0 ;0
L 0.89646998 -2.03616004 0.95445 -2.03616004 0 P 0 ;0
L 0.89651004 -2.03516004 0.95535 -2.03516004 0 P 0 ;0
L 0.89653996 -2.03416004 0.95636998 -2.03416004 0 P 0 ;0
L 0.89656998 -2.03316004 0.95756998 -2.03316004 0 P 0 ;0
L 0.8966 -2.03216004 0.95893996 -2.03216004 0 P 0 ;0
L 0.89663996 -2.03116004 0.96055 -2.03116004 0 P 0 ;0
L 0.89666998 -2.03016004 0.96278002 -2.03016004 0 P 0 ;0
L 0.8967 -2.02916004 0.96676004 -2.02916004 0 P 0 ;0
L 0.89673996 -2.02816004 1.03838996 -2.02816004 0 P 0 ;0
L 0.89676998 -2.02716004 1.03838002 -2.02716004 0 P 0 ;0
L 0.8968 -2.02616004 1.03833996 -2.02616004 0 P 0 ;0
L 0.89683996 -2.02516004 1.03828996 -2.02516004 0 P 0 ;0
L 0.89686998 -2.02416004 1.03823002 -2.02416004 0 P 0 ;0
L 0.8969 -2.02316004 1.03816004 -2.02316004 0 P 0 ;0
L 0.89693996 -2.02216004 1.0381 -2.02216004 0 P 0 ;0
L 0.89696998 -2.02116004 1.03803996 -2.02116004 0 P 0 ;0
L 0.897 -2.02016004 1.0379 -2.02016004 0 P 0 ;0
L 0.89703002 -2.01916004 1.03773996 -2.01916004 0 P 0 ;0
L 0.89706004 -2.01816004 1.03751998 -2.01816004 0 P 0 ;0
L 0.89708996 -2.01716004 1.03728002 -2.01716004 0 P 0 ;0
L 0.89711998 -2.01616004 1.03698996 -2.01616004 0 P 0 ;0
L 0.89713996 -2.01516004 1.03668002 -2.01516004 0 P 0 ;0
L 0.89716998 -2.01416004 1.03631004 -2.01416004 0 P 0 ;0
L 0.8972 -2.01316004 1.03591998 -2.01316004 0 P 0 ;0
L 0.89721998 -2.01216004 1.03548996 -2.01216004 0 P 0 ;0
L 0.89725 -2.01116004 1.03505 -2.01116004 0 P 0 ;0
L 0.89726998 -2.01016004 1.03458002 -2.01016004 0 P 0 ;0
L 0.8973 -2.00916004 1.03405 -2.00916004 0 P 0 ;0
L 0.89733002 -2.00816004 1.03351998 -2.00816004 0 P 0 ;0
L 0.89736004 -2.00716004 0.94676004 -2.00716004 0 P 0 ;0
L 0.89738002 -2.00616004 0.9461 -2.00616004 0 P 0 ;0
L 0.89741004 -2.00516004 0.94563996 -2.00516004 0 P 0 ;0
L 0.89743996 -2.00416004 0.94563996 -2.00416004 0 P 0 ;0
L 0.89746004 -2.00316004 0.94563996 -2.00316004 0 P 0 ;0
L 0.89748996 -2.00216004 0.94563996 -2.00216004 0 P 0 ;0
L 0.89751004 -2.00116004 0.94563996 -2.00116004 0 P 0 ;0
L 0.89753996 -2.00016004 0.94563996 -2.00016004 0 P 0 ;0
L 0.89756998 -1.99916004 0.94563996 -1.99916004 0 P 0 ;0
L 0.8976 -1.99816004 0.94563996 -1.99816004 0 P 0 ;0
L 0.89761998 -1.99716004 0.94563996 -1.99716004 0 P 0 ;0
L 0.89765 -1.99616004 0.94563996 -1.99616004 0 P 0 ;0
L 0.89768002 -1.99516004 0.94563996 -1.99516004 0 P 0 ;0
L 0.97546998 -1.98933996 0.97236998 -1.99006004 0 P 0 ;0
L 0.97236998 -1.99006004 0.96931998 -1.99103002 0 P 0 ;0
L 0.96931998 -1.99103002 0.96603002 -1.99233002 0 P 0 ;0
L 0.96603002 -1.99233002 0.96281004 -1.99383002 0 P 0 ;0
L 0.96281004 -1.99383002 0.95976004 -1.99546998 0 P 0 ;0
L 0.95976004 -1.99546998 0.95681004 -1.99728996 0 P 0 ;0
L 0.95681004 -1.99728996 0.95521004 -1.99841004 0 P 0 ;0
L 0.95521004 -1.99841004 0.95368996 -1.99963002 0 P 0 ;0
L 0.95368996 -1.99963002 0.95223996 -2.00095 0 P 0 ;0
L 0.95223996 -2.00095 0.94763996 -2.00546998 0 P 0 ;0
L 0.94763996 -2.00546998 0.94763996 -1.99243996 0 P 0 ;0
L 0.94763996 -1.99243996 0.89575 -1.99243996 0 P 0 ;0
L 0.89575 -1.99243996 0.89505 -2.01878002 0 P 0 ;0
L 0.89505 -2.01878002 0.89423996 -2.04316004 0 P 0 ;0
L 0.89423996 -2.04316004 0.89321998 -2.0661 0 P 0 ;0
L 0.89321998 -2.0661 0.89198996 -2.08728996 0 P 0 ;0
L 0.89198996 -2.08728996 0.89055 -2.1063 0 P 0 ;0
L 0.89055 -2.1063 0.88993996 -2.11358002 0 P 0 ;0
L 0.88993996 -2.11358002 0.88943002 -2.11988002 0 P 0 ;0
L 0.88943002 -2.11988002 0.88898996 -2.12533996 0 P 0 ;0
L 0.88898996 -2.12533996 0.88896004 -2.12613002 0 P 0 ;0
L 0.88896004 -2.12613002 0.88896998 -2.12621004 0 P 0 ;0
L 0.88896998 -2.12621004 0.88898002 -2.12625 0 P 0 ;0
L 0.88898002 -2.12625 0.88898996 -2.12628002 0 P 0 ;0
L 0.88898996 -2.12628002 0.88901998 -2.12636004 0 P 0 ;0
L 0.88901998 -2.12636004 0.88903996 -2.12638996 0 P 0 ;0
L 0.88903996 -2.12638996 0.88906998 -2.12641998 0 P 0 ;0
L 0.88906998 -2.12641998 0.88908996 -2.12645 0 P 0 ;0
L 0.88908996 -2.12645 0.88911998 -2.12646998 0 P 0 ;0
L 0.88911998 -2.12646998 0.88915 -2.1265 0 P 0 ;0
L 0.88915 -2.1265 0.88921004 -2.12653996 0 P 0 ;0
L 0.88921004 -2.12653996 0.88925 -2.12655 0 P 0 ;0
L 0.88925 -2.12655 0.88928002 -2.12656004 0 P 0 ;0
L 0.88928002 -2.12656004 0.88931998 -2.12658002 0 P 0 ;0
L 0.88931998 -2.12658002 0.8894 -2.12658002 0 P 0 ;0
L 0.8894 -2.12658002 0.89648002 -2.12686998 0 P 0 ;0
L 0.89648002 -2.12686998 0.90518996 -2.1271 0 P 0 ;0
L 0.90518996 -2.1271 0.9165 -2.12716004 0 P 0 ;0
L 0.9165 -2.12716004 0.94403996 -2.12716004 0 P 0 ;0
L 0.94403996 -2.12716004 0.94468996 -2.10135 0 P 0 ;0
L 0.94468996 -2.10135 0.9461 -2.07171998 0 P 0 ;0
L 0.9461 -2.07171998 0.94713002 -2.06233002 0 P 0 ;0
L 0.94713002 -2.06233002 0.9489 -2.05308002 0 P 0 ;0
L 0.9489 -2.05308002 0.94975 -2.04995 0 P 0 ;0
L 0.94975 -2.04995 0.9508 -2.04688996 0 P 0 ;0
L 0.9508 -2.04688996 0.95205 -2.0439 0 P 0 ;0
L 0.95205 -2.0439 0.95351004 -2.041 0 P 0 ;0
L 0.95351004 -2.041 0.9544 -2.03951004 0 P 0 ;0
L 0.9544 -2.03951004 0.95541998 -2.03811004 0 P 0 ;0
L 0.95541998 -2.03811004 0.95655 -2.03678996 0 P 0 ;0
L 0.95655 -2.03678996 0.95778996 -2.03556998 0 P 0 ;0
L 0.95778996 -2.03556998 0.95911998 -2.03446998 0 P 0 ;0
L 0.95911998 -2.03446998 0.96056998 -2.03346998 0 P 0 ;0
L 0.96056998 -2.03346998 0.96151004 -2.03291004 0 P 0 ;0
L 0.96151004 -2.03291004 0.96248996 -2.03243002 0 P 0 ;0
L 0.96248996 -2.03243002 0.96351004 -2.03201998 0 P 0 ;0
L 0.96351004 -2.03201998 0.96455 -2.03168996 0 P 0 ;0
L 0.96455 -2.03168996 0.96613002 -2.0313 0 P 0 ;0
L 0.96613002 -2.0313 0.96773002 -2.03101998 0 P 0 ;0
L 0.96773002 -2.03101998 0.96935 -2.03086004 0 P 0 ;0
L 0.96935 -2.03086004 0.97095 -2.03081004 0 P 0 ;0
L 0.97095 -2.03081004 0.97255 -2.03086998 0 P 0 ;0
L 0.97255 -2.03086998 0.97413002 -2.03105 0 P 0 ;0
L 0.97413002 -2.03105 0.97513002 -2.03123996 0 P 0 ;0
L 0.97513002 -2.03123996 0.9761 -2.03151004 0 P 0 ;0
L 0.9761 -2.03151004 0.97706004 -2.03186004 0 P 0 ;0
L 0.97706004 -2.03186004 0.97796998 -2.0323 0 P 0 ;0
L 0.97796998 -2.0323 0.97885 -2.0328 0 P 0 ;0
L 0.97885 -2.0328 0.97968002 -2.03336998 0 P 0 ;0
L 0.97968002 -2.03336998 0.98046998 -2.03398996 0 P 0 ;0
L 0.98046998 -2.03398996 0.98121998 -2.03468002 0 P 0 ;0
L 0.98121998 -2.03468002 0.98191004 -2.03541998 0 P 0 ;0
L 0.98191004 -2.03541998 0.98253996 -2.0362 0 P 0 ;0
L 0.98253996 -2.0362 0.9831 -2.03703002 0 P 0 ;0
L 0.9831 -2.03703002 0.9836 -2.03788996 0 P 0 ;0
L 0.9836 -2.03788996 0.98403996 -2.0388 0 P 0 ;0
L 0.98403996 -2.0388 0.9844 -2.03973996 0 P 0 ;0
L 0.9844 -2.03973996 0.98505 -2.04188996 0 P 0 ;0
L 0.98505 -2.04188996 0.98553002 -2.04408002 0 P 0 ;0
L 0.98553002 -2.04408002 0.98583002 -2.0463 0 P 0 ;0
L 0.98583002 -2.0463 0.98653002 -2.05705 0 P 0 ;0
L 0.98653002 -2.05705 0.9866 -2.06961004 0 P 0 ;0
L 0.9866 -2.06961004 0.98596004 -2.08908002 0 P 0 ;0
L 0.98596004 -2.08908002 0.98498002 -2.10858002 0 P 0 ;0
L 0.98498002 -2.10858002 0.98388002 -2.12146998 0 P 0 ;0
L 0.98388002 -2.12146998 0.98323002 -2.12716004 0 P 0 ;0
L 0.98323002 -2.12716004 1.03741004 -2.12716004 0 P 0 ;0
L 1.03741004 -2.12716004 1.03896004 -2.09103002 0 P 0 ;0
L 1.03896004 -2.09103002 1.03956004 -2.0759 0 P 0 ;0
L 1.03956004 -2.0759 1.04005 -2.06025 0 P 0 ;0
L 1.04005 -2.06025 1.04038996 -2.04626004 0 P 0 ;0
L 1.04038996 -2.04626004 1.04048002 -2.03698996 0 P 0 ;0
L 1.04048002 -2.03698996 1.04036998 -2.02651998 0 P 0 ;0
L 1.04036998 -2.02651998 1.04003996 -2.02096998 0 P 0 ;0
L 1.04003996 -2.02096998 1.03975 -2.01895 0 P 0 ;0
L 1.03975 -2.01895 1.0393 -2.01693996 0 P 0 ;0
L 1.0393 -2.01693996 1.03868996 -2.01483996 0 P 0 ;0
L 1.03868996 -2.01483996 1.03793996 -2.01278002 0 P 0 ;0
L 1.03793996 -2.01278002 1.03658996 -2.00968002 0 P 0 ;0
L 1.03658996 -2.00968002 1.03501004 -2.00668996 0 P 0 ;0
L 1.03501004 -2.00668996 1.0332 -2.0038 0 P 0 ;0
L 1.0332 -2.0038 1.03186998 -2.002 0 P 0 ;0
L 1.03186998 -2.002 1.0304 -2.0003 0 P 0 ;0
L 1.0304 -2.0003 1.0288 -1.99873002 0 P 0 ;0
L 1.0288 -1.99873002 1.02708002 -1.99728996 0 P 0 ;0
L 1.02708002 -1.99728996 1.02518002 -1.99593002 0 P 0 ;0
L 1.02518002 -1.99593002 1.02318002 -1.99471998 0 P 0 ;0
L 1.02318002 -1.99471998 1.0211 -1.99365 0 P 0 ;0
L 1.0211 -1.99365 1.01893002 -1.99273996 0 P 0 ;0
L 1.01893002 -1.99273996 1.01358996 -1.99098996 0 P 0 ;0
L 1.01358996 -1.99098996 1.0081 -1.98971004 0 P 0 ;0
L 1.0081 -1.98971004 1.00428996 -1.98908996 0 P 0 ;0
L 1.00428996 -1.98908996 1.00043996 -1.98868002 0 P 0 ;0
L 1.00043996 -1.98868002 0.99138002 -1.98826004 0 P 0 ;0
L 0.99138002 -1.98826004 0.98251998 -1.98846998 0 P 0 ;0
L 0.98251998 -1.98846998 0.97898996 -1.98878996 0 P 0 ;0
L 0.97898996 -1.98878996 0.97546998 -1.98933996 0 P 0 ;0
L 0.91651004 -2.12516004 0.94208996 -2.12516004 0 P 0 ;0
L 0.8911 -2.12416004 0.94211004 -2.12416004 0 P 0 ;0
L 0.89118002 -2.12316004 0.94213996 -2.12316004 0 P 0 ;0
L 0.89125 -2.12216004 0.94216004 -2.12216004 0 P 0 ;0
L 0.89133002 -2.12116004 0.94218996 -2.12116004 0 P 0 ;0
L 0.89141004 -2.12016004 0.94221004 -2.12016004 0 P 0 ;0
L 0.89148996 -2.11916004 0.94223996 -2.11916004 0 P 0 ;0
L 0.89156998 -2.11816004 0.94226998 -2.11816004 0 P 0 ;0
L 0.89166004 -2.11716004 0.94228996 -2.11716004 0 P 0 ;0
L 0.89173996 -2.11616004 0.94231004 -2.11616004 0 P 0 ;0
L 0.89181998 -2.11516004 0.94233996 -2.11516004 0 P 0 ;0
L 0.8919 -2.11416004 0.94236004 -2.11416004 0 P 0 ;0
L 0.89198002 -2.11316004 0.94238996 -2.11316004 0 P 0 ;0
L 0.89206998 -2.11216004 0.94241998 -2.11216004 0 P 0 ;0
L 0.89215 -2.11116004 0.94243996 -2.11116004 0 P 0 ;0
L 0.89223002 -2.11016004 0.94246998 -2.11016004 0 P 0 ;0
L 0.89231998 -2.10916004 0.94248996 -2.10916004 0 P 0 ;0
L 0.8924 -2.10816004 0.94251998 -2.10816004 0 P 0 ;0
L 0.89248002 -2.10716004 0.94255 -2.10716004 0 P 0 ;0
L 0.89256998 -2.10616004 0.94256998 -2.10616004 0 P 0 ;0
L 0.89263996 -2.10516004 0.94258996 -2.10516004 0 P 0 ;0
L 0.89271004 -2.10416004 0.94261998 -2.10416004 0 P 0 ;0
L 0.89278996 -2.10316004 0.94263996 -2.10316004 0 P 0 ;0
L 0.89286998 -2.10216004 0.94266998 -2.10216004 0 P 0 ;0
L 0.89293996 -2.10116004 0.9427 -2.10116004 0 P 0 ;0
L 0.89301998 -2.10016004 0.94275 -2.10016004 0 P 0 ;0
L 0.89308996 -2.09916004 0.94278996 -2.09916004 0 P 0 ;0
L 0.89316998 -2.09816004 0.94283996 -2.09816004 0 P 0 ;0
L 0.89325 -2.09716004 0.94288996 -2.09716004 0 P 0 ;0
L 0.89331998 -2.09616004 0.94293996 -2.09616004 0 P 0 ;0
L 0.8934 -2.09516004 0.94298002 -2.09516004 0 P 0 ;0
L 0.89346998 -2.09416004 0.94303002 -2.09416004 0 P 0 ;0
L 0.89355 -2.09316004 0.94308002 -2.09316004 0 P 0 ;0
L 0.89361998 -2.09216004 0.94313002 -2.09216004 0 P 0 ;0
L 0.8937 -2.09116004 0.94318002 -2.09116004 0 P 0 ;0
L 0.89378002 -2.09016004 0.94321998 -2.09016004 0 P 0 ;0
L 0.89385 -2.08916004 0.94326998 -2.08916004 0 P 0 ;0
L 0.89393002 -2.08816004 0.94331998 -2.08816004 0 P 0 ;0
L 0.894 -2.08716004 0.94336004 -2.08716004 0 P 0 ;0
L 0.89406004 -2.08616004 0.94341004 -2.08616004 0 P 0 ;0
L 0.89411998 -2.08516004 0.94346004 -2.08516004 0 P 0 ;0
L 0.89418002 -2.08416004 0.94351004 -2.08416004 0 P 0 ;0
L 0.91651004 -2.12516004 0.90521998 -2.1251 0 P 0 ;0
L 0.90521998 -2.1251 0.89655 -2.12486998 0 P 0 ;0
L 0.89655 -2.12486998 0.89106004 -2.12465 0 P 0 ;0
L 0.89106004 -2.12465 0.89141998 -2.12003996 0 P 0 ;0
L 0.89141998 -2.12003996 0.89193996 -2.11373996 0 P 0 ;0
L 0.89193996 -2.11373996 0.89253996 -2.10645 0 P 0 ;0
L 0.89253996 -2.10645 0.89398002 -2.08741998 0 P 0 ;0
L 0.89398002 -2.08741998 0.89521998 -2.06621998 0 P 0 ;0
L 0.89521998 -2.06621998 0.89521998 -2.06618996 0 P 0 ;0
L 0.89521998 -2.06618996 0.89623996 -2.04323002 0 P 0 ;0
L 0.89623996 -2.04323002 0.89703996 -2.01883002 0 P 0 ;0
L 0.89703996 -2.01883002 0.8977 -1.99443996 0 P 0 ;0
L 0.8977 -1.99443996 0.94563996 -1.99443996 0 P 0 ;0
L 0.94563996 -1.99443996 0.94563996 -2.00546998 0 P 0 ;0
L 0.94563996 -2.00546998 0.94686004 -2.00731004 0 P 0 ;0
L 0.94686004 -2.00731004 0.94903002 -2.00688996 0 P 0 ;0
L 0.94903002 -2.00688996 0.95361998 -2.00241004 0 P 0 ;0
L 0.95361998 -2.00241004 0.95498996 -2.00115 0 P 0 ;0
L 0.95498996 -2.00115 0.95641998 -2.00001004 0 P 0 ;0
L 0.95641998 -2.00001004 0.9579 -1.99896004 0 P 0 ;0
L 0.9579 -1.99896004 0.96076004 -1.9972 0 P 0 ;0
L 0.96076004 -1.9972 0.9637 -1.99561998 0 P 0 ;0
L 0.9637 -1.99561998 0.96683002 -1.99416998 0 P 0 ;0
L 0.96683002 -1.99416998 0.96998996 -1.99291998 0 P 0 ;0
L 0.96998996 -1.99291998 0.9729 -1.99198996 0 P 0 ;0
L 0.9729 -1.99198996 0.97586004 -1.9913 0 P 0 ;0
L 0.97586004 -1.9913 0.97923002 -1.99076998 0 P 0 ;0
L 0.97923002 -1.99076998 0.98263002 -1.99046998 0 P 0 ;0
L 0.98263002 -1.99046998 0.99136004 -1.99026004 0 P 0 ;0
L 0.99136004 -1.99026004 1.00028996 -1.99066998 0 P 0 ;0
L 1.00028996 -1.99066998 1.00403002 -1.99108002 0 P 0 ;0
L 1.00403002 -1.99108002 1.00771004 -1.99166998 0 P 0 ;0
L 1.00771004 -1.99166998 1.01305 -1.99291998 0 P 0 ;0
L 1.01305 -1.99291998 1.01823002 -1.99461998 0 P 0 ;0
L 1.01823002 -1.99461998 1.02026004 -1.99546998 0 P 0 ;0
L 1.02026004 -1.99546998 1.02221004 -1.99646998 0 P 0 ;0
L 1.02221004 -1.99646998 1.02408002 -1.9976 0 P 0 ;0
L 1.02408002 -1.9976 1.02585 -1.99886998 0 P 0 ;0
L 1.02585 -1.99886998 1.02746004 -2.00021004 0 P 0 ;0
L 1.02746004 -2.00021004 1.02893996 -2.00166998 0 P 0 ;0
L 1.02893996 -2.00166998 1.03031004 -2.00325 0 P 0 ;0
L 1.03031004 -2.00325 1.03155 -2.00493002 0 P 0 ;0
L 1.03155 -2.00493002 1.03326998 -2.00768002 0 P 0 ;0
L 1.03326998 -2.00768002 1.03478002 -2.01055 0 P 0 ;0
L 1.03478002 -2.01055 1.03608002 -2.01351998 0 P 0 ;0
L 1.03608002 -2.01351998 1.03678996 -2.01546998 0 P 0 ;0
L 1.03678996 -2.01546998 1.03736004 -2.01743002 0 P 0 ;0
L 1.03736004 -2.01743002 1.03778002 -2.0193 0 P 0 ;0
L 1.03778002 -2.0193 1.03805 -2.02116998 0 P 0 ;0
L 1.03805 -2.02116998 1.03836998 -2.02658996 0 P 0 ;0
L 1.03836998 -2.02658996 1.03848002 -2.03698996 0 P 0 ;0
L 1.03848002 -2.03698996 1.03838996 -2.04623002 0 P 0 ;0
L 1.03838996 -2.04623002 1.03805 -2.06018996 0 P 0 ;0
L 1.03805 -2.06018996 1.03756004 -2.07583002 0 P 0 ;0
L 1.03756004 -2.07583002 1.03696998 -2.09095 0 P 0 ;0
L 1.03696998 -2.09095 1.03548996 -2.12516004 0 P 0 ;0
L 1.03548996 -2.12516004 0.98546998 -2.12516004 0 P 0 ;0
L 0.98546998 -2.12516004 0.98586998 -2.12166004 0 P 0 ;0
L 0.98586998 -2.12166004 0.98696998 -2.10871998 0 P 0 ;0
L 0.98696998 -2.10871998 0.98796004 -2.08916004 0 P 0 ;0
L 0.98796004 -2.08916004 0.9886 -2.06963002 0 P 0 ;0
L 0.9886 -2.06963002 0.98853002 -2.05698002 0 P 0 ;0
L 0.98853002 -2.05698002 0.98781998 -2.0461 0 P 0 ;0
L 0.98781998 -2.0461 0.9875 -2.04373002 0 P 0 ;0
L 0.9875 -2.04373002 0.98748002 -2.04365 0 P 0 ;0
L 0.98748002 -2.04365 0.98698996 -2.04138996 0 P 0 ;0
L 0.98698996 -2.04138996 0.9863 -2.03908002 0 P 0 ;0
L 0.9863 -2.03908002 0.98588002 -2.038 0 P 0 ;0
L 0.98588002 -2.038 0.98538002 -2.03696004 0 P 0 ;0
L 0.98538002 -2.03696004 0.9848 -2.03596004 0 P 0 ;0
L 0.9848 -2.03596004 0.98413996 -2.03501004 0 P 0 ;0
L 0.98413996 -2.03501004 0.98341998 -2.03411004 0 P 0 ;0
L 0.98341998 -2.03411004 0.98336998 -2.03405 0 P 0 ;0
L 0.98336998 -2.03405 0.98263002 -2.03326004 0 P 0 ;0
L 0.98263002 -2.03326004 0.98176998 -2.03246998 0 P 0 ;0
L 0.98176998 -2.03246998 0.98086998 -2.03175 0 P 0 ;0
L 0.98086998 -2.03175 0.97991004 -2.0311 0 P 0 ;0
L 0.97991004 -2.0311 0.9789 -2.03051998 0 P 0 ;0
L 0.9789 -2.03051998 0.97783002 -2.03001998 0 P 0 ;0
L 0.97783002 -2.03001998 0.97673002 -2.02961004 0 P 0 ;0
L 0.97673002 -2.02961004 0.97663996 -2.02958002 0 P 0 ;0
L 0.97663996 -2.02958002 0.97558996 -2.02928996 0 P 0 ;0
L 0.97558996 -2.02928996 0.97443002 -2.02906998 0 P 0 ;0
L 0.97443002 -2.02906998 0.9727 -2.02888002 0 P 0 ;0
L 0.9727 -2.02888002 0.97261998 -2.02886998 0 P 0 ;0
L 0.97261998 -2.02886998 0.97096004 -2.02881004 0 P 0 ;0
L 0.97096004 -2.02881004 0.96921004 -2.02886004 0 P 0 ;0
L 0.96921004 -2.02886004 0.96745 -2.02903996 0 P 0 ;0
L 0.96745 -2.02903996 0.96571004 -2.02933996 0 P 0 ;0
L 0.96571004 -2.02933996 0.964 -2.02976004 0 P 0 ;0
L 0.964 -2.02976004 0.96283002 -2.03013996 0 P 0 ;0
L 0.96283002 -2.03013996 0.96168002 -2.0306 0 P 0 ;0
L 0.96168002 -2.0306 0.96056998 -2.03115 0 P 0 ;0
L 0.96056998 -2.03115 0.95948996 -2.03178002 0 P 0 ;0
L 0.95948996 -2.03178002 0.95791004 -2.03286998 0 P 0 ;0
L 0.95791004 -2.03286998 0.95645 -2.03408996 0 P 0 ;0
L 0.95645 -2.03408996 0.95508996 -2.03541998 0 P 0 ;0
L 0.95508996 -2.03541998 0.95383996 -2.03686998 0 P 0 ;0
L 0.95383996 -2.03686998 0.9538 -2.03693002 0 P 0 ;0
L 0.9538 -2.03693002 0.95273002 -2.03841004 0 P 0 ;0
L 0.95273002 -2.03841004 0.95175 -2.04003996 0 P 0 ;0
L 0.95175 -2.04003996 0.95023002 -2.04306004 0 P 0 ;0
L 0.95023002 -2.04306004 0.94896004 -2.04611004 0 P 0 ;0
L 0.94896004 -2.04611004 0.94893002 -2.04616998 0 P 0 ;0
L 0.94893002 -2.04616998 0.94783002 -2.04936004 0 P 0 ;0
L 0.94783002 -2.04936004 0.94695 -2.05263002 0 P 0 ;0
L 0.94695 -2.05263002 0.94515 -2.06203002 0 P 0 ;0
L 0.94515 -2.06203002 0.9441 -2.07156004 0 P 0 ;0
L 0.9441 -2.07156004 0.9427 -2.10128002 0 P 0 ;0
L 0.9427 -2.10128002 0.94208996 -2.12516004 0 P 0 ;0
L 0.94208996 -2.12516004 0.91651004 -2.12516004 0 P 0 ;0
L 0.93143002 -2.21261998 1.00578996 -2.21261998 0 P 0 ;0
L 0.94051004 -2.21161998 1.00803002 -2.21161998 0 P 0 ;0
L 0.94941998 -2.21061998 1.01026004 -2.21061998 0 P 0 ;0
L 0.9555 -2.20961998 1.0125 -2.20961998 0 P 0 ;0
L 0.96158002 -2.20861998 1.01473996 -2.20861998 0 P 0 ;0
L 0.96766004 -2.20761998 1.01696998 -2.20761998 0 P 0 ;0
L 0.97373002 -2.20661998 1.01921004 -2.20661998 0 P 0 ;0
L 0.97981004 -2.20561998 1.02145 -2.20561998 0 P 0 ;0
L 0.98498996 -2.20461998 1.02368996 -2.20461998 0 P 0 ;0
L 0.98973996 -2.20361998 1.02591998 -2.20361998 0 P 0 ;0
L 0.99448996 -2.20261998 1.02816004 -2.20261998 0 P 0 ;0
L 0.99923996 -2.20161998 1.0304 -2.20161998 0 P 0 ;0
L 1.00398996 -2.20061998 1.03243996 -2.20061998 0 P 0 ;0
L 1.00875 -2.19961998 1.0344 -2.19961998 0 P 0 ;0
L 1.01348996 -2.19861998 1.03636998 -2.19861998 0 P 0 ;0
L 1.0178 -2.19761998 1.03833996 -2.19761998 0 P 0 ;0
L 1.02168996 -2.19661998 1.04031004 -2.19661998 0 P 0 ;0
L 1.02558002 -2.19561998 1.04228002 -2.19561998 0 P 0 ;0
L 1.02946998 -2.19461998 1.04415 -2.19461998 0 P 0 ;0
L 1.03336004 -2.19361998 1.04596998 -2.19361998 0 P 0 ;0
L 1.03725 -2.19261998 1.04778996 -2.19261998 0 P 0 ;0
L 1.04113996 -2.19161998 1.0496 -2.19161998 0 P 0 ;0
L 1.14356998 -1.98926998 1.13261004 -1.99086004 0 P 0 ;0
L 1.13261004 -1.99086004 1.12165 -1.9934 0 P 0 ;0
L 1.12165 -1.9934 1.11125 -1.99673002 0 P 0 ;0
L 1.11125 -1.99673002 1.10658002 -1.99858996 0 P 0 ;0
L 1.10658002 -1.99858996 1.10198996 -2.00071004 0 P 0 ;0
L 1.10198996 -2.00071004 1.09653002 -2.00358996 0 P 0 ;0
L 1.09653002 -2.00358996 1.09436998 -2.00488996 0 P 0 ;0
L 1.09436998 -2.00488996 1.09226004 -2.00631004 0 P 0 ;0
L 1.09226004 -2.00631004 1.09028002 -2.00781004 0 P 0 ;0
L 1.09028002 -2.00781004 1.08836998 -2.00941998 0 P 0 ;0
L 1.08836998 -2.00941998 1.08405 -2.0135 0 P 0 ;0
L 1.08405 -2.0135 1.08096998 -2.01678996 0 P 0 ;0
L 1.08096998 -2.01678996 1.07808002 -2.02026998 0 P 0 ;0
L 1.07808002 -2.02026998 1.0754 -2.02393002 0 P 0 ;0
L 1.0754 -2.02393002 1.07313996 -2.02748002 0 P 0 ;0
L 1.07313996 -2.02748002 1.07116004 -2.03118996 0 P 0 ;0
L 1.07116004 -2.03118996 1.06943996 -2.03505 0 P 0 ;0
L 1.06943996 -2.03505 1.06795 -2.03918996 0 P 0 ;0
L 1.06795 -2.03918996 1.06673996 -2.04343996 0 P 0 ;0
L 1.06673996 -2.04343996 1.06583002 -2.04778002 0 P 0 ;0
L 1.06583002 -2.04778002 1.06476998 -2.05538996 0 P 0 ;0
L 1.06476998 -2.05538996 1.06421004 -2.06306004 0 P 0 ;0
L 1.06421004 -2.06306004 1.06415 -2.07076004 0 P 0 ;0
L 1.06415 -2.07076004 1.06456998 -2.0785 0 P 0 ;0
L 1.06456998 -2.0785 1.06508996 -2.08276004 0 P 0 ;0
L 1.06508996 -2.08276004 1.06591004 -2.08696004 0 P 0 ;0
L 1.06591004 -2.08696004 1.06703002 -2.09108002 0 P 0 ;0
L 1.06703002 -2.09108002 1.06833002 -2.09473002 0 P 0 ;0
L 1.06833002 -2.09473002 1.06991998 -2.09823996 0 P 0 ;0
L 1.06991998 -2.09823996 1.0718 -2.10161998 0 P 0 ;0
L 1.0718 -2.10161998 1.07398002 -2.10491998 0 P 0 ;0
L 1.07398002 -2.10491998 1.07641998 -2.10803002 0 P 0 ;0
L 1.07641998 -2.10803002 1.07908996 -2.11095 0 P 0 ;0
L 1.07908996 -2.11095 1.08175 -2.11345 0 P 0 ;0
L 1.08175 -2.11345 1.08458996 -2.11573996 0 P 0 ;0
L 1.08458996 -2.11573996 1.08758996 -2.1178 0 P 0 ;0
L 1.08758996 -2.1178 1.09073002 -2.11963996 0 P 0 ;0
L 1.09073002 -2.11963996 1.094 -2.12123996 0 P 0 ;0
L 1.094 -2.12123996 1.0986 -2.12306998 0 P 0 ;0
L 1.0986 -2.12306998 1.10331004 -2.12456004 0 P 0 ;0
L 1.10331004 -2.12456004 1.10811004 -2.12568996 0 P 0 ;0
L 1.10811004 -2.12568996 1.11298002 -2.12646998 0 P 0 ;0
L 1.11298002 -2.12646998 1.1182 -2.12693002 0 P 0 ;0
L 1.1182 -2.12693002 1.12343996 -2.12703002 0 P 0 ;0
L 1.12343996 -2.12703002 1.12866998 -2.12676004 0 P 0 ;0
L 1.12866998 -2.12676004 1.13388002 -2.12613002 0 P 0 ;0
L 1.13388002 -2.12613002 1.14086004 -2.12473996 0 P 0 ;0
L 1.14086004 -2.12473996 1.1477 -2.12273996 0 P 0 ;0
L 1.1477 -2.12273996 1.15433996 -2.12015 0 P 0 ;0
L 1.15433996 -2.12015 1.1545 -2.12008996 0 P 0 ;0
L 1.1545 -2.12008996 1.15466004 -2.12003996 0 P 0 ;0
L 1.15466004 -2.12003996 1.15483002 -2.12001004 0 P 0 ;0
L 1.15483002 -2.12001004 1.15498996 -2.11998996 0 P 0 ;0
L 1.15498996 -2.11998996 1.15533002 -2.11998996 0 P 0 ;0
L 1.15533002 -2.11998996 1.15538996 -2.12 0 P 0 ;0
L 1.15538996 -2.12 1.15545 -2.12001998 0 P 0 ;0
L 1.15545 -2.12001998 1.15551004 -2.12003002 0 P 0 ;0
L 1.15551004 -2.12003002 1.15556004 -2.12006004 0 P 0 ;0
L 1.15556004 -2.12006004 1.15561004 -2.12008002 0 P 0 ;0
L 1.15561004 -2.12008002 1.15566004 -2.12011004 0 P 0 ;0
L 1.15566004 -2.12011004 1.15571004 -2.12015 0 P 0 ;0
L 1.15571004 -2.12015 1.15575 -2.12018996 0 P 0 ;0
L 1.15575 -2.12018996 1.15578996 -2.12023996 0 P 0 ;0
L 1.15578996 -2.12023996 1.15583002 -2.12028002 0 P 0 ;0
L 1.15583002 -2.12028002 1.15586004 -2.12033996 0 P 0 ;0
L 1.15586004 -2.12033996 1.15588002 -2.12038996 0 P 0 ;0
L 1.15588002 -2.12038996 1.15591004 -2.12043996 0 P 0 ;0
L 1.15591004 -2.12043996 1.15601998 -2.12076004 0 P 0 ;0
L 1.15601998 -2.12076004 1.1561 -2.12108002 0 P 0 ;0
L 1.1561 -2.12108002 1.15616004 -2.12141998 0 P 0 ;0
L 1.15616004 -2.12141998 1.15618002 -2.12175 0 P 0 ;0
L 1.15618002 -2.12175 1.15623996 -2.12505 0 P 0 ;0
L 1.15623996 -2.12505 1.15616004 -2.12688002 0 P 0 ;0
L 1.15616004 -2.12688002 1.15593002 -2.12871004 0 P 0 ;0
L 1.15593002 -2.12871004 1.15553996 -2.13051998 0 P 0 ;0
L 1.15553996 -2.13051998 1.15516004 -2.1318 0 P 0 ;0
L 1.15516004 -2.1318 1.1547 -2.13305 0 P 0 ;0
L 1.1547 -2.13305 1.15415 -2.13426004 0 P 0 ;0
L 1.15415 -2.13426004 1.15351004 -2.13545 0 P 0 ;0
L 1.15351004 -2.13545 1.15278996 -2.1366 0 P 0 ;0
L 1.15278996 -2.1366 1.15198002 -2.13768996 0 P 0 ;0
L 1.15198002 -2.13768996 1.15111004 -2.13873002 0 P 0 ;0
L 1.15111004 -2.13873002 1.15016004 -2.13971004 0 P 0 ;0
L 1.15016004 -2.13971004 1.14876004 -2.14096004 0 P 0 ;0
L 1.14876004 -2.14096004 1.14726004 -2.1421 0 P 0 ;0
L 1.14726004 -2.1421 1.14566998 -2.14311004 0 P 0 ;0
L 1.14566998 -2.14311004 1.144 -2.144 0 P 0 ;0
L 1.144 -2.144 1.14226004 -2.14476004 0 P 0 ;0
L 1.14226004 -2.14476004 1.14046004 -2.14536998 0 P 0 ;0
L 1.14046004 -2.14536998 1.13863002 -2.14583002 0 P 0 ;0
L 1.13863002 -2.14583002 1.13676004 -2.14613996 0 P 0 ;0
L 1.13676004 -2.14613996 1.13041998 -2.14663996 0 P 0 ;0
L 1.13041998 -2.14663996 1.12403996 -2.1466 0 P 0 ;0
L 1.12403996 -2.1466 1.11621998 -2.14593996 0 P 0 ;0
L 1.11621998 -2.14593996 1.10843996 -2.14471004 0 P 0 ;0
L 1.10843996 -2.14471004 1.09946998 -2.14276998 0 P 0 ;0
L 1.09946998 -2.14276998 1.0905 -2.14041004 0 P 0 ;0
L 1.0905 -2.14041004 1.07963996 -2.13728996 0 P 0 ;0
L 1.07963996 -2.13728996 1.07936004 -2.1401 0 P 0 ;0
L 1.07936004 -2.1401 1.07931004 -2.14103996 0 P 0 ;0
L 1.07931004 -2.14103996 1.07931998 -2.14198002 0 P 0 ;0
L 1.07931998 -2.14198002 1.07956998 -2.14735 0 P 0 ;0
L 1.07956998 -2.14735 1.07993996 -2.15375 0 P 0 ;0
L 1.07993996 -2.15375 1.08045 -2.16081998 0 P 0 ;0
L 1.08045 -2.16081998 1.08181004 -2.17873002 0 P 0 ;0
L 1.08181004 -2.17873002 1.08996004 -2.18061004 0 P 0 ;0
L 1.08996004 -2.18061004 1.09951004 -2.18246004 0 P 0 ;0
L 1.09951004 -2.18246004 1.11243996 -2.18416998 0 P 0 ;0
L 1.11243996 -2.18416998 1.1254 -2.18543002 0 P 0 ;0
L 1.1254 -2.18543002 1.13508002 -2.18583002 0 P 0 ;0
L 1.13508002 -2.18583002 1.14765 -2.18528996 0 P 0 ;0
L 1.14765 -2.18528996 1.15368002 -2.18461004 0 P 0 ;0
L 1.15368002 -2.18461004 1.15971004 -2.18363996 0 P 0 ;0
L 1.15971004 -2.18363996 1.16521004 -2.18248002 0 P 0 ;0
L 1.16521004 -2.18248002 1.17063996 -2.18103002 0 P 0 ;0
L 1.17063996 -2.18103002 1.17528996 -2.17946998 0 P 0 ;0
L 1.17528996 -2.17946998 1.17978002 -2.17753996 0 P 0 ;0
L 1.17978002 -2.17753996 1.18216998 -2.1763 0 P 0 ;0
L 1.18216998 -2.1763 1.18446004 -2.17488996 0 P 0 ;0
L 1.18446004 -2.17488996 1.18663996 -2.17331004 0 P 0 ;0
L 1.18663996 -2.17331004 1.18871004 -2.17156004 0 P 0 ;0
L 1.18871004 -2.17156004 1.19161004 -2.16871998 0 P 0 ;0
L 1.19161004 -2.16871998 1.19431004 -2.16568996 0 P 0 ;0
L 1.19431004 -2.16568996 1.19678996 -2.16246998 0 P 0 ;0
L 1.19678996 -2.16246998 1.19908996 -2.15901998 0 P 0 ;0
L 1.19908996 -2.15901998 1.20113996 -2.15543996 0 P 0 ;0
L 1.20113996 -2.15543996 1.20295 -2.15171004 0 P 0 ;0
L 1.20295 -2.15171004 1.20435 -2.14815 0 P 0 ;0
L 1.20435 -2.14815 1.20543996 -2.14448996 0 P 0 ;0
L 1.20543996 -2.14448996 1.20621004 -2.14073996 0 P 0 ;0
L 1.20621004 -2.14073996 1.20651998 -2.13855 0 P 0 ;0
L 1.20651998 -2.13855 1.20671998 -2.13633996 0 P 0 ;0
L 1.20671998 -2.13633996 1.20761998 -2.12321004 0 P 0 ;0
L 1.20761998 -2.12321004 1.20858002 -2.10753996 0 P 0 ;0
L 1.20858002 -2.10753996 1.20951004 -2.09021998 0 P 0 ;0
L 1.20951004 -2.09021998 1.21048002 -2.07166004 0 P 0 ;0
L 1.21048002 -2.07166004 1.21156004 -2.05228002 0 P 0 ;0
L 1.21156004 -2.05228002 1.21258002 -2.03478996 0 P 0 ;0
L 1.21258002 -2.03478996 1.21333002 -2.02286004 0 P 0 ;0
L 1.21333002 -2.02286004 1.21393996 -2.01373996 0 P 0 ;0
L 1.21393996 -2.01373996 1.21443996 -2.00568996 0 P 0 ;0
L 1.21443996 -2.00568996 1.21485 -1.99883996 0 P 0 ;0
L 1.21485 -1.99883996 1.2149 -1.99721004 0 P 0 ;0
L 1.2149 -1.99721004 1.21488996 -1.99703996 0 P 0 ;0
L 1.21488996 -1.99703996 1.21486998 -1.99686004 0 P 0 ;0
L 1.21486998 -1.99686004 1.21483996 -1.99668996 0 P 0 ;0
L 1.21483996 -1.99668996 1.21478996 -1.99653002 0 P 0 ;0
L 1.21478996 -1.99653002 1.21473002 -1.99636998 0 P 0 ;0
L 1.21473002 -1.99636998 1.21466004 -1.99621004 0 P 0 ;0
L 1.21466004 -1.99621004 1.21458002 -1.99606004 0 P 0 ;0
L 1.21458002 -1.99606004 1.21448002 -1.99591004 0 P 0 ;0
L 1.21448002 -1.99591004 1.21433002 -1.99571998 0 P 0 ;0
L 1.21433002 -1.99571998 1.21416998 -1.99553996 0 P 0 ;0
L 1.21416998 -1.99553996 1.21398996 -1.99538002 0 P 0 ;0
L 1.21398996 -1.99538002 1.21378996 -1.99523996 0 P 0 ;0
L 1.21378996 -1.99523996 1.21358002 -1.99511004 0 P 0 ;0
L 1.21358002 -1.99511004 1.21336004 -1.995 0 P 0 ;0
L 1.21336004 -1.995 1.21261004 -1.99468996 0 P 0 ;0
L 1.21261004 -1.99468996 1.21183996 -1.99443996 0 P 0 ;0
L 1.21183996 -1.99443996 1.21105 -1.99423002 0 P 0 ;0
L 1.21105 -1.99423002 1.20593996 -1.99318002 0 P 0 ;0
L 1.20593996 -1.99318002 1.18996998 -1.99065 0 P 0 ;0
L 1.18996998 -1.99065 1.17318996 -1.98908002 0 P 0 ;0
L 1.17318996 -1.98908002 1.15718996 -1.98858002 0 P 0 ;0
L 1.15718996 -1.98858002 1.1504 -1.98876004 0 P 0 ;0
L 1.1504 -1.98876004 1.14356998 -1.98926998 0 P 0 ;0
L 1.04503996 -2.19061998 1.05141998 -2.19061998 0 P 0 ;0
L 1.04893002 -2.18961998 1.05323002 -2.18961998 0 P 0 ;0
L 1.05263002 -2.18861998 1.05503996 -2.18861998 0 P 0 ;0
L 1.05628996 -2.18761998 1.05676004 -2.18761998 0 P 0 ;0
L 1.09645 -2.17983002 1.16738002 -2.17983002 0 P 0 ;0
L 1.09126004 -2.17883002 1.17091004 -2.17883002 0 P 0 ;0
L 1.0868 -2.17783002 1.17386998 -2.17783002 0 P 0 ;0
L 1.08368002 -2.17683002 1.17636004 -2.17683002 0 P 0 ;0
L 1.0836 -2.17583002 1.1787 -2.17583002 0 P 0 ;0
L 1.08351998 -2.17483002 1.18066998 -2.17483002 0 P 0 ;0
L 1.08345 -2.17383002 1.18236998 -2.17383002 0 P 0 ;0
L 1.08336998 -2.17283002 1.1839 -2.17283002 0 P 0 ;0
L 1.08328996 -2.17183002 1.18526998 -2.17183002 0 P 0 ;0
L 1.08321998 -2.17083002 1.18646998 -2.17083002 0 P 0 ;0
L 1.08313996 -2.16983002 1.18761998 -2.16983002 0 P 0 ;0
L 1.08306998 -2.16883002 1.18863996 -2.16883002 0 P 0 ;0
L 1.08298996 -2.16783002 1.18966004 -2.16783002 0 P 0 ;0
L 1.08291998 -2.16683002 1.19061004 -2.16683002 0 P 0 ;0
L 1.08283996 -2.16583002 1.1915 -2.16583002 0 P 0 ;0
L 1.08276004 -2.16483002 1.19238996 -2.16483002 0 P 0 ;0
L 1.08268996 -2.16383002 1.19321004 -2.16383002 0 P 0 ;0
L 1.08261004 -2.16283002 1.19398002 -2.16283002 0 P 0 ;0
L 1.08253002 -2.16183002 1.19476004 -2.16183002 0 P 0 ;0
L 1.08246004 -2.16083002 1.19548002 -2.16083002 0 P 0 ;0
L 1.08238002 -2.15983002 1.19613996 -2.15983002 0 P 0 ;0
L 1.08231004 -2.15883002 1.19681004 -2.15883002 0 P 0 ;0
L 1.08223996 -2.15783002 1.19746004 -2.15783002 0 P 0 ;0
L 1.13506998 -2.18383002 1.12553002 -2.18343996 0 P 0 ;0
L 1.12553002 -2.18343996 1.11266004 -2.18218002 0 P 0 ;0
L 1.11266004 -2.18218002 1.09983002 -2.18048002 0 P 0 ;0
L 1.09983002 -2.18048002 1.09036998 -2.17866004 0 P 0 ;0
L 1.09036998 -2.17866004 1.0837 -2.17711004 0 P 0 ;0
L 1.0837 -2.17711004 1.08245 -2.16066998 0 P 0 ;0
L 1.08245 -2.16066998 1.08193996 -2.15361998 0 P 0 ;0
L 1.08193996 -2.15361998 1.08156998 -2.14726004 0 P 0 ;0
L 1.08156998 -2.14726004 1.08131998 -2.14191004 0 P 0 ;0
L 1.08131998 -2.14191004 1.08131004 -2.14108996 0 P 0 ;0
L 1.08131004 -2.14108996 1.08136004 -2.14026004 0 P 0 ;0
L 1.08136004 -2.14026004 1.0814 -2.13986998 0 P 0 ;0
L 1.0814 -2.13986998 1.08996004 -2.14233002 0 P 0 ;0
L 1.08996004 -2.14233002 1.08996998 -2.14233996 0 P 0 ;0
L 1.08996998 -2.14233996 1.08998996 -2.14233996 0 P 0 ;0
L 1.08998996 -2.14233996 1.099 -2.14471998 0 P 0 ;0
L 1.099 -2.14471998 1.10806998 -2.14668002 0 P 0 ;0
L 1.10806998 -2.14668002 1.11598002 -2.14791998 0 P 0 ;0
L 1.11598002 -2.14791998 1.12395 -2.1486 0 P 0 ;0
L 1.12395 -2.1486 1.13048996 -2.14863996 0 P 0 ;0
L 1.13048996 -2.14863996 1.137 -2.14811998 0 P 0 ;0
L 1.137 -2.14811998 1.13903002 -2.14778996 0 P 0 ;0
L 1.13903002 -2.14778996 1.14103002 -2.14728996 0 P 0 ;0
L 1.14103002 -2.14728996 1.14298002 -2.14661998 0 P 0 ;0
L 1.14298002 -2.14661998 1.14486998 -2.14581004 0 P 0 ;0
L 1.14486998 -2.14581004 1.14668002 -2.14483996 0 P 0 ;0
L 1.14668002 -2.14483996 1.1484 -2.14373996 0 P 0 ;0
L 1.1484 -2.14373996 1.15003002 -2.1425 0 P 0 ;0
L 1.15003002 -2.1425 1.15155 -2.14115 0 P 0 ;0
L 1.15155 -2.14115 1.1526 -2.14006998 0 P 0 ;0
L 1.1526 -2.14006998 1.15263996 -2.14001998 0 P 0 ;0
L 1.15263996 -2.14001998 1.15356004 -2.13893002 0 P 0 ;0
L 1.15356004 -2.13893002 1.15443996 -2.13771998 0 P 0 ;0
L 1.15443996 -2.13771998 1.15523002 -2.13646004 0 P 0 ;0
L 1.15523002 -2.13646004 1.15593996 -2.13515 0 P 0 ;0
L 1.15593996 -2.13515 1.15655 -2.13381004 0 P 0 ;0
L 1.15655 -2.13381004 1.15706004 -2.13243002 0 P 0 ;0
L 1.15706004 -2.13243002 1.15748002 -2.13101004 0 P 0 ;0
L 1.15748002 -2.13101004 1.1579 -2.12905 0 P 0 ;0
L 1.1579 -2.12905 1.15816004 -2.12706004 0 P 0 ;0
L 1.15816004 -2.12706004 1.15825 -2.12506998 0 P 0 ;0
L 1.15825 -2.12506998 1.15818002 -2.12165 0 P 0 ;0
L 1.15818002 -2.12165 1.15813996 -2.12118002 0 P 0 ;0
L 1.15813996 -2.12118002 1.15813002 -2.1211 0 P 0 ;0
L 1.15813002 -2.1211 1.15806004 -2.12068002 0 P 0 ;0
L 1.15806004 -2.12068002 1.15793996 -2.12018996 0 P 0 ;0
L 1.15793996 -2.12018996 1.15778002 -2.11973002 0 P 0 ;0
L 1.15778002 -2.11973002 1.1577 -2.11953002 0 P 0 ;0
L 1.1577 -2.11953002 1.15758996 -2.11933002 0 P 0 ;0
L 1.15758996 -2.11933002 1.15746998 -2.11913996 0 P 0 ;0
L 1.15746998 -2.11913996 1.15733002 -2.11895 0 P 0 ;0
L 1.15733002 -2.11895 1.15716998 -2.11878002 0 P 0 ;0
L 1.15716998 -2.11878002 1.157 -2.11863002 0 P 0 ;0
L 1.157 -2.11863002 1.15681998 -2.11848996 0 P 0 ;0
L 1.15681998 -2.11848996 1.15663002 -2.11836004 0 P 0 ;0
L 1.15663002 -2.11836004 1.15641998 -2.11825 0 P 0 ;0
L 1.15641998 -2.11825 1.15621004 -2.11816004 0 P 0 ;0
L 1.15621004 -2.11816004 1.15598996 -2.11808996 0 P 0 ;0
L 1.15598996 -2.11808996 1.15576998 -2.11803996 0 P 0 ;0
L 1.15576998 -2.11803996 1.15553002 -2.118 0 P 0 ;0
L 1.15553002 -2.118 1.15518002 -2.11798002 0 P 0 ;0
L 1.15518002 -2.11798002 1.15483996 -2.11798996 0 P 0 ;0
L 1.15483996 -2.11798996 1.15451004 -2.11803002 0 P 0 ;0
L 1.15451004 -2.11803002 1.15418002 -2.1181 0 P 0 ;0
L 1.15418002 -2.1181 1.15386004 -2.1182 0 P 0 ;0
L 1.15386004 -2.1182 1.15361004 -2.11828996 0 P 0 ;0
L 1.15361004 -2.11828996 1.14705 -2.12083996 0 P 0 ;0
L 1.14705 -2.12083996 1.14038996 -2.12278996 0 P 0 ;0
L 1.14038996 -2.12278996 1.13356004 -2.12416004 0 P 0 ;0
L 1.13356004 -2.12416004 1.1285 -2.12476998 0 P 0 ;0
L 1.1285 -2.12476998 1.12341004 -2.12501998 0 P 0 ;0
L 1.12341004 -2.12501998 1.11831004 -2.12493002 0 P 0 ;0
L 1.11831004 -2.12493002 1.11323002 -2.12448996 0 P 0 ;0
L 1.11323002 -2.12448996 1.10848996 -2.12373002 0 P 0 ;0
L 1.10848996 -2.12373002 1.10383996 -2.12263002 0 P 0 ;0
L 1.10383996 -2.12263002 1.09926998 -2.12118996 0 P 0 ;0
L 1.09926998 -2.12118996 1.09481004 -2.11941004 0 P 0 ;0
L 1.09481004 -2.11941004 1.09168002 -2.11788002 0 P 0 ;0
L 1.09168002 -2.11788002 1.08866004 -2.11611998 0 P 0 ;0
L 1.08866004 -2.11611998 1.08578002 -2.11413002 0 P 0 ;0
L 1.08578002 -2.11413002 1.08306998 -2.11193996 0 P 0 ;0
L 1.08306998 -2.11193996 1.08051998 -2.10955 0 P 0 ;0
L 1.08051998 -2.10955 1.07793996 -2.10673002 0 P 0 ;0
L 1.07793996 -2.10673002 1.07561004 -2.10373996 0 P 0 ;0
L 1.07561004 -2.10373996 1.07351004 -2.10058002 0 P 0 ;0
L 1.07351004 -2.10058002 1.07171004 -2.09733996 0 P 0 ;0
L 1.07171004 -2.09733996 1.07018002 -2.09396998 0 P 0 ;0
L 1.07018002 -2.09396998 1.06893996 -2.09048002 0 P 0 ;0
L 1.06893996 -2.09048002 1.06786004 -2.0865 0 P 0 ;0
L 1.06786004 -2.0865 1.06706004 -2.08243996 0 P 0 ;0
L 1.06706004 -2.08243996 1.06656004 -2.07833002 0 P 0 ;0
L 1.06656004 -2.07833002 1.06615 -2.07071004 0 P 0 ;0
L 1.06615 -2.07071004 1.06621004 -2.06313996 0 P 0 ;0
L 1.06621004 -2.06313996 1.06675 -2.0556 0 P 0 ;0
L 1.06675 -2.0556 1.0678 -2.04813002 0 P 0 ;0
L 1.0678 -2.04813002 1.06868996 -2.04391998 0 P 0 ;0
L 1.06868996 -2.04391998 1.06985 -2.03981004 0 P 0 ;0
L 1.06985 -2.03981004 1.0713 -2.03578996 0 P 0 ;0
L 1.0713 -2.03578996 1.07296004 -2.03206998 0 P 0 ;0
L 1.07296004 -2.03206998 1.07486998 -2.02848996 0 P 0 ;0
L 1.07486998 -2.02848996 1.07705 -2.02506004 0 P 0 ;0
L 1.07705 -2.02506004 1.07966004 -2.0215 0 P 0 ;0
L 1.07966004 -2.0215 1.08246998 -2.01811004 0 P 0 ;0
L 1.08246998 -2.01811004 1.08546998 -2.01491004 0 P 0 ;0
L 1.08546998 -2.01491004 1.0897 -2.01091004 0 P 0 ;0
L 1.0897 -2.01091004 1.09153002 -2.00936998 0 P 0 ;0
L 1.09153002 -2.00936998 1.09341998 -2.00793996 0 P 0 ;0
L 1.09341998 -2.00793996 1.09545 -2.00658002 0 P 0 ;0
L 1.09545 -2.00658002 1.09751004 -2.00533996 0 P 0 ;0
L 1.09751004 -2.00533996 1.10288002 -2.0025 0 P 0 ;0
L 1.10288002 -2.0025 1.10736998 -2.00043002 0 P 0 ;0
L 1.10736998 -2.00043002 1.11193002 -1.99861004 0 P 0 ;0
L 1.11193002 -1.99861004 1.12218002 -1.99533002 0 P 0 ;0
L 1.12218002 -1.99533002 1.13298002 -1.99281998 0 P 0 ;0
L 1.13298002 -1.99281998 1.14378996 -1.99126004 0 P 0 ;0
L 1.14378996 -1.99126004 1.1505 -1.99075 0 P 0 ;0
L 1.1505 -1.99075 1.15718002 -1.99058996 0 P 0 ;0
L 1.15718002 -1.99058996 1.17306998 -1.99108002 0 P 0 ;0
L 1.17306998 -1.99108002 1.18971998 -1.99263002 0 P 0 ;0
L 1.18971998 -1.99263002 1.20558002 -1.99515 0 P 0 ;0
L 1.20558002 -1.99515 1.21058996 -1.99618002 0 P 0 ;0
L 1.21058996 -1.99618002 1.21126998 -1.99636004 0 P 0 ;0
L 1.21126998 -1.99636004 1.21191998 -1.99656998 0 P 0 ;0
L 1.21191998 -1.99656998 1.21253002 -1.99681998 0 P 0 ;0
L 1.21253002 -1.99681998 1.21261004 -1.99686004 0 P 0 ;0
L 1.21261004 -1.99686004 1.21266004 -1.99688996 0 P 0 ;0
L 1.21266004 -1.99688996 1.21271998 -1.99693002 0 P 0 ;0
L 1.21271998 -1.99693002 1.21281998 -1.99703002 0 P 0 ;0
L 1.21281998 -1.99703002 1.21286004 -1.99708996 0 P 0 ;0
L 1.21286004 -1.99708996 1.21288002 -1.99711004 0 P 0 ;0
L 1.21288002 -1.99711004 1.21288002 -1.99711998 0 P 0 ;0
L 1.21288002 -1.99711998 1.21288996 -1.99715 0 P 0 ;0
L 1.21288996 -1.99715 1.2129 -1.99716998 0 P 0 ;0
L 1.2129 -1.99716998 1.2129 -1.99721998 0 P 0 ;0
L 1.2129 -1.99721998 1.21285 -1.99875 0 P 0 ;0
L 1.21285 -1.99875 1.21243996 -2.00556998 0 P 0 ;0
L 1.21243996 -2.00556998 1.21193996 -2.01361004 0 P 0 ;0
L 1.21193996 -2.01361004 1.21133996 -2.02273002 0 P 0 ;0
L 1.21133996 -2.02273002 1.21133996 -2.02273996 0 P 0 ;0
L 1.21133996 -2.02273996 1.21058996 -2.03468002 0 P 0 ;0
L 1.21058996 -2.03468002 1.20956004 -2.05216998 0 P 0 ;0
L 1.20956004 -2.05216998 1.20848996 -2.07156004 0 P 0 ;0
L 1.20848996 -2.07156004 1.20848996 -2.07156998 0 P 0 ;0
L 1.20848996 -2.07156998 1.20751004 -2.09011004 0 P 0 ;0
L 1.20751004 -2.09011004 1.20658996 -2.10743996 0 P 0 ;0
L 1.20658996 -2.10743996 1.20561998 -2.12308996 0 P 0 ;0
L 1.20561998 -2.12308996 1.20473002 -2.13618996 0 P 0 ;0
L 1.20473002 -2.13618996 1.20453002 -2.13831998 0 P 0 ;0
L 1.20453002 -2.13831998 1.20423996 -2.14041004 0 P 0 ;0
L 1.20423996 -2.14041004 1.2035 -2.144 0 P 0 ;0
L 1.2035 -2.144 1.20246004 -2.1475 0 P 0 ;0
L 1.20246004 -2.1475 1.20111998 -2.1509 0 P 0 ;0
L 1.20111998 -2.1509 1.19936998 -2.1545 0 P 0 ;0
L 1.19936998 -2.1545 1.19738002 -2.15796998 0 P 0 ;0
L 1.19738002 -2.15796998 1.19516004 -2.1613 0 P 0 ;0
L 1.19516004 -2.1613 1.19276998 -2.16441004 0 P 0 ;0
L 1.19276998 -2.16441004 1.19016004 -2.16733996 0 P 0 ;0
L 1.19016004 -2.16733996 1.18736004 -2.17008002 0 P 0 ;0
L 1.18736004 -2.17008002 1.1854 -2.17173996 0 P 0 ;0
L 1.1854 -2.17173996 1.18335 -2.17323002 0 P 0 ;0
L 1.18335 -2.17323002 1.18118002 -2.17456004 0 P 0 ;0
L 1.18118002 -2.17456004 1.17893002 -2.17573002 0 P 0 ;0
L 1.17893002 -2.17573002 1.17456998 -2.1776 0 P 0 ;0
L 1.17456998 -2.1776 1.17006998 -2.17911998 0 P 0 ;0
L 1.17006998 -2.17911998 1.16473996 -2.18053002 0 P 0 ;0
L 1.16473996 -2.18053002 1.15935 -2.18166998 0 P 0 ;0
L 1.15935 -2.18166998 1.15341998 -2.18263002 0 P 0 ;0
L 1.15341998 -2.18263002 1.1475 -2.18328996 0 P 0 ;0
L 1.1475 -2.18328996 1.13506998 -2.18383002 0 P 0 ;0
L 0.90491998 -2.21461998 1.00131004 -2.21461998 0 P 0 ;0
L 0.92235 -2.21361998 1.00355 -2.21361998 0 P 0 ;0
L 0.76925 -1.8965 0.85586998 -1.8965 0 P 0 ;0
L 0.76958996 -1.8955 0.85556004 -1.8955 0 P 0 ;0
L 0.76995 -1.8945 0.85521004 -1.8945 0 P 0 ;0
L 0.77031004 -1.8935 0.85486004 -1.8935 0 P 0 ;0
L 0.77071004 -1.8925 0.85443996 -1.8925 0 P 0 ;0
L 0.77115 -1.8915 0.85401004 -1.8915 0 P 0 ;0
L 0.7716 -1.8905 0.85355 -1.8905 0 P 0 ;0
L 0.77206004 -1.8895 0.85303002 -1.8895 0 P 0 ;0
L 0.7726 -1.8885 0.85251004 -1.8885 0 P 0 ;0
L 0.77313996 -1.8875 0.85198996 -1.8875 0 P 0 ;0
L 0.77368996 -1.8865 0.85138002 -1.8865 0 P 0 ;0
L 0.77433002 -1.8855 0.85073996 -1.8855 0 P 0 ;0
L 0.77496004 -1.8845 0.85011004 -1.8845 0 P 0 ;0
L 0.77561998 -1.8835 0.84943002 -1.8835 0 P 0 ;0
L 0.77636004 -1.8825 0.84866998 -1.8825 0 P 0 ;0
L 0.77711004 -1.8815 0.84791004 -1.8815 0 P 0 ;0
L 0.7779 -1.8805 0.84713002 -1.8805 0 P 0 ;0
L 0.77876998 -1.8795 0.84623002 -1.8795 0 P 0 ;0
L 0.77963996 -1.8785 0.84533002 -1.8785 0 P 0 ;0
L 0.7806 -1.8775 0.8444 -1.8775 0 P 0 ;0
L 0.78161004 -1.8765 0.84335 -1.8765 0 P 0 ;0
L 0.78265 -1.8755 0.84228996 -1.8755 0 P 0 ;0
L 0.78381998 -1.8745 0.84108996 -1.8745 0 P 0 ;0
L 0.78498996 -1.8735 0.83986998 -1.8735 0 P 0 ;0
L 0.78635 -1.8725 0.83848002 -1.8725 0 P 0 ;0
L 0.78773002 -1.8715 0.83706004 -1.8715 0 P 0 ;0
L 0.78933002 -1.8705 0.83541998 -1.8705 0 P 0 ;0
L 0.791 -1.8695 0.83366004 -1.8695 0 P 0 ;0
L 0.793 -1.8685 0.83171998 -1.8685 0 P 0 ;0
L 0.79525 -1.8675 0.82941998 -1.8675 0 P 0 ;0
L 0.79791998 -1.8665 0.82671004 -1.8665 0 P 0 ;0
L 0.80143996 -1.8655 0.82328996 -1.8655 0 P 0 ;0
L 0.80705 -1.8645 0.81776004 -1.8645 0 P 0 ;0
L 0.74543002 -1.89661998 0.75033002 -1.89661998 0 P 0 ;0
L 0.74751004 -1.89561998 0.75058996 -1.89561998 0 P 0 ;0
L 0.74958996 -1.89461998 0.75086004 -1.89461998 0 P 0 ;0
L 0.76733996 -1.9125 0.85751998 -1.9125 0 P 0 ;0
L 0.76728996 -1.9115 0.85756004 -1.9115 0 P 0 ;0
L 0.76723996 -1.9105 0.85758996 -1.9105 0 P 0 ;0
L 0.76721998 -1.9095 0.85763002 -1.9095 0 P 0 ;0
L 0.76725 -1.9085 0.85761004 -1.9085 0 P 0 ;0
L 0.76728002 -1.9075 0.85756998 -1.9075 0 P 0 ;0
L 0.76731004 -1.9065 0.85753002 -1.9065 0 P 0 ;0
L 0.76741998 -1.9055 0.85748996 -1.9055 0 P 0 ;0
L 0.76753996 -1.9045 0.85738002 -1.9045 0 P 0 ;0
L 0.76766004 -1.9035 0.85726004 -1.9035 0 P 0 ;0
L 0.76781998 -1.9025 0.85713996 -1.9025 0 P 0 ;0
L 0.76801998 -1.9015 0.85701004 -1.9015 0 P 0 ;0
L 0.76821004 -1.9005 0.85683002 -1.9005 0 P 0 ;0
L 0.76841998 -1.8995 0.85661998 -1.8995 0 P 0 ;0
L 0.7687 -1.8985 0.85641004 -1.8985 0 P 0 ;0
L 0.76896998 -1.8975 0.85613996 -1.8975 0 P 0 ;0
L 0.76751004 -2.08325 0.8416 -2.08325 0 P 0 ;0
L 0.76761998 -2.08225 0.84161998 -2.08225 0 P 0 ;0
L 0.76773996 -2.08125 0.84166998 -2.08125 0 P 0 ;0
L 0.76786004 -2.08025 0.84171998 -2.08025 0 P 0 ;0
L 0.76796998 -2.07925 0.84176998 -2.07925 0 P 0 ;0
L 0.76808002 -2.07825 0.84181004 -2.07825 0 P 0 ;0
L 0.76818002 -2.07725 0.84186004 -2.07725 0 P 0 ;0
L 0.76828996 -2.07625 0.8419 -2.07625 0 P 0 ;0
L 0.76838996 -2.07525 0.84195 -2.07525 0 P 0 ;0
L 0.76848996 -2.07425 0.842 -2.07425 0 P 0 ;0
L 0.7686 -2.07325 0.84205 -2.07325 0 P 0 ;0
L 0.7687 -2.07225 0.84208996 -2.07225 0 P 0 ;0
L 0.7688 -2.07125 0.84213996 -2.07125 0 P 0 ;0
L 0.7689 -2.07025 0.84218002 -2.07025 0 P 0 ;0
L 0.76901004 -2.06925 0.84223002 -2.06925 0 P 0 ;0
L 0.76911004 -2.06825 0.84228002 -2.06825 0 P 0 ;0
L 0.76921004 -2.06725 0.84233002 -2.06725 0 P 0 ;0
L 0.76931998 -2.06625 0.84236998 -2.06625 0 P 0 ;0
L 0.76941998 -2.06525 0.84241998 -2.06525 0 P 0 ;0
L 0.76948996 -2.06425 0.84246004 -2.06425 0 P 0 ;0
L 0.76956004 -2.06325 0.84251004 -2.06325 0 P 0 ;0
L 0.76963002 -2.06225 0.84256004 -2.06225 0 P 0 ;0
L 0.7697 -2.06125 0.8426 -2.06125 0 P 0 ;0
L 0.76976998 -2.06025 0.84265 -2.06025 0 P 0 ;0
L 0.76983996 -2.05925 0.8427 -2.05925 0 P 0 ;0
L 0.76991004 -2.05825 0.84273996 -2.05825 0 P 0 ;0
L 0.76996998 -2.05725 0.84278996 -2.05725 0 P 0 ;0
L 0.77001004 -2.05625 0.84283996 -2.05625 0 P 0 ;0
L 0.77003996 -2.05525 0.84288002 -2.05525 0 P 0 ;0
L 0.77008002 -2.05425 0.84295 -2.05425 0 P 0 ;0
L 0.77011998 -2.05325 0.84303996 -2.05325 0 P 0 ;0
L 0.77016004 -2.05225 0.84311998 -2.05225 0 P 0 ;0
L 0.77018996 -2.05125 0.84321004 -2.05125 0 P 0 ;0
L 0.77023002 -2.05025 0.8433 -2.05025 0 P 0 ;0
L 0.77026998 -2.04925 0.84338002 -2.04925 0 P 0 ;0
L 0.77031004 -2.04825 0.84346998 -2.04825 0 P 0 ;0
L 0.77033996 -2.04725 0.84356004 -2.04725 0 P 0 ;0
L 0.77038002 -2.04625 0.84363996 -2.04625 0 P 0 ;0
L 0.77041004 -2.04525 0.84373002 -2.04525 0 P 0 ;0
L 0.77043996 -2.04425 0.84381004 -2.04425 0 P 0 ;0
L 0.77046004 -2.04325 0.8439 -2.04325 0 P 0 ;0
L 0.77048002 -2.04225 0.84398996 -2.04225 0 P 0 ;0
L 0.77051004 -2.04125 0.84406998 -2.04125 0 P 0 ;0
L 0.77053002 -2.04025 0.84416004 -2.04025 0 P 0 ;0
L 0.77055 -2.03925 0.84425 -2.03925 0 P 0 ;0
L 0.77058002 -2.03825 0.84433002 -2.03825 0 P 0 ;0
L 0.7706 -2.03725 0.84441998 -2.03725 0 P 0 ;0
L 0.77061998 -2.03625 0.84451004 -2.03625 0 P 0 ;0
L 0.77065 -2.03525 0.84458996 -2.03525 0 P 0 ;0
L 0.77066998 -2.03425 0.84468002 -2.03425 0 P 0 ;0
L 0.7707 -2.03325 0.84476998 -2.03325 0 P 0 ;0
L 0.77071998 -2.03225 0.84485 -2.03225 0 P 0 ;0
L 0.77073002 -2.03125 0.84493996 -2.03125 0 P 0 ;0
L 0.77073996 -2.03025 0.84503002 -2.03025 0 P 0 ;0
L 0.79986004 -1.8638 0.79643996 -1.86486998 0 P 0 ;0
L 0.79643996 -1.86486998 0.79311998 -1.86621004 0 P 0 ;0
L 0.79311998 -1.86621004 0.78991004 -1.86781004 0 P 0 ;0
L 0.78991004 -1.86781004 0.78683996 -1.86966998 0 P 0 ;0
L 0.78683996 -1.86966998 0.78391998 -1.87178002 0 P 0 ;0
L 0.78391998 -1.87178002 0.78111998 -1.87416998 0 P 0 ;0
L 0.78111998 -1.87416998 0.7785 -1.87676004 0 P 0 ;0
L 0.7785 -1.87676004 0.77608002 -1.87953996 0 P 0 ;0
L 0.77608002 -1.87953996 0.77386998 -1.8825 0 P 0 ;0
L 0.77386998 -1.8825 0.77188002 -1.88561998 0 P 0 ;0
L 0.77188002 -1.88561998 0.77013996 -1.88886004 0 P 0 ;0
L 0.77013996 -1.88886004 0.76863996 -1.89221004 0 P 0 ;0
L 0.76863996 -1.89221004 0.7674 -1.89566998 0 P 0 ;0
L 0.7674 -1.89566998 0.76643002 -1.89921004 0 P 0 ;0
L 0.76643002 -1.89921004 0.76571004 -1.90283996 0 P 0 ;0
L 0.76571004 -1.90283996 0.76531004 -1.90636004 0 P 0 ;0
L 0.76531004 -1.90636004 0.7652 -1.90991004 0 P 0 ;0
L 0.7652 -1.90991004 0.76538996 -1.91345 0 P 0 ;0
L 0.76538996 -1.91345 0.76586998 -1.91696998 0 P 0 ;0
L 0.76586998 -1.91696998 0.76663996 -1.92046004 0 P 0 ;0
L 0.76663996 -1.92046004 0.76803002 -1.92493996 0 P 0 ;0
L 0.76803002 -1.92493996 0.76978002 -1.9293 0 P 0 ;0
L 0.76978002 -1.9293 0.77106998 -1.93193996 0 P 0 ;0
L 0.77106998 -1.93193996 0.77253002 -1.93448002 0 P 0 ;0
L 0.77253002 -1.93448002 0.77416004 -1.93693996 0 P 0 ;0
L 0.77416004 -1.93693996 0.77593002 -1.93923002 0 P 0 ;0
L 0.77593002 -1.93923002 0.77783996 -1.94141004 0 P 0 ;0
L 0.77783996 -1.94141004 0.77988996 -1.94345 0 P 0 ;0
L 0.77988996 -1.94345 0.78216004 -1.94545 0 P 0 ;0
L 0.78216004 -1.94545 0.78453996 -1.9473 0 P 0 ;0
L 0.78453996 -1.9473 0.78703002 -1.94901998 0 P 0 ;0
L 0.78703002 -1.94901998 0.79016998 -1.95088002 0 P 0 ;0
L 0.79016998 -1.95088002 0.79343996 -1.95248996 0 P 0 ;0
L 0.79343996 -1.95248996 0.79683002 -1.95383996 0 P 0 ;0
L 0.79683002 -1.95383996 0.80031998 -1.95491998 0 P 0 ;0
L 0.80031998 -1.95491998 0.80391004 -1.95573996 0 P 0 ;0
L 0.80391004 -1.95573996 0.80751998 -1.95626004 0 P 0 ;0
L 0.80751998 -1.95626004 0.81116004 -1.9565 0 P 0 ;0
L 0.81116004 -1.9565 0.81481004 -1.95646004 0 P 0 ;0
L 0.81481004 -1.95646004 0.81843996 -1.95613002 0 P 0 ;0
L 0.81843996 -1.95613002 0.82205 -1.95551004 0 P 0 ;0
L 0.82205 -1.95551004 0.82561998 -1.95461004 0 P 0 ;0
L 0.82561998 -1.95461004 0.82911004 -1.95345 0 P 0 ;0
L 0.82911004 -1.95345 0.83248996 -1.95201004 0 P 0 ;0
L 0.83248996 -1.95201004 0.83576004 -1.95031998 0 P 0 ;0
L 0.83576004 -1.95031998 0.83891998 -1.94836004 0 P 0 ;0
L 0.83891998 -1.94836004 0.84191998 -1.94616998 0 P 0 ;0
L 0.84191998 -1.94616998 0.84475 -1.94375 0 P 0 ;0
L 0.84475 -1.94375 0.84738996 -1.94113996 0 P 0 ;0
L 0.84738996 -1.94113996 0.84983002 -1.93833996 0 P 0 ;0
L 0.84983002 -1.93833996 0.85206998 -1.93533996 0 P 0 ;0
L 0.85206998 -1.93533996 0.8536 -1.93291998 0 P 0 ;0
L 0.8536 -1.93291998 0.85496004 -1.93041004 0 P 0 ;0
L 0.85496004 -1.93041004 0.85613996 -1.9278 0 P 0 ;0
L 0.85613996 -1.9278 0.85711998 -1.92511004 0 P 0 ;0
L 0.85711998 -1.92511004 0.85823002 -1.92123002 0 P 0 ;0
L 0.85823002 -1.92123002 0.85901998 -1.91726998 0 P 0 ;0
L 0.85901998 -1.91726998 0.85948996 -1.91323996 0 P 0 ;0
L 0.85948996 -1.91323996 0.85963996 -1.90918002 0 P 0 ;0
L 0.85963996 -1.90918002 0.85946998 -1.90513002 0 P 0 ;0
L 0.85946998 -1.90513002 0.85898002 -1.9011 0 P 0 ;0
L 0.85898002 -1.9011 0.85841998 -1.89826004 0 P 0 ;0
L 0.85841998 -1.89826004 0.85766004 -1.89546004 0 P 0 ;0
L 0.85766004 -1.89546004 0.85671004 -1.89273002 0 P 0 ;0
L 0.85671004 -1.89273002 0.85556998 -1.89006004 0 P 0 ;0
L 0.85556998 -1.89006004 0.85361998 -1.88631004 0 P 0 ;0
L 0.85361998 -1.88631004 0.85136004 -1.88273996 0 P 0 ;0
L 0.85136004 -1.88273996 0.84881004 -1.87938002 0 P 0 ;0
L 0.84881004 -1.87938002 0.84596998 -1.87623002 0 P 0 ;0
L 0.84596998 -1.87623002 0.84355 -1.87393996 0 P 0 ;0
L 0.84355 -1.87393996 0.84096998 -1.87181998 0 P 0 ;0
L 0.84096998 -1.87181998 0.83826004 -1.86988996 0 P 0 ;0
L 0.83826004 -1.86988996 0.83541004 -1.86815 0 P 0 ;0
L 0.83541004 -1.86815 0.83243996 -1.86661004 0 P 0 ;0
L 0.83243996 -1.86661004 0.82938996 -1.86531004 0 P 0 ;0
L 0.82938996 -1.86531004 0.82625 -1.86423002 0 P 0 ;0
L 0.82625 -1.86423002 0.82303996 -1.86336004 0 P 0 ;0
L 0.82303996 -1.86336004 0.81978002 -1.86273002 0 P 0 ;0
L 0.81978002 -1.86273002 0.81646998 -1.86233002 0 P 0 ;0
L 0.81646998 -1.86233002 0.81228996 -1.86215 0 P 0 ;0
L 0.81228996 -1.86215 0.80811004 -1.86233996 0 P 0 ;0
L 0.80811004 -1.86233996 0.80396004 -1.86288996 0 P 0 ;0
L 0.80396004 -1.86288996 0.79986004 -1.8638 0 P 0 ;0
L 0.80308996 -1.9535 0.82186004 -1.9535 0 P 0 ;0
L 0.79926004 -1.9525 0.82563996 -1.9525 0 P 0 ;0
L 0.79636004 -1.9515 0.82856998 -1.9515 0 P 0 ;0
L 0.79393002 -1.9505 0.83093996 -1.9505 0 P 0 ;0
L 0.7919 -1.9495 0.83298996 -1.9495 0 P 0 ;0
L 0.79008002 -1.9485 0.8349 -1.9485 0 P 0 ;0
L 0.78838996 -1.9475 0.83651004 -1.9475 0 P 0 ;0
L 0.7869 -1.9465 0.83806998 -1.9465 0 P 0 ;0
L 0.78548002 -1.9455 0.83943996 -1.9455 0 P 0 ;0
L 0.7842 -1.9445 0.84078996 -1.9445 0 P 0 ;0
L 0.78298002 -1.9435 0.84196998 -1.9435 0 P 0 ;0
L 0.78183996 -1.9425 0.84313996 -1.9425 0 P 0 ;0
L 0.78076998 -1.9415 0.84418996 -1.9415 0 P 0 ;0
L 0.77976004 -1.9405 0.8452 -1.9405 0 P 0 ;0
L 0.77883002 -1.9395 0.84616998 -1.9395 0 P 0 ;0
L 0.77793996 -1.9385 0.84703996 -1.9385 0 P 0 ;0
L 0.77711998 -1.9375 0.84791004 -1.9375 0 P 0 ;0
L 0.77635 -1.9365 0.84871004 -1.9365 0 P 0 ;0
L 0.77561004 -1.9355 0.84945 -1.9355 0 P 0 ;0
L 0.77493996 -1.9345 0.8502 -1.9345 0 P 0 ;0
L 0.77428002 -1.9335 0.85086998 -1.9335 0 P 0 ;0
L 0.7737 -1.9325 0.8515 -1.9325 0 P 0 ;0
L 0.77311998 -1.9315 0.8521 -1.9315 0 P 0 ;0
L 0.77258996 -1.9305 0.85263996 -1.9305 0 P 0 ;0
L 0.7721 -1.9295 0.85318002 -1.9295 0 P 0 ;0
L 0.77161004 -1.9285 0.85363002 -1.9285 0 P 0 ;0
L 0.77121004 -1.9275 0.85408002 -1.9275 0 P 0 ;0
L 0.77081004 -1.9265 0.85448002 -1.9265 0 P 0 ;0
L 0.77041004 -1.9255 0.85485 -1.9255 0 P 0 ;0
L 0.77001004 -1.9245 0.85521998 -1.9245 0 P 0 ;0
L 0.76968002 -1.9235 0.8555 -1.9235 0 P 0 ;0
L 0.76936998 -1.9225 0.85578996 -1.9225 0 P 0 ;0
L 0.76906004 -1.9215 0.85606998 -1.9215 0 P 0 ;0
L 0.76875 -1.9205 0.85633002 -1.9205 0 P 0 ;0
L 0.76848002 -1.9195 0.85653002 -1.9195 0 P 0 ;0
L 0.76826004 -1.9185 0.85673002 -1.9185 0 P 0 ;0
L 0.76803002 -1.9175 0.85693002 -1.9175 0 P 0 ;0
L 0.76783002 -1.9165 0.85708996 -1.9165 0 P 0 ;0
L 0.76768996 -1.9155 0.85721004 -1.9155 0 P 0 ;0
L 0.76755 -1.9145 0.85733002 -1.9145 0 P 0 ;0
L 0.76741998 -1.9135 0.85745 -1.9135 0 P 0 ;0
L 0.81121004 -1.9545 0.80773002 -1.95426998 0 P 0 ;0
L 0.80773002 -1.95426998 0.80426998 -1.95376998 0 P 0 ;0
L 0.80426998 -1.95376998 0.80083996 -1.95298996 0 P 0 ;0
L 0.80083996 -1.95298996 0.7975 -1.95195 0 P 0 ;0
L 0.7975 -1.95195 0.79426004 -1.95066004 0 P 0 ;0
L 0.79426004 -1.95066004 0.79111998 -1.94911998 0 P 0 ;0
L 0.79111998 -1.94911998 0.78811004 -1.94733002 0 P 0 ;0
L 0.78811004 -1.94733002 0.78573002 -1.94568996 0 P 0 ;0
L 0.78573002 -1.94568996 0.78343996 -1.9439 0 P 0 ;0
L 0.78343996 -1.9439 0.78126004 -1.94198996 0 P 0 ;0
L 0.78126004 -1.94198996 0.7793 -1.94003996 0 P 0 ;0
L 0.7793 -1.94003996 0.77746998 -1.93796004 0 P 0 ;0
L 0.77746998 -1.93796004 0.77578996 -1.93576998 0 P 0 ;0
L 0.77578996 -1.93576998 0.77423002 -1.93343002 0 P 0 ;0
L 0.77423002 -1.93343002 0.77283996 -1.931 0 P 0 ;0
L 0.77283996 -1.931 0.77161004 -1.92848996 0 P 0 ;0
L 0.77161004 -1.92848996 0.76991998 -1.92426998 0 P 0 ;0
L 0.76991998 -1.92426998 0.76858002 -1.91993996 0 P 0 ;0
L 0.76858002 -1.91993996 0.76783996 -1.91661998 0 P 0 ;0
L 0.76783996 -1.91661998 0.76738002 -1.91326998 0 P 0 ;0
L 0.76738002 -1.91326998 0.76721004 -1.90988996 0 P 0 ;0
L 0.76721004 -1.90988996 0.76731004 -1.90651004 0 P 0 ;0
L 0.76731004 -1.90651004 0.7677 -1.90315 0 P 0 ;0
L 0.7677 -1.90315 0.76838002 -1.89966998 0 P 0 ;0
L 0.76838002 -1.89966998 0.76931004 -1.89626998 0 P 0 ;0
L 0.76931004 -1.89626998 0.7705 -1.89296004 0 P 0 ;0
L 0.7705 -1.89296004 0.77193996 -1.88973996 0 P 0 ;0
L 0.77193996 -1.88973996 0.7736 -1.88663996 0 P 0 ;0
L 0.7736 -1.88663996 0.77551004 -1.88363996 0 P 0 ;0
L 0.77551004 -1.88363996 0.77763002 -1.8808 0 P 0 ;0
L 0.77763002 -1.8808 0.77996004 -1.87813002 0 P 0 ;0
L 0.77996004 -1.87813002 0.78246998 -1.87565 0 P 0 ;0
L 0.78246998 -1.87565 0.78516004 -1.87336004 0 P 0 ;0
L 0.78516004 -1.87336004 0.78795 -1.87133996 0 P 0 ;0
L 0.78795 -1.87133996 0.79088002 -1.86956004 0 P 0 ;0
L 0.79088002 -1.86956004 0.79393996 -1.86803002 0 P 0 ;0
L 0.79393996 -1.86803002 0.79711004 -1.86675 0 P 0 ;0
L 0.79711004 -1.86675 0.80038002 -1.86573002 0 P 0 ;0
L 0.80038002 -1.86573002 0.80431004 -1.86486004 0 P 0 ;0
L 0.80431004 -1.86486004 0.80828996 -1.86433996 0 P 0 ;0
L 0.80828996 -1.86433996 0.8123 -1.86416004 0 P 0 ;0
L 0.8123 -1.86416004 0.81631004 -1.86431998 0 P 0 ;0
L 0.81631004 -1.86431998 0.81946998 -1.86471004 0 P 0 ;0
L 0.81946998 -1.86471004 0.82258996 -1.86531004 0 P 0 ;0
L 0.82258996 -1.86531004 0.82566004 -1.86613996 0 P 0 ;0
L 0.82566004 -1.86613996 0.82866998 -1.86718002 0 P 0 ;0
L 0.82866998 -1.86718002 0.83158996 -1.86843002 0 P 0 ;0
L 0.83158996 -1.86843002 0.83443002 -1.86988996 0 P 0 ;0
L 0.83443002 -1.86988996 0.83716004 -1.87156004 0 P 0 ;0
L 0.83716004 -1.87156004 0.83976004 -1.87341004 0 P 0 ;0
L 0.83976004 -1.87341004 0.84223002 -1.87543996 0 P 0 ;0
L 0.84223002 -1.87543996 0.84453996 -1.87763002 0 P 0 ;0
L 0.84453996 -1.87763002 0.84726998 -1.88065 0 P 0 ;0
L 0.84726998 -1.88065 0.84971998 -1.88388002 0 P 0 ;0
L 0.84971998 -1.88388002 0.85188996 -1.88731004 0 P 0 ;0
L 0.85188996 -1.88731004 0.85376004 -1.89091004 0 P 0 ;0
L 0.85376004 -1.89091004 0.85483996 -1.89345 0 P 0 ;0
L 0.85483996 -1.89345 0.85575 -1.89605 0 P 0 ;0
L 0.85575 -1.89605 0.85646998 -1.89871004 0 P 0 ;0
L 0.85646998 -1.89871004 0.857 -1.90141004 0 P 0 ;0
L 0.857 -1.90141004 0.85748002 -1.9053 0 P 0 ;0
L 0.85748002 -1.9053 0.85763996 -1.90918996 0 P 0 ;0
L 0.85763996 -1.90918996 0.8575 -1.91308002 0 P 0 ;0
L 0.8575 -1.91308002 0.85703996 -1.91696004 0 P 0 ;0
L 0.85703996 -1.91696004 0.85628002 -1.92076004 0 P 0 ;0
L 0.85628002 -1.92076004 0.85521998 -1.92448996 0 P 0 ;0
L 0.85521998 -1.92448996 0.85428002 -1.92705 0 P 0 ;0
L 0.85428002 -1.92705 0.85316998 -1.92951998 0 P 0 ;0
L 0.85316998 -1.92951998 0.85188002 -1.93191004 0 P 0 ;0
L 0.85188002 -1.93191004 0.85041998 -1.9342 0 P 0 ;0
L 0.85041998 -1.9342 0.84826998 -1.93708002 0 P 0 ;0
L 0.84826998 -1.93708002 0.84593002 -1.93976998 0 P 0 ;0
L 0.84593002 -1.93976998 0.8434 -1.94228002 0 P 0 ;0
L 0.8434 -1.94228002 0.84068002 -1.9446 0 P 0 ;0
L 0.84068002 -1.9446 0.8378 -1.9467 0 P 0 ;0
L 0.8378 -1.9467 0.83476998 -1.94858002 0 P 0 ;0
L 0.83476998 -1.94858002 0.83163996 -1.9502 0 P 0 ;0
L 0.83163996 -1.9502 0.8284 -1.95158002 0 P 0 ;0
L 0.8284 -1.95158002 0.82506004 -1.95268996 0 P 0 ;0
L 0.82506004 -1.95268996 0.82163996 -1.95356004 0 P 0 ;0
L 0.82163996 -1.95356004 0.81818002 -1.95413996 0 P 0 ;0
L 0.81818002 -1.95413996 0.8147 -1.95446004 0 P 0 ;0
L 0.8147 -1.95446004 0.81121004 -1.9545 0 P 0 ;0
L 0.77075 -2.02925 0.84511004 -2.02925 0 P 0 ;0
L 0.77076004 -2.02825 0.8452 -2.02825 0 P 0 ;0
L 0.77076998 -2.02725 0.84528996 -2.02725 0 P 0 ;0
L 0.77078002 -2.02625 0.84536998 -2.02625 0 P 0 ;0
L 0.77078996 -2.02525 0.84548996 -2.02525 0 P 0 ;0
L 0.7708 -2.02425 0.84561998 -2.02425 0 P 0 ;0
L 0.77081004 -2.02325 0.84575 -2.02325 0 P 0 ;0
L 0.77081998 -2.02225 0.84588002 -2.02225 0 P 0 ;0
L 0.77083002 -2.02125 0.84601004 -2.02125 0 P 0 ;0
L 0.77083996 -2.02025 0.84613996 -2.02025 0 P 0 ;0
L 0.77085 -2.01925 0.84626004 -2.01925 0 P 0 ;0
L 0.77085 -2.01825 0.84638996 -2.01825 0 P 0 ;0
L 0.77085 -2.01725 0.84651998 -2.01725 0 P 0 ;0
L 0.77086004 -2.01625 0.84663996 -2.01625 0 P 0 ;0
L 0.77086004 -2.01525 0.84676998 -2.01525 0 P 0 ;0
L 0.77086004 -2.01425 0.8469 -2.01425 0 P 0 ;0
L 0.77086004 -2.01325 0.84703002 -2.01325 0 P 0 ;0
L 0.77086004 -2.01225 0.84716004 -2.01225 0 P 0 ;0
L 0.77086004 -2.01125 0.84728996 -2.01125 0 P 0 ;0
L 0.77086004 -2.01025 0.84741004 -2.01025 0 P 0 ;0
L 0.77086998 -2.00925 0.84753996 -2.00925 0 P 0 ;0
L 0.77086998 -2.00825 0.84766998 -2.00825 0 P 0 ;0
L 0.77086998 -2.00725 0.84778996 -2.00725 0 P 0 ;0
L 0.77086998 -2.00625 0.84791998 -2.00625 0 P 0 ;0
L 0.77086998 -2.00525 0.84805 -2.00525 0 P 0 ;0
L 0.77086998 -2.00425 0.84818002 -2.00425 0 P 0 ;0
L 0.77088002 -2.00325 0.84831004 -2.00325 0 P 0 ;0
L 0.77088002 -2.00225 0.84843996 -2.00225 0 P 0 ;0
L 0.77088002 -2.00125 0.84856004 -2.00125 0 P 0 ;0
L 0.77088002 -2.00025 0.84868996 -2.00025 0 P 0 ;0
L 0.77088002 -1.99925 0.84881998 -1.99925 0 P 0 ;0
L 0.77088002 -1.99825 0.84896004 -1.99825 0 P 0 ;0
L 0.77088002 -1.99725 0.84911004 -1.99725 0 P 0 ;0
L 0.77088996 -1.99625 0.84926998 -1.99625 0 P 0 ;0
L 0.77088996 -1.99525 0.84941998 -1.99525 0 P 0 ;0
L 0.77088996 -1.99425 0.84956998 -1.99425 0 P 0 ;0
L 0.77088996 -1.99325 0.84971998 -1.99325 0 P 0 ;0
L 0.77088996 -1.99225 0.84986998 -1.99225 0 P 0 ;0
L 0.77088996 -1.99125 0.85003002 -1.99125 0 P 0 ;0
L 0.7709 -1.99025 0.85018002 -1.99025 0 P 0 ;0
L 0.7709 -1.98925 0.85033002 -1.98925 0 P 0 ;0
L 0.76885 -2.01878002 0.76871998 -2.03201998 0 P 0 ;0
L 0.76871998 -2.03201998 0.7684 -2.04553996 0 P 0 ;0
L 0.7684 -2.04553996 0.76796004 -2.05751004 0 P 0 ;0
L 0.76796004 -2.05751004 0.76741004 -2.06523002 0 P 0 ;0
L 0.76741004 -2.06523002 0.76596004 -2.07933996 0 P 0 ;0
L 0.76596004 -2.07933996 0.7636 -2.09918002 0 P 0 ;0
L 0.7636 -2.09918002 0.76116004 -2.119 0 P 0 ;0
L 0.76116004 -2.119 0.76011998 -2.12526004 0 P 0 ;0
L 0.76011998 -2.12526004 0.75948996 -2.12825 0 P 0 ;0
L 0.75948996 -2.12825 0.84418002 -2.12825 0 P 0 ;0
L 0.84418002 -2.12825 0.84361998 -2.10788002 0 P 0 ;0
L 0.84361998 -2.10788002 0.8436 -2.08276004 0 P 0 ;0
L 0.8436 -2.08276004 0.8449 -2.05491998 0 P 0 ;0
L 0.8449 -2.05491998 0.84736004 -2.02641004 0 P 0 ;0
L 0.84736004 -2.02641004 0.85083996 -1.99923002 0 P 0 ;0
L 0.85083996 -1.99923002 0.85268996 -1.987 0 P 0 ;0
L 0.85268996 -1.987 0.7689 -1.987 0 P 0 ;0
L 0.7689 -1.987 0.76885 -2.01878002 0 P 0 ;0
L 0.76195 -2.12625 0.84211998 -2.12625 0 P 0 ;0
L 0.76213996 -2.12525 0.8421 -2.12525 0 P 0 ;0
L 0.76231004 -2.12425 0.84206998 -2.12425 0 P 0 ;0
L 0.76248002 -2.12325 0.84203996 -2.12325 0 P 0 ;0
L 0.76263996 -2.12225 0.84201004 -2.12225 0 P 0 ;0
L 0.76281004 -2.12125 0.84198996 -2.12125 0 P 0 ;0
L 0.76296998 -2.12025 0.84196004 -2.12025 0 P 0 ;0
L 0.76313996 -2.11925 0.84193002 -2.11925 0 P 0 ;0
L 0.76326998 -2.11825 0.8419 -2.11825 0 P 0 ;0
L 0.76338996 -2.11725 0.84188002 -2.11725 0 P 0 ;0
L 0.76351004 -2.11625 0.84185 -2.11625 0 P 0 ;0
L 0.76363996 -2.11525 0.84181998 -2.11525 0 P 0 ;0
L 0.76376004 -2.11425 0.84178996 -2.11425 0 P 0 ;0
L 0.76388002 -2.11325 0.84176998 -2.11325 0 P 0 ;0
L 0.76401004 -2.11225 0.84173996 -2.11225 0 P 0 ;0
L 0.76413002 -2.11125 0.84171004 -2.11125 0 P 0 ;0
L 0.76425 -2.11025 0.84168002 -2.11025 0 P 0 ;0
L 0.76438002 -2.10925 0.84166004 -2.10925 0 P 0 ;0
L 0.7645 -2.10825 0.84163002 -2.10825 0 P 0 ;0
L 0.76461998 -2.10725 0.84161998 -2.10725 0 P 0 ;0
L 0.76475 -2.10625 0.84161998 -2.10625 0 P 0 ;0
L 0.76486998 -2.10525 0.84161998 -2.10525 0 P 0 ;0
L 0.76498996 -2.10425 0.84161998 -2.10425 0 P 0 ;0
L 0.76511998 -2.10325 0.84161998 -2.10325 0 P 0 ;0
L 0.76523996 -2.10225 0.84161998 -2.10225 0 P 0 ;0
L 0.76536004 -2.10125 0.84161998 -2.10125 0 P 0 ;0
L 0.76548996 -2.10025 0.84161998 -2.10025 0 P 0 ;0
L 0.76561004 -2.09925 0.84161998 -2.09925 0 P 0 ;0
L 0.76573002 -2.09825 0.84161004 -2.09825 0 P 0 ;0
L 0.76583996 -2.09725 0.84161004 -2.09725 0 P 0 ;0
L 0.76596998 -2.09625 0.84161004 -2.09625 0 P 0 ;0
L 0.76608996 -2.09525 0.84161004 -2.09525 0 P 0 ;0
L 0.7662 -2.09425 0.84161004 -2.09425 0 P 0 ;0
L 0.76631998 -2.09325 0.84161004 -2.09325 0 P 0 ;0
L 0.76643996 -2.09225 0.84161004 -2.09225 0 P 0 ;0
L 0.76656004 -2.09125 0.84161004 -2.09125 0 P 0 ;0
L 0.76668002 -2.09025 0.84161004 -2.09025 0 P 0 ;0
L 0.76678996 -2.08925 0.84161004 -2.08925 0 P 0 ;0
L 0.76691998 -2.08825 0.84161004 -2.08825 0 P 0 ;0
L 0.76703002 -2.08725 0.84161004 -2.08725 0 P 0 ;0
L 0.76715 -2.08625 0.8416 -2.08625 0 P 0 ;0
L 0.76726998 -2.08525 0.8416 -2.08525 0 P 0 ;0
L 0.76738996 -2.08425 0.8416 -2.08425 0 P 0 ;0
L 0.76195 -2.12625 0.76208002 -2.12561998 0 P 0 ;0
L 0.76208002 -2.12561998 0.76313996 -2.11928996 0 P 0 ;0
L 0.76313996 -2.11928996 0.76558996 -2.09941998 0 P 0 ;0
L 0.76558996 -2.09941998 0.76558996 -2.09941004 0 P 0 ;0
L 0.76558996 -2.09941004 0.76793996 -2.07956004 0 P 0 ;0
L 0.76793996 -2.07956004 0.7694 -2.0654 0 P 0 ;0
L 0.7694 -2.0654 0.76941004 -2.06536004 0 P 0 ;0
L 0.76941004 -2.06536004 0.76996004 -2.05761998 0 P 0 ;0
L 0.76996004 -2.05761998 0.76996004 -2.05758996 0 P 0 ;0
L 0.76996004 -2.05758996 0.7704 -2.0456 0 P 0 ;0
L 0.7704 -2.0456 0.77071998 -2.03206004 0 P 0 ;0
L 0.77071998 -2.03206004 0.77085 -2.01878002 0 P 0 ;0
L 0.77085 -2.01878002 0.7709 -1.989 0 P 0 ;0
L 0.7709 -1.989 0.85036004 -1.989 0 P 0 ;0
L 0.85036004 -1.989 0.84886004 -1.99895 0 P 0 ;0
L 0.84886004 -1.99895 0.84538002 -2.02618996 0 P 0 ;0
L 0.84538002 -2.02618996 0.8429 -2.05478996 0 P 0 ;0
L 0.8429 -2.05478996 0.8416 -2.08271004 0 P 0 ;0
L 0.8416 -2.08271004 0.84161998 -2.10791004 0 P 0 ;0
L 0.84161998 -2.10791004 0.84211998 -2.12625 0 P 0 ;0
L 0.84211998 -2.12625 0.76195 -2.12625 0 P 0 ;0
L 0.71628996 -1.91261998 0.74938002 -1.91261998 0 P 0 ;0
L 0.71783002 -1.91161998 0.74933002 -1.91161998 0 P 0 ;0
L 0.71953002 -1.91061998 0.74931004 -1.91061998 0 P 0 ;0
L 0.72133002 -1.90961998 0.74928996 -1.90961998 0 P 0 ;0
L 0.72313996 -1.90861998 0.74926998 -1.90861998 0 P 0 ;0
L 0.72493996 -1.90761998 0.74928996 -1.90761998 0 P 0 ;0
L 0.72673996 -1.90661998 0.74931998 -1.90661998 0 P 0 ;0
L 0.72855 -1.90561998 0.74935 -1.90561998 0 P 0 ;0
L 0.73035 -1.90461998 0.74938996 -1.90461998 0 P 0 ;0
L 0.73215 -1.90361998 0.74946998 -1.90361998 0 P 0 ;0
L 0.73396004 -1.90261998 0.74953996 -1.90261998 0 P 0 ;0
L 0.73576004 -1.90161998 0.74961998 -1.90161998 0 P 0 ;0
L 0.73756998 -1.90061998 0.74973996 -1.90061998 0 P 0 ;0
L 0.73943002 -1.89961998 0.74986004 -1.89961998 0 P 0 ;0
L 0.74141998 -1.89861998 0.74998996 -1.89861998 0 P 0 ;0
L 0.74341004 -1.89761998 0.75015 -1.89761998 0 P 0 ;0
L 0.59843002 -2.08361998 0.6754 -2.08361998 0 P 0 ;0
L 0.59846004 -2.08261998 0.67538996 -2.08261998 0 P 0 ;0
L 0.59848002 -2.08161998 0.67538002 -2.08161998 0 P 0 ;0
L 0.59851004 -2.08061998 0.67538002 -2.08061998 0 P 0 ;0
L 0.59853002 -2.07961998 0.67546004 -2.07961998 0 P 0 ;0
L 0.59856004 -2.07861998 0.67553996 -2.07861998 0 P 0 ;0
L 0.59861998 -2.07761998 0.67561004 -2.07761998 0 P 0 ;0
L 0.5987 -2.07661998 0.67568996 -2.07661998 0 P 0 ;0
L 0.59878002 -2.07561998 0.67576004 -2.07561998 0 P 0 ;0
L 0.59885 -2.07461998 0.67583996 -2.07461998 0 P 0 ;0
L 0.59893002 -2.07361998 0.67591998 -2.07361998 0 P 0 ;0
L 0.59901004 -2.07261998 0.67598996 -2.07261998 0 P 0 ;0
L 0.59908002 -2.07161998 0.67606998 -2.07161998 0 P 0 ;0
L 0.59916004 -2.07061998 0.67613996 -2.07061998 0 P 0 ;0
L 0.59923002 -2.06961998 0.67621004 -2.06961998 0 P 0 ;0
L 0.59936004 -2.06861998 0.6763 -2.06861998 0 P 0 ;0
L 0.59948996 -2.06761998 0.67645 -2.06761998 0 P 0 ;0
L 0.59963002 -2.06661998 0.6766 -2.06661998 0 P 0 ;0
L 0.59976998 -2.06561998 0.67676004 -2.06561998 0 P 0 ;0
L 0.5999 -2.06461998 0.67691998 -2.06461998 0 P 0 ;0
L 0.60003002 -2.06361998 0.67706998 -2.06361998 0 P 0 ;0
L 0.60016998 -2.06261998 0.6773 -2.06261998 0 P 0 ;0
L 0.60031004 -2.06161998 0.67753002 -2.06161998 0 P 0 ;0
L 0.60051004 -2.06061998 0.67776004 -2.06061998 0 P 0 ;0
L 0.60071004 -2.05961998 0.67798996 -2.05961998 0 P 0 ;0
L 0.60091998 -2.05861998 0.67823002 -2.05861998 0 P 0 ;0
L 0.60111998 -2.05761998 0.67853002 -2.05761998 0 P 0 ;0
L 0.60133002 -2.05661998 0.67883996 -2.05661998 0 P 0 ;0
L 0.60153996 -2.05561998 0.67913996 -2.05561998 0 P 0 ;0
L 0.60173996 -2.05461998 0.67945 -2.05461998 0 P 0 ;0
L 0.60195 -2.05361998 0.67975 -2.05361998 0 P 0 ;0
L 0.60223002 -2.05261998 0.68006004 -2.05261998 0 P 0 ;0
L 0.60251004 -2.05161998 0.68036004 -2.05161998 0 P 0 ;0
L 0.60278996 -2.05061998 0.68066998 -2.05061998 0 P 0 ;0
L 0.60306004 -2.04961998 0.68096998 -2.04961998 0 P 0 ;0
L 0.60333996 -2.04861998 0.68135 -2.04861998 0 P 0 ;0
L 0.60361998 -2.04761998 0.68173002 -2.04761998 0 P 0 ;0
L 0.6039 -2.04661998 0.68211004 -2.04661998 0 P 0 ;0
L 0.60418002 -2.04561998 0.68248996 -2.04561998 0 P 0 ;0
L 0.60453002 -2.04461998 0.68288002 -2.04461998 0 P 0 ;0
L 0.60488002 -2.04361998 0.68326004 -2.04361998 0 P 0 ;0
L 0.60523002 -2.04261998 0.68363996 -2.04261998 0 P 0 ;0
L 0.60556998 -2.04161998 0.68401998 -2.04161998 0 P 0 ;0
L 0.60591998 -2.04061998 0.6844 -2.04061998 0 P 0 ;0
L 0.60626998 -2.03961998 0.68486004 -2.03961998 0 P 0 ;0
L 0.60661998 -2.03861998 0.68531998 -2.03861998 0 P 0 ;0
L 0.60698996 -2.03761998 0.68578002 -2.03761998 0 P 0 ;0
L 0.60743002 -2.03661998 0.68623996 -2.03661998 0 P 0 ;0
L 0.60786004 -2.03561998 0.6867 -2.03561998 0 P 0 ;0
L 0.60828996 -2.03461998 0.68716004 -2.03461998 0 P 0 ;0
L 0.60873002 -2.03361998 0.68761998 -2.03361998 0 P 0 ;0
L 0.60916004 -2.03261998 0.68808996 -2.03261998 0 P 0 ;0
L 0.60958996 -2.03161998 0.68856998 -2.03161998 0 P 0 ;0
L 0.61003002 -2.03061998 0.68911004 -2.03061998 0 P 0 ;0
L 0.61046004 -2.02961998 0.68965 -2.02961998 0 P 0 ;0
L 0.61088996 -2.02861998 0.69018996 -2.02861998 0 P 0 ;0
L 0.61133002 -2.02761998 0.69073002 -2.02761998 0 P 0 ;0
L 0.61176004 -2.02661998 0.69126998 -2.02661998 0 P 0 ;0
L 0.6122 -2.02561998 0.69181004 -2.02561998 0 P 0 ;0
L 0.61263002 -2.02461998 0.69235 -2.02461998 0 P 0 ;0
L 0.61306004 -2.02361998 0.69288002 -2.02361998 0 P 0 ;0
L 0.61348996 -2.02261998 0.69346998 -2.02261998 0 P 0 ;0
L 0.61393002 -2.02161998 0.69408996 -2.02161998 0 P 0 ;0
L 0.61436004 -2.02061998 0.6947 -2.02061998 0 P 0 ;0
L 0.61478996 -2.01961998 0.69531998 -2.01961998 0 P 0 ;0
L 0.61531004 -2.01861998 0.69593996 -2.01861998 0 P 0 ;0
L 0.61583996 -2.01761998 0.69656004 -2.01761998 0 P 0 ;0
L 0.61636004 -2.01661998 0.69718002 -2.01661998 0 P 0 ;0
L 0.61688002 -2.01561998 0.69778996 -2.01561998 0 P 0 ;0
L 0.6174 -2.01461998 0.69841998 -2.01461998 0 P 0 ;0
L 0.61791998 -2.01361998 0.69911998 -2.01361998 0 P 0 ;0
L 0.61843996 -2.01261998 0.69981998 -2.01261998 0 P 0 ;0
L 0.61896004 -2.01161998 0.70051998 -2.01161998 0 P 0 ;0
L 0.61948002 -2.01061998 0.70123002 -2.01061998 0 P 0 ;0
L 0.62 -2.00961998 0.70193002 -2.00961998 0 P 0 ;0
L 0.62051998 -2.00861998 0.70263002 -2.00861998 0 P 0 ;0
L 0.62103996 -2.00761998 0.70333002 -2.00761998 0 P 0 ;0
L 0.62163996 -2.00661998 0.70403996 -2.00661998 0 P 0 ;0
L 0.62225 -2.00561998 0.70483002 -2.00561998 0 P 0 ;0
L 0.62285 -2.00461998 0.70565 -2.00461998 0 P 0 ;0
L 0.62346004 -2.00361998 0.70646004 -2.00361998 0 P 0 ;0
L 0.62406004 -2.00261998 0.70726998 -2.00261998 0 P 0 ;0
L 0.62466004 -2.00161998 0.70808996 -2.00161998 0 P 0 ;0
L 0.62526998 -2.00061998 0.7089 -2.00061998 0 P 0 ;0
L 0.62586998 -1.99961998 0.70971004 -1.99961998 0 P 0 ;0
L 0.62648002 -1.99861998 0.71053002 -1.99861998 0 P 0 ;0
L 0.62708002 -1.99761998 0.71133996 -1.99761998 0 P 0 ;0
L 0.62768996 -1.99661998 0.71216004 -1.99661998 0 P 0 ;0
L 0.62831998 -1.99561998 0.71296998 -1.99561998 0 P 0 ;0
L 0.62901004 -1.99461998 0.71378996 -1.99461998 0 P 0 ;0
L 0.62971004 -1.99361998 0.71466004 -1.99361998 0 P 0 ;0
L 0.6304 -1.99261998 0.71561004 -1.99261998 0 P 0 ;0
L 0.6311 -1.99161998 0.71656998 -1.99161998 0 P 0 ;0
L 0.63178996 -1.99061998 0.71753002 -1.99061998 0 P 0 ;0
L 0.63248996 -1.98961998 0.71848996 -1.98961998 0 P 0 ;0
L 0.63318002 -1.98861998 0.71945 -1.98861998 0 P 0 ;0
L 0.63388002 -1.98761998 0.72041004 -1.98761998 0 P 0 ;0
L 0.63456998 -1.98661998 0.72136998 -1.98661998 0 P 0 ;0
L 0.63526998 -1.98561998 0.72233002 -1.98561998 0 P 0 ;0
L 0.63598002 -1.98461998 0.72328996 -1.98461998 0 P 0 ;0
L 0.63678996 -1.98361998 0.72425 -1.98361998 0 P 0 ;0
L 0.6376 -1.98261998 0.72521004 -1.98261998 0 P 0 ;0
L 0.63841004 -1.98161998 0.72628002 -1.98161998 0 P 0 ;0
L 0.63921998 -1.98061998 0.72738996 -1.98061998 0 P 0 ;0
L 0.64003002 -1.97961998 0.7285 -1.97961998 0 P 0 ;0
L 0.64083996 -1.97861998 0.72961004 -1.97861998 0 P 0 ;0
L 0.64165 -1.97761998 0.73071004 -1.97761998 0 P 0 ;0
L 0.64246004 -1.97661998 0.73181998 -1.97661998 0 P 0 ;0
L 0.64326998 -1.97561998 0.73293002 -1.97561998 0 P 0 ;0
L 0.64406998 -1.97461998 0.73403996 -1.97461998 0 P 0 ;0
L 0.64488002 -1.97361998 0.73515 -1.97361998 0 P 0 ;0
L 0.64568996 -1.97261998 0.73625 -1.97261998 0 P 0 ;0
L 0.6465 -1.97161998 0.73736004 -1.97161998 0 P 0 ;0
L 0.64731004 -1.97061998 0.73848002 -1.97061998 0 P 0 ;0
L 0.64811998 -1.96961998 0.73973002 -1.96961998 0 P 0 ;0
L 0.64893002 -1.96861998 0.74098996 -1.96861998 0 P 0 ;0
L 0.64981004 -1.96761998 0.74225 -1.96761998 0 P 0 ;0
L 0.65076004 -1.96661998 0.74351004 -1.96661998 0 P 0 ;0
L 0.65171004 -1.96561998 0.74476998 -1.96561998 0 P 0 ;0
L 0.65266998 -1.96461998 0.74603002 -1.96461998 0 P 0 ;0
L 0.65361998 -1.96361998 0.74728996 -1.96361998 0 P 0 ;0
L 0.65458002 -1.96261998 0.74855 -1.96261998 0 P 0 ;0
L 0.65553002 -1.96161998 0.74981004 -1.96161998 0 P 0 ;0
L 0.65648996 -1.96061998 0.75106004 -1.96061998 0 P 0 ;0
L 0.65743996 -1.95961998 0.75233996 -1.95961998 0 P 0 ;0
L 0.6584 -1.95861998 0.7537 -1.95861998 0 P 0 ;0
L 0.65935 -1.95761998 0.75506004 -1.95761998 0 P 0 ;0
L 0.66031004 -1.95661998 0.75641998 -1.95661998 0 P 0 ;0
L 0.66126004 -1.95561998 0.75778996 -1.95561998 0 P 0 ;0
L 0.66221004 -1.95461998 0.75916004 -1.95461998 0 P 0 ;0
L 0.66316998 -1.95361998 0.76053996 -1.95361998 0 P 0 ;0
L 0.66411998 -1.95261998 0.76193996 -1.95261998 0 P 0 ;0
L 0.66523002 -1.95161998 0.76333996 -1.95161998 0 P 0 ;0
L 0.66636004 -1.95061998 0.76406998 -1.95061998 0 P 0 ;0
L 0.66746998 -1.94961998 0.76355 -1.94961998 0 P 0 ;0
L 0.6686 -1.94861998 0.76291998 -1.94861998 0 P 0 ;0
L 0.66971004 -1.94761998 0.76226998 -1.94761998 0 P 0 ;0
L 0.67083996 -1.94661998 0.76161998 -1.94661998 0 P 0 ;0
L 0.67196004 -1.94561998 0.76096998 -1.94561998 0 P 0 ;0
L 0.67306998 -1.94461998 0.76033002 -1.94461998 0 P 0 ;0
L 0.6742 -1.94361998 0.75968996 -1.94361998 0 P 0 ;0
L 0.67531004 -1.94261998 0.75905 -1.94261998 0 P 0 ;0
L 0.67643996 -1.94161998 0.75846004 -1.94161998 0 P 0 ;0
L 0.67755 -1.94061998 0.75788996 -1.94061998 0 P 0 ;0
L 0.67868002 -1.93961998 0.75731998 -1.93961998 0 P 0 ;0
L 0.67978996 -1.93861998 0.75676998 -1.93861998 0 P 0 ;0
L 0.68091998 -1.93761998 0.75626998 -1.93761998 0 P 0 ;0
L 0.68221004 -1.93661998 0.75576998 -1.93661998 0 P 0 ;0
L 0.68353002 -1.93561998 0.75528002 -1.93561998 0 P 0 ;0
L 0.68483996 -1.93461998 0.75483996 -1.93461998 0 P 0 ;0
L 0.68616004 -1.93361998 0.75441004 -1.93361998 0 P 0 ;0
L 0.68746998 -1.93261998 0.75398002 -1.93261998 0 P 0 ;0
L 0.68878002 -1.93161998 0.7536 -1.93161998 0 P 0 ;0
L 0.6901 -1.93061998 0.75323996 -1.93061998 0 P 0 ;0
L 0.69141004 -1.92961998 0.75286998 -1.92961998 0 P 0 ;0
L 0.69271998 -1.92861998 0.75253996 -1.92861998 0 P 0 ;0
L 0.69403002 -1.92761998 0.75223002 -1.92761998 0 P 0 ;0
L 0.69535 -1.92661998 0.75193002 -1.92661998 0 P 0 ;0
L 0.69666004 -1.92561998 0.75163002 -1.92561998 0 P 0 ;0
L 0.69796998 -1.92461998 0.75138002 -1.92461998 0 P 0 ;0
L 0.69936998 -1.92361998 0.75113996 -1.92361998 0 P 0 ;0
L 0.70091004 -1.92261998 0.75088996 -1.92261998 0 P 0 ;0
L 0.70243996 -1.92161998 0.75066004 -1.92161998 0 P 0 ;0
L 0.70398002 -1.92061998 0.75046004 -1.92061998 0 P 0 ;0
L 0.70551998 -1.91961998 0.75026004 -1.91961998 0 P 0 ;0
L 0.70706004 -1.91861998 0.75006998 -1.91861998 0 P 0 ;0
L 0.7086 -1.91761998 0.7499 -1.91761998 0 P 0 ;0
L 0.71013996 -1.91661998 0.74976998 -1.91661998 0 P 0 ;0
L 0.71166998 -1.91561998 0.74961998 -1.91561998 0 P 0 ;0
L 0.71321004 -1.91461998 0.74951998 -1.91461998 0 P 0 ;0
L 0.71475 -1.91361998 0.74945 -1.91361998 0 P 0 ;0
L 0.61556998 -2.15661998 0.70655 -2.15661998 0 P 0 ;0
L 0.61503002 -2.15561998 0.7056 -2.15561998 0 P 0 ;0
L 0.61448996 -2.15461998 0.70465 -2.15461998 0 P 0 ;0
L 0.61395 -2.15361998 0.7037 -2.15361998 0 P 0 ;0
L 0.61341004 -2.15261998 0.70273996 -2.15261998 0 P 0 ;0
L 0.61286998 -2.15161998 0.70178996 -2.15161998 0 P 0 ;0
L 0.61233002 -2.15061998 0.70095 -2.15061998 0 P 0 ;0
L 0.61188002 -2.14961998 0.70015 -2.14961998 0 P 0 ;0
L 0.61143002 -2.14861998 0.69935 -2.14861998 0 P 0 ;0
L 0.61098002 -2.14761998 0.69855 -2.14761998 0 P 0 ;0
L 0.61053002 -2.14661998 0.69775 -2.14661998 0 P 0 ;0
L 0.61008002 -2.14561998 0.69695 -2.14561998 0 P 0 ;0
L 0.60963002 -2.14461998 0.69615 -2.14461998 0 P 0 ;0
L 0.60918002 -2.14361998 0.69535 -2.14361998 0 P 0 ;0
L 0.60873002 -2.14261998 0.69455 -2.14261998 0 P 0 ;0
L 0.60831004 -2.14161998 0.69381998 -2.14161998 0 P 0 ;0
L 0.60793996 -2.14061998 0.69315 -2.14061998 0 P 0 ;0
L 0.60756998 -2.13961998 0.69248002 -2.13961998 0 P 0 ;0
L 0.60721004 -2.13861998 0.69181004 -2.13861998 0 P 0 ;0
L 0.60683996 -2.13761998 0.69115 -2.13761998 0 P 0 ;0
L 0.60646998 -2.13661998 0.69048002 -2.13661998 0 P 0 ;0
L 0.60611004 -2.13561998 0.68981004 -2.13561998 0 P 0 ;0
L 0.60573996 -2.13461998 0.68918002 -2.13461998 0 P 0 ;0
L 0.60538002 -2.13361998 0.68863002 -2.13361998 0 P 0 ;0
L 0.60503996 -2.13261998 0.68808002 -2.13261998 0 P 0 ;0
L 0.60476004 -2.13161998 0.68753002 -2.13161998 0 P 0 ;0
L 0.60446998 -2.13061998 0.68698002 -2.13061998 0 P 0 ;0
L 0.60418002 -2.12961998 0.68643002 -2.12961998 0 P 0 ;0
L 0.6039 -2.12861998 0.68588002 -2.12861998 0 P 0 ;0
L 0.60361004 -2.12761998 0.68533002 -2.12761998 0 P 0 ;0
L 0.60331998 -2.12661998 0.68486004 -2.12661998 0 P 0 ;0
L 0.60303002 -2.12561998 0.68441998 -2.12561998 0 P 0 ;0
L 0.60275 -2.12461998 0.68396998 -2.12461998 0 P 0 ;0
L 0.60246004 -2.12361998 0.68353002 -2.12361998 0 P 0 ;0
L 0.60218002 -2.12261998 0.68308996 -2.12261998 0 P 0 ;0
L 0.60188996 -2.12161998 0.68263996 -2.12161998 0 P 0 ;0
L 0.60166998 -2.12061998 0.6822 -2.12061998 0 P 0 ;0
L 0.60145 -2.11961998 0.68176004 -2.11961998 0 P 0 ;0
L 0.60123002 -2.11861998 0.68138996 -2.11861998 0 P 0 ;0
L 0.60101004 -2.11761998 0.68105 -2.11761998 0 P 0 ;0
L 0.60078002 -2.11661998 0.68071004 -2.11661998 0 P 0 ;0
L 0.6006 -2.11561998 0.68036004 -2.11561998 0 P 0 ;0
L 0.60043002 -2.11461998 0.68001998 -2.11461998 0 P 0 ;0
L 0.60025 -2.11361998 0.67968002 -2.11361998 0 P 0 ;0
L 0.60008002 -2.11261998 0.67933002 -2.11261998 0 P 0 ;0
L 0.59991004 -2.11161998 0.67898996 -2.11161998 0 P 0 ;0
L 0.59976004 -2.11061998 0.6787 -2.11061998 0 P 0 ;0
L 0.59963996 -2.10961998 0.67845 -2.10961998 0 P 0 ;0
L 0.59951004 -2.10861998 0.6782 -2.10861998 0 P 0 ;0
L 0.59938002 -2.10761998 0.67795 -2.10761998 0 P 0 ;0
L 0.59925 -2.10661998 0.6777 -2.10661998 0 P 0 ;0
L 0.59913002 -2.10561998 0.67746004 -2.10561998 0 P 0 ;0
L 0.59905 -2.10461998 0.67721004 -2.10461998 0 P 0 ;0
L 0.59896998 -2.10361998 0.67696004 -2.10361998 0 P 0 ;0
L 0.59888002 -2.10261998 0.67671004 -2.10261998 0 P 0 ;0
L 0.5988 -2.10161998 0.67653996 -2.10161998 0 P 0 ;0
L 0.59871998 -2.10061998 0.67638002 -2.10061998 0 P 0 ;0
L 0.59866998 -2.09961998 0.67621004 -2.09961998 0 P 0 ;0
L 0.59863996 -2.09861998 0.67605 -2.09861998 0 P 0 ;0
L 0.59861004 -2.09761998 0.67588996 -2.09761998 0 P 0 ;0
L 0.59858996 -2.09661998 0.6758 -2.09661998 0 P 0 ;0
L 0.59856004 -2.09561998 0.67571004 -2.09561998 0 P 0 ;0
L 0.59853002 -2.09461998 0.67563002 -2.09461998 0 P 0 ;0
L 0.5985 -2.09361998 0.67553996 -2.09361998 0 P 0 ;0
L 0.59846998 -2.09261998 0.67546004 -2.09261998 0 P 0 ;0
L 0.59843996 -2.09161998 0.67546004 -2.09161998 0 P 0 ;0
L 0.59841998 -2.09061998 0.67545 -2.09061998 0 P 0 ;0
L 0.59838002 -2.08961998 0.67543996 -2.08961998 0 P 0 ;0
L 0.59836004 -2.08861998 0.67543002 -2.08861998 0 P 0 ;0
L 0.59833002 -2.08761998 0.67543002 -2.08761998 0 P 0 ;0
L 0.59835 -2.08661998 0.67541998 -2.08661998 0 P 0 ;0
L 0.59836998 -2.08561998 0.67541004 -2.08561998 0 P 0 ;0
L 0.5984 -2.08461998 0.67541004 -2.08461998 0 P 0 ;0
L 0.80005 -2.25161998 0.85543996 -2.25161998 0 P 0 ;0
L 0.78651998 -2.25061998 0.86596004 -2.25061998 0 P 0 ;0
L 0.77878996 -2.24961998 0.87636004 -2.24961998 0 P 0 ;0
L 0.77106004 -2.24861998 0.88285 -2.24861998 0 P 0 ;0
L 0.76398996 -2.24761998 0.88933996 -2.24761998 0 P 0 ;0
L 0.75891998 -2.24661998 0.89583996 -2.24661998 0 P 0 ;0
L 0.73781004 -1.8982 0.71738996 -1.90951998 0 P 0 ;0
L 0.71738996 -1.90951998 0.69766998 -1.92233996 0 P 0 ;0
L 0.69766998 -1.92233996 0.67971004 -1.93601998 0 P 0 ;0
L 0.67971004 -1.93601998 0.66278996 -1.95113002 0 P 0 ;0
L 0.66278996 -1.95113002 0.64786998 -1.96675 0 P 0 ;0
L 0.64786998 -1.96675 0.63423996 -1.98358996 0 P 0 ;0
L 0.63423996 -1.98358996 0.62643996 -1.99483002 0 P 0 ;0
L 0.62643996 -1.99483002 0.61933996 -2.00655 0 P 0 ;0
L 0.61933996 -2.00655 0.61298996 -2.01873996 0 P 0 ;0
L 0.61298996 -2.01873996 0.60503002 -2.03713002 0 P 0 ;0
L 0.60503002 -2.03713002 0.60225 -2.04506004 0 P 0 ;0
L 0.60225 -2.04506004 0.59998996 -2.05323002 0 P 0 ;0
L 0.59998996 -2.05323002 0.59833996 -2.0612 0 P 0 ;0
L 0.59833996 -2.0612 0.59725 -2.06928996 0 P 0 ;0
L 0.59725 -2.06928996 0.59656998 -2.07833996 0 P 0 ;0
L 0.59656998 -2.07833996 0.59633002 -2.0875 0 P 0 ;0
L 0.59633002 -2.0875 0.59668996 -2.10036998 0 P 0 ;0
L 0.59668996 -2.10036998 0.59715 -2.10596004 0 P 0 ;0
L 0.59715 -2.10596004 0.59786004 -2.11151004 0 P 0 ;0
L 0.59786004 -2.11151004 0.59878996 -2.11686998 0 P 0 ;0
L 0.59878996 -2.11686998 0.59996998 -2.1222 0 P 0 ;0
L 0.59996998 -2.1222 0.60326998 -2.13368996 0 P 0 ;0
L 0.60326998 -2.13368996 0.60656998 -2.1427 0 P 0 ;0
L 0.60656998 -2.1427 0.6105 -2.15143996 0 P 0 ;0
L 0.6105 -2.15143996 0.61505 -2.15988002 0 P 0 ;0
L 0.61505 -2.15988002 0.62023996 -2.16803996 0 P 0 ;0
L 0.62023996 -2.16803996 0.62828996 -2.17873002 0 P 0 ;0
L 0.62828996 -2.17873002 0.63718996 -2.18871004 0 P 0 ;0
L 0.63718996 -2.18871004 0.64693002 -2.19795 0 P 0 ;0
L 0.64693002 -2.19795 0.6582 -2.20701998 0 P 0 ;0
L 0.6582 -2.20701998 0.67011004 -2.21518996 0 P 0 ;0
L 0.67011004 -2.21518996 0.68261004 -2.22243002 0 P 0 ;0
L 0.68261004 -2.22243002 0.69673996 -2.22936004 0 P 0 ;0
L 0.69673996 -2.22936004 0.71123002 -2.23543996 0 P 0 ;0
L 0.71123002 -2.23543996 0.72611998 -2.24066998 0 P 0 ;0
L 0.72611998 -2.24066998 0.74536004 -2.24598996 0 P 0 ;0
L 0.74536004 -2.24598996 0.76493002 -2.24985 0 P 0 ;0
L 0.76493002 -2.24985 0.78671998 -2.25266998 0 P 0 ;0
L 0.78671998 -2.25266998 0.80863002 -2.25425 0 P 0 ;0
L 0.80863002 -2.25425 0.83146004 -2.25463002 0 P 0 ;0
L 0.83146004 -2.25463002 0.85418002 -2.25375 0 P 0 ;0
L 0.85418002 -2.25375 0.87641004 -2.25163996 0 P 0 ;0
L 0.87641004 -2.25163996 0.89853002 -2.24823002 0 P 0 ;0
L 0.89853002 -2.24823002 0.93045 -2.24101998 0 P 0 ;0
L 0.93045 -2.24101998 0.96466004 -2.23063002 0 P 0 ;0
L 0.96466004 -2.23063002 0.99911004 -2.2178 0 P 0 ;0
L 0.99911004 -2.2178 1.03183002 -2.20318002 0 P 0 ;0
L 1.03183002 -2.20318002 1.04391998 -2.19703002 0 P 0 ;0
L 1.04391998 -2.19703002 1.05581004 -2.19048996 0 P 0 ;0
L 1.05581004 -2.19048996 1.06676004 -2.18411998 0 P 0 ;0
L 1.06676004 -2.18411998 1.06681004 -2.18408996 0 P 0 ;0
L 1.06681004 -2.18408996 1.06685 -2.18405 0 P 0 ;0
L 1.06685 -2.18405 1.0669 -2.18401004 0 P 0 ;0
L 1.0669 -2.18401004 1.06693996 -2.18396998 0 P 0 ;0
L 1.06693996 -2.18396998 1.06696998 -2.18391998 0 P 0 ;0
L 1.06696998 -2.18391998 1.06701004 -2.18386998 0 P 0 ;0
L 1.06701004 -2.18386998 1.06703002 -2.18381998 0 P 0 ;0
L 1.06703002 -2.18381998 1.06706004 -2.18376004 0 P 0 ;0
L 1.06706004 -2.18376004 1.06706998 -2.18371004 0 P 0 ;0
L 1.06706998 -2.18371004 1.06708996 -2.18365 0 P 0 ;0
L 1.06708996 -2.18365 1.06708996 -2.18358996 0 P 0 ;0
L 1.06708996 -2.18358996 1.0671 -2.18353002 0 P 0 ;0
L 1.0671 -2.18353002 1.0671 -2.18346998 0 P 0 ;0
L 1.0671 -2.18346998 1.06708996 -2.18341004 0 P 0 ;0
L 1.06708996 -2.18341004 1.06706998 -2.18336004 0 P 0 ;0
L 1.06706998 -2.18336004 1.06706004 -2.1833 0 P 0 ;0
L 1.06706004 -2.1833 1.06703002 -2.18323996 0 P 0 ;0
L 1.06703002 -2.18323996 1.06701004 -2.18318996 0 P 0 ;0
L 1.06701004 -2.18318996 1.06696998 -2.18313996 0 P 0 ;0
L 1.06696998 -2.18313996 1.06693996 -2.18308996 0 P 0 ;0
L 1.06693996 -2.18308996 1.06688002 -2.18303002 0 P 0 ;0
L 1.06688002 -2.18303002 1.06678996 -2.18296998 0 P 0 ;0
L 1.06678996 -2.18296998 1.06673002 -2.18295 0 P 0 ;0
L 1.06673002 -2.18295 1.0667 -2.18295 0 P 0 ;0
L 1.0667 -2.18295 1.06666004 -2.18293996 0 P 0 ;0
L 1.06666004 -2.18293996 1.0666 -2.18293996 0 P 0 ;0
L 1.0666 -2.18293996 1.06656998 -2.18295 0 P 0 ;0
L 1.06656998 -2.18295 1.06653002 -2.18295 0 P 0 ;0
L 1.06653002 -2.18295 1.06153002 -2.1842 0 P 0 ;0
L 1.06153002 -2.1842 1.05583996 -2.18566998 0 P 0 ;0
L 1.05583996 -2.18566998 1.04916998 -2.1875 0 P 0 ;0
L 1.04916998 -2.1875 1.0153 -2.1962 0 P 0 ;0
L 1.0153 -2.1962 0.9814 -2.20333996 0 P 0 ;0
L 0.9814 -2.20333996 0.94881998 -2.2087 0 P 0 ;0
L 0.94881998 -2.2087 0.9189 -2.21198996 0 P 0 ;0
L 0.9189 -2.21198996 0.90113996 -2.21278996 0 P 0 ;0
L 0.90113996 -2.21278996 0.87738002 -2.21265 0 P 0 ;0
L 0.87738002 -2.21265 0.854 -2.21183002 0 P 0 ;0
L 0.854 -2.21183002 0.83788996 -2.21033996 0 P 0 ;0
L 0.83788996 -2.21033996 0.8174 -2.20693002 0 P 0 ;0
L 0.8174 -2.20693002 0.79708996 -2.2023 0 P 0 ;0
L 0.79708996 -2.2023 0.7769 -2.19641004 0 P 0 ;0
L 0.7769 -2.19641004 0.76433002 -2.19183996 0 P 0 ;0
L 0.76433002 -2.19183996 0.75208996 -2.18638002 0 P 0 ;0
L 0.75208996 -2.18638002 0.74026998 -2.18006998 0 P 0 ;0
L 0.74026998 -2.18006998 0.72886998 -2.17291004 0 P 0 ;0
L 0.72886998 -2.17291004 0.71961998 -2.16603002 0 P 0 ;0
L 0.71961998 -2.16603002 0.71098996 -2.15838996 0 P 0 ;0
L 0.71098996 -2.15838996 0.70303002 -2.15003002 0 P 0 ;0
L 0.70303002 -2.15003002 0.6958 -2.14098996 0 P 0 ;0
L 0.6958 -2.14098996 0.69106998 -2.1339 0 P 0 ;0
L 0.69106998 -2.1339 0.68696004 -2.12643002 0 P 0 ;0
L 0.68696004 -2.12643002 0.68351004 -2.11863002 0 P 0 ;0
L 0.68351004 -2.11863002 0.68073996 -2.11056004 0 P 0 ;0
L 0.68073996 -2.11056004 0.67866004 -2.10218996 0 P 0 ;0
L 0.67866004 -2.10218996 0.67788002 -2.09741998 0 P 0 ;0
L 0.67788002 -2.09741998 0.67746004 -2.0926 0 P 0 ;0
L 0.67746004 -2.0926 0.67738002 -2.08076004 0 P 0 ;0
L 0.67738002 -2.08076004 0.67828002 -2.06891004 0 P 0 ;0
L 0.67828002 -2.06891004 0.67903002 -2.06403996 0 P 0 ;0
L 0.67903002 -2.06403996 0.68013002 -2.05923996 0 P 0 ;0
L 0.68013002 -2.05923996 0.68288002 -2.05021998 0 P 0 ;0
L 0.68288002 -2.05021998 0.68623996 -2.04141004 0 P 0 ;0
L 0.68623996 -2.04141004 0.69018002 -2.03286004 0 P 0 ;0
L 0.69018002 -2.03286004 0.69486004 -2.02418002 0 P 0 ;0
L 0.69486004 -2.02418002 0.70003996 -2.0158 0 P 0 ;0
L 0.70003996 -2.0158 0.70573002 -2.00768996 0 P 0 ;0
L 0.70573002 -2.00768996 0.7158 -1.99531998 0 P 0 ;0
L 0.7158 -1.99531998 0.72681004 -1.98385 0 P 0 ;0
L 0.72681004 -1.98385 0.73971004 -1.9722 0 P 0 ;0
L 0.73971004 -1.9722 0.7533 -1.9614 0 P 0 ;0
L 0.7533 -1.9614 0.75753996 -1.95828002 0 P 0 ;0
L 0.75753996 -1.95828002 0.76138002 -1.95548002 0 P 0 ;0
L 0.76138002 -1.95548002 0.76463002 -1.95316004 0 P 0 ;0
L 0.76463002 -1.95316004 0.76516004 -1.95281004 0 P 0 ;0
L 0.76516004 -1.95281004 0.7657 -1.95248996 0 P 0 ;0
L 0.7657 -1.95248996 0.76578002 -1.95243996 0 P 0 ;0
L 0.76578002 -1.95243996 0.76586004 -1.95238002 0 P 0 ;0
L 0.76586004 -1.95238002 0.76593002 -1.95231998 0 P 0 ;0
L 0.76593002 -1.95231998 0.766 -1.95223996 0 P 0 ;0
L 0.766 -1.95223996 0.76606004 -1.95216998 0 P 0 ;0
L 0.76606004 -1.95216998 0.76616004 -1.95201004 0 P 0 ;0
L 0.76616004 -1.95201004 0.7662 -1.95191998 0 P 0 ;0
L 0.7662 -1.95191998 0.76626004 -1.95173996 0 P 0 ;0
L 0.76626004 -1.95173996 0.76628002 -1.95163996 0 P 0 ;0
L 0.76628002 -1.95163996 0.7663 -1.95143002 0 P 0 ;0
L 0.7663 -1.95143002 0.7663 -1.95121004 0 P 0 ;0
L 0.7663 -1.95121004 0.76628996 -1.951 0 P 0 ;0
L 0.76628996 -1.951 0.76625 -1.95078996 0 P 0 ;0
L 0.76625 -1.95078996 0.7662 -1.95058002 0 P 0 ;0
L 0.7662 -1.95058002 0.76613002 -1.95036998 0 P 0 ;0
L 0.76613002 -1.95036998 0.76583002 -1.94966998 0 P 0 ;0
L 0.76583002 -1.94966998 0.76548996 -1.94896998 0 P 0 ;0
L 0.76548996 -1.94896998 0.76508996 -1.9483 0 P 0 ;0
L 0.76508996 -1.9483 0.76253002 -1.94436004 0 P 0 ;0
L 0.76253002 -1.94436004 0.76056998 -1.94126998 0 P 0 ;0
L 0.76056998 -1.94126998 0.75871998 -1.93806004 0 P 0 ;0
L 0.75871998 -1.93806004 0.75716998 -1.93496998 0 P 0 ;0
L 0.75716998 -1.93496998 0.7558 -1.93178002 0 P 0 ;0
L 0.7558 -1.93178002 0.7546 -1.92853996 0 P 0 ;0
L 0.7546 -1.92853996 0.75358996 -1.92521004 0 P 0 ;0
L 0.75358996 -1.92521004 0.7527 -1.92161998 0 P 0 ;0
L 0.7527 -1.92161998 0.75196998 -1.91796004 0 P 0 ;0
L 0.75196998 -1.91796004 0.75155 -1.91496004 0 P 0 ;0
L 0.75155 -1.91496004 0.75133002 -1.91193002 0 P 0 ;0
L 0.75133002 -1.91193002 0.75126998 -1.9085 0 P 0 ;0
L 0.75126998 -1.9085 0.75136004 -1.90506004 0 P 0 ;0
L 0.75136004 -1.90506004 0.75161004 -1.90181998 0 P 0 ;0
L 0.75161004 -1.90181998 0.752 -1.8986 0 P 0 ;0
L 0.752 -1.8986 0.75228996 -1.89701998 0 P 0 ;0
L 0.75228996 -1.89701998 0.75268996 -1.89546998 0 P 0 ;0
L 0.75268996 -1.89546998 0.7532 -1.89395 0 P 0 ;0
L 0.7532 -1.89395 0.75358996 -1.89281998 0 P 0 ;0
L 0.75358996 -1.89281998 0.75373002 -1.89231998 0 P 0 ;0
L 0.75373002 -1.89231998 0.75383996 -1.8918 0 P 0 ;0
L 0.75383996 -1.8918 0.75391998 -1.89138996 0 P 0 ;0
L 0.75391998 -1.89138996 0.75396998 -1.89098996 0 P 0 ;0
L 0.75396998 -1.89098996 0.75396998 -1.89086004 0 P 0 ;0
L 0.75396998 -1.89086004 0.75393996 -1.89076998 0 P 0 ;0
L 0.75393996 -1.89076998 0.7539 -1.89071004 0 P 0 ;0
L 0.7539 -1.89071004 0.75386004 -1.89066998 0 P 0 ;0
L 0.75386004 -1.89066998 0.75381004 -1.89063002 0 P 0 ;0
L 0.75381004 -1.89063002 0.75378996 -1.89061004 0 P 0 ;0
L 0.75378996 -1.89061004 0.75373002 -1.89058996 0 P 0 ;0
L 0.75373002 -1.89058996 0.75368002 -1.89056998 0 P 0 ;0
L 0.75368002 -1.89056998 0.75356004 -1.89056998 0 P 0 ;0
L 0.75356004 -1.89056998 0.75346998 -1.8906 0 P 0 ;0
L 0.75346998 -1.8906 0.74898002 -1.8927 0 P 0 ;0
L 0.74898002 -1.8927 0.74383002 -1.89518002 0 P 0 ;0
L 0.74383002 -1.89518002 0.73781004 -1.8982 0 P 0 ;0
L 0.69776998 -2.22761998 0.96701004 -2.22761998 0 P 0 ;0
L 0.6957 -2.22661998 0.96968996 -2.22661998 0 P 0 ;0
L 0.69366998 -2.22561998 0.97238002 -2.22561998 0 P 0 ;0
L 0.69163002 -2.22461998 0.97506004 -2.22461998 0 P 0 ;0
L 0.68958996 -2.22361998 0.97775 -2.22361998 0 P 0 ;0
L 0.68756004 -2.22261998 0.98043002 -2.22261998 0 P 0 ;0
L 0.68551998 -2.22161998 0.98311004 -2.22161998 0 P 0 ;0
L 0.68348996 -2.22061998 0.9858 -2.22061998 0 P 0 ;0
L 0.68176998 -2.21961998 0.98848002 -2.21961998 0 P 0 ;0
L 0.68003996 -2.21861998 0.99116998 -2.21861998 0 P 0 ;0
L 0.67831004 -2.21761998 0.99385 -2.21761998 0 P 0 ;0
L 0.67658002 -2.21661998 0.99653996 -2.21661998 0 P 0 ;0
L 0.67485 -2.21561998 0.99908002 -2.21561998 0 P 0 ;0
L 0.67311998 -2.21461998 0.87665 -2.21461998 0 P 0 ;0
L 0.6714 -2.21361998 0.85166004 -2.21361998 0 P 0 ;0
L 0.6699 -2.21261998 0.84083002 -2.21261998 0 P 0 ;0
L 0.66845 -2.21161998 0.8334 -2.21161998 0 P 0 ;0
L 0.66698996 -2.21061998 0.8274 -2.21061998 0 P 0 ;0
L 0.66553002 -2.20961998 0.82138996 -2.20961998 0 P 0 ;0
L 0.66406998 -2.20861998 0.81583002 -2.20861998 0 P 0 ;0
L 0.66261998 -2.20761998 0.81143996 -2.20761998 0 P 0 ;0
L 0.66116004 -2.20661998 0.80706004 -2.20661998 0 P 0 ;0
L 0.6597 -2.20561998 0.80266998 -2.20561998 0 P 0 ;0
L 0.65841004 -2.20461998 0.79828996 -2.20461998 0 P 0 ;0
L 0.65716998 -2.20361998 0.79448996 -2.20361998 0 P 0 ;0
L 0.65593002 -2.20261998 0.79106004 -2.20261998 0 P 0 ;0
L 0.65468996 -2.20161998 0.78763996 -2.20161998 0 P 0 ;0
L 0.83143002 -2.25261998 0.80871998 -2.25225 0 P 0 ;0
L 0.80871998 -2.25225 0.78691998 -2.25066998 0 P 0 ;0
L 0.78691998 -2.25066998 0.76525 -2.24786998 0 P 0 ;0
L 0.76525 -2.24786998 0.74581998 -2.24403996 0 P 0 ;0
L 0.74581998 -2.24403996 0.72671004 -2.23876004 0 P 0 ;0
L 0.72671004 -2.23876004 0.71196004 -2.23356998 0 P 0 ;0
L 0.71196004 -2.23356998 0.69756998 -2.22753996 0 P 0 ;0
L 0.69756998 -2.22753996 0.68355 -2.22066004 0 P 0 ;0
L 0.68355 -2.22066004 0.67118002 -2.2135 0 P 0 ;0
L 0.67118002 -2.2135 0.65938996 -2.20541004 0 P 0 ;0
L 0.65938996 -2.20541004 0.64825 -2.19643996 0 P 0 ;0
L 0.64825 -2.19643996 0.63861998 -2.18731998 0 P 0 ;0
L 0.63861998 -2.18731998 0.62983002 -2.17746998 0 P 0 ;0
L 0.62983002 -2.17746998 0.62188996 -2.1669 0 P 0 ;0
L 0.62188996 -2.1669 0.61678002 -2.15886998 0 P 0 ;0
L 0.61678002 -2.15886998 0.6123 -2.15056004 0 P 0 ;0
L 0.6123 -2.15056004 0.60841998 -2.14193996 0 P 0 ;0
L 0.60841998 -2.14193996 0.60516998 -2.13306998 0 P 0 ;0
L 0.60516998 -2.13306998 0.60191004 -2.12171004 0 P 0 ;0
L 0.60191004 -2.12171004 0.60075 -2.11648002 0 P 0 ;0
L 0.60075 -2.11648002 0.59983996 -2.11121004 0 P 0 ;0
L 0.59983996 -2.11121004 0.59913996 -2.10576004 0 P 0 ;0
L 0.59913996 -2.10576004 0.59868996 -2.10026004 0 P 0 ;0
L 0.59868996 -2.10026004 0.59833002 -2.0875 0 P 0 ;0
L 0.59833002 -2.0875 0.59856998 -2.07843996 0 P 0 ;0
L 0.59856998 -2.07843996 0.59923996 -2.0695 0 P 0 ;0
L 0.59923996 -2.0695 0.60031998 -2.06153996 0 P 0 ;0
L 0.60031998 -2.06153996 0.60193002 -2.05368996 0 P 0 ;0
L 0.60193002 -2.05368996 0.60416004 -2.04566004 0 P 0 ;0
L 0.60416004 -2.04566004 0.60688996 -2.03786004 0 P 0 ;0
L 0.60688996 -2.03786004 0.6148 -2.01961004 0 P 0 ;0
L 0.6148 -2.01961004 0.62108996 -2.00753002 0 P 0 ;0
L 0.62108996 -2.00753002 0.62811998 -1.99591998 0 P 0 ;0
L 0.62811998 -1.99591998 0.63583996 -1.98478996 0 P 0 ;0
L 0.63583996 -1.98478996 0.64936998 -1.96808002 0 P 0 ;0
L 0.64936998 -1.96808002 0.66418002 -1.95256998 0 P 0 ;0
L 0.66418002 -1.95256998 0.68098002 -1.93756004 0 P 0 ;0
L 0.68098002 -1.93756004 0.69881998 -1.92398002 0 P 0 ;0
L 0.69881998 -1.92398002 0.71841998 -1.91123996 0 P 0 ;0
L 0.71841998 -1.91123996 0.73875 -1.89996998 0 P 0 ;0
L 0.73875 -1.89996998 0.74471004 -1.89696998 0 P 0 ;0
L 0.74471004 -1.89696998 0.74983002 -1.89451004 0 P 0 ;0
L 0.74983002 -1.89451004 0.7511 -1.89391004 0 P 0 ;0
L 0.7511 -1.89391004 0.75076998 -1.89488996 0 P 0 ;0
L 0.75076998 -1.89488996 0.75033996 -1.89658996 0 P 0 ;0
L 0.75033996 -1.89658996 0.75003002 -1.8983 0 P 0 ;0
L 0.75003002 -1.8983 0.74961998 -1.90161998 0 P 0 ;0
L 0.74961998 -1.90161998 0.74936004 -1.90496004 0 P 0 ;0
L 0.74936004 -1.90496004 0.74926998 -1.9085 0 P 0 ;0
L 0.74926998 -1.9085 0.74933002 -1.91201998 0 P 0 ;0
L 0.74933002 -1.91201998 0.74956004 -1.91516998 0 P 0 ;0
L 0.74956004 -1.91516998 0.75 -1.91828996 0 P 0 ;0
L 0.75 -1.91828996 0.75075 -1.92205 0 P 0 ;0
L 0.75075 -1.92205 0.75166004 -1.92573996 0 P 0 ;0
L 0.75166004 -1.92573996 0.7527 -1.92916998 0 P 0 ;0
L 0.7527 -1.92916998 0.75393996 -1.93253002 0 P 0 ;0
L 0.75393996 -1.93253002 0.75536004 -1.93581998 0 P 0 ;0
L 0.75536004 -1.93581998 0.75696004 -1.939 0 P 0 ;0
L 0.75696004 -1.939 0.75885 -1.94231004 0 P 0 ;0
L 0.75885 -1.94231004 0.76083996 -1.94543996 0 P 0 ;0
L 0.76083996 -1.94543996 0.76338996 -1.94933996 0 P 0 ;0
L 0.76338996 -1.94933996 0.76371998 -1.94991998 0 P 0 ;0
L 0.76371998 -1.94991998 0.76401004 -1.9505 0 P 0 ;0
L 0.76401004 -1.9505 0.76423996 -1.95103002 0 P 0 ;0
L 0.76423996 -1.95103002 0.76408996 -1.95111004 0 P 0 ;0
L 0.76408996 -1.95111004 0.76348996 -1.95151004 0 P 0 ;0
L 0.76348996 -1.95151004 0.76021004 -1.95386004 0 P 0 ;0
L 0.76021004 -1.95386004 0.7602 -1.95386998 0 P 0 ;0
L 0.7602 -1.95386998 0.75636998 -1.95666004 0 P 0 ;0
L 0.75636998 -1.95666004 0.75636004 -1.95666998 0 P 0 ;0
L 0.75636004 -1.95666998 0.75635 -1.95666998 0 P 0 ;0
L 0.75635 -1.95666998 0.75208996 -1.95981004 0 P 0 ;0
L 0.75208996 -1.95981004 0.73841004 -1.97066998 0 P 0 ;0
L 0.73841004 -1.97066998 0.72541004 -1.98241004 0 P 0 ;0
L 0.72541004 -1.98241004 0.7143 -1.994 0 P 0 ;0
L 0.7143 -1.994 0.71425 -1.99406004 0 P 0 ;0
L 0.71425 -1.99406004 0.70413996 -2.00648002 0 P 0 ;0
L 0.70413996 -2.00648002 0.69836998 -2.01468996 0 P 0 ;0
L 0.69836998 -2.01468996 0.69313002 -2.02318002 0 P 0 ;0
L 0.69313002 -2.02318002 0.68838996 -2.03196004 0 P 0 ;0
L 0.68838996 -2.03196004 0.68438996 -2.04063996 0 P 0 ;0
L 0.68438996 -2.04063996 0.68098996 -2.04958002 0 P 0 ;0
L 0.68098996 -2.04958002 0.6782 -2.05873002 0 P 0 ;0
L 0.6782 -2.05873002 0.67706004 -2.06366004 0 P 0 ;0
L 0.67706004 -2.06366004 0.67628996 -2.06866998 0 P 0 ;0
L 0.67628996 -2.06866998 0.67538002 -2.08068996 0 P 0 ;0
L 0.67538002 -2.08068996 0.67546004 -2.09268996 0 P 0 ;0
L 0.67546004 -2.09268996 0.67588996 -2.09766998 0 P 0 ;0
L 0.67588996 -2.09766998 0.6767 -2.10258996 0 P 0 ;0
L 0.6767 -2.10258996 0.67881998 -2.11111998 0 P 0 ;0
L 0.67881998 -2.11111998 0.68163996 -2.11936004 0 P 0 ;0
L 0.68163996 -2.11936004 0.68516004 -2.12731998 0 P 0 ;0
L 0.68516004 -2.12731998 0.68935 -2.13493996 0 P 0 ;0
L 0.68935 -2.13493996 0.69418002 -2.14216998 0 P 0 ;0
L 0.69418002 -2.14216998 0.70153002 -2.15135 0 P 0 ;0
L 0.70153002 -2.15135 0.7096 -2.15983002 0 P 0 ;0
L 0.7096 -2.15983002 0.71836004 -2.16758996 0 P 0 ;0
L 0.71836004 -2.16758996 0.71843002 -2.16763996 0 P 0 ;0
L 0.71843002 -2.16763996 0.72773996 -2.17456004 0 P 0 ;0
L 0.72773996 -2.17456004 0.73926998 -2.1818 0 P 0 ;0
L 0.73926998 -2.1818 0.75121004 -2.18818002 0 P 0 ;0
L 0.75121004 -2.18818002 0.75128002 -2.18821004 0 P 0 ;0
L 0.75128002 -2.18821004 0.76358002 -2.19368996 0 P 0 ;0
L 0.76358002 -2.19368996 0.77628002 -2.19831004 0 P 0 ;0
L 0.77628002 -2.19831004 0.79658996 -2.20423996 0 P 0 ;0
L 0.79658996 -2.20423996 0.81701004 -2.20888996 0 P 0 ;0
L 0.81701004 -2.20888996 0.83763996 -2.21233002 0 P 0 ;0
L 0.83763996 -2.21233002 0.85388002 -2.21383002 0 P 0 ;0
L 0.85388002 -2.21383002 0.87733996 -2.21465 0 P 0 ;0
L 0.87733996 -2.21465 0.90118002 -2.21478996 0 P 0 ;0
L 0.90118002 -2.21478996 0.91906004 -2.21398996 0 P 0 ;0
L 0.91906004 -2.21398996 0.94908996 -2.21068002 0 P 0 ;0
L 0.94908996 -2.21068002 0.98176998 -2.2053 0 P 0 ;0
L 0.98176998 -2.2053 1.01575 -2.19815 0 P 0 ;0
L 1.01575 -2.19815 1.04968002 -2.18943002 0 P 0 ;0
L 1.04968002 -2.18943002 1.05633996 -2.18761004 0 P 0 ;0
L 1.05633996 -2.18761004 1.05713996 -2.1874 0 P 0 ;0
L 1.05713996 -2.1874 1.05483002 -2.18875 0 P 0 ;0
L 1.05483002 -2.18875 1.04298996 -2.19526004 0 P 0 ;0
L 1.04298996 -2.19526004 1.03096998 -2.20136998 0 P 0 ;0
L 1.03096998 -2.20136998 0.99835 -2.21595 0 P 0 ;0
L 0.99835 -2.21595 0.96401998 -2.22873996 0 P 0 ;0
L 0.96401998 -2.22873996 0.92993996 -2.23908002 0 P 0 ;0
L 0.92993996 -2.23908002 0.89816004 -2.24626004 0 P 0 ;0
L 0.89816004 -2.24626004 0.87616004 -2.24965 0 P 0 ;0
L 0.87616004 -2.24965 0.85405 -2.25176004 0 P 0 ;0
L 0.85405 -2.25176004 0.83143002 -2.25261998 0 P 0 ;0
L 0.65345 -2.20061998 0.78421004 -2.20061998 0 P 0 ;0
L 0.65221004 -2.19961998 0.78078002 -2.19961998 0 P 0 ;0
L 0.65096004 -2.19861998 0.77735 -2.19861998 0 P 0 ;0
L 0.64971998 -2.19761998 0.77438996 -2.19761998 0 P 0 ;0
L 0.64848002 -2.19661998 0.77163996 -2.19661998 0 P 0 ;0
L 0.64738996 -2.19561998 0.76888996 -2.19561998 0 P 0 ;0
L 0.64633996 -2.19461998 0.76613996 -2.19461998 0 P 0 ;0
L 0.64528002 -2.19361998 0.76343002 -2.19361998 0 P 0 ;0
L 0.64421998 -2.19261998 0.76118996 -2.19261998 0 P 0 ;0
L 0.64316998 -2.19161998 0.75893996 -2.19161998 0 P 0 ;0
L 0.64211004 -2.19061998 0.7567 -2.19061998 0 P 0 ;0
L 0.64106004 -2.18961998 0.75446004 -2.18961998 0 P 0 ;0
L 0.64 -2.18861998 0.75221004 -2.18861998 0 P 0 ;0
L 0.63895 -2.18761998 0.75018002 -2.18761998 0 P 0 ;0
L 0.63801004 -2.18661998 0.74831004 -2.18661998 0 P 0 ;0
L 0.63711004 -2.18561998 0.74643002 -2.18561998 0 P 0 ;0
L 0.63621998 -2.18461998 0.74456004 -2.18461998 0 P 0 ;0
L 0.63533002 -2.18361998 0.74268002 -2.18361998 0 P 0 ;0
L 0.63443996 -2.18261998 0.74081004 -2.18261998 0 P 0 ;0
L 0.63353996 -2.18161998 0.73898996 -2.18161998 0 P 0 ;0
L 0.63265 -2.18061998 0.73738996 -2.18061998 0 P 0 ;0
L 0.63176004 -2.17961998 0.7358 -2.17961998 0 P 0 ;0
L 0.63086998 -2.17861998 0.73421004 -2.17861998 0 P 0 ;0
L 0.62996998 -2.17761998 0.73261998 -2.17761998 0 P 0 ;0
L 0.6292 -2.17661998 0.73103002 -2.17661998 0 P 0 ;0
L 0.62845 -2.17561998 0.72943996 -2.17561998 0 P 0 ;0
L 0.6277 -2.17461998 0.72783996 -2.17461998 0 P 0 ;0
L 0.62693996 -2.17361998 0.72648002 -2.17361998 0 P 0 ;0
L 0.62618996 -2.17261998 0.72513996 -2.17261998 0 P 0 ;0
L 0.62543996 -2.17161998 0.72378996 -2.17161998 0 P 0 ;0
L 0.62468996 -2.17061998 0.72245 -2.17061998 0 P 0 ;0
L 0.62393996 -2.16961998 0.7211 -2.16961998 0 P 0 ;0
L 0.62318002 -2.16861998 0.71976004 -2.16861998 0 P 0 ;0
L 0.62243996 -2.16761998 0.71841004 -2.16761998 0 P 0 ;0
L 0.62171004 -2.16661998 0.71726998 -2.16661998 0 P 0 ;0
L 0.62108002 -2.16561998 0.71613996 -2.16561998 0 P 0 ;0
L 0.62043996 -2.16461998 0.71501004 -2.16461998 0 P 0 ;0
L 0.61981004 -2.16361998 0.71388002 -2.16361998 0 P 0 ;0
L 0.61916998 -2.16261998 0.71276004 -2.16261998 0 P 0 ;0
L 0.61853002 -2.16161998 0.71163002 -2.16161998 0 P 0 ;0
L 0.6179 -2.16061998 0.7105 -2.16061998 0 P 0 ;0
L 0.61726004 -2.15961998 0.7094 -2.15961998 0 P 0 ;0
L 0.61665 -2.15861998 0.70845 -2.15861998 0 P 0 ;0
L 0.61611004 -2.15761998 0.7075 -2.15761998 0 P 0 ;0
L 0.75383996 -2.24561998 0.901 -2.24561998 0 P 0 ;0
L 0.74876998 -2.24461998 0.90541998 -2.24461998 0 P 0 ;0
L 0.74431004 -2.24361998 0.90985 -2.24361998 0 P 0 ;0
L 0.7407 -2.24261998 0.91426998 -2.24261998 0 P 0 ;0
L 0.73708002 -2.24161998 0.9187 -2.24161998 0 P 0 ;0
L 0.73346998 -2.24061998 0.92311998 -2.24061998 0 P 0 ;0
L 0.72986004 -2.23961998 0.92753996 -2.23961998 0 P 0 ;0
L 0.72633996 -2.23861998 0.93145 -2.23861998 0 P 0 ;0
L 0.72348996 -2.23761998 0.93473996 -2.23761998 0 P 0 ;0
L 0.72063996 -2.23661998 0.93803996 -2.23661998 0 P 0 ;0
L 0.7178 -2.23561998 0.94133002 -2.23561998 0 P 0 ;0
L 0.71495 -2.23461998 0.94461998 -2.23461998 0 P 0 ;0
L 0.7121 -2.23361998 0.94791998 -2.23361998 0 P 0 ;0
L 0.70968996 -2.23261998 0.95121004 -2.23261998 0 P 0 ;0
L 0.70731004 -2.23161998 0.95451004 -2.23161998 0 P 0 ;0
L 0.70491998 -2.23061998 0.9578 -2.23061998 0 P 0 ;0
L 0.70253996 -2.22961998 0.9611 -2.22961998 0 P 0 ;0
L 0.70015 -2.22861998 0.96431998 -2.22861998 0 P 0 ;0
L 9.40448996 5.22001998 9.42358002 5.23911004 1 P 0 
L 9.41013996 5.21931004 9.42428996 5.23346004 3 P 0 
L 9.42358002 5.20588002 9.43771998 5.22001998 3 P 0 
L 9.42358002 5.23911004 9.44266998 5.22001998 1 P 0 
L 9.41933996 5.21011998 9.43348002 5.22426004 3 P 0 
L 9.41438996 5.21506998 9.42853002 5.22921004 3 P 0 
L 9.42358002 5.20093002 9.40448996 5.22001998 1 P 0 
L 9.44266998 5.22001998 9.42358002 5.20093002 1 P 0 
L 9.37013996 5.21931004 9.38428996 5.23346004 3 P 0 
L 9.37438996 5.21506998 9.38853002 5.22921004 3 P 0 
L 9.37933996 5.21011998 9.39348002 5.22426004 3 P 0 
L 9.36448996 5.22001998 9.38358002 5.23911004 1 P 0 
L 9.38358002 5.23911004 9.40266998 5.22001998 1 P 0 
L 9.38358002 5.20588002 9.39771998 5.22001998 3 P 0 
L 9.40266998 5.22001998 9.38358002 5.20093002 1 P 0 
L 9.38358002 5.20093002 9.36448996 5.22001998 1 P 0 
L 8.17891998 5.04855 8.19306004 5.06268996 3 P 0 
L 8.18386998 5.0436 8.19801004 5.05773996 3 P 0 
L 8.18811004 5.07258996 8.2072 5.0535 1 P 0 
L 8.18811004 5.03936004 8.20225 5.0535 3 P 0 
L 8.2072 5.0535 8.18811004 5.03441004 1 P 0 
L 8.17466998 5.05278996 8.18881998 5.06693996 3 P 0 
L 8.16901998 5.0535 8.18811004 5.07258996 1 P 0 
L 8.18811004 5.03441004 8.16901998 5.0535 1 P 0 
L 8.4198 5.115 8.40071004 5.09591004 1 P 0 
L 8.40071004 5.09591004 8.38161998 5.115 1 P 0 
L 8.36071004 5.09591004 8.34161998 5.115 1 P 0 
L 8.3798 5.115 8.36071004 5.09591004 1 P 0 
L 8.36071004 5.10086004 8.37485 5.115 3 P 0 
L 8.39151998 5.11005 8.40566004 5.12418996 3 P 0 
L 8.39646998 5.1051 8.41061004 5.11923996 3 P 0 
L 8.40071004 5.13408996 8.4198 5.115 1 P 0 
L 8.40071004 5.10086004 8.41485 5.115 3 P 0 
L 8.38726998 5.11428996 8.40141998 5.12843996 3 P 0 
L 8.38161998 5.115 8.40071004 5.13408996 1 P 0 
L 8.36071004 5.13408996 8.3798 5.115 1 P 0 
L 8.34161998 5.115 8.36071004 5.13408996 1 P 0 
L 8.35646998 5.1051 8.37061004 5.11923996 3 P 0 
L 8.35151998 5.11005 8.36566004 5.12418996 3 P 0 
L 8.34726998 5.11428996 8.36141998 5.12843996 3 P 0 
L 8.2529 4.66205 8.26703996 4.67618996 3 P 0 
L 8.25785 4.6571 8.27198996 4.67123996 3 P 0 
L 8.26208996 4.68608996 8.28118002 4.667 1 P 0 
L 8.24865 4.66628996 8.2628 4.68043996 3 P 0 
L 8.243 4.667 8.26208996 4.68608996 1 P 0 
L 8.22208996 4.68608996 8.24118002 4.667 1 P 0 
L 8.203 4.667 8.22208996 4.68608996 1 P 0 
L 8.21785 4.6571 8.23198996 4.67123996 3 P 0 
L 8.2129 4.66205 8.22703996 4.67618996 3 P 0 
L 8.20865 4.66628996 8.2228 4.68043996 3 P 0 
L 8.27806998 4.78291998 8.25898002 4.76383002 1 P 0 
L 8.25898002 4.76383002 8.23988996 4.78291998 1 P 0 
L 8.21898002 4.76383002 8.19988996 4.78291998 1 P 0 
L 8.23806998 4.78291998 8.21898002 4.76383002 1 P 0 
L 8.21898002 4.76878002 8.23311998 4.78291998 3 P 0 
L 8.24978996 4.77796998 8.26393002 4.79211004 3 P 0 
L 8.25473996 4.77301998 8.26888002 4.78716004 3 P 0 
L 8.25898002 4.80201004 8.27806998 4.78291998 1 P 0 
L 8.25898002 4.76878002 8.27311998 4.78291998 3 P 0 
L 8.24553996 4.78221004 8.25968996 4.79636004 3 P 0 
L 8.23988996 4.78291998 8.25898002 4.80201004 1 P 0 
L 8.21898002 4.80201004 8.23806998 4.78291998 1 P 0 
L 8.19988996 4.78291998 8.21898002 4.80201004 1 P 0 
L 8.21473996 4.77301998 8.22888002 4.78716004 3 P 0 
L 8.20978996 4.77796998 8.22393002 4.79211004 3 P 0 
L 8.20553996 4.78221004 8.21968996 4.79636004 3 P 0 
L 8.28118002 4.667 8.26208996 4.64791004 1 P 0 
L 8.26208996 4.64791004 8.243 4.667 1 P 0 
L 8.22208996 4.64791004 8.203 4.667 1 P 0 
L 8.24118002 4.667 8.22208996 4.64791004 1 P 0 
L 8.22208996 4.65286004 8.23623002 4.667 3 P 0 
L 8.26208996 4.65286004 8.27623002 4.667 3 P 0 
L 8.40071004 4.72291004 8.38161998 4.742 1 P 0 
L 8.38161998 4.742 8.40071004 4.76108996 1 P 0 
L 8.38726998 4.74128996 8.40141998 4.75543996 3 P 0 
L 8.4198 4.742 8.40071004 4.72291004 1 P 0 
L 8.40071004 4.72786004 8.41485 4.742 3 P 0 
L 8.40071004 4.76108996 8.4198 4.742 1 P 0 
L 8.39646998 4.7321 8.41061004 4.74623996 3 P 0 
L 8.39151998 4.73705 8.40566004 4.75118996 3 P 0 
L 8.36071004 4.72786004 8.37485 4.742 3 P 0 
L 8.3798 4.742 8.36071004 4.72291004 1 P 0 
L 8.36071004 4.72291004 8.34161998 4.742 1 P 0 
L 8.34726998 4.74128996 8.36141998 4.75543996 3 P 0 
L 8.35151998 4.73705 8.36566004 4.75118996 3 P 0 
L 8.35646998 4.7321 8.37061004 4.74623996 3 P 0 
L 8.34161998 4.742 8.36071004 4.76108996 1 P 0 
L 8.36071004 4.76108996 8.3798 4.742 1 P 0 
L 8.11725 5.14991004 8.09816004 5.169 1 P 0 
L 8.09816004 5.169 8.11725 5.18808996 1 P 0 
L 8.10381004 5.16828996 8.11796004 5.18243996 3 P 0 
L 8.13633996 5.169 8.11725 5.14991004 1 P 0 
L 8.11725 5.15486004 8.13138996 5.169 3 P 0 
L 8.11725 5.18808996 8.13633996 5.169 1 P 0 
L 8.11301004 5.1591 8.12715 5.17323996 3 P 0 
L 8.10806004 5.16405 8.1222 5.17818996 3 P 0 
L 8.07725 5.15486004 8.09138996 5.169 3 P 0 
L 8.09633996 5.169 8.07725 5.14991004 1 P 0 
L 8.07725 5.14991004 8.05816004 5.169 1 P 0 
L 8.06381004 5.16828996 8.07796004 5.18243996 3 P 0 
L 8.06806004 5.16405 8.0822 5.17818996 3 P 0 
L 8.07301004 5.1591 8.08715 5.17323996 3 P 0 
L 8.05816004 5.169 8.07725 5.18808996 1 P 0 
L 8.07725 5.18808996 8.09633996 5.169 1 P 0 
L 7.92373996 5.169 7.90465 5.14991004 1 P 0 
L 7.90465 5.18808996 7.92373996 5.169 1 P 0 
L 7.93551004 5.03936004 7.94965 5.0535 3 P 0 
L 7.9546 5.0535 7.93551004 5.03441004 1 P 0 
L 7.93551004 5.03441004 7.91641998 5.0535 1 P 0 
L 7.97551004 5.03441004 7.95641998 5.0535 1 P 0 
L 7.92206998 5.05278996 7.93621998 5.06693996 3 P 0 
L 7.92631998 5.04855 7.94046004 5.06268996 3 P 0 
L 7.93126998 5.0436 7.94541004 5.05773996 3 P 0 
L 7.91641998 5.0535 7.93551004 5.07258996 1 P 0 
L 7.93551004 5.07258996 7.9546 5.0535 1 P 0 
L 7.95641998 5.0535 7.97551004 5.07258996 1 P 0 
L 7.96206998 5.05278996 7.97621998 5.06693996 3 P 0 
L 7.9946 5.0535 7.97551004 5.03441004 1 P 0 
L 7.97551004 5.03936004 7.98965 5.0535 3 P 0 
L 7.97551004 5.07258996 7.9946 5.0535 1 P 0 
L 7.97126998 5.0436 7.98541004 5.05773996 3 P 0 
L 7.96631998 5.04855 7.98046004 5.06268996 3 P 0 
L 8.14811004 5.07258996 8.1672 5.0535 1 P 0 
L 8.12901998 5.0535 8.14811004 5.07258996 1 P 0 
L 8.14386998 5.0436 8.15801004 5.05773996 3 P 0 
L 8.13891998 5.04855 8.15306004 5.06268996 3 P 0 
L 8.13466998 5.05278996 8.14881998 5.06693996 3 P 0 
L 8.14811004 5.03441004 8.12901998 5.0535 1 P 0 
L 8.1672 5.0535 8.14811004 5.03441004 1 P 0 
L 8.14811004 5.03936004 8.16225 5.0535 3 P 0 
L 8.06288002 4.66193996 8.07701998 4.67608002 3 P 0 
L 8.06783002 4.65698996 8.08196998 4.67113002 3 P 0 
L 8.07206998 4.68598002 8.09116004 4.66688996 1 P 0 
L 8.07206998 4.65275 8.08621004 4.66688996 3 P 0 
L 8.05863002 4.66618002 8.07278002 4.68033002 3 P 0 
L 8.05298002 4.66688996 8.07206998 4.68598002 1 P 0 
L 8.03206998 4.68598002 8.05116004 4.66688996 1 P 0 
L 8.01298002 4.66688996 8.03206998 4.68598002 1 P 0 
L 8.02783002 4.65698996 8.04196998 4.67113002 3 P 0 
L 8.02288002 4.66193996 8.03701998 4.67608002 3 P 0 
L 8.01863002 4.66618002 8.03278002 4.68033002 3 P 0 
L 8.09116004 4.66688996 8.07206998 4.6478 1 P 0 
L 8.07206998 4.6478 8.05298002 4.66688996 1 P 0 
L 8.03206998 4.6478 8.01298002 4.66688996 1 P 0 
L 8.05116004 4.66688996 8.03206998 4.6478 1 P 0 
L 8.03206998 4.65275 8.04621004 4.66688996 3 P 0 
L 8.13633996 4.78291998 8.11725 4.76383002 1 P 0 
L 8.11725 4.76383002 8.09816004 4.78291998 1 P 0 
L 8.07725 4.76383002 8.05816004 4.78291998 1 P 0 
L 8.09633996 4.78291998 8.07725 4.76383002 1 P 0 
L 8.07725 4.76878002 8.09138996 4.78291998 3 P 0 
L 8.10806004 4.77796998 8.1222 4.79211004 3 P 0 
L 8.11301004 4.77301998 8.12715 4.78716004 3 P 0 
L 8.11725 4.80201004 8.13633996 4.78291998 1 P 0 
L 8.11725 4.76878002 8.13138996 4.78291998 3 P 0 
L 8.10381004 4.78221004 8.11796004 4.79636004 3 P 0 
L 8.09816004 4.78291998 8.11725 4.80201004 1 P 0 
L 8.07725 4.80201004 8.09633996 4.78291998 1 P 0 
L 8.05816004 4.78291998 8.07725 4.80201004 1 P 0 
L 8.07301004 4.77301998 8.08715 4.78716004 3 P 0 
L 8.06806004 4.77796998 8.0822 4.79211004 3 P 0 
L 8.06381004 4.78221004 8.07796004 4.79636004 3 P 0 
L 7.90465 4.67608996 7.92373996 4.657 1 P 0 
L 7.92373996 4.657 7.90465 4.63791004 1 P 0 
L 7.90465 5.14991004 7.88556004 5.169 1 P 0 
L 7.88556004 5.169 7.90465 5.18808996 1 P 0 
L 7.89121004 5.16828996 7.90536004 5.18243996 3 P 0 
L 7.90465 5.15486004 7.91878996 5.169 3 P 0 
L 7.90041004 5.1591 7.91455 5.17323996 3 P 0 
L 7.89546004 5.16405 7.9096 5.17818996 3 P 0 
L 7.86465 5.15486004 7.87878996 5.169 3 P 0 
L 7.88373996 5.169 7.86465 5.14991004 1 P 0 
L 7.86465 5.14991004 7.84556004 5.169 1 P 0 
L 7.85121004 5.16828996 7.86536004 5.18243996 3 P 0 
L 7.85546004 5.16405 7.8696 5.17818996 3 P 0 
L 7.86041004 5.1591 7.87455 5.17323996 3 P 0 
L 7.84556004 5.169 7.86465 5.18808996 1 P 0 
L 7.86465 5.18808996 7.88373996 5.169 1 P 0 
L 7.69203996 5.03441004 7.67295 5.0535 1 P 0 
L 7.67295 5.0535 7.69203996 5.07258996 1 P 0 
L 7.6786 5.05278996 7.69275 5.06693996 3 P 0 
L 7.71113002 5.0535 7.69203996 5.03441004 1 P 0 
L 7.69203996 5.03936004 7.70618002 5.0535 3 P 0 
L 7.69203996 5.07258996 7.71113002 5.0535 1 P 0 
L 7.6878 5.0436 7.70193996 5.05773996 3 P 0 
L 7.68285 5.04855 7.69698996 5.06268996 3 P 0 
L 7.69205 4.76383002 7.67296004 4.78291998 1 P 0 
L 7.67296004 4.78291998 7.69205 4.80201004 1 P 0 
L 7.67861004 4.78221004 7.69276004 4.79636004 3 P 0 
L 7.71113996 4.78291998 7.69205 4.76383002 1 P 0 
L 7.69205 4.76878002 7.70618996 4.78291998 3 P 0 
L 7.69205 4.80201004 7.71113996 4.78291998 1 P 0 
L 7.68781004 4.77301998 7.70195 4.78716004 3 P 0 
L 7.68286004 4.77796998 7.697 4.79211004 3 P 0 
L 7.79378996 4.76878002 7.80793002 4.78291998 3 P 0 
L 7.81288002 4.78291998 7.79378996 4.76383002 1 P 0 
L 7.79378996 4.76383002 7.7747 4.78291998 1 P 0 
L 7.83378996 4.76383002 7.8147 4.78291998 1 P 0 
L 7.78035 4.78221004 7.7945 4.79636004 3 P 0 
L 7.7846 4.77796998 7.79873996 4.79211004 3 P 0 
L 7.78955 4.77301998 7.80368996 4.78716004 3 P 0 
L 7.7747 4.78291998 7.79378996 4.80201004 1 P 0 
L 7.79378996 4.80201004 7.81288002 4.78291998 1 P 0 
L 7.8147 4.78291998 7.83378996 4.80201004 1 P 0 
L 7.82035 4.78221004 7.8345 4.79636004 3 P 0 
L 7.85288002 4.78291998 7.83378996 4.76383002 1 P 0 
L 7.83378996 4.76878002 7.84793002 4.78291998 3 P 0 
L 7.83378996 4.80201004 7.85288002 4.78291998 1 P 0 
L 7.82955 4.77301998 7.84368996 4.78716004 3 P 0 
L 7.8246 4.77796998 7.83873996 4.79211004 3 P 0 
L 7.88556004 4.657 7.90465 4.67608996 1 P 0 
L 7.89121004 4.65628996 7.90536004 4.67043996 3 P 0 
L 7.89546004 4.65205 7.9096 4.66618996 3 P 0 
L 7.85121004 4.65628996 7.86536004 4.67043996 3 P 0 
L 7.85546004 4.65205 7.8696 4.66618996 3 P 0 
L 7.84556004 4.657 7.86465 4.67608996 1 P 0 
L 7.86465 4.67608996 7.88373996 4.657 1 P 0 
L 7.90465 4.63791004 7.88556004 4.657 1 P 0 
L 7.90465 4.64286004 7.91878996 4.657 3 P 0 
L 7.90041004 4.6471 7.91455 4.66123996 3 P 0 
L 7.86465 4.64286004 7.87878996 4.657 3 P 0 
L 7.88373996 4.657 7.86465 4.63791004 1 P 0 
L 7.86465 4.63791004 7.84556004 4.657 1 P 0 
L 7.86041004 4.6471 7.87455 4.66123996 3 P 0 
L 7.62118996 5.14991004 7.6021 5.169 1 P 0 
L 7.6021 5.169 7.62118996 5.18808996 1 P 0 
L 7.60775 5.16828996 7.6219 5.18243996 3 P 0 
L 7.64028002 5.169 7.62118996 5.14991004 1 P 0 
L 7.62118996 5.15486004 7.63533002 5.169 3 P 0 
L 7.62118996 5.18808996 7.64028002 5.169 1 P 0 
L 7.61695 5.1591 7.63108996 5.17323996 3 P 0 
L 7.612 5.16405 7.62613996 5.17818996 3 P 0 
L 7.58118996 5.15486004 7.59533002 5.169 3 P 0 
L 7.60028002 5.169 7.58118996 5.14991004 1 P 0 
L 7.58118996 5.14991004 7.5621 5.169 1 P 0 
L 7.56775 5.16828996 7.5819 5.18243996 3 P 0 
L 7.572 5.16405 7.58613996 5.17818996 3 P 0 
L 7.57695 5.1591 7.59108996 5.17323996 3 P 0 
L 7.5621 5.169 7.58118996 5.18808996 1 P 0 
L 7.58118996 5.18808996 7.60028002 5.169 1 P 0 
L 7.65203996 5.03936004 7.66618002 5.0535 3 P 0 
L 7.67113002 5.0535 7.65203996 5.03441004 1 P 0 
L 7.65203996 5.03441004 7.63295 5.0535 1 P 0 
L 7.6386 5.05278996 7.65275 5.06693996 3 P 0 
L 7.64285 5.04855 7.65698996 5.06268996 3 P 0 
L 7.6478 5.0436 7.66193996 5.05773996 3 P 0 
L 7.63295 5.0535 7.65203996 5.07258996 1 P 0 
L 7.65203996 5.07258996 7.67113002 5.0535 1 P 0 
L 7.65205 4.76878002 7.66618996 4.78291998 3 P 0 
L 7.67113996 4.78291998 7.65205 4.76383002 1 P 0 
L 7.65205 4.76383002 7.63296004 4.78291998 1 P 0 
L 7.63861004 4.78221004 7.65276004 4.79636004 3 P 0 
L 7.64286004 4.77796998 7.657 4.79211004 3 P 0 
L 7.64781004 4.77301998 7.66195 4.78716004 3 P 0 
L 7.63296004 4.78291998 7.65205 4.80201004 1 P 0 
L 7.65205 4.80201004 7.67113996 4.78291998 1 P 0 
L 7.58118996 4.72608996 7.60028002 4.707 1 P 0 
L 7.5621 4.707 7.58118996 4.72608996 1 P 0 
L 7.57695 4.6971 7.59108996 4.71123996 3 P 0 
L 7.572 4.70205 7.58613996 4.71618996 3 P 0 
L 7.56775 4.70628996 7.5819 4.72043996 3 P 0 
L 7.58118996 4.68791004 7.5621 4.707 1 P 0 
L 7.60028002 4.707 7.58118996 4.68791004 1 P 0 
L 7.58118996 4.69286004 7.59533002 4.707 3 P 0 
L 7.612 4.70205 7.62613996 4.71618996 3 P 0 
L 7.61695 4.6971 7.63108996 4.71123996 3 P 0 
L 7.62118996 4.72608996 7.64028002 4.707 1 P 0 
L 7.62118996 4.69286004 7.63533002 4.707 3 P 0 
L 7.64028002 4.707 7.62118996 4.68791004 1 P 0 
L 7.60775 4.70628996 7.6219 4.72043996 3 P 0 
L 7.6021 4.707 7.62118996 4.72608996 1 P 0 
L 7.62118996 4.68791004 7.6021 4.707 1 P 0 
L 1.57765 5.18808996 1.59673996 5.169 1 P 0 
L 1.55856004 5.169 1.57765 5.18808996 1 P 0 
L 1.57341004 5.1591 1.58755 5.17323996 3 P 0 
L 1.56846004 5.16405 1.5826 5.17818996 3 P 0 
L 1.56421004 5.16828996 1.57836004 5.18243996 3 P 0 
L 1.57765 5.14991004 1.55856004 5.169 1 P 0 
L 1.59673996 5.169 1.57765 5.14991004 1 P 0 
L 1.57765 5.15486004 1.59178996 5.169 3 P 0 
L 1.60846004 5.16405 1.6226 5.17818996 3 P 0 
L 1.61341004 5.1591 1.62755 5.17323996 3 P 0 
L 1.61765 5.18808996 1.63673996 5.169 1 P 0 
L 1.61765 5.15486004 1.63178996 5.169 3 P 0 
L 1.63673996 5.169 1.61765 5.14991004 1 P 0 
L 1.60421004 5.16828996 1.61836004 5.18243996 3 P 0 
L 1.59856004 5.169 1.61765 5.18808996 1 P 0 
L 1.61765 5.14991004 1.59856004 5.169 1 P 0 
L 1.86111004 5.18808996 1.8802 5.169 1 P 0 
L 1.84201998 5.169 1.86111004 5.18808996 1 P 0 
L 1.85686998 5.1591 1.87101004 5.17323996 3 P 0 
L 1.85191998 5.16405 1.86606004 5.17818996 3 P 0 
L 1.84766998 5.16828996 1.86181998 5.18243996 3 P 0 
L 1.86111004 5.14991004 1.84201998 5.169 1 P 0 
L 1.8802 5.169 1.86111004 5.14991004 1 P 0 
L 1.86111004 5.15486004 1.87525 5.169 3 P 0 
L 1.89191998 5.16405 1.90606004 5.17818996 3 P 0 
L 1.89686998 5.1591 1.91101004 5.17323996 3 P 0 
L 1.90111004 5.18808996 1.9202 5.169 1 P 0 
L 1.90111004 5.15486004 1.91525 5.169 3 P 0 
L 1.9202 5.169 1.90111004 5.14991004 1 P 0 
L 1.88766998 5.16828996 1.90181998 5.18243996 3 P 0 
L 1.88201998 5.169 1.90111004 5.18808996 1 P 0 
L 1.90111004 5.14991004 1.88201998 5.169 1 P 0 
L 2.07371004 5.18808996 2.0928 5.169 1 P 0 
L 2.05461998 5.169 2.07371004 5.18808996 1 P 0 
L 2.06946998 5.1591 2.08361004 5.17323996 3 P 0 
L 2.06451998 5.16405 2.07866004 5.17818996 3 P 0 
L 2.06026998 5.16828996 2.07441998 5.18243996 3 P 0 
L 2.07371004 5.14991004 2.05461998 5.169 1 P 0 
L 2.0928 5.169 2.07371004 5.14991004 1 P 0 
L 2.07371004 5.15486004 2.08785 5.169 3 P 0 
L 2.10451998 5.16405 2.11866004 5.17818996 3 P 0 
L 2.10946998 5.1591 2.12361004 5.17323996 3 P 0 
L 2.11371004 5.18808996 2.1328 5.169 1 P 0 
L 2.11371004 5.15486004 2.12785 5.169 3 P 0 
L 2.1328 5.169 2.11371004 5.14991004 1 P 0 
L 2.10026998 5.16828996 2.11441998 5.18243996 3 P 0 
L 2.09461998 5.169 2.11371004 5.18808996 1 P 0 
L 2.11371004 5.14991004 2.09461998 5.169 1 P 0 
L 2.35716998 4.76108996 2.37626004 4.742 1 P 0 
L 2.33808002 4.742 2.35716998 4.76108996 1 P 0 
L 2.35293002 4.7321 2.36706998 4.74623996 3 P 0 
L 2.34798002 4.73705 2.36211998 4.75118996 3 P 0 
L 2.34373002 4.74128996 2.35788002 4.75543996 3 P 0 
L 2.35716998 4.72291004 2.33808002 4.742 1 P 0 
L 2.37626004 4.742 2.35716998 4.72291004 1 P 0 
L 2.35716998 4.72786004 2.37131004 4.742 3 P 0 
L 2.38798002 4.73705 2.40211998 4.75118996 3 P 0 
L 2.39293002 4.7321 2.40706998 4.74623996 3 P 0 
L 2.39716998 4.76108996 2.41626004 4.742 1 P 0 
L 2.39716998 4.72786004 2.41131004 4.742 3 P 0 
L 2.41626004 4.742 2.39716998 4.72291004 1 P 0 
L 2.38373002 4.74128996 2.39788002 4.75543996 3 P 0 
L 2.37808002 4.742 2.39716998 4.76108996 1 P 0 
L 2.39716998 4.72291004 2.37808002 4.742 1 P 0 
L 1.86111004 4.67608996 1.8802 4.657 1 P 0 
L 1.84201998 4.657 1.86111004 4.67608996 1 P 0 
L 1.85686998 4.6471 1.87101004 4.66123996 3 P 0 
L 1.85191998 4.65205 1.86606004 4.66618996 3 P 0 
L 1.84766998 4.65628996 1.86181998 4.67043996 3 P 0 
L 1.86111004 4.63791004 1.84201998 4.657 1 P 0 
L 1.8802 4.657 1.86111004 4.63791004 1 P 0 
L 1.86111004 4.64286004 1.87525 4.657 3 P 0 
L 1.89191998 4.65205 1.90606004 4.66618996 3 P 0 
L 1.89686998 4.6471 1.91101004 4.66123996 3 P 0 
L 1.90111004 4.67608996 1.9202 4.657 1 P 0 
L 1.90111004 4.64286004 1.91525 4.657 3 P 0 
L 1.9202 4.657 1.90111004 4.63791004 1 P 0 
L 1.88766998 4.65628996 1.90181998 4.67043996 3 P 0 
L 1.88201998 4.657 1.90111004 4.67608996 1 P 0 
L 1.90111004 4.63791004 1.88201998 4.657 1 P 0 
L 1.61765 4.68791004 1.59856004 4.707 1 P 0 
L 1.59856004 4.707 1.61765 4.72608996 1 P 0 
L 1.60421004 4.70628996 1.61836004 4.72043996 3 P 0 
L 1.63673996 4.707 1.61765 4.68791004 1 P 0 
L 1.61765 4.69286004 1.63178996 4.707 3 P 0 
L 1.61765 4.72608996 1.63673996 4.707 1 P 0 
L 1.61341004 4.6971 1.62755 4.71123996 3 P 0 
L 1.60846004 4.70205 1.6226 4.71618996 3 P 0 
L 1.57765 4.69286004 1.59178996 4.707 3 P 0 
L 1.59673996 4.707 1.57765 4.68791004 1 P 0 
L 1.57765 4.68791004 1.55856004 4.707 1 P 0 
L 1.56421004 4.70628996 1.57836004 4.72043996 3 P 0 
L 1.56846004 4.70205 1.5826 4.71618996 3 P 0 
L 1.57341004 4.6971 1.58755 4.71123996 3 P 0 
L 1.55856004 4.707 1.57765 4.72608996 1 P 0 
L 1.57765 4.72608996 1.59673996 4.707 1 P 0 
L 8.45 3.66615 8.45 3.71615 8 P 0 
L 8.5 3.76615 8.5 3.81615 8 P 0 
L 8.45 3.81615 8.45 3.86615 8 P 0 
L 8.5 3.46615 8.5 3.51615 8 P 0 
L 8.45 3.41615 8.45 3.46615 8 P 0 
L 8.5 3.61615 8.5 3.66615 8 P 0 
L 8.45 3.26615 8.45 3.31615 8 P 0 
L 8.5 3.31615 8.5 3.36615 8 P 0 
L 8.2 3.66615 8.2 3.71615 8 P 0 
L 8.35 3.66615 8.35 3.71615 8 P 0 
L 8.4 3.76615 8.4 3.81615 8 P 0 
L 8.35 3.81615 8.35 3.86615 8 P 0 
L 8.2 3.81615 8.2 3.86615 8 P 0 
L 8.4 3.46615 8.4 3.51615 8 P 0 
L 8.35 3.41615 8.35 3.46615 8 P 0 
L 8.2 3.41615 8.2 3.46615 8 P 0 
L 8.4 3.61615 8.4 3.66615 8 P 0 
L 8.35 3.26615 8.35 3.31615 8 P 0 
L 8.4 3.31615 8.4 3.36615 8 P 0 
L 8.2 3.26615 8.2 3.31615 8 P 0 
L 8.25 2.86615 8.3 2.86615 8 P 0 
L 8.1 3.66615 8.1 3.71615 8 P 0 
L 8.15 3.76615 8.15 3.81615 8 P 0 
L 8.1 3.81615 8.1 3.86615 8 P 0 
L 8.05 3.76615 8.05 3.81615 8 P 0 
L 8.1 3.41615 8.1 3.46615 8 P 0 
L 8.15 3.46615 8.15 3.51615 8 P 0 
L 8 3.46615 8 3.51615 8 P 0 
L 8.05 3.61615 8.05 3.66615 8 P 0 
L 8.15 3.61615 8.15 3.66615 8 P 0 
L 8.1 3.26615 8.1 3.31615 8 P 0 
L 8.15 3.31615 8.15 3.36615 8 P 0 
L 8.05 3.31615 8.05 3.36615 8 P 0 
L 5.42048002 1.91835 5.42048002 1.87835 8 P 0 
L 5.57531004 1.8508 5.57531004 1.8108 8 P 0 
L 2.05933996 4.66193996 2.07348002 4.67608002 3 P 0 
L 2.06428996 4.65698996 2.07843002 4.67113002 3 P 0 
L 2.06853002 4.68598002 2.08761998 4.66688996 1 P 0 
L 2.06853002 4.65275 2.08266998 4.66688996 3 P 0 
L 2.05508996 4.66618002 2.06923996 4.68033002 3 P 0 
L 2.04943996 4.66688996 2.06853002 4.68598002 1 P 0 
L 2.02853002 4.68598002 2.04761998 4.66688996 1 P 0 
L 2.00943996 4.66688996 2.02853002 4.68598002 1 P 0 
L 2.02428996 4.65698996 2.03843002 4.67113002 3 P 0 
L 2.01933996 4.66193996 2.03348002 4.67608002 3 P 0 
L 2.01508996 4.66618002 2.02923996 4.68033002 3 P 0 
L 2.08761998 4.66688996 2.06853002 4.6478 1 P 0 
L 2.06853002 4.6478 2.04943996 4.66688996 1 P 0 
L 2.02853002 4.6478 2.00943996 4.66688996 1 P 0 
L 2.04761998 4.66688996 2.02853002 4.6478 1 P 0 
L 2.02853002 4.65275 2.04266998 4.66688996 3 P 0 
L 2.34606004 3.26615 2.34606004 3.31615 8 P 0 
L 2.39606004 3.31615 2.39606004 3.36615 8 P 0 
L 2.44606004 3.26615 2.44606004 3.31615 8 P 0 
L 2.49606004 3.31615 2.49606004 3.36615 8 P 0 
L 2.49606004 3.46615 2.49606004 3.51615 8 P 0 
L 2.44606004 3.41615 2.44606004 3.46615 8 P 0 
L 2.39606004 3.46615 2.39606004 3.51615 8 P 0 
L 2.34606004 3.41615 2.34606004 3.46615 8 P 0 
L 2.19606004 3.26615 2.19606004 3.31615 8 P 0 
L 2.09606004 3.26615 2.09606004 3.31615 8 P 0 
L 2.14606004 3.31615 2.14606004 3.36615 8 P 0 
L 2.19606004 3.41615 2.19606004 3.46615 8 P 0 
L 2.09606004 3.41615 2.09606004 3.46615 8 P 0 
L 2.04606004 3.31615 2.04606004 3.36615 8 P 0 
L 2.14606004 3.46615 2.14606004 3.51615 8 P 0 
L 1.99606004 3.46615 1.99606004 3.51615 8 P 0 
L 2.04606004 3.61615 2.04606004 3.66615 8 P 0 
L 2.09606004 3.66615 2.09606004 3.71615 8 P 0 
L 2.14606004 3.61615 2.14606004 3.66615 8 P 0 
L 2.19606004 3.66615 2.19606004 3.71615 8 P 0 
L 2.49606004 3.61615 2.49606004 3.66615 8 P 0 
L 2.34606004 3.66615 2.34606004 3.71615 8 P 0 
L 2.39606004 3.61615 2.39606004 3.66615 8 P 0 
L 2.44606004 3.66615 2.44606004 3.71615 8 P 0 
L 2.49606004 3.76615 2.49606004 3.81615 8 P 0 
L 2.44606004 3.81615 2.44606004 3.86615 8 P 0 
L 2.39606004 3.76615 2.39606004 3.81615 8 P 0 
L 2.34606004 3.81615 2.34606004 3.86615 8 P 0 
L 2.14606004 3.76615 2.14606004 3.81615 8 P 0 
L 2.19606004 3.81615 2.19606004 3.86615 8 P 0 
L 2.09606004 3.81615 2.09606004 3.86615 8 P 0 
L 2.04606004 3.76615 2.04606004 3.81615 8 P 0 
L 2.24606004 2.86615 2.29606004 2.86615 8 P 0 
L 3.3666 5.21931004 3.38075 5.23346004 3 P 0 
L 3.37085 5.21506998 3.38498996 5.22921004 3 P 0 
L 3.3758 5.21011998 3.38993996 5.22426004 3 P 0 
L 3.36095 5.22001998 3.38003996 5.23911004 1 P 0 
L 3.38003996 5.23911004 3.39913002 5.22001998 1 P 0 
L 3.40095 5.22001998 3.42003996 5.23911004 1 P 0 
L 3.4066 5.21931004 3.42075 5.23346004 3 P 0 
L 3.42003996 5.20588002 3.43418002 5.22001998 3 P 0 
L 3.42003996 5.23911004 3.43913002 5.22001998 1 P 0 
L 3.4158 5.21011998 3.42993996 5.22426004 3 P 0 
L 3.41085 5.21506998 3.42498996 5.22921004 3 P 0 
L 3.38003996 5.20588002 3.39418002 5.22001998 3 P 0 
L 3.39913002 5.22001998 3.38003996 5.20093002 1 P 0 
L 3.38003996 5.20093002 3.36095 5.22001998 1 P 0 
L 3.42003996 5.20093002 3.40095 5.22001998 1 P 0 
L 3.43913002 5.22001998 3.42003996 5.20093002 1 P 0 
L 2.24936004 4.66205 2.2635 4.67618996 3 P 0 
L 2.25431004 4.6571 2.26845 4.67123996 3 P 0 
L 2.25855 4.68608996 2.27763996 4.667 1 P 0 
L 2.24511004 4.66628996 2.25926004 4.68043996 3 P 0 
L 2.23946004 4.667 2.25855 4.68608996 1 P 0 
L 2.21855 4.68608996 2.23763996 4.667 1 P 0 
L 2.19946004 4.667 2.21855 4.68608996 1 P 0 
L 2.21431004 4.6571 2.22845 4.67123996 3 P 0 
L 2.20936004 4.66205 2.2235 4.67618996 3 P 0 
L 2.20511004 4.66628996 2.21926004 4.68043996 3 P 0 
L 2.27453002 4.78291998 2.25543996 4.76383002 1 P 0 
L 2.25543996 4.76383002 2.23635 4.78291998 1 P 0 
L 2.21543996 4.76383002 2.19635 4.78291998 1 P 0 
L 2.23453002 4.78291998 2.21543996 4.76383002 1 P 0 
L 2.21543996 4.76878002 2.22958002 4.78291998 3 P 0 
L 2.24625 4.77796998 2.26038996 4.79211004 3 P 0 
L 2.2512 4.77301998 2.26533996 4.78716004 3 P 0 
L 2.25543996 4.80201004 2.27453002 4.78291998 1 P 0 
L 2.25543996 4.76878002 2.26958002 4.78291998 3 P 0 
L 2.242 4.78221004 2.25615 4.79636004 3 P 0 
L 2.23635 4.78291998 2.25543996 4.80201004 1 P 0 
L 2.21543996 4.80201004 2.23453002 4.78291998 1 P 0 
L 2.19635 4.78291998 2.21543996 4.80201004 1 P 0 
L 2.2112 4.77301998 2.22533996 4.78716004 3 P 0 
L 2.20625 4.77796998 2.22038996 4.79211004 3 P 0 
L 2.202 4.78221004 2.21615 4.79636004 3 P 0 
L 2.27763996 4.667 2.25855 4.64791004 1 P 0 
L 2.25855 4.64791004 2.23946004 4.667 1 P 0 
L 2.21855 4.64791004 2.19946004 4.667 1 P 0 
L 2.23763996 4.667 2.21855 4.64791004 1 P 0 
L 2.21855 4.65286004 2.23268996 4.667 3 P 0 
L 2.25855 4.65286004 2.27268996 4.667 3 P 0 
L 2.1328 4.78291998 2.11371004 4.76383002 1 P 0 
L 2.11371004 4.76383002 2.09461998 4.78291998 1 P 0 
L 2.07371004 4.76383002 2.05461998 4.78291998 1 P 0 
L 2.0928 4.78291998 2.07371004 4.76383002 1 P 0 
L 2.07371004 4.76878002 2.08785 4.78291998 3 P 0 
L 2.10451998 4.77796998 2.11866004 4.79211004 3 P 0 
L 2.10946998 4.77301998 2.12361004 4.78716004 3 P 0 
L 2.11371004 4.80201004 2.1328 4.78291998 1 P 0 
L 2.11371004 4.76878002 2.12785 4.78291998 3 P 0 
L 2.10026998 4.78221004 2.11441998 4.79636004 3 P 0 
L 2.09461998 4.78291998 2.11371004 4.80201004 1 P 0 
L 2.07371004 4.80201004 2.0928 4.78291998 1 P 0 
L 2.05461998 4.78291998 2.07371004 4.80201004 1 P 0 
L 2.06946998 4.77301998 2.08361004 4.78716004 3 P 0 
L 2.06451998 4.77796998 2.07866004 4.79211004 3 P 0 
L 2.06026998 4.78221004 2.07441998 4.79636004 3 P 0 
L 1.68851004 4.76383002 1.66941998 4.78291998 1 P 0 
L 1.66941998 4.78291998 1.68851004 4.80201004 1 P 0 
L 1.67506998 4.78221004 1.68921998 4.79636004 3 P 0 
L 1.7076 4.78291998 1.68851004 4.76383002 1 P 0 
L 1.68851004 4.76878002 1.70265 4.78291998 3 P 0 
L 1.68851004 4.80201004 1.7076 4.78291998 1 P 0 
L 1.68426998 4.77301998 1.69841004 4.78716004 3 P 0 
L 1.67931998 4.77796998 1.69346004 4.79211004 3 P 0 
L 1.79025 4.76878002 1.80438996 4.78291998 3 P 0 
L 1.80933996 4.78291998 1.79025 4.76383002 1 P 0 
L 1.79025 4.76383002 1.77116004 4.78291998 1 P 0 
L 1.83025 4.76383002 1.81116004 4.78291998 1 P 0 
L 1.77681004 4.78221004 1.79096004 4.79636004 3 P 0 
L 1.78106004 4.77796998 1.7952 4.79211004 3 P 0 
L 1.78601004 4.77301998 1.80015 4.78716004 3 P 0 
L 1.77116004 4.78291998 1.79025 4.80201004 1 P 0 
L 1.79025 4.80201004 1.80933996 4.78291998 1 P 0 
L 1.81116004 4.78291998 1.83025 4.80201004 1 P 0 
L 1.81681004 4.78221004 1.83096004 4.79636004 3 P 0 
L 1.84933996 4.78291998 1.83025 4.76383002 1 P 0 
L 1.83025 4.76878002 1.84438996 4.78291998 3 P 0 
L 1.83025 4.80201004 1.84933996 4.78291998 1 P 0 
L 1.82601004 4.77301998 1.84015 4.78716004 3 P 0 
L 1.82106004 4.77796998 1.8352 4.79211004 3 P 0 
L 1.64851004 4.76878002 1.66265 4.78291998 3 P 0 
L 1.6676 4.78291998 1.64851004 4.76383002 1 P 0 
L 1.64851004 4.76383002 1.62941998 4.78291998 1 P 0 
L 1.63506998 4.78221004 1.64921998 4.79636004 3 P 0 
L 1.63931998 4.77796998 1.65346004 4.79211004 3 P 0 
L 1.64426998 4.77301998 1.65841004 4.78716004 3 P 0 
L 1.62941998 4.78291998 1.64851004 4.80201004 1 P 0 
L 1.64851004 4.80201004 1.6676 4.78291998 1 P 0 
L 2.17538002 5.04855 2.18951998 5.06268996 3 P 0 
L 2.18033002 5.0436 2.19446998 5.05773996 3 P 0 
L 2.18456998 5.07258996 2.20366004 5.0535 1 P 0 
L 2.18456998 5.03936004 2.19871004 5.0535 3 P 0 
L 2.20366004 5.0535 2.18456998 5.03441004 1 P 0 
L 2.17113002 5.05278996 2.18528002 5.06693996 3 P 0 
L 2.16548002 5.0535 2.18456998 5.07258996 1 P 0 
L 2.18456998 5.03441004 2.16548002 5.0535 1 P 0 
L 2.41626004 5.115 2.39716998 5.09591004 1 P 0 
L 2.39716998 5.09591004 2.37808002 5.115 1 P 0 
L 2.35716998 5.09591004 2.33808002 5.115 1 P 0 
L 2.37626004 5.115 2.35716998 5.09591004 1 P 0 
L 2.35716998 5.10086004 2.37131004 5.115 3 P 0 
L 2.38798002 5.11005 2.40211998 5.12418996 3 P 0 
L 2.39293002 5.1051 2.40706998 5.11923996 3 P 0 
L 2.39716998 5.13408996 2.41626004 5.115 1 P 0 
L 2.39716998 5.10086004 2.41131004 5.115 3 P 0 
L 2.38373002 5.11428996 2.39788002 5.12843996 3 P 0 
L 2.37808002 5.115 2.39716998 5.13408996 1 P 0 
L 2.35716998 5.13408996 2.37626004 5.115 1 P 0 
L 2.33808002 5.115 2.35716998 5.13408996 1 P 0 
L 2.35293002 5.1051 2.36706998 5.11923996 3 P 0 
L 2.34798002 5.11005 2.36211998 5.12418996 3 P 0 
L 2.34373002 5.11428996 2.35788002 5.12843996 3 P 0 
L 1.93196998 5.03936004 1.94611004 5.0535 3 P 0 
L 1.95106004 5.0535 1.93196998 5.03441004 1 P 0 
L 1.93196998 5.03441004 1.91288002 5.0535 1 P 0 
L 1.97196998 5.03441004 1.95288002 5.0535 1 P 0 
L 1.91853002 5.05278996 1.93268002 5.06693996 3 P 0 
L 1.92278002 5.04855 1.93691998 5.06268996 3 P 0 
L 1.92773002 5.0436 1.94186998 5.05773996 3 P 0 
L 1.91288002 5.0535 1.93196998 5.07258996 1 P 0 
L 1.93196998 5.07258996 1.95106004 5.0535 1 P 0 
L 1.95288002 5.0535 1.97196998 5.07258996 1 P 0 
L 1.95853002 5.05278996 1.97268002 5.06693996 3 P 0 
L 1.99106004 5.0535 1.97196998 5.03441004 1 P 0 
L 1.97196998 5.03936004 1.98611004 5.0535 3 P 0 
L 1.97196998 5.07258996 1.99106004 5.0535 1 P 0 
L 1.96773002 5.0436 1.98186998 5.05773996 3 P 0 
L 1.96278002 5.04855 1.97691998 5.06268996 3 P 0 
L 2.14456998 5.07258996 2.16366004 5.0535 1 P 0 
L 2.12548002 5.0535 2.14456998 5.07258996 1 P 0 
L 2.14033002 5.0436 2.15446998 5.05773996 3 P 0 
L 2.13538002 5.04855 2.14951998 5.06268996 3 P 0 
L 2.13113002 5.05278996 2.14528002 5.06693996 3 P 0 
L 2.14456998 5.03441004 2.12548002 5.0535 1 P 0 
L 2.16366004 5.0535 2.14456998 5.03441004 1 P 0 
L 2.14456998 5.03936004 2.15871004 5.0535 3 P 0 
L 1.6885 5.03441004 1.66941004 5.0535 1 P 0 
L 1.66941004 5.0535 1.6885 5.07258996 1 P 0 
L 1.67506004 5.05278996 1.68921004 5.06693996 3 P 0 
L 1.70758996 5.0535 1.6885 5.03441004 1 P 0 
L 1.6885 5.03936004 1.70263996 5.0535 3 P 0 
L 1.6885 5.07258996 1.70758996 5.0535 1 P 0 
L 1.68426004 5.0436 1.6984 5.05773996 3 P 0 
L 1.67931004 5.04855 1.69345 5.06268996 3 P 0 
L 1.6485 5.03936004 1.66263996 5.0535 3 P 0 
L 1.66758996 5.0535 1.6485 5.03441004 1 P 0 
L 1.6485 5.03441004 1.62941004 5.0535 1 P 0 
L 1.63506004 5.05278996 1.64921004 5.06693996 3 P 0 
L 1.63931004 5.04855 1.65345 5.06268996 3 P 0 
L 1.64426004 5.0436 1.6584 5.05773996 3 P 0 
L 1.62941004 5.0535 1.6485 5.07258996 1 P 0 
L 1.6485 5.07258996 1.66758996 5.0535 1 P 0 
L 5.42048002 1.6433 5.42048002 1.6033 8 P 0 
L 5.57531004 1.7118 5.57531004 1.6718 8 P 0 
L 5.42048002 1.7796 5.42048002 1.7396 8 P 0 
L 5.57531004 1.9869 5.57531004 1.9469 8 P 0 
L 5.42048002 2.0547 5.42048002 2.0147 8 P 0 
L 5.57531004 2.1278 5.57531004 2.0878 8 P 0 
L 5.42048002 2.1954 5.42048002 2.1554 8 P 0 
L 5.57531004 2.2632 5.57531004 2.2232 8 P 0 
L 5.42048002 2.3308 5.42048002 2.2908 8 P 0 
L 5.57531004 2.3986 5.57531004 2.3586 8 P 0 
L 5.42048002 2.4662 5.42048002 2.4262 8 P 0 
L 5.57531004 2.5378 5.57531004 2.4978 8 P 0 
L 5.57531004 2.673 5.57531004 2.633 8 P 0 
L 5.42048002 2.6054 5.42048002 2.5654 8 P 0 
L 10.09 2.73655 10.09 2.69655 8 P 0 
L 9.975 2.66445 9.975 2.62445 8 P 0 
L 9.975 2.5109 9.975 2.4709 8 P 0 
L 10.09 2.57845 10.09 2.53845 8 P 0 
L 10.09 2.44335 10.09 2.40335 8 P 0 
L 9.975 2.3758 9.975 2.3358 8 P 0 
L 10.09 2.30825 10.09 2.26825 8 P 0 
L 9.975 2.23955 9.975 2.19955 8 P 0 
L 10.09 2.17095 10.09 2.13095 8 P 0 
L 10.09 2.05655 10.09 2.01655 8 P 0 
L 10.225 1.96645 10.225 1.92645 8 P 0 
L 10.26025 1.86845 10.26025 1.82845 8 P 0 
L 10.26 1.70445 10.26 1.66445 8 P 0 
L 10.35543996 1.52156004 10.38371998 1.49328002 9 P 0 
L 10.46445 1.395 10.42445 1.395 8 P 0 
L 10.395 1.28555 10.395 1.32555 8 P 0 
L 11.53316004 1.412 11.53316004 1.452 8 P 0 
L 11.73316004 1.492 11.73316004 1.532 8 P 0 
L 11.53316004 1.572 11.53316004 1.612 8 P 0 
L 11.78316004 1.652 11.78316004 1.692 8 P 0 
L 11.53316004 1.732 11.53316004 1.772 8 P 0 
L 11.73316004 1.812 11.73316004 1.852 8 P 0 
L 11.53316004 1.892 11.53316004 1.932 8 P 0 
L 11.53316004 2.052 11.53316004 2.092 8 P 0 
L 11.73316004 1.972 11.73316004 2.012 8 P 0 
L 11.73316004 2.132 11.73316004 2.172 8 P 0 
L 11.83316004 2.212 11.83316004 2.252 8 P 0 
L 11.73316004 2.292 11.73316004 2.332 8 P 0 
L 11.53316004 2.372 11.53316004 2.412 8 P 0 
L 11.53316004 2.532 11.53316004 2.572 8 P 0 
L 11.73316004 2.452 11.73316004 2.492 8 P 0 
L 11.73316004 2.612 11.73316004 2.652 8 P 0 
L 8.98115 2.825 8.98115 2.865 8 P 0 
L 2.97721004 2.825 2.97721004 2.865 8 P 0 
L 11.03661004 2.46615 11.03661004 2.51615 8 P 0 
L 11.08661004 2.21615 11.08661004 2.26615 8 P 0 
L 10.98661004 2.21615 10.98661004 2.26615 8 P 0 
L 11.03661004 2.26615 11.03661004 2.31615 8 P 0 
L 10.93661004 2.26615 10.93661004 2.31615 8 P 0 
L 10.98661004 2.36615 10.98661004 2.41615 8 P 0 
L 10.93661004 2.41615 10.93661004 2.46615 8 P 0 
L 11.08661004 2.36615 11.08661004 2.41615 8 P 0 
L 10.93661004 2.01615 10.93661004 2.06615 8 P 0 
L 10.98661004 2.06615 10.98661004 2.11615 8 P 0 
L 11.03661004 2.01615 11.03661004 2.06615 8 P 0 
L 11.08661004 2.06615 11.08661004 2.11615 8 P 0 
L 10.93661004 1.86615 10.93661004 1.91615 8 P 0 
L 11.03661004 1.86615 11.03661004 1.91615 8 P 0 
L 10.98661004 1.91615 10.98661004 1.96615 8 P 0 
L 11.08661004 1.91615 11.08661004 1.96615 8 P 0 
L 10.73661004 2.46615 10.73661004 2.41615 8 P 0 
L 10.68661004 2.41615 10.68661004 2.36615 8 P 0 
L 10.68661004 2.26615 10.68661004 2.21615 8 P 0 
L 10.73661004 2.31615 10.73661004 2.26615 8 P 0 
L 10.68661004 2.11615 10.68661004 2.06615 8 P 0 
L 10.83661004 2.16615 10.88661004 2.16615 8 P 0 
L 10.73661004 2.01615 10.73661004 2.06615 8 P 0 
L 10.68661004 1.91615 10.68661004 1.96615 8 P 0 
L 10.73661004 1.86615 10.73661004 1.91615 8 P 0 
L 10.63661004 2.46615 10.63661004 2.41615 8 P 0 
L 10.58661004 2.41615 10.58661004 2.36615 8 P 0 
L 10.63661004 2.31615 10.63661004 2.26615 8 P 0 
L 10.58661004 2.26615 10.58661004 2.21615 8 P 0 
L 10.58661004 2.11615 10.58661004 2.06615 8 P 0 
L 10.63661004 2.01615 10.63661004 2.06615 8 P 0 
L 10.58661004 1.91615 10.58661004 1.96615 8 P 0 
L 10.63661004 1.86615 10.63661004 1.91615 8 P 0 
L 0.69348996 1.86611998 0.69348996 1.90611998 8 P 0 
L 5.03268002 2.46615 5.03268002 2.51615 8 P 0 
L 5.08268002 2.36615 5.08268002 2.41615 8 P 0 
L 4.93268002 2.41615 4.93268002 2.46615 8 P 0 
L 4.98268002 2.36615 4.98268002 2.41615 8 P 0 
L 4.93268002 2.26615 4.93268002 2.31615 8 P 0 
L 5.03268002 2.26615 5.03268002 2.31615 8 P 0 
L 4.98268002 2.21615 4.98268002 2.26615 8 P 0 
L 5.08268002 2.21615 5.08268002 2.26615 8 P 0 
L 5.08268002 2.06615 5.08268002 2.11615 8 P 0 
L 5.03268002 2.01615 5.03268002 2.06615 8 P 0 
L 4.98268002 2.06615 4.98268002 2.11615 8 P 0 
L 4.93268002 2.01615 4.93268002 2.06615 8 P 0 
L 5.08268002 1.91615 5.08268002 1.96615 8 P 0 
L 4.98268002 1.91615 4.98268002 1.96615 8 P 0 
L 5.03268002 1.86615 5.03268002 1.91615 8 P 0 
L 4.93268002 1.86615 4.93268002 1.91615 8 P 0 
L 4.73268002 1.86615 4.73268002 1.91615 8 P 0 
L 4.63268002 1.86615 4.63268002 1.91615 8 P 0 
L 4.68268002 1.91615 4.68268002 1.96615 8 P 0 
L 4.58268002 1.91615 4.58268002 1.96615 8 P 0 
L 4.63268002 2.01615 4.63268002 2.06615 8 P 0 
L 4.73268002 2.01615 4.73268002 2.06615 8 P 0 
L 4.83268002 2.16615 4.88268002 2.16615 8 P 0 
L 4.58268002 2.11615 4.58268002 2.06615 8 P 0 
L 4.68268002 2.11615 4.68268002 2.06615 8 P 0 
L 4.73268002 2.31615 4.73268002 2.26615 8 P 0 
L 4.68268002 2.26615 4.68268002 2.21615 8 P 0 
L 4.58268002 2.26615 4.58268002 2.21615 8 P 0 
L 4.63268002 2.31615 4.63268002 2.26615 8 P 0 
L 4.58268002 2.41615 4.58268002 2.36615 8 P 0 
L 4.68268002 2.41615 4.68268002 2.36615 8 P 0 
L 4.63268002 2.46615 4.63268002 2.41615 8 P 0 
L 4.73268002 2.46615 4.73268002 2.41615 8 P 0 
A 12.75476004 4.52361998 12.75476004 4.52361998 12.73621004 4.52361998 5 P 0 N
A 12.8335 4.48425 12.8335 4.48425 12.81495 4.48425 5 P 0 N
L 12.73621004 4.52361998 12.81495 4.48425 11 P 0 
L 12.73621004 4.36613996 12.81495 4.32676998 11 P 0 
A 12.8335 4.32676998 12.8335 4.32676998 12.81495 4.32676998 5 P 0 N
A 12.75476004 4.36613996 12.75476004 4.36613996 12.73621004 4.36613996 5 P 0 N
L 12.73621004 4.20866004 12.81495 4.16928996 11 P 0 
A 12.8335 4.16928996 12.8335 4.16928996 12.81495 4.16928996 5 P 0 N
A 12.75476004 4.20866004 12.75476004 4.20866004 12.73621004 4.20866004 5 P 0 N
L 12.73621004 4.05118002 12.81495 4.01181004 11 P 0 
A 12.8335 4.01181004 12.8335 4.01181004 12.81495 4.01181004 5 P 0 N
A 12.75476004 4.05118002 12.75476004 4.05118002 12.73621004 4.05118002 5 P 0 N
L 12.73621004 3.8937 12.81495 3.85433002 11 P 0 
A 12.8335 3.85433002 12.8335 3.85433002 12.81495 3.85433002 5 P 0 N
A 12.75476004 3.8937 12.75476004 3.8937 12.73621004 3.8937 5 P 0 N
A 12.75476004 3.73621998 12.75476004 3.73621998 12.73621004 3.73621998 5 P 0 N
L 12.73621004 3.73621998 12.81495 3.69685 11 P 0 
A 12.8335 3.69685 12.8335 3.69685 12.81495 3.69685 5 P 0 N
L 12.73621004 3.57873996 12.81495 3.53936998 11 P 0 
A 12.8335 3.53936998 12.8335 3.53936998 12.81495 3.53936998 5 P 0 N
A 12.75476004 3.57873996 12.75476004 3.57873996 12.73621004 3.57873996 5 P 0 N
L 12.73621004 3.42126004 12.81495 3.38188996 11 P 0 
A 12.8335 3.38188996 12.8335 3.38188996 12.81495 3.38188996 5 P 0 N
A 12.75476004 3.42126004 12.75476004 3.42126004 12.73621004 3.42126004 5 P 0 N
A 12.8335 3.22441004 12.8335 3.22441004 12.81495 3.22441004 5 P 0 N
L 12.73621004 3.02756004 12.81495 3.06693002 11 P 0 
A 12.8335 3.06693002 12.8335 3.06693002 12.81495 3.06693002 5 P 0 N
A 12.75476004 3.02756004 12.75476004 3.02756004 12.73621004 3.02756004 5 P 0 N
L 12.73621004 3.18503996 12.81495 3.22441004 11 P 0 
A 12.75476004 3.18503996 12.75476004 3.18503996 12.73621004 3.18503996 5 P 0 N
A 12.8335 2.75196998 12.8335 2.75196998 12.81495 2.75196998 5 P 0 N
L 12.73621004 2.87008002 12.81495 2.90945 11 P 0 
A 12.8335 2.90945 12.8335 2.90945 12.81495 2.90945 5 P 0 N
A 12.75476004 2.87008002 12.75476004 2.87008002 12.73621004 2.87008002 5 P 0 N
A 12.8335 2.51575 12.8335 2.51575 12.81495 2.51575 5 P 0 N
A 12.75476004 2.47638002 12.75476004 2.47638002 12.73621004 2.47638002 5 P 0 N
L 12.73621004 2.7126 12.81495 2.75196998 11 P 0 
A 12.75476004 2.7126 12.75476004 2.7126 12.73621004 2.7126 5 P 0 N
L 12.73621004 2.3189 12.81495 2.35826998 11 P 0 
A 12.8335 2.35826998 12.8335 2.35826998 12.81495 2.35826998 5 P 0 N
A 12.75476004 2.3189 12.75476004 2.3189 12.73621004 2.3189 5 P 0 N
L 12.73621004 2.47638002 12.81495 2.51575 11 P 0 
A 12.75476004 2.00393996 12.75476004 2.00393996 12.73621004 2.00393996 5 P 0 N
L 12.73621004 2.16141998 12.81495 2.20078996 11 P 0 
A 12.8335 2.20078996 12.8335 2.20078996 12.81495 2.20078996 5 P 0 N
A 12.75476004 2.16141998 12.75476004 2.16141998 12.73621004 2.16141998 5 P 0 N
L 12.73621004 2.00393996 12.81495 1.96456998 11 P 0 
A 12.8335 1.96456998 12.8335 1.96456998 12.81495 1.96456998 5 P 0 N
L 12.55905 4.563 12.63778996 4.60236998 11 P 0 
A 12.65633996 4.60236998 12.65633996 4.60236998 12.63778996 4.60236998 5 P 0 N
A 12.5776 4.563 12.5776 4.563 12.55905 4.563 5 P 0 N
L 12.55905 4.24803002 12.63778996 4.2874 11 P 0 
A 12.65633996 4.2874 12.65633996 4.2874 12.63778996 4.2874 5 P 0 N
A 12.5776 4.24803002 12.5776 4.24803002 12.55905 4.24803002 5 P 0 N
L 12.55905 4.40551004 12.63778996 4.44488002 11 P 0 
A 12.65633996 4.44488002 12.65633996 4.44488002 12.63778996 4.44488002 5 P 0 N
A 12.5776 4.40551004 12.5776 4.40551004 12.55905 4.40551004 5 P 0 N
A 12.65633996 3.97243996 12.65633996 3.97243996 12.63778996 3.97243996 5 P 0 N
L 12.55905 4.09055 12.63778996 4.12991998 11 P 0 
A 12.65633996 4.12991998 12.65633996 4.12991998 12.63778996 4.12991998 5 P 0 N
A 12.5776 4.09055 12.5776 4.09055 12.55905 4.09055 5 P 0 N
L 12.55905 3.77558996 12.63778996 3.81496004 11 P 0 
A 12.65633996 3.81496004 12.65633996 3.81496004 12.63778996 3.81496004 5 P 0 N
A 12.5776 3.77558996 12.5776 3.77558996 12.55905 3.77558996 5 P 0 N
L 12.55905 3.93306998 12.63778996 3.97243996 11 P 0 
A 12.5776 3.93306998 12.5776 3.93306998 12.55905 3.93306998 5 P 0 N
A 12.65633996 3.5 12.65633996 3.5 12.63778996 3.5 5 P 0 N
L 12.55905 3.61811004 12.63778996 3.65748002 11 P 0 
A 12.65633996 3.65748002 12.65633996 3.65748002 12.63778996 3.65748002 5 P 0 N
A 12.5776 3.61811004 12.5776 3.61811004 12.55905 3.61811004 5 P 0 N
L 12.55905 3.30315 12.63778996 3.26378002 11 P 0 
A 12.65633996 3.26378002 12.65633996 3.26378002 12.63778996 3.26378002 5 P 0 N
A 12.5776 3.30315 12.5776 3.30315 12.55905 3.30315 5 P 0 N
L 12.55905 3.46063002 12.63778996 3.5 11 P 0 
A 12.5776 3.46063002 12.5776 3.46063002 12.55905 3.46063002 5 P 0 N
L 12.55905 3.14566998 12.63778996 3.1063 11 P 0 
A 12.65633996 3.1063 12.65633996 3.1063 12.63778996 3.1063 5 P 0 N
A 12.5776 3.14566998 12.5776 3.14566998 12.55905 3.14566998 5 P 0 N
A 12.5776 2.98818996 12.5776 2.98818996 12.55905 2.98818996 5 P 0 N
L 12.55905 2.98818996 12.63778996 2.94881998 11 P 0 
A 12.65633996 2.94881998 12.65633996 2.94881998 12.63778996 2.94881998 5 P 0 N
L 12.55905 2.83071004 12.63778996 2.79133996 11 P 0 
A 12.65633996 2.79133996 12.65633996 2.79133996 12.63778996 2.79133996 5 P 0 N
A 12.5776 2.83071004 12.5776 2.83071004 12.55905 2.83071004 5 P 0 N
L 12.55905 2.59448996 12.63778996 2.55511998 11 P 0 
A 12.65633996 2.55511998 12.65633996 2.55511998 12.63778996 2.55511998 5 P 0 N
A 12.5776 2.59448996 12.5776 2.59448996 12.55905 2.59448996 5 P 0 N
L 12.55905 2.43701004 12.63778996 2.39763996 11 P 0 
A 12.65633996 2.39763996 12.65633996 2.39763996 12.63778996 2.39763996 5 P 0 N
A 12.5776 2.43701004 12.5776 2.43701004 12.55905 2.43701004 5 P 0 N
L 12.55905 2.27953002 12.63778996 2.24016004 11 P 0 
A 12.65633996 2.24016004 12.65633996 2.24016004 12.63778996 2.24016004 5 P 0 N
A 12.5776 2.27953002 12.5776 2.27953002 12.55905 2.27953002 5 P 0 N
A 12.5776 2.04331004 12.5776 2.04331004 12.55905 2.04331004 5 P 0 N
A 12.65633996 2.08268002 12.65633996 2.08268002 12.63778996 2.08268002 5 P 0 N
L 12.55905 2.04331004 12.63778996 2.08268002 11 P 0 
L 12.55905 1.96456998 12.63778996 1.9252 11 P 0 
A 12.65633996 1.9252 12.65633996 1.9252 12.63778996 1.9252 5 P 0 N
A 12.5776 1.96456998 12.5776 1.96456998 12.55905 1.96456998 5 P 0 N
A 0.11303996 4.52363002 0.11303996 4.52363002 0.09448996 4.52363002 5 P 0 N
A 0.19178002 4.563 0.19178002 4.563 0.17323002 4.563 5 P 0 N
L 0.09448996 4.52363002 0.17323002 4.563 11 P 0 
A 0.11303996 4.36613996 0.11303996 4.36613996 0.09448996 4.36613996 5 P 0 N
A 0.19178002 4.40551004 0.19178002 4.40551004 0.17323002 4.40551004 5 P 0 N
L 0.09448996 4.36613996 0.17323002 4.40551004 11 P 0 
A 0.11303996 4.20866004 0.11303996 4.20866004 0.09448996 4.20866004 5 P 0 N
A 0.19178002 4.24803002 0.19178002 4.24803002 0.17323002 4.24803002 5 P 0 N
L 0.09448996 4.20866004 0.17323002 4.24803002 11 P 0 
A 0.11303996 4.05118002 0.11303996 4.05118002 0.09448996 4.05118002 5 P 0 N
A 0.19178002 4.09055 0.19178002 4.09055 0.17323002 4.09055 5 P 0 N
L 0.09448996 4.05118002 0.17323002 4.09055 11 P 0 
A 0.11303996 3.8937 0.11303996 3.8937 0.09448996 3.8937 5 P 0 N
A 0.19178002 3.93306998 0.19178002 3.93306998 0.17323002 3.93306998 5 P 0 N
L 0.09448996 3.8937 0.17323002 3.93306998 11 P 0 
A 0.11303996 3.73621998 0.11303996 3.73621998 0.09448996 3.73621998 5 P 0 N
A 0.19178002 3.77558996 0.19178002 3.77558996 0.17323002 3.77558996 5 P 0 N
L 0.09448996 3.73621998 0.17323002 3.77558996 11 P 0 
A 0.11303996 3.57873996 0.11303996 3.57873996 0.09448996 3.57873996 5 P 0 N
A 0.19178002 3.61811004 0.19178002 3.61811004 0.17323002 3.61811004 5 P 0 N
L 0.09448996 3.57873996 0.17323002 3.61811004 11 P 0 
A 0.11303996 3.42126004 0.11303996 3.42126004 0.09448996 3.42126004 5 P 0 N
A 0.19178002 3.46063002 0.19178002 3.46063002 0.17323002 3.46063002 5 P 0 N
L 0.09448996 3.42126004 0.17323002 3.46063002 11 P 0 
A 0.2902 3.14566998 0.2902 3.14566998 0.27165 3.14566998 5 P 0 N
A 0.36893996 3.18503996 0.36893996 3.18503996 0.35038996 3.18503996 5 P 0 N
L 0.27165 3.14566998 0.35038996 3.18503996 11 P 0 
A 0.2902 2.98818996 0.2902 2.98818996 0.27165 2.98818996 5 P 0 N
A 0.36893996 3.02756004 0.36893996 3.02756004 0.35038996 3.02756004 5 P 0 N
L 0.27165 2.98818996 0.35038996 3.02756004 11 P 0 
A 0.2902 2.83071004 0.2902 2.83071004 0.27165 2.83071004 5 P 0 N
A 0.36893996 2.87008002 0.36893996 2.87008002 0.35038996 2.87008002 5 P 0 N
L 0.27165 2.83071004 0.35038996 2.87008002 11 P 0 
A 0.2902 2.67323002 0.2902 2.67323002 0.27165 2.67323002 5 P 0 N
A 0.36893996 2.7126 0.36893996 2.7126 0.35038996 2.7126 5 P 0 N
L 0.27165 2.67323002 0.35038996 2.7126 11 P 0 
A 0.2902 2.43701004 0.2902 2.43701004 0.27165 2.43701004 5 P 0 N
A 0.36893996 2.47638002 0.36893996 2.47638002 0.35038996 2.47638002 5 P 0 N
L 0.27165 2.43701004 0.35038996 2.47638002 11 P 0 
A 0.2902 2.27953002 0.2902 2.27953002 0.27165 2.27953002 5 P 0 N
A 0.36893996 2.3189 0.36893996 2.3189 0.35038996 2.3189 5 P 0 N
L 0.27165 2.27953002 0.35038996 2.3189 11 P 0 
A 0.2902 2.12205 0.2902 2.12205 0.27165 2.12205 5 P 0 N
A 0.36893996 2.16141998 0.36893996 2.16141998 0.35038996 2.16141998 5 P 0 N
L 0.27165 2.12205 0.35038996 2.16141998 11 P 0 
L 0.09448996 2.00393996 0.17323002 2.04331004 11 P 0 
A 0.19178002 2.04331004 0.19178002 2.04331004 0.17323002 2.04331004 5 P 0 N
A 0.11303996 2.00393996 0.11303996 2.00393996 0.09448996 2.00393996 5 P 0 N
A 0.2902 1.96456998 0.2902 1.96456998 0.27165 1.96456998 5 P 0 N
A 0.36893996 1.9252 0.36893996 1.9252 0.35038996 1.9252 5 P 0 N
L 0.27165 1.96456998 0.35038996 1.9252 10 P 0 
A 0.11303996 1.9252 0.11303996 1.9252 0.09448996 1.9252 5 P 0 N
A 0.19178002 1.88583002 0.19178002 1.88583002 0.17323002 1.88583002 5 P 0 N
L 0.09448996 1.9252 0.17323002 1.88583002 11 P 0 
A 0.11303996 2.24016004 0.11303996 2.24016004 0.09448996 2.24016004 5 P 0 N
A 0.19178002 2.20078996 0.19178002 2.20078996 0.17323002 2.20078996 5 P 0 N
L 0.09448996 2.24016004 0.17323002 2.20078996 11 P 0 
A 0.11303996 2.39763996 0.11303996 2.39763996 0.09448996 2.39763996 5 P 0 N
A 0.19178002 2.35826998 0.19178002 2.35826998 0.17323002 2.35826998 5 P 0 N
L 0.09448996 2.39763996 0.17323002 2.35826998 11 P 0 
A 0.11303996 2.55511998 0.11303996 2.55511998 0.09448996 2.55511998 5 P 0 N
A 0.19178002 2.51575 0.19178002 2.51575 0.17323002 2.51575 5 P 0 N
L 0.09448996 2.55511998 0.17323002 2.51575 11 P 0 
A 0.11303996 2.79133996 0.11303996 2.79133996 0.09448996 2.79133996 5 P 0 N
A 0.19178002 2.75196998 0.19178002 2.75196998 0.17323002 2.75196998 5 P 0 N
L 0.09448996 2.79133996 0.17323002 2.75196998 11 P 0 
A 0.11303996 2.94881998 0.11303996 2.94881998 0.09448996 2.94881998 5 P 0 N
A 0.19178002 2.90945 0.19178002 2.90945 0.17323002 2.90945 5 P 0 N
L 0.09448996 2.94881998 0.17323002 2.90945 11 P 0 
A 0.11303996 3.1063 0.11303996 3.1063 0.09448996 3.1063 5 P 0 N
A 0.19178002 3.06693002 0.19178002 3.06693002 0.17323002 3.06693002 5 P 0 N
L 0.09448996 3.1063 0.17323002 3.06693002 11 P 0 
A 0.11303996 3.26378002 0.11303996 3.26378002 0.09448996 3.26378002 5 P 0 N
A 0.19178002 3.22441004 0.19178002 3.22441004 0.17323002 3.22441004 5 P 0 N
L 0.09448996 3.26378002 0.17323002 3.22441004 11 P 0 
A 0.2902 3.38188996 0.2902 3.38188996 0.27165 3.38188996 5 P 0 N
A 0.36893996 3.34251998 0.36893996 3.34251998 0.35038996 3.34251998 5 P 0 N
L 0.27165 3.38188996 0.35038996 3.34251998 11 P 0 
A 0.2902 3.53936998 0.2902 3.53936998 0.27165 3.53936998 5 P 0 N
A 0.36893996 3.5 0.36893996 3.5 0.35038996 3.5 5 P 0 N
L 0.27165 3.53936998 0.35038996 3.5 11 P 0 
A 0.2902 3.69685 0.2902 3.69685 0.27165 3.69685 5 P 0 N
A 0.36893996 3.65748002 0.36893996 3.65748002 0.35038996 3.65748002 5 P 0 N
L 0.27165 3.69685 0.35038996 3.65748002 11 P 0 
A 0.2902 3.85433002 0.2902 3.85433002 0.27165 3.85433002 5 P 0 N
A 0.36893996 3.81496004 0.36893996 3.81496004 0.35038996 3.81496004 5 P 0 N
L 0.27165 3.85433002 0.35038996 3.81496004 11 P 0 
A 0.2902 4.01181004 0.2902 4.01181004 0.27165 4.01181004 5 P 0 N
A 0.36893996 3.97243996 0.36893996 3.97243996 0.35038996 3.97243996 5 P 0 N
L 0.27165 4.01181004 0.35038996 3.97243996 11 P 0 
A 0.2902 4.16928996 0.2902 4.16928996 0.27165 4.16928996 5 P 0 N
A 0.36893996 4.12991998 0.36893996 4.12991998 0.35038996 4.12991998 5 P 0 N
L 0.27165 4.16928996 0.35038996 4.12991998 11 P 0 
A 0.2902 4.32676998 0.2902 4.32676998 0.27165 4.32676998 5 P 0 N
A 0.36893996 4.2874 0.36893996 4.2874 0.35038996 4.2874 5 P 0 N
L 0.27165 4.32676998 0.35038996 4.2874 11 P 0 
L 0.27165 4.48425 0.35038996 4.44488002 11 P 0 
A 0.36893996 4.44488002 0.36893996 4.44488002 0.35038996 4.44488002 5 P 0 N
A 0.2902 4.48425 0.2902 4.48425 0.27165 4.48425 5 P 0 N
L 4.87 0.025 6.565 0.025 16 P 0 
L 4.885 0.085 6.53 0.085 16 P 0 
L 4.895 0.15 6.54 0.15 16 P 0 
L 4.89 0.215 6.555 0.215 16 P 0 
L 4.89 0.3 6.535 0.3 16 P 0 
L 4.895 0.37 6.54 0.37 16 P 0 
A 12.84646004 6.02361998 12.9252 5.94488002 12.84646004 5.94488002 11 P 0 Y
A 12.9252 0.07873996 12.84646004 0 12.84646004 0.07873996 11 P 0 Y
L 12.9252 5.94488002 12.9252 0.07873996 11 P 0 
L 12.84646004 0 6.66536004 0 11 P 0 
A 6.58661998 0.35433002 6.50788002 0.43306998 6.50788002 0.35433002 11 P 0 N
A 6.66536004 0 6.58661998 0.07873996 6.66535994 0.07873996 11 P 0 Y
L 6.58661998 0.07873996 6.58661998 0.35433002 11 P 0 
A 4.93308002 0.43306998 4.85433996 0.35433002 4.93307992 0.35433002 11 P 0 N
L 6.50788002 0.43306998 4.93308002 0.43306998 11 P 0 
L 4.85433996 0.35433002 4.85433996 0.07873996 11 P 0 
A 4.85433996 0.07873996 4.77558996 0 4.7755999 0.07873996 11 P 0 Y
A 0.07873996 0 0 0.07873996 0.07873996 0.07873996 11 P 0 Y
L 4.77558996 0 0.07873996 0 11 P 0 
L 0.07873996 6.02361998 12.84646004 6.02361998 11 P 0 
A 0 5.94488002 0.07873996 6.02361998 0.07873996 5.94488002 11 P 0 Y
L 0 0.07873996 0 5.94488002 11 P 0 
L 0 6.07011998 12.89 6.07011998 16 P 0 
L 0 -0.0465 12.89 -0.0465 16 P 0 
L 0.005 6.16 0.035 6.13 5 P 0 
L 12.91 6.15 12.88 6.12 5 P 0 
L 12.91 -0.13 12.88 -0.1 5 P 0 
L 0.005 -0.135 0.035 -0.105 5 P 0 
L 0 -0.41426004 0 -0.093 11 P 0 
A 0.07873996 -0.493 0 -0.41426004 0.07873996 -0.41426004 11 P 0 Y
L 12.84646004 -0.493 0.07873996 -0.493 11 P 0 
A 12.9252 -0.41426004 12.84646004 -0.493 12.84646004 -0.41426004 11 P 0 Y
L 12.9252 -0.093 12.9252 -0.41426004 11 P 0 
L 0 -0.093 12.9252 -0.093 11 P 0 
L 0 6.11661998 12.9252 6.11661998 11 P 0 
L 0 6.43788002 0 6.11661998 11 P 0 
A 0.07873996 6.51661998 0 6.43788002 0.07873996 6.43788002 11 P 0 N
L 12.84646004 6.51661998 0.07873996 6.51661998 11 P 0 
A 12.9252 6.43788002 12.84646004 6.51661998 12.84646004 6.43788002 11 P 0 N
L 12.9252 6.11661998 12.9252 6.43788002 11 P 0 
L 0.0349 -2.3038 0.0349 -1.0038 4 P 0 ;0
L 0.0349 -1.0038 4.5349 -1.0038 4 P 0 ;0
L 4.5349 -1.0038 4.5349 -2.3038 4 P 0 ;0
L 4.5349 -2.3038 0.0349 -2.3038 4 P 0 ;0
L 0.0349 -1.6038 4.5349 -1.6038 4 P 0 ;0
L 0.0349 -1.8038 4.5349 -1.8038 4 P 0 ;0
L 2.4349 -2.1038 4.0349 -2.1038 4 P 0 ;0
L 2.4349 -2.3038 2.4349 -1.8038 4 P 0 ;0
L 3.2349 -2.1038 3.2349 -1.8038 4 P 0 ;0
L 4.0349 -2.3038 4.0349 -1.8038 4 P 0 ;0
L 0.0723999 -1.6844687 0.07906663 -1.69030079 2 P 0 ;0
L 0.07906663 -1.69030079 0.08656654 -1.6938 2 P 0 ;0
L 0.08656654 -1.6938 0.09323337 -1.6938 2 P 0 ;0
L 0.09323337 -1.6938 0.0999001 -1.69030079 2 P 0 ;0
L 0.0999001 -1.69030079 0.10490059 -1.6844687 2 P 0 ;0
L 0.10490059 -1.6844687 0.1074 -1.67629951 2 P 0 ;0
L 0.1074 -1.67629951 0.10573376 -1.66813455 2 P 0 ;0
L 0.10573376 -1.66813455 0.10156644 -1.66113396 2 P 0 ;0
L 0.10156644 -1.66113396 0.09406654 -1.65646614 2 P 0 ;0
L 0.09406654 -1.65646614 0.08406713 -1.65413327 2 P 0 ;0
L 0.08406713 -1.65413327 0.07823346 -1.64946762 2 P 0 ;0
L 0.07823346 -1.64946762 0.07573248 -1.64130059 2 P 0 ;0
L 0.07573248 -1.64130059 0.0774003 -1.63313356 2 P 0 ;0
L 0.0774003 -1.63313356 0.08156614 -1.62730148 2 P 0 ;0
L 0.08156614 -1.62730148 0.0873997 -1.6238 2 P 0 ;0
L 0.0873997 -1.6238 0.09323337 -1.6238 2 P 8191 ;0
L 0.09323337 -1.6238 0.09906693 -1.62613287 2 P 0 ;0
L 0.09906693 -1.62613287 0.10406742 -1.63196713 2 P 0 ;0
L 0.1383999 -1.6938 0.1383999 -1.6238 2 P 0 ;0
L 0.1734 -1.6238 0.1734 -1.6938 2 P 0 ;0
L 0.1734 -1.65880108 0.1383999 -1.65880108 2 P 0 ;0
L 0.23856683 -1.6938 0.20523307 -1.6938 2 P 0 ;0
L 0.20523307 -1.6938 0.20523307 -1.6238 2 P 0 ;0
L 0.20523307 -1.6238 0.23856683 -1.6238 2 P 0 ;0
L 0.22523337 -1.65763258 0.20523307 -1.65763258 2 P 0 ;0
L 0.30456683 -1.6938 0.27123307 -1.6938 2 P 0 ;0
L 0.27123307 -1.6938 0.27123307 -1.6238 2 P 0 ;0
L 0.27123307 -1.6238 0.30456683 -1.6238 2 P 0 ;0
L 0.29123337 -1.65763258 0.27123307 -1.65763258 2 P 0 ;0
L 0.35389921 -1.6238 0.35389921 -1.6938 2 P 0 ;0
L 0.33473356 -1.6238 0.37306634 -1.6238 2 P 0 ;0
L 0.09489921 -1.7188 0.09489921 -1.7888 2 P 0 ;0
L 0.07573356 -1.7188 0.11406634 -1.7188 2 P 0 ;0
L 0.1508998 -1.7188 0.17089862 -1.7188 2 P 0 ;0
L 0.16089921 -1.7188 0.16089921 -1.7888 2 P 0 ;0
L 0.1508998 -1.7888 0.17089862 -1.7888 2 P 0 ;0
L 0.22689921 -1.7188 0.22689921 -1.7888 2 P 0 ;0
L 0.20773356 -1.7188 0.24606634 -1.7188 2 P 0 ;0
L 0.27623307 -1.7188 0.27623307 -1.7888 2 P 0 ;0
L 0.27623307 -1.7888 0.30956683 -1.7888 2 P 0 ;0
L 0.37556683 -1.7888 0.34223307 -1.7888 2 P 0 ;0
L 0.34223307 -1.7888 0.34223307 -1.7188 2 P 0 ;0
L 0.34223307 -1.7188 0.37556683 -1.7188 2 P 0 ;0
L 0.36223337 -1.75263258 0.34223307 -1.75263258 2 P 0 ;0
L 2.5438999 -1.96813563 2.5519 -1.97480089 2 P 0 ;0
L 2.5519 -1.97480089 2.5608999 -1.9788 2 P 0 ;0
L 2.5608999 -1.9788 2.5689 -1.9788 2 P 0 ;0
L 2.5689 -1.9788 2.5769001 -1.97480089 2 P 0 ;0
L 2.5769001 -1.97480089 2.58290069 -1.96813563 2 P 0 ;0
L 2.58290069 -1.96813563 2.5859 -1.95879941 2 P 0 ;0
L 2.5859 -1.95879941 2.58390049 -1.94946811 2 P 0 ;0
L 2.58390049 -1.94946811 2.5788997 -1.94146732 2 P 0 ;0
L 2.5788997 -1.94146732 2.5698998 -1.93613278 2 P 0 ;0
L 2.5698998 -1.93613278 2.55790049 -1.93346663 2 P 0 ;0
L 2.55790049 -1.93346663 2.5509002 -1.92813445 2 P 0 ;0
L 2.5509002 -1.92813445 2.54789902 -1.91880069 2 P 0 ;0
L 2.54789902 -1.91880069 2.54990039 -1.90946683 2 P 0 ;0
L 2.54990039 -1.90946683 2.55489931 -1.90280167 2 P 0 ;0
L 2.55489931 -1.90280167 2.5618997 -1.8988 2 P 0 ;0
L 2.5618997 -1.8988 2.5689 -1.8988 2 P 0 ;0
L 2.5689 -1.8988 2.57590039 -1.90146614 2 P 0 ;0
L 2.57590039 -1.90146614 2.58190089 -1.90813386 2 P 0 ;0
L 2.6648998 -1.90546772 2.65889931 -1.90146614 2 P 0 ;0
L 2.65889931 -1.90146614 2.65190079 -1.8988 2 P 0 ;0
L 2.65190079 -1.8988 2.64390069 -1.8988 2 P 0 ;0
L 2.64390069 -1.8988 2.63489892 -1.90280167 2 P 0 ;0
L 2.63489892 -1.90280167 2.62790039 -1.90946683 2 P 0 ;0
L 2.62790039 -1.90946683 2.62289961 -1.91746762 2 P 0 ;0
L 2.62289961 -1.91746762 2.61889862 -1.93080049 2 P 0 ;0
L 2.61889862 -1.93080049 2.61789892 -1.94280039 2 P 0 ;0
L 2.61789892 -1.94280039 2.6199003 -1.9548003 2 P 0 ;0
L 2.6199003 -1.9548003 2.62289961 -1.96280098 2 P 0 ;0
L 2.62289961 -1.96280098 2.6289002 -1.97080177 2 P 0 ;0
L 2.6289002 -1.97080177 2.63590049 -1.97613396 2 P 0 ;0
L 2.63590049 -1.97613396 2.64289902 -1.9788 2 P 0 ;0
L 2.64289902 -1.9788 2.64989941 -1.9788 2 P 0 ;0
L 2.64989941 -1.9788 2.6568997 -1.97613396 2 P 0 ;0
L 2.6568997 -1.97613396 2.6629003 -1.97213484 2 P 0 ;0
L 2.6629003 -1.97213484 2.66790098 -1.96680266 2 P 0 ;0
L 2.69589892 -1.9788 2.72089902 -1.8988 2 P 0 ;0
L 2.72089902 -1.8988 2.74590098 -1.9788 2 P 0 ;0
L 2.73689931 -1.95080118 2.70489882 -1.95080118 2 P 0 ;0
L 2.77889961 -1.8988 2.77889961 -1.9788 2 P 0 ;0
L 2.77889961 -1.9788 2.8189003 -1.9788 2 P 0 ;0
L 2.8969003 -1.9788 2.85689961 -1.9788 2 P 0 ;0
L 2.85689961 -1.9788 2.85689961 -1.8988 2 P 0 ;0
L 2.85689961 -1.8988 2.8969003 -1.8988 2 P 0 ;0
L 2.8809 -1.93746575 2.85689961 -1.93746575 2 P 0 ;0
L 3.03289902 -1.9788 3.03289902 -1.8988 2 P 0 ;0
L 3.03289902 -1.8988 3.0208998 -1.91479911 2 P 0 ;0
L 3.0208998 -1.9788 3.04489833 -1.9788 2 P 0 ;0
L 3.11089902 -1.98146604 3.10889951 -1.98013297 2 P 8191 ;0
L 3.10889951 -1.98013297 3.10889951 -1.97746703 2 P 8191 ;0
L 3.10889951 -1.97746703 3.11089902 -1.97613396 2 P 8191 ;0
L 3.11089902 -1.97613396 3.11290039 -1.97746703 2 P 8191 ;0
L 3.11290039 -1.97746703 3.11290039 -1.98013297 2 P 8191 ;0
L 3.11290039 -1.98013297 3.11089902 -1.98146604 2 P 8191 ;0
L 3.11089902 -1.945469 3.10889951 -1.94413346 2 P 8191 ;0
L 3.10889951 -1.94413346 3.10889951 -1.94146732 2 P 8191 ;0
L 3.10889951 -1.94146732 3.11089902 -1.94013435 2 P 8191 ;0
L 3.11089902 -1.94013435 3.11290039 -1.94146732 2 P 8191 ;0
L 3.11290039 -1.94146732 3.11290039 -1.94413346 2 P 8191 ;0
L 3.11290039 -1.94413346 3.11089902 -1.945469 2 P 8191 ;0
L 3.18889902 -1.9788 3.18889902 -1.8988 2 P 0 ;0
L 3.18889902 -1.8988 3.1768998 -1.91479911 2 P 0 ;0
L 3.1768998 -1.9788 3.20089833 -1.9788 2 P 0 ;0
L 2.5138999 -2.23313563 2.5219 -2.23980089 2 P 0 ;0
L 2.5219 -2.23980089 2.5308999 -2.2438 2 P 0 ;0
L 2.5308999 -2.2438 2.5389 -2.2438 2 P 0 ;0
L 2.5389 -2.2438 2.5469001 -2.23980089 2 P 0 ;0
L 2.5469001 -2.23980089 2.55290069 -2.23313563 2 P 0 ;0
L 2.55290069 -2.23313563 2.5559 -2.22379941 2 P 0 ;0
L 2.5559 -2.22379941 2.55390049 -2.21446811 2 P 0 ;0
L 2.55390049 -2.21446811 2.5488997 -2.20646732 2 P 0 ;0
L 2.5488997 -2.20646732 2.5398998 -2.20113278 2 P 0 ;0
L 2.5398998 -2.20113278 2.52790049 -2.19846663 2 P 0 ;0
L 2.52790049 -2.19846663 2.5209002 -2.19313445 2 P 0 ;0
L 2.5209002 -2.19313445 2.51789902 -2.18380069 2 P 0 ;0
L 2.51789902 -2.18380069 2.51990039 -2.17446683 2 P 0 ;0
L 2.51990039 -2.17446683 2.52489931 -2.16780167 2 P 0 ;0
L 2.52489931 -2.16780167 2.5318997 -2.1638 2 P 0 ;0
L 2.5318997 -2.1638 2.5389 -2.1638 2 P 0 ;0
L 2.5389 -2.1638 2.54590039 -2.16646614 2 P 0 ;0
L 2.54590039 -2.16646614 2.55190089 -2.17313386 2 P 0 ;0
L 2.5918999 -2.2438 2.5918999 -2.1638 2 P 0 ;0
L 2.6339 -2.1638 2.6339 -2.2438 2 P 0 ;0
L 2.6339 -2.20380128 2.5918999 -2.20380128 2 P 0 ;0
L 2.7109003 -2.2438 2.67089961 -2.2438 2 P 0 ;0
L 2.67089961 -2.2438 2.67089961 -2.1638 2 P 0 ;0
L 2.67089961 -2.1638 2.7109003 -2.1638 2 P 0 ;0
L 2.6949 -2.20246575 2.67089961 -2.20246575 2 P 0 ;0
L 2.7889003 -2.2438 2.74889961 -2.2438 2 P 0 ;0
L 2.74889961 -2.2438 2.74889961 -2.1638 2 P 0 ;0
L 2.74889961 -2.1638 2.7889003 -2.1638 2 P 0 ;0
L 2.7729 -2.20246575 2.74889961 -2.20246575 2 P 0 ;0
L 2.84689902 -2.1638 2.84689902 -2.2438 2 P 0 ;0
L 2.8239003 -2.1638 2.86989961 -2.1638 2 P 0 ;0
L 3.29489961 -1.9238 3.29489961 -2.0038 2 P 0 ;0
L 3.29489961 -2.0038 3.3349003 -2.0038 2 P 0 ;0
L 3.36789892 -2.0038 3.39289902 -1.9238 2 P 0 ;0
L 3.39289902 -1.9238 3.41790098 -2.0038 2 P 0 ;0
L 3.40889931 -1.97580118 3.37689882 -1.97580118 2 P 0 ;0
L 3.47089902 -2.0038 3.47089902 -1.96780039 2 P 0 ;0
L 3.47089902 -1.96780039 3.45089961 -1.9238 2 P 0 ;0
L 3.4909003 -1.9238 3.47089902 -1.96780039 2 P 0 ;0
L 3.5689003 -2.0038 3.52889961 -2.0038 2 P 0 ;0
L 3.52889961 -2.0038 3.52889961 -1.9238 2 P 0 ;0
L 3.52889961 -1.9238 3.5689003 -1.9238 2 P 0 ;0
L 3.5529 -1.96246575 3.52889961 -1.96246575 2 P 0 ;0
L 3.60689961 -2.0038 3.60689961 -1.9238 2 P 0 ;0
L 3.60689961 -1.9238 3.6318998 -1.9238 2 P 0 ;0
L 3.6318998 -1.9238 3.6398999 -1.92780167 2 P 0 ;0
L 3.6398999 -1.92780167 3.64490069 -1.93313386 2 P 0 ;0
L 3.64490069 -1.93313386 3.6469003 -1.94380069 2 P 0 ;0
L 3.6469003 -1.94380069 3.64490069 -1.95446752 2 P 0 ;0
L 3.64490069 -1.95446752 3.6389001 -1.96113278 2 P 0 ;0
L 3.6389001 -1.96113278 3.6318998 -1.96513435 2 P 0 ;0
L 3.6318998 -1.96513435 3.60689961 -1.96513435 2 P 0 ;0
L 3.6318998 -1.96513435 3.6469003 -2.0038 2 P 0 ;0
L 3.33989902 -2.2538 3.33189892 -2.25246703 2 P 0 ;0
L 3.33189892 -2.25246703 3.32490039 -2.24713484 2 P 0 ;0
L 3.32490039 -2.24713484 3.3188999 -2.23913406 2 P 0 ;0
L 3.3188999 -2.23913406 3.31489892 -2.2298003 2 P 0 ;0
L 3.31489892 -2.2298003 3.31289931 -2.21913346 2 P 0 ;0
L 3.31289931 -2.21913346 3.31289931 -2.20846663 2 P 0 ;0
L 3.31289931 -2.20846663 3.31489892 -2.1977998 2 P 0 ;0
L 3.31489892 -2.1977998 3.3188999 -2.18846604 2 P 0 ;0
L 3.3188999 -2.18846604 3.32490039 -2.18046772 2 P 0 ;0
L 3.32490039 -2.18046772 3.33189892 -2.17513307 2 P 0 ;0
L 3.33189892 -2.17513307 3.33989902 -2.1738 2 P 0 ;0
L 3.33989902 -2.1738 3.34789911 -2.17513307 2 P 0 ;0
L 3.34789911 -2.17513307 3.35489951 -2.18046772 2 P 0 ;0
L 3.35489951 -2.18046772 3.3609 -2.18846604 2 P 0 ;0
L 3.3609 -2.18846604 3.36490098 -2.1977998 2 P 0 ;0
L 3.36490098 -2.1977998 3.36690059 -2.20846663 2 P 0 ;0
L 3.36690059 -2.20846663 3.36690059 -2.21913346 2 P 0 ;0
L 3.36690059 -2.21913346 3.36490098 -2.2298003 2 P 0 ;0
L 3.36490098 -2.2298003 3.3609 -2.23913406 2 P 0 ;0
L 3.3609 -2.23913406 3.35489951 -2.24713484 2 P 0 ;0
L 3.35489951 -2.24713484 3.34789911 -2.25246703 2 P 0 ;0
L 3.34789911 -2.25246703 3.33989902 -2.2538 2 P 0 ;0
L 3.39889941 -2.2538 3.39889941 -2.1738 2 P 0 ;0
L 3.39889941 -2.1738 3.43690049 -2.1738 2 P 0 ;0
L 3.4228998 -2.21246575 3.39889941 -2.21246575 2 P 0 ;0
L 0.16489872 -1.0538 0.16489872 -1.1538 2 P 0 ;0
L 0.13423376 -1.0538 0.19556614 -1.0538 2 P 0 ;0
L 0.2588997 -1.0538 0.29089774 -1.0538 2 P 0 ;0
L 0.27489872 -1.0538 0.27489872 -1.1538 2 P 0 ;0
L 0.2588997 -1.1538 0.29089774 -1.1538 2 P 0 ;0
L 0.38489872 -1.0538 0.38489872 -1.1538 2 P 0 ;0
L 0.35423376 -1.0538 0.41556614 -1.0538 2 P 0 ;0
L 0.46823287 -1.0538 0.46823287 -1.1538 2 P 0 ;0
L 0.46823287 -1.1538 0.52156703 -1.1538 2 P 0 ;0
L 0.63156703 -1.1538 0.57823287 -1.1538 2 P 0 ;0
L 0.57823287 -1.1538 0.57823287 -1.0538 2 P 0 ;0
L 0.57823287 -1.0538 0.63156703 -1.0538 2 P 0 ;0
L 0.61023337 -1.10213219 0.57823287 -1.10213219 2 P 0 ;0
L 4.18989892 -1.9538 4.21489902 -1.8738 2 P 0 ;0
L 4.21489902 -1.8738 4.23990098 -1.9538 2 P 0 ;0
L 4.23089931 -1.92580118 4.19889882 -1.92580118 2 P 0 ;0
L 4.27289961 -1.9538 4.27289961 -1.8738 2 P 0 ;0
L 4.27289961 -1.8738 4.2978998 -1.8738 2 P 0 ;0
L 4.2978998 -1.8738 4.3058999 -1.87780167 2 P 0 ;0
L 4.3058999 -1.87780167 4.31090069 -1.88313386 2 P 0 ;0
L 4.31090069 -1.88313386 4.3129003 -1.89380069 2 P 0 ;0
L 4.3129003 -1.89380069 4.31090069 -1.90446752 2 P 0 ;0
L 4.31090069 -1.90446752 4.3049001 -1.91113278 2 P 0 ;0
L 4.3049001 -1.91113278 4.2978998 -1.91513435 2 P 0 ;0
L 4.2978998 -1.91513435 4.27289961 -1.91513435 2 P 0 ;0
L 4.2978998 -1.91513435 4.3129003 -1.9538 2 P 0 ;0
L 4.37089902 -1.8738 4.37089902 -1.9538 2 P 0 ;0
L 4.3479003 -1.8738 4.39389961 -1.8738 2 P 0 ;0
L 3.61989892 -2.2538 3.61989892 -2.1638 2 P 0 ;0
L 3.61989892 -2.1638 3.6058997 -2.18179892 2 P 0 ;0
L 3.6058997 -2.2538 3.63389803 -2.2538 2 P 0 ;0
L 3.68773268 -2.17879961 3.69473337 -2.16980148 2 P 0 ;0
L 3.69473337 -2.16980148 3.70290039 -2.1652997 2 P 0 ;0
L 3.70290039 -2.1652997 3.71223386 -2.1638 2 P 0 ;0
L 3.71223386 -2.1638 3.7239002 -2.16679941 2 P 0 ;0
L 3.7239002 -2.16679941 3.73206722 -2.17430059 2 P 0 ;0
L 3.73206722 -2.17430059 3.7344001 -2.18329862 2 P 0 ;0
L 3.7344001 -2.18329862 3.73323366 -2.19230217 2 P 0 ;0
L 3.73323366 -2.19230217 3.72856585 -2.19980059 2 P 0 ;0
L 3.72856585 -2.19980059 3.70523317 -2.2148001 2 P 0 ;0
L 3.70523317 -2.2148001 3.69473337 -2.22530069 2 P 0 ;0
L 3.69473337 -2.22530069 3.68773268 -2.24030295 2 P 0 ;0
L 3.68773268 -2.24030295 3.6853998 -2.2538 2 P 0 ;0
L 3.6853998 -2.2538 3.7344001 -2.2538 2 P 0 ;0
L 0.5058997 -1.6638 0.53389803 -1.6638 2 P 0 ;0
L 0.51989892 -1.6638 0.51989892 -1.7538 2 P 0 ;0
L 0.5058997 -1.7538 0.53389803 -1.7538 2 P 0 ;0
L 0.58306703 -1.7538 0.58306703 -1.6638 2 P 0 ;0
L 0.58306703 -1.6638 0.63673287 -1.7538 2 P 0 ;0
L 0.63673287 -1.7538 0.63673287 -1.6638 2 P 0 ;0
L 0.69989892 -1.6638 0.69989892 -1.7538 2 P 0 ;0
L 0.67306703 -1.6638 0.72673287 -1.6638 2 P 0 ;0
L 0.81323366 -1.7538 0.76656624 -1.7538 2 P 0 ;0
L 0.76656624 -1.7538 0.76656624 -1.6638 2 P 0 ;0
L 0.76656624 -1.6638 0.81323366 -1.6638 2 P 0 ;0
L 0.79456673 -1.70729902 0.76656624 -1.70729902 2 P 0 ;0
L 0.85656624 -1.7538 0.85656624 -1.6638 2 P 0 ;0
L 0.85656624 -1.6638 0.88573307 -1.6638 2 P 0 ;0
L 0.88573307 -1.6638 0.89506654 -1.66830187 2 P 0 ;0
L 0.89506654 -1.66830187 0.90090079 -1.67430059 2 P 0 ;0
L 0.90090079 -1.67430059 0.90323366 -1.68630069 2 P 0 ;0
L 0.90323366 -1.68630069 0.90090079 -1.69830089 2 P 0 ;0
L 0.90090079 -1.69830089 0.8939002 -1.70579931 2 P 0 ;0
L 0.8939002 -1.70579931 0.88573307 -1.71030108 2 P 0 ;0
L 0.88573307 -1.71030108 0.85656624 -1.71030108 2 P 0 ;0
L 0.88573307 -1.71030108 0.90323366 -1.7538 2 P 0 ;0
L 0.94306703 -1.7538 0.94306703 -1.6638 2 P 0 ;0
L 0.94306703 -1.6638 0.99673287 -1.7538 2 P 0 ;0
L 0.99673287 -1.7538 0.99673287 -1.6638 2 P 0 ;0
L 1.03073209 -1.7538 1.05989892 -1.6638 2 P 0 ;0
L 1.05989892 -1.6638 1.08906782 -1.7538 2 P 0 ;0
L 1.07856585 -1.72230128 1.04123189 -1.72230128 2 P 0 ;0
L 1.12656624 -1.6638 1.12656624 -1.7538 2 P 0 ;0
L 1.12656624 -1.7538 1.17323366 -1.7538 2 P 0 ;0
L 1.30656624 -1.6638 1.30656624 -1.7538 2 P 0 ;0
L 1.30656624 -1.7538 1.35323366 -1.7538 2 P 0 ;0
L 1.39073209 -1.7538 1.41989892 -1.6638 2 P 0 ;0
L 1.41989892 -1.6638 1.44906782 -1.7538 2 P 0 ;0
L 1.43856585 -1.72230128 1.40123189 -1.72230128 2 P 0 ;0
L 1.50989892 -1.7538 1.50989892 -1.71330049 2 P 0 ;0
L 1.50989892 -1.71330049 1.48656624 -1.6638 2 P 0 ;0
L 1.53323366 -1.6638 1.50989892 -1.71330049 2 P 0 ;0
L 1.62323366 -1.7538 1.57656624 -1.7538 2 P 0 ;0
L 1.57656624 -1.7538 1.57656624 -1.6638 2 P 0 ;0
L 1.57656624 -1.6638 1.62323366 -1.6638 2 P 0 ;0
L 1.60456673 -1.70729902 1.57656624 -1.70729902 2 P 0 ;0
L 1.66656624 -1.7538 1.66656624 -1.6638 2 P 0 ;0
L 1.66656624 -1.6638 1.69573307 -1.6638 2 P 0 ;0
L 1.69573307 -1.6638 1.70506654 -1.66830187 2 P 0 ;0
L 1.70506654 -1.66830187 1.71090079 -1.67430059 2 P 0 ;0
L 1.71090079 -1.67430059 1.71323366 -1.68630069 2 P 0 ;0
L 1.71323366 -1.68630069 1.71090079 -1.69830089 2 P 0 ;0
L 1.71090079 -1.69830089 1.7039002 -1.70579931 2 P 0 ;0
L 1.7039002 -1.70579931 1.69573307 -1.71030108 2 P 0 ;0
L 1.69573307 -1.71030108 1.66656624 -1.71030108 2 P 0 ;0
L 1.69573307 -1.71030108 1.71323366 -1.7538 2 P 0 ;0
L 1.8839002 -1.7538 1.8839002 -1.6638 2 P 0 ;0
L 1.8839002 -1.6638 1.84073209 -1.7283 2 P 0 ;0
L 1.84073209 -1.7283 1.89906782 -1.7283 2 P 0 ;0
L 3.0839002 -2.2538 3.0839002 -2.1638 2 P 0 ;0
L 3.0839002 -2.1638 3.04073209 -2.2283 2 P 0 ;0
L 3.04073209 -2.2283 3.09906782 -2.2283 2 P 0 ;0
L 3.8339002 -2.0038 3.8339002 -1.9138 2 P 0 ;0
L 3.8339002 -1.9138 3.79073209 -1.9783 2 P 0 ;0
L 3.79073209 -1.9783 3.84906782 -1.9783 2 P 0 ;0
L 0.59099833 -1.36499882 0.5990003 -1.35750039 2 P 0 ;0
L 0.5990003 -1.35750039 0.60499902 -1.34500315 2 P 0 ;0
L 0.60499902 -1.34500315 0.60900187 -1.32749764 2 P 0 ;0
L 0.60900187 -1.32749764 0.60499902 -1.31250089 2 P 0 ;0
L 0.60499902 -1.31250089 0.59700079 -1.30250305 2 P 0 ;0
L 0.59700079 -1.30250305 0.5830001 -1.295 2 P 0 ;0
L 0.5830001 -1.295 0.52900059 -1.295 2 P 0 ;0
L 0.52900059 -1.295 0.52900059 -1.445 2 P 0 ;0
L 0.52900059 -1.445 0.59500118 -1.445 2 P 0 ;0
L 0.59500118 -1.445 0.60900187 -1.43500217 2 P 0 ;0
L 0.60900187 -1.43500217 0.6170001 -1.42000079 2 P 0 ;0
L 0.6170001 -1.42000079 0.62099931 -1.4025 2 P 0 ;0
L 0.62099931 -1.4025 0.6170001 -1.38500374 2 P 0 ;0
L 0.6170001 -1.38500374 0.60499902 -1.37000236 2 P 0 ;0
L 0.60499902 -1.37000236 0.59099833 -1.36499882 2 P 0 ;0
L 0.59099833 -1.36499882 0.52900059 -1.36499882 2 P 0 ;0
L 0.77100138 -1.445 0.77100138 -1.34500315 2 P 0 ;0
L 0.77100138 -1.36249941 0.76299951 -1.35250148 2 P 0 ;0
L 0.76299951 -1.35250148 0.75099833 -1.34750256 2 P 0 ;0
L 0.75099833 -1.34750256 0.73700138 -1.34500315 2 P 0 ;0
L 0.73700138 -1.34500315 0.72300069 -1.35000207 2 P 0 ;0
L 0.72300069 -1.35000207 0.71099961 -1.3599999 2 P 0 ;0
L 0.71099961 -1.3599999 0.70299764 -1.37500128 2 P 0 ;0
L 0.70299764 -1.37500128 0.69899852 -1.39500157 2 P 0 ;0
L 0.69899852 -1.39500157 0.70299764 -1.41500187 2 P 0 ;0
L 0.70299764 -1.41500187 0.71099961 -1.43000325 2 P 0 ;0
L 0.71099961 -1.43000325 0.72300069 -1.44000108 2 P 0 ;0
L 0.72300069 -1.44000108 0.73700138 -1.445 2 P 0 ;0
L 0.73700138 -1.445 0.75099833 -1.44250059 2 P 0 ;0
L 0.75099833 -1.44250059 0.76299951 -1.43500217 2 P 0 ;0
L 0.76299951 -1.43500217 0.77100138 -1.42500433 2 P 0 ;0
L 0.86700039 -1.445 0.86700039 -1.34500315 2 P 0 ;0
L 0.86700039 -1.36499882 0.87699833 -1.35500098 2 P 0 ;0
L 0.87699833 -1.35500098 0.8869998 -1.34750256 2 P 0 ;0
L 0.8869998 -1.34750256 0.90100049 -1.34500315 2 P 0 ;0
L 0.90100049 -1.34500315 0.91099833 -1.34750256 2 P 0 ;0
L 0.91099833 -1.34750256 0.92299951 -1.35500098 2 P 0 ;0
L 1.02700039 -1.445 1.02700039 -1.34500315 2 P 0 ;0
L 1.02700039 -1.36499882 1.03699833 -1.35500098 2 P 0 ;0
L 1.03699833 -1.35500098 1.0469998 -1.34750256 2 P 0 ;0
L 1.0469998 -1.34750256 1.06100049 -1.34500315 2 P 0 ;0
L 1.06100049 -1.34500315 1.07099833 -1.34750256 2 P 0 ;0
L 1.07099833 -1.34750256 1.08299951 -1.35500098 2 P 0 ;0
L 1.18500089 -1.37750069 1.24900187 -1.37750069 2 P 0 ;0
L 1.24900187 -1.37750069 1.24299951 -1.3599999 2 P 0 ;0
L 1.24299951 -1.3599999 1.23300157 -1.35000207 2 P 0 ;0
L 1.23300157 -1.35000207 1.21900089 -1.34500315 2 P 0 ;0
L 1.21900089 -1.34500315 1.2050003 -1.34750256 2 P 0 ;0
L 1.2050003 -1.34750256 1.19299911 -1.35500098 2 P 0 ;0
L 1.19299911 -1.35500098 1.18500089 -1.37250177 2 P 0 ;0
L 1.18500089 -1.37250177 1.18099803 -1.38750315 2 P 0 ;0
L 1.18099803 -1.38750315 1.18099803 -1.4025 2 P 0 ;0
L 1.18099803 -1.4025 1.18500089 -1.41750138 2 P 0 ;0
L 1.18500089 -1.41750138 1.19499872 -1.43250276 2 P 0 ;0
L 1.19499872 -1.43250276 1.2069998 -1.44250059 2 P 0 ;0
L 1.2069998 -1.44250059 1.22100049 -1.445 2 P 0 ;0
L 1.22100049 -1.445 1.23500118 -1.44000108 2 P 0 ;0
L 1.23500118 -1.44000108 1.24900187 -1.42500433 2 P 0 ;0
L 1.37499813 -1.445 1.37499813 -1.295 2 P 0 ;0
L 1.50500089 -1.37750069 1.56900187 -1.37750069 2 P 0 ;0
L 1.56900187 -1.37750069 1.56299951 -1.3599999 2 P 0 ;0
L 1.56299951 -1.3599999 1.55300157 -1.35000207 2 P 0 ;0
L 1.55300157 -1.35000207 1.53900089 -1.34500315 2 P 0 ;0
L 1.53900089 -1.34500315 1.5250003 -1.34750256 2 P 0 ;0
L 1.5250003 -1.34750256 1.51299911 -1.35500098 2 P 0 ;0
L 1.51299911 -1.35500098 1.50500089 -1.37250177 2 P 0 ;0
L 1.50500089 -1.37250177 1.50099803 -1.38750315 2 P 0 ;0
L 1.50099803 -1.38750315 1.50099803 -1.4025 2 P 0 ;0
L 1.50099803 -1.4025 1.50500089 -1.41750138 2 P 0 ;0
L 1.50500089 -1.41750138 1.51499872 -1.43250276 2 P 0 ;0
L 1.51499872 -1.43250276 1.5269998 -1.44250059 2 P 0 ;0
L 1.5269998 -1.44250059 1.54100049 -1.445 2 P 0 ;0
L 1.54100049 -1.445 1.55500118 -1.44000108 2 P 0 ;0
L 1.55500118 -1.44000108 1.56900187 -1.42500433 2 P 0 ;0
L 1.6529998 -1.48999951 1.66500089 -1.49499843 2 P 0 ;0
L 1.66500089 -1.49499843 1.68100108 -1.48999951 2 P 0 ;0
L 1.68100108 -1.48999951 1.69099902 -1.48000167 2 P 0 ;0
L 1.69099902 -1.48000167 1.69900089 -1.4674997 2 P 0 ;0
L 1.69900089 -1.4674997 1.71099833 -1.42750374 2 P 0 ;0
L 1.71099833 -1.42750374 1.7370001 -1.34500315 2 P 0 ;0
L 1.67299911 -1.34500315 1.71099833 -1.42750374 2 P 0 ;0
L 1.82500089 -1.37750069 1.88900187 -1.37750069 2 P 0 ;0
L 1.88900187 -1.37750069 1.88299951 -1.3599999 2 P 0 ;0
L 1.88299951 -1.3599999 1.87300157 -1.35000207 2 P 0 ;0
L 1.87300157 -1.35000207 1.85900089 -1.34500315 2 P 0 ;0
L 1.85900089 -1.34500315 1.8450003 -1.34750256 2 P 0 ;0
L 1.8450003 -1.34750256 1.83299911 -1.35500098 2 P 0 ;0
L 1.83299911 -1.35500098 1.82500089 -1.37250177 2 P 0 ;0
L 1.82500089 -1.37250177 1.82099803 -1.38750315 2 P 0 ;0
L 1.82099803 -1.38750315 1.82099803 -1.4025 2 P 0 ;0
L 1.82099803 -1.4025 1.82500089 -1.41750138 2 P 0 ;0
L 1.82500089 -1.41750138 1.83499872 -1.43250276 2 P 0 ;0
L 1.83499872 -1.43250276 1.8469998 -1.44250059 2 P 0 ;0
L 1.8469998 -1.44250059 1.86100049 -1.445 2 P 0 ;0
L 1.86100049 -1.445 1.87500118 -1.44000108 2 P 0 ;0
L 1.87500118 -1.44000108 1.88900187 -1.42500433 2 P 0 ;0
L 2.18699921 -1.37000236 2.22700167 -1.37000236 2 P 0 ;0
L 2.22700167 -1.37000236 2.22700167 -1.41500187 2 P 0 ;0
L 2.22700167 -1.41500187 2.21500059 -1.43000325 2 P 0 ;0
L 2.21500059 -1.43000325 2.2009999 -1.44000108 2 P 0 ;0
L 2.2009999 -1.44000108 2.18100049 -1.445 2 P 0 ;0
L 2.18100049 -1.445 2.16100108 -1.44000108 2 P 0 ;0
L 2.16100108 -1.44000108 2.14700039 -1.43000325 2 P 0 ;0
L 2.14700039 -1.43000325 2.13499931 -1.41500187 2 P 0 ;0
L 2.13499931 -1.41500187 2.12699734 -1.39750108 2 P 0 ;0
L 2.12699734 -1.39750108 2.12299823 -1.37750069 2 P 0 ;0
L 2.12299823 -1.37750069 2.12299823 -1.3599999 2 P 0 ;0
L 2.12299823 -1.3599999 2.12699734 -1.34500315 2 P 0 ;0
L 2.12699734 -1.34500315 2.13499931 -1.32749764 2 P 0 ;0
L 2.13499931 -1.32749764 2.14700039 -1.31250089 2 P 0 ;0
L 2.14700039 -1.31250089 2.15899783 -1.30250305 2 P 0 ;0
L 2.15899783 -1.30250305 2.17499813 -1.295 2 P 0 ;0
L 2.17499813 -1.295 2.18899882 -1.295 2 P 0 ;0
L 2.18899882 -1.295 2.20499902 -1.29999902 2 P 0 ;0
L 2.20499902 -1.29999902 2.2170001 -1.31000138 2 P 0 ;0
L 2.29699892 -1.31999931 2.309 -1.30500246 2 P 0 ;0
L 2.309 -1.30500246 2.32300069 -1.29749951 2 P 0 ;0
L 2.32300069 -1.29749951 2.33900089 -1.295 2 P 0 ;0
L 2.33900089 -1.295 2.3590003 -1.29999902 2 P 0 ;0
L 2.3590003 -1.29999902 2.37300098 -1.31250089 2 P 0 ;0
L 2.37300098 -1.31250089 2.3770001 -1.32749764 2 P 0 ;0
L 2.3770001 -1.32749764 2.37500059 -1.34250364 2 P 0 ;0
L 2.37500059 -1.34250364 2.36699862 -1.35500098 2 P 0 ;0
L 2.36699862 -1.35500098 2.3269998 -1.3800002 2 P 0 ;0
L 2.3269998 -1.3800002 2.309 -1.39750108 2 P 0 ;0
L 2.309 -1.39750108 2.29699892 -1.42250482 2 P 0 ;0
L 2.29699892 -1.42250482 2.2929998 -1.445 2 P 0 ;0
L 2.2929998 -1.445 2.3770001 -1.445 2 P 0 ;0
L 2.6129998 -1.42500433 2.629 -1.43750167 2 P 0 ;0
L 2.629 -1.43750167 2.6469998 -1.445 2 P 0 ;0
L 2.6469998 -1.445 2.6630001 -1.445 2 P 0 ;0
L 2.6630001 -1.445 2.6790003 -1.43750167 2 P 0 ;0
L 2.6790003 -1.43750167 2.69100138 -1.42500433 2 P 0 ;0
L 2.69100138 -1.42500433 2.6970001 -1.40749892 2 P 0 ;0
L 2.6970001 -1.40749892 2.69300098 -1.39000266 2 P 0 ;0
L 2.69300098 -1.39000266 2.68299951 -1.37500128 2 P 0 ;0
L 2.68299951 -1.37500128 2.66499961 -1.36499882 2 P 0 ;0
L 2.66499961 -1.36499882 2.64100108 -1.3599999 2 P 0 ;0
L 2.64100108 -1.3599999 2.62700039 -1.35000207 2 P 0 ;0
L 2.62700039 -1.35000207 2.62099803 -1.33250118 2 P 0 ;0
L 2.62099803 -1.33250118 2.62500089 -1.31500039 2 P 0 ;0
L 2.62500089 -1.31500039 2.63499872 -1.30250305 2 P 0 ;0
L 2.63499872 -1.30250305 2.64899941 -1.295 2 P 0 ;0
L 2.64899941 -1.295 2.6630001 -1.295 2 P 0 ;0
L 2.6630001 -1.295 2.67700079 -1.29999902 2 P 0 ;0
L 2.67700079 -1.29999902 2.68900187 -1.31250089 2 P 0 ;0
L 2.7729998 -1.445 2.8570001 -1.295 2 P 0 ;0
L 2.7729998 -1.295 2.8570001 -1.445 2 P 0 ;0
L 2.92299823 -1.445 2.92299823 -1.295 2 P 0 ;0
L 2.92299823 -1.295 2.97499813 -1.42000079 2 P 0 ;0
L 2.97499813 -1.42000079 3.02700167 -1.295 2 P 0 ;0
L 3.02700167 -1.295 3.02700167 -1.445 2 P 0 ;0
L 3.09699892 -1.31999931 3.109 -1.30500246 2 P 0 ;0
L 3.109 -1.30500246 3.12300069 -1.29749951 2 P 0 ;0
L 3.12300069 -1.29749951 3.13900089 -1.295 2 P 0 ;0
L 3.13900089 -1.295 3.1590003 -1.29999902 2 P 0 ;0
L 3.1590003 -1.29999902 3.17300098 -1.31250089 2 P 0 ;0
L 3.17300098 -1.31250089 3.1770001 -1.32749764 2 P 0 ;0
L 3.1770001 -1.32749764 3.17500059 -1.34250364 2 P 0 ;0
L 3.17500059 -1.34250364 3.16699862 -1.35500098 2 P 0 ;0
L 3.16699862 -1.35500098 3.1269998 -1.3800002 2 P 0 ;0
L 3.1269998 -1.3800002 3.109 -1.39750108 2 P 0 ;0
L 3.109 -1.39750108 3.09699892 -1.42250482 2 P 0 ;0
L 3.09699892 -1.42250482 3.0929998 -1.445 2 P 0 ;0
L 3.0929998 -1.445 3.1770001 -1.445 2 P 0 ;0
L 3.269 -1.39500157 3.3209999 -1.39500157 2 P 0 ;0
L 3.41499931 -1.445 3.41499931 -1.295 2 P 0 ;0
L 3.41499931 -1.295 3.46499961 -1.295 2 P 0 ;0
L 3.46499961 -1.295 3.4809999 -1.30250305 2 P 0 ;0
L 3.4809999 -1.30250305 3.49100138 -1.31250089 2 P 0 ;0
L 3.49100138 -1.31250089 3.49500059 -1.33250118 2 P 0 ;0
L 3.49500059 -1.33250118 3.49100138 -1.35250148 2 P 0 ;0
L 3.49100138 -1.35250148 3.4790003 -1.36499882 2 P 0 ;0
L 3.4790003 -1.36499882 3.46499961 -1.37250177 2 P 0 ;0
L 3.46499961 -1.37250177 3.41499931 -1.37250177 2 P 0 ;0
L 3.46499961 -1.37250177 3.49500059 -1.445 2 P 0 ;0
L 3.61499813 -1.34500315 3.61499813 -1.445 2 P 0 ;0
L 3.61499813 -1.30500246 3.61099902 -1.30250305 2 P 8191 ;0
L 3.61099902 -1.30250305 3.61099902 -1.29749951 2 P 8191 ;0
L 3.61099902 -1.29749951 3.61499813 -1.295 2 P 8191 ;0
L 3.61499813 -1.295 3.61900089 -1.29749951 2 P 8191 ;0
L 3.61900089 -1.29749951 3.61900089 -1.30250305 2 P 8191 ;0
L 3.61900089 -1.30250305 3.61499813 -1.30500246 2 P 8191 ;0
L 3.74500089 -1.42750374 3.75499872 -1.43750167 2 P 0 ;0
L 3.75499872 -1.43750167 3.76899941 -1.445 2 P 0 ;0
L 3.76899941 -1.445 3.78100049 -1.445 2 P 0 ;0
L 3.78100049 -1.445 3.79300157 -1.44000108 2 P 0 ;0
L 3.79300157 -1.44000108 3.8009999 -1.43250276 2 P 0 ;0
L 3.8009999 -1.43250276 3.80499902 -1.42250482 2 P 0 ;0
L 3.80499902 -1.42250482 3.80299951 -1.40749892 2 P 0 ;0
L 3.80299951 -1.40749892 3.79500118 -1.40000049 2 P 0 ;0
L 3.79500118 -1.40000049 3.75899783 -1.38500374 2 P 0 ;0
L 3.75899783 -1.38500374 3.75099961 -1.36749833 2 P 0 ;0
L 3.75099961 -1.36749833 3.75499872 -1.35500098 2 P 0 ;0
L 3.75499872 -1.35500098 3.76300069 -1.34750256 2 P 0 ;0
L 3.76300069 -1.34750256 3.77499813 -1.34500315 2 P 0 ;0
L 3.77499813 -1.34500315 3.78699921 -1.34750256 2 P 0 ;0
L 3.78699921 -1.34750256 3.7990003 -1.35500098 2 P 0 ;0
L 3.90500089 -1.37750069 3.96900187 -1.37750069 2 P 0 ;0
L 3.96900187 -1.37750069 3.96299951 -1.3599999 2 P 0 ;0
L 3.96299951 -1.3599999 3.95300157 -1.35000207 2 P 0 ;0
L 3.95300157 -1.35000207 3.93900089 -1.34500315 2 P 0 ;0
L 3.93900089 -1.34500315 3.9250003 -1.34750256 2 P 0 ;0
L 3.9250003 -1.34750256 3.91299911 -1.35500098 2 P 0 ;0
L 3.91299911 -1.35500098 3.90500089 -1.37250177 2 P 0 ;0
L 3.90500089 -1.37250177 3.90099803 -1.38750315 2 P 0 ;0
L 3.90099803 -1.38750315 3.90099803 -1.4025 2 P 0 ;0
L 3.90099803 -1.4025 3.90500089 -1.41750138 2 P 0 ;0
L 3.90500089 -1.41750138 3.91499872 -1.43250276 2 P 0 ;0
L 3.91499872 -1.43250276 3.9269998 -1.44250059 2 P 0 ;0
L 3.9269998 -1.44250059 3.94100049 -1.445 2 P 0 ;0
L 3.94100049 -1.445 3.95500118 -1.44000108 2 P 0 ;0
L 3.95500118 -1.44000108 3.96900187 -1.42500433 2 P 0 ;0
L 4.06700039 -1.445 4.06700039 -1.34500315 2 P 0 ;0
L 4.06700039 -1.36499882 4.07699833 -1.35500098 2 P 0 ;0
L 4.07699833 -1.35500098 4.0869998 -1.34750256 2 P 0 ;0
L 4.0869998 -1.34750256 4.10100049 -1.34500315 2 P 0 ;0
L 4.10100049 -1.34500315 4.11099833 -1.34750256 2 P 0 ;0
L 4.11099833 -1.34750256 4.12299951 -1.35500098 2 P 0 ;0
L 4.16964783 -2.2038 4.21839813 -2.0478 2 P 0 ;0
L 4.21839813 -2.0478 4.26715207 -2.2038 2 P 0 ;0
L 4.24959862 -2.14920217 4.18719774 -2.14920217 2 P 0 ;0
L 4.37939813 -2.2038 4.37939813 -2.0478 2 P 0 ;0
L 4.37939813 -2.0478 4.35599961 -2.07899813 2 P 0 ;0
L 4.35599961 -2.2038 4.40279675 -2.2038 2 P 0 ;0
L 2.0009002 -0.9538 2.0009002 -0.8038 2 P 0 ;0
L 2.0009002 -0.8038 2.04089902 -0.8038 2 P 0 ;0
L 2.04089902 -0.8038 2.05689921 -0.81130305 2 P 0 ;0
L 2.05689921 -0.81130305 2.0689003 -0.82130089 2 P 0 ;0
L 2.0689003 -0.82130089 2.07890187 -0.83629764 2 P 0 ;0
L 2.07890187 -0.83629764 2.0869001 -0.85380315 2 P 0 ;0
L 2.0869001 -0.85380315 2.0888997 -0.87880236 2 P 0 ;0
L 2.0888997 -0.87880236 2.0869001 -0.90380157 2 P 0 ;0
L 2.0869001 -0.90380157 2.07890187 -0.92130246 2 P 0 ;0
L 2.07890187 -0.92130246 2.0689003 -0.93630374 2 P 0 ;0
L 2.0689003 -0.93630374 2.05689921 -0.94630167 2 P 0 ;0
L 2.05689921 -0.94630167 2.04089902 -0.9538 2 P 0 ;0
L 2.04089902 -0.9538 2.0009002 -0.9538 2 P 0 ;0
L 2.15489783 -0.9538 2.20489813 -0.8038 2 P 0 ;0
L 2.20489813 -0.8038 2.25490207 -0.9538 2 P 0 ;0
L 2.23689862 -0.90130207 2.17289764 -0.90130207 2 P 0 ;0
L 2.36489813 -0.8038 2.36489813 -0.9538 2 P 0 ;0
L 2.31890059 -0.8038 2.41089931 -0.8038 2 P 0 ;0
L 2.56490059 -0.9538 2.48489931 -0.9538 2 P 0 ;0
L 2.48489931 -0.9538 2.48489931 -0.8038 2 P 0 ;0
L 2.48489931 -0.8038 2.56490059 -0.8038 2 P 0 ;0
L 2.5329001 -0.87629833 2.48489931 -0.87629833 2 P 0 ;0
L 2.84489813 -0.9538 2.82889783 -0.95130059 2 P 0 ;0
L 2.82889783 -0.95130059 2.81490089 -0.94130276 2 P 0 ;0
L 2.81490089 -0.94130276 2.8028998 -0.92630138 2 P 0 ;0
L 2.8028998 -0.92630138 2.79489783 -0.90880049 2 P 0 ;0
L 2.79489783 -0.90880049 2.79089862 -0.8888002 2 P 0 ;0
L 2.79089862 -0.8888002 2.79089862 -0.8687999 2 P 0 ;0
L 2.79089862 -0.8687999 2.79489783 -0.84879961 2 P 0 ;0
L 2.79489783 -0.84879961 2.8028998 -0.83129872 2 P 0 ;0
L 2.8028998 -0.83129872 2.81490089 -0.81630197 2 P 0 ;0
L 2.81490089 -0.81630197 2.82889783 -0.80629951 2 P 0 ;0
L 2.82889783 -0.80629951 2.84489813 -0.8038 2 P 0 ;0
L 2.84489813 -0.8038 2.86089833 -0.80629951 2 P 0 ;0
L 2.86089833 -0.80629951 2.87489902 -0.81630197 2 P 0 ;0
L 2.87489902 -0.81630197 2.8869001 -0.83129872 2 P 0 ;0
L 2.8869001 -0.83129872 2.89490207 -0.84879961 2 P 0 ;0
L 2.89490207 -0.84879961 2.89890128 -0.8687999 2 P 0 ;0
L 2.89890128 -0.8687999 2.89890128 -0.8888002 2 P 0 ;0
L 2.89890128 -0.8888002 2.89490207 -0.90880049 2 P 0 ;0
L 2.89490207 -0.90880049 2.8869001 -0.92630138 2 P 0 ;0
L 2.8869001 -0.92630138 2.87489902 -0.94130276 2 P 0 ;0
L 2.87489902 -0.94130276 2.86089833 -0.95130059 2 P 0 ;0
L 2.86089833 -0.95130059 2.84489813 -0.9538 2 P 0 ;0
L 3.0488997 -0.81630197 3.03689862 -0.80879902 2 P 0 ;0
L 3.03689862 -0.80879902 3.02290157 -0.8038 2 P 0 ;0
L 3.02290157 -0.8038 3.00690138 -0.8038 2 P 0 ;0
L 3.00690138 -0.8038 2.98889783 -0.81130305 2 P 0 ;0
L 2.98889783 -0.81130305 2.97490089 -0.82380039 2 P 0 ;0
L 2.97490089 -0.82380039 2.96489931 -0.83880177 2 P 0 ;0
L 2.96489931 -0.83880177 2.95689734 -0.86380098 2 P 0 ;0
L 2.95689734 -0.86380098 2.95489783 -0.88630069 2 P 0 ;0
L 2.95489783 -0.88630069 2.95890059 -0.90880049 2 P 0 ;0
L 2.95890059 -0.90880049 2.96489931 -0.92380187 2 P 0 ;0
L 2.96489931 -0.92380187 2.97690039 -0.93880325 2 P 0 ;0
L 2.97690039 -0.93880325 2.99090108 -0.94880108 2 P 0 ;0
L 2.99090108 -0.94880108 3.00489813 -0.9538 2 P 0 ;0
L 3.00489813 -0.9538 3.01889882 -0.9538 2 P 0 ;0
L 3.01889882 -0.9538 3.03289951 -0.94880108 2 P 0 ;0
L 3.03289951 -0.94880108 3.04490059 -0.94130276 2 P 0 ;0
L 3.04490059 -0.94130276 3.05490207 -0.93130482 2 P 0 ;0
L 3.16489813 -0.8038 3.16489813 -0.9538 2 P 0 ;0
L 3.11890059 -0.8038 3.21089931 -0.8038 2 P 0 ;0
L 3.28889852 -0.95879892 3.36090138 -0.8038 2 P 0 ;0
L 3.44689892 -0.82879931 3.4589 -0.81380246 2 P 0 ;0
L 3.4589 -0.81380246 3.47290069 -0.80629951 2 P 0 ;0
L 3.47290069 -0.80629951 3.48890089 -0.8038 2 P 0 ;0
L 3.48890089 -0.8038 3.5089003 -0.80879902 2 P 0 ;0
L 3.5089003 -0.80879902 3.52290098 -0.82130089 2 P 0 ;0
L 3.52290098 -0.82130089 3.5269001 -0.83629764 2 P 0 ;0
L 3.5269001 -0.83629764 3.52490059 -0.85130364 2 P 0 ;0
L 3.52490059 -0.85130364 3.51689862 -0.86380098 2 P 0 ;0
L 3.51689862 -0.86380098 3.4768998 -0.8888002 2 P 0 ;0
L 3.4768998 -0.8888002 3.4589 -0.90630108 2 P 0 ;0
L 3.4589 -0.90630108 3.44689892 -0.93130482 2 P 0 ;0
L 3.44689892 -0.93130482 3.4428998 -0.9538 2 P 0 ;0
L 3.4428998 -0.9538 3.5269001 -0.9538 2 P 0 ;0
L 3.64089902 -0.9538 3.64489813 -0.92130246 2 P 0 ;0
L 3.64489813 -0.92130246 3.65090049 -0.89380374 2 P 0 ;0
L 3.65090049 -0.89380374 3.65889882 -0.8687999 2 P 0 ;0
L 3.65889882 -0.8687999 3.6689003 -0.84130118 2 P 0 ;0
L 3.6689003 -0.84130118 3.68490059 -0.8038 2 P 0 ;0
L 3.68490059 -0.8038 3.60489931 -0.8038 2 P 0 ;0
L 3.76889852 -0.95879892 3.84090138 -0.8038 2 P 0 ;0
L 3.92689892 -0.82879931 3.9389 -0.81380246 2 P 0 ;0
L 3.9389 -0.81380246 3.95290069 -0.80629951 2 P 0 ;0
L 3.95290069 -0.80629951 3.96890089 -0.8038 2 P 0 ;0
L 3.96890089 -0.8038 3.9889003 -0.80879902 2 P 0 ;0
L 3.9889003 -0.80879902 4.00290098 -0.82130089 2 P 0 ;0
L 4.00290098 -0.82130089 4.0069001 -0.83629764 2 P 0 ;0
L 4.0069001 -0.83629764 4.00490059 -0.85130364 2 P 0 ;0
L 4.00490059 -0.85130364 3.99689862 -0.86380098 2 P 0 ;0
L 3.99689862 -0.86380098 3.9568998 -0.8888002 2 P 0 ;0
L 3.9568998 -0.8888002 3.9389 -0.90630108 2 P 0 ;0
L 3.9389 -0.90630108 3.92689892 -0.93130482 2 P 0 ;0
L 3.92689892 -0.93130482 3.9228998 -0.9538 2 P 0 ;0
L 3.9228998 -0.9538 4.0069001 -0.9538 2 P 0 ;0
L 4.12489813 -0.8038 4.10889783 -0.80879902 2 P 0 ;0
L 4.10889783 -0.80879902 4.09690039 -0.82130089 2 P 0 ;0
L 4.09690039 -0.82130089 4.08889852 -0.83629764 2 P 0 ;0
L 4.08889852 -0.83629764 4.0828998 -0.85630256 2 P 0 ;0
L 4.0828998 -0.85630256 4.0809002 -0.87880236 2 P 0 ;0
L 4.0809002 -0.87880236 4.0828998 -0.90130207 2 P 0 ;0
L 4.0828998 -0.90130207 4.08889852 -0.92130246 2 P 0 ;0
L 4.08889852 -0.92130246 4.09690039 -0.93630374 2 P 0 ;0
L 4.09690039 -0.93630374 4.10889783 -0.94880108 2 P 0 ;0
L 4.10889783 -0.94880108 4.12489813 -0.9538 2 P 0 ;0
L 4.12489813 -0.9538 4.14089833 -0.94880108 2 P 0 ;0
L 4.14089833 -0.94880108 4.15289951 -0.93630374 2 P 0 ;0
L 4.15289951 -0.93630374 4.16090138 -0.92130246 2 P 0 ;0
L 4.16090138 -0.92130246 4.1669001 -0.90130207 2 P 0 ;0
L 4.1669001 -0.90130207 4.1688997 -0.87880236 2 P 0 ;0
L 4.1688997 -0.87880236 4.1669001 -0.85630256 2 P 0 ;0
L 4.1669001 -0.85630256 4.16090138 -0.83629764 2 P 0 ;0
L 4.16090138 -0.83629764 4.15289951 -0.82130089 2 P 0 ;0
L 4.15289951 -0.82130089 4.14089833 -0.80879902 2 P 0 ;0
L 4.14089833 -0.80879902 4.12489813 -0.8038 2 P 0 ;0
L 4.28489813 -0.9538 4.28489813 -0.8038 2 P 0 ;0
L 4.28489813 -0.8038 4.26089961 -0.83379823 2 P 0 ;0
L 4.26089961 -0.9538 4.30889665 -0.9538 2 P 0 ;0
L 4.44089902 -0.9538 4.44489813 -0.92130246 2 P 0 ;0
L 4.44489813 -0.92130246 4.45090049 -0.89380374 2 P 0 ;0
L 4.45090049 -0.89380374 4.45889882 -0.8687999 2 P 0 ;0
L 4.45889882 -0.8687999 4.4689003 -0.84130118 2 P 0 ;0
L 4.4689003 -0.84130118 4.48490059 -0.8038 2 P 0 ;0
L 4.48490059 -0.8038 4.40489931 -0.8038 2 P 0 ;0

### steps/drc/layers/l5/features
#
#Feature symbol names
#
$0 r2
$1 r3.7
$2 r4.5
$3 r6
$4 r15
$5 r17
$6 r20
$7 r43.7
$8 r74.8
$9 s15

#
#Feature attribute names
#
@0 .nomenclature
@1 .pattern_fill
@2 .geometry
@3 .string
@4 .pad_usage
@5 .string_angle

#
#Feature attribute text strings
#
&0 C1_11P0_7TP
&1 V20D10AT28SM14
&2 TPB30V20D10AT28BPM
&3 V17D8AT30SM11
&4 C1_11P0_7
&5 C1_9P1_4
&6 S1_9P1_4
&7 SHEET
&8 TITLE
&9 SCALE 1:1
&10 LAYER
&11 OF
&12 ART
&13 12
&14 INTERNAL LAYER 5
&15 5
&16 Barreleye G2 SXM2-Riser
&17 A1
&18 DATE OCT/27/2017

#
#Layer features
#
P 1.29 6.26 7 P 0 0;2=0,4=0
L 9.24625 6.30625 1.2937 6.30625 1 P 0 
L 1.2937 6.30625 1.29 6.30255 1 P 0 
L 1.29 6.30255 1.29 6.26 1 P 0 
P 1.29 6.36 7 P 0 0;2=0,4=0
L 9.24625 6.31375 1.2937 6.31375 1 P 0 
L 1.2937 6.31375 1.29 6.31745 1 P 0 
L 1.29 6.31745 1.29 6.36 1 P 0 
L 4.02 4.355 4.02 2.83 2 P 0 
L 4.02 2.83 4.125 2.725 2 P 0 
P 4.125 2.725 6 P 0 0;2=1,4=1
P 4.02 4.355 6 P 0 0;2=2,4=1
L 7.425 3.43 7.425 1.725 2 P 0 
L 7.425 1.725 7.445 1.705 2 P 0 
P 7.425 3.43 6 P 0 0;2=2,4=1
P 7.445 1.705 6 P 0 0;2=1,4=1
P 11.03661004 3.81615 5 P 0 0;2=3,4=1
P 11.135 2.845 6 P 0 0;2=1,4=1
L 11.135 2.845 11.135 3.78 2 P 0 
L 11.135 3.78 11.09885 3.81615 2 P 0 
L 11.09885 3.81615 11.03661004 3.81615 2 P 0 
P 4.68268002 2.36615 5 P 0 0;2=3,4=1
P 0.27165 4.01181004 7 P 0 0;2=4,4=0
L 4.68268002 2.36615 4.68268002 2.3837 1 P 0 
L 4.68268002 2.3837 4.67898002 2.3874 1 P 0 
L 4.67898002 2.3874 4.66513002 2.3874 1 P 0 
L 4.66513002 2.3874 4.66143002 2.3837 1 P 0 
L 4.66143002 2.3837 4.66143002 2.34568996 1 P 0 
L 4.66143002 2.34568996 4.65313996 2.3374 1 P 0 
L 4.65313996 2.3374 4.52488002 2.3374 1 P 0 
L 4.52488002 2.3374 4.29991998 2.29773996 1 P 0 
L 4.29991998 2.29773996 3.78113002 1.93446998 1 P 0 
L 3.78113002 1.93446998 3.54756998 1.89328996 1 P 0 
L 3.54756998 1.89328996 2.42483996 1.69531004 1 P 0 
L 2.42483996 1.69531004 2.23846004 1.72816998 1 P 0 
L 2.23846004 1.72816998 2.15061004 1.71268002 1 P 0 
L 2.15061004 1.71268002 1.96481998 1.74543002 1 P 0 
L 1.96481998 1.74543002 1.82623002 1.84248002 1 P 0 
L 1.82623002 1.84248002 1.39988002 2.45136004 1 P 0 
L 1.39988002 2.45136004 1.36811004 2.63151998 1 P 0 
L 1.36811004 2.63151998 0.52731004 3.8323 1 P 0 
L 0.52731004 3.8323 0.39668002 3.92376998 1 P 0 
L 0.39668002 3.92376998 0.36273996 3.92976004 1 P 0 
L 0.36273996 3.92976004 0.33138996 3.92976004 1 P 0 
L 0.33138996 3.92976004 0.30286998 3.95828002 1 P 0 
L 0.30286998 3.95828002 0.30286998 3.98058996 1 P 0 
L 0.30286998 3.98058996 0.27165 4.01181004 1 P 0 
P 4.58268002 2.36615 5 P 0 0;2=3,4=1
P 0.27165 4.16928996 7 P 0 0;2=4,4=0
L 4.58268002 2.36615 4.58268002 2.3837 1 P 0 
L 4.58268002 2.3837 4.57898002 2.3874 1 P 0 
L 4.57898002 2.3874 4.52116004 2.3874 1 P 0 
L 4.52116004 2.3874 4.30011998 2.34841998 1 P 0 
L 4.30011998 2.34841998 3.74806998 1.96188002 1 P 0 
L 3.74806998 1.96188002 3.54268996 1.92566998 1 P 0 
L 3.54268996 1.92566998 2.40423002 1.72496004 1 P 0 
L 2.40423002 1.72496004 2.24068002 1.75378996 1 P 0 
L 2.24068002 1.75378996 2.1495 1.73771004 1 P 0 
L 2.1495 1.73771004 1.99586004 1.7648 1 P 0 
L 1.99586004 1.7648 1.85991998 1.85996998 1 P 0 
L 1.85991998 1.85996998 1.45786004 2.43418002 1 P 0 
L 1.45786004 2.43418002 1.41421998 2.68171004 1 P 0 
L 1.41421998 2.68171004 0.45591004 4.05031004 1 P 0 
L 0.45591004 4.05031004 0.41678002 4.07771004 1 P 0 
L 0.41678002 4.07771004 0.36273996 4.08723996 1 P 0 
L 0.36273996 4.08723996 0.33138996 4.08723996 1 P 0 
L 0.33138996 4.08723996 0.30286998 4.11576004 1 P 0 
L 0.30286998 4.11576004 0.30286998 4.13806998 1 P 0 
L 0.30286998 4.13806998 0.27165 4.16928996 1 P 0 
P 4.63268002 2.41615 5 P 0 0;2=3,4=1
P 0.27165 4.32676998 7 P 0 0;2=4,4=0
L 4.63268002 2.41615 4.63268002 2.4337 1 P 0 
L 4.63268002 2.4337 4.62898002 2.4374 1 P 0 
L 4.62898002 2.4374 4.54768996 2.4374 1 P 0 
L 4.54768996 2.4374 4.29788002 2.39335 1 P 0 
L 4.29788002 2.39335 3.71761004 1.98703996 1 P 0 
L 3.71761004 1.98703996 3.53748002 1.95528002 1 P 0 
L 3.53748002 1.95528002 2.39186998 1.75331004 1 P 0 
L 2.39186998 1.75331004 2.24101998 1.7799 1 P 0 
L 2.24101998 1.7799 2.14846998 1.76358002 1 P 0 
L 2.14846998 1.76358002 2.00955 1.78808002 1 P 0 
L 2.00955 1.78808002 1.89291998 1.86973002 1 P 0 
L 1.89291998 1.86973002 1.51641998 2.40746004 1 P 0 
L 1.51641998 2.40746004 1.45576004 2.75141004 1 P 0 
L 1.45576004 2.75141004 0.42845 4.21858002 1 P 0 
L 0.42845 4.21858002 0.40066998 4.23803002 1 P 0 
L 0.40066998 4.23803002 0.36273996 4.24471998 1 P 0 
L 0.36273996 4.24471998 0.33138996 4.24471998 1 P 0 
L 0.33138996 4.24471998 0.30286998 4.27323996 1 P 0 
L 0.30286998 4.27323996 0.30286998 4.29555 1 P 0 
L 0.30286998 4.29555 0.27165 4.32676998 1 P 0 
P 4.73268002 2.26615 5 P 0 0;2=3,4=1
P 0.27165 3.38188996 7 P 0 0;2=4,4=0
L 0.27165 3.38188996 0.30286998 3.35066998 1 P 0 
L 0.30286998 3.35066998 0.30286998 3.32836004 1 P 0 
L 0.30286998 3.32836004 0.33138996 3.29983996 1 P 0 
L 0.33138996 3.29983996 0.36273996 3.29983996 1 P 0 
L 0.36273996 3.29983996 0.38903002 3.2952 1 P 0 
L 0.38903002 3.2952 0.42525 3.26983002 1 P 0 
L 0.42525 3.26983002 0.64998002 2.9489 1 P 0 
L 0.64998002 2.9489 0.6873 2.73723002 1 P 0 
L 0.6873 2.73723002 0.95115 2.3604 1 P 0 
L 0.95115 2.3604 1.4705 1.99675 1 P 0 
L 1.4705 1.99675 1.95818996 1.30026998 1 P 0 
L 1.95818996 1.30026998 2.12156998 1.18586998 1 P 0 
L 2.12156998 1.18586998 2.24458996 1.16416998 1 P 0 
L 2.24458996 1.16416998 2.5726 1.22201004 1 P 0 
L 2.5726 1.22201004 3.19041998 1.33095 1 P 0 
L 3.19041998 1.33095 4.31883002 2.12101998 1 P 0 
L 4.31883002 2.12101998 4.5535 2.1624 1 P 0 
L 4.5535 2.1624 4.59676998 2.1624 1 P 0 
L 4.59676998 2.1624 4.62176998 2.1874 1 P 0 
L 4.62176998 2.1874 4.70313996 2.1874 1 P 0 
L 4.70313996 2.1874 4.71143002 2.19568996 1 P 0 
L 4.71143002 2.19568996 4.71143002 2.2837 1 P 0 
L 4.71143002 2.2837 4.71513002 2.2874 1 P 0 
L 4.71513002 2.2874 4.72898002 2.2874 1 P 0 
L 4.72898002 2.2874 4.73268002 2.2837 1 P 0 
L 4.73268002 2.2837 4.73268002 2.26615 1 P 0 
P 4.73268002 2.41615 5 P 0 0;2=3,4=1
P 0.27165 4.48425 7 P 0 0;2=4,4=0
L 4.73268002 2.41615 4.73268002 2.4337 1 P 0 
L 4.73268002 2.4337 4.72898002 2.4374 1 P 0 
L 4.72898002 2.4374 4.71201998 2.4374 1 P 0 
L 4.71201998 2.4374 4.70393002 2.44548996 1 P 0 
L 4.70393002 2.44548996 4.70393002 2.4837 1 P 0 
L 4.70393002 2.4837 4.70023002 2.4874 1 P 0 
L 4.70023002 2.4874 4.5574 2.4874 1 P 0 
L 4.5574 2.4874 4.29986004 2.442 1 P 0 
L 4.29986004 2.442 3.6867 2.01265 1 P 0 
L 3.6867 2.01265 2.3771 1.78171998 1 P 0 
L 2.3771 1.78171998 2.2401 1.80588002 1 P 0 
L 2.2401 1.80588002 2.14638996 1.78936004 1 P 0 
L 2.14638996 1.78936004 2.01961998 1.81171998 1 P 0 
L 2.01961998 1.81171998 1.97853996 1.84048002 1 P 0 
L 1.97853996 1.84048002 1.56473996 2.43145 1 P 0 
L 1.56473996 2.43145 1.49016004 2.85441998 1 P 0 
L 1.49016004 2.85441998 0.42831998 4.37088002 1 P 0 
L 0.42831998 4.37088002 0.40946004 4.38408996 1 P 0 
L 0.40946004 4.38408996 0.40945 4.38408996 1 P 0 
L 0.40945 4.38408996 0.39063002 4.39728002 1 P 0 
L 0.39063002 4.39728002 0.36273996 4.4022 1 P 0 
L 0.36273996 4.4022 0.33138996 4.4022 1 P 0 
L 0.33138996 4.4022 0.30286998 4.43071998 1 P 0 
L 0.30286998 4.43071998 0.30286998 4.45303002 1 P 0 
L 0.30286998 4.45303002 0.27165 4.48425 1 P 0 
P 4.68268002 2.21615 5 P 0 0;2=3,4=1
P 0.27165 3.53936998 7 P 0 0;2=4,4=0
L 0.27165 3.53936998 0.30286998 3.50815 1 P 0 
L 0.30286998 3.50815 0.30286998 3.48583996 1 P 0 
L 0.30286998 3.48583996 0.33138996 3.45731998 1 P 0 
L 0.33138996 3.45731998 0.36273996 3.45731998 1 P 0 
L 0.36273996 3.45731998 0.40658002 3.44958996 1 P 0 
L 0.40658002 3.44958996 0.48138002 3.39721004 1 P 0 
L 0.48138002 3.39721004 0.66165 3.13976998 1 P 0 
L 0.66165 3.13976998 0.72511998 2.77978002 1 P 0 
L 0.72511998 2.77978002 0.9989 2.38878002 1 P 0 
L 0.9989 2.38878002 1.48146004 2.05088996 1 P 0 
L 1.48146004 2.05088996 2.00046998 1.30966998 1 P 0 
L 2.00046998 1.30966998 2.13703002 1.21406004 1 P 0 
L 2.13703002 1.21406004 2.23806998 1.19623996 1 P 0 
L 2.23806998 1.19623996 3.17885 1.36213002 1 P 0 
L 3.17885 1.36213002 4.30498996 2.15065 1 P 0 
L 4.30498996 2.15065 4.51338996 2.1874 1 P 0 
L 4.51338996 2.1874 4.5946 2.1874 1 P 0 
L 4.5946 2.1874 4.61143002 2.20423002 1 P 0 
L 4.61143002 2.20423002 4.61143002 2.2337 1 P 0 
L 4.61143002 2.2337 4.61513002 2.2374 1 P 0 
L 4.61513002 2.2374 4.67898002 2.2374 1 P 0 
L 4.67898002 2.2374 4.68268002 2.2337 1 P 0 
L 4.68268002 2.2337 4.68268002 2.21615 1 P 0 
P 4.63268002 2.26615 5 P 0 0;2=3,4=1
P 0.27165 3.85433002 7 P 0 0;2=4,4=0
L 4.63268002 2.26615 4.63268002 2.2837 1 P 0 
L 4.63268002 2.2837 4.62898002 2.2874 1 P 0 
L 4.62898002 2.2874 4.5563 2.2874 1 P 0 
L 4.5563 2.2874 4.28953002 2.24036004 1 P 0 
L 4.28953002 2.24036004 3.13771998 1.43386998 1 P 0 
L 3.13771998 1.43386998 2.24383996 1.27626004 1 P 0 
L 2.24383996 1.27626004 2.15856004 1.2913 1 P 0 
L 2.15856004 1.2913 2.05601998 1.36308996 1 P 0 
L 2.05601998 1.36308996 1.35548002 2.36358996 1 P 0 
L 1.35548002 2.36358996 1.31231004 2.60841004 1 P 0 
L 1.31231004 2.60841004 0.58926004 3.64103002 1 P 0 
L 0.58926004 3.64103002 0.41496998 3.76306998 1 P 0 
L 0.41496998 3.76306998 0.36273996 3.77228002 1 P 0 
L 0.36273996 3.77228002 0.33138996 3.77228002 1 P 0 
L 0.33138996 3.77228002 0.30286998 3.8008 1 P 0 
L 0.30286998 3.8008 0.30286998 3.82311004 1 P 0 
L 0.30286998 3.82311004 0.27165 3.85433002 1 P 0 
P 4.58268002 2.06615 5 P 0 0;2=3,4=1
P 0.35038996 3.02756004 7 P 0 0;2=4,4=0
L 4.58268002 2.06615 4.58268002 2.0837 1 P 0 
L 4.58268002 2.0837 4.57898002 2.0874 1 P 0 
L 4.57898002 2.0874 4.5535 2.0874 1 P 0 
L 4.5535 2.0874 4.34793002 2.05115 1 P 0 
L 4.34793002 2.05115 3.22818996 1.26708996 1 P 0 
L 3.22818996 1.26708996 2.58678002 1.15398996 1 P 0 
L 2.58678002 1.15398996 2.2385 1.09258002 1 P 0 
L 2.2385 1.09258002 2.07691004 1.12108002 1 P 0 
L 2.07691004 1.12108002 1.86598996 1.26876004 1 P 0 
L 1.86598996 1.26876004 1.40593996 1.92576998 1 P 0 
L 1.40593996 1.92576998 0.86398002 2.30528002 1 P 0 
L 0.86398002 2.30528002 0.61048996 2.66731004 1 P 0 
L 0.61048996 2.66731004 0.58228996 2.82725 1 P 0 
L 0.58228996 2.82725 0.43996998 3.03046998 1 P 0 
L 0.43996998 3.03046998 0.40121004 3.05761004 1 P 0 
L 0.40121004 3.05761004 0.37223996 3.06271998 1 P 0 
L 0.37223996 3.06271998 0.3301 3.06271998 1 P 0 
L 0.3301 3.06271998 0.3078 3.04041998 1 P 0 
L 0.3078 3.04041998 0.3078 3.01611998 1 P 0 
L 0.3078 3.01611998 0.3136 3.01031998 1 P 0 
L 0.3136 3.01031998 0.33315 3.01031998 1 P 0 
L 0.33315 3.01031998 0.35038996 3.02756004 1 P 0 
P 4.58268002 2.11615 5 P 0 0;2=3,4=1
P 0.27165 2.98818996 7 P 0 0;2=4,4=0
L 4.58268002 2.11615 4.58268002 2.0986 1 P 0 
L 4.58268002 2.0986 4.57898002 2.0949 1 P 0 
L 4.57898002 2.0949 4.55283996 2.0949 1 P 0 
L 4.55283996 2.0949 4.34498996 2.05825 1 P 0 
L 4.34498996 2.05825 3.22525 1.27418996 1 P 0 
L 3.22525 1.27418996 2.58548002 1.16138002 1 P 0 
L 2.58548002 1.16138002 2.2385 1.1002 1 P 0 
L 2.2385 1.1002 2.07985 1.12818002 1 P 0 
L 2.07985 1.12818002 1.87138002 1.27415 1 P 0 
L 1.87138002 1.27415 1.41133002 1.93116004 1 P 0 
L 1.41133002 1.93116004 0.86936998 2.31066998 1 P 0 
L 0.86936998 2.31066998 0.61758996 2.67025 1 P 0 
L 0.61758996 2.67025 0.58938996 2.83018996 1 P 0 
L 0.58938996 2.83018996 0.44536004 3.03586004 1 P 0 
L 0.44536004 3.03586004 0.40415 3.06471004 1 P 0 
L 0.40415 3.06471004 0.3729 3.07021998 1 P 0 
L 0.3729 3.07021998 0.32698996 3.07021998 1 P 0 
L 0.32698996 3.07021998 0.3003 3.04353002 1 P 0 
L 0.3003 3.04353002 0.3003 3.01683996 1 P 0 
L 0.3003 3.01683996 0.27165 2.98818996 1 P 0 
P 4.63268002 1.86615 5 P 0 0;2=3,4=1
P 0.35038996 2.3189 7 P 0 0;2=4,4=0
L 0.35038996 2.3189 0.33315 2.30166004 1 P 0 
L 0.33315 2.30166004 0.3136 2.30166004 1 P 0 
L 0.3136 2.30166004 0.3078 2.30746004 1 P 0 
L 0.3078 2.30746004 0.3078 2.33176004 1 P 0 
L 0.3078 2.33176004 0.3301 2.35406004 1 P 0 
L 0.3301 2.35406004 0.36001998 2.35406004 1 P 0 
L 0.36001998 2.35406004 0.49073002 2.33101004 1 P 0 
L 0.49073002 2.33101004 1.23493002 1.80991004 1 P 0 
L 1.23493002 1.80991004 1.65778996 1.20596004 1 P 0 
L 1.65778996 1.20596004 1.98683002 0.97558996 1 P 0 
L 1.98683002 0.97558996 2.23935 0.93106998 1 P 0 
L 2.23935 0.93106998 3.27778996 1.11416998 1 P 0 
L 3.27778996 1.11416998 4.16143996 1.73291998 1 P 0 
L 4.16143996 1.73291998 4.55233996 1.80183002 1 P 0 
L 4.55233996 1.80183002 4.60313996 1.8374 1 P 0 
L 4.60313996 1.8374 4.61143002 1.84568996 1 P 0 
L 4.61143002 1.84568996 4.61143002 1.8837 1 P 0 
L 4.61143002 1.8837 4.61513002 1.8874 1 P 0 
L 4.61513002 1.8874 4.62898002 1.8874 1 P 0 
L 4.62898002 1.8874 4.63268002 1.8837 1 P 0 
L 4.63268002 1.8837 4.63268002 1.86615 1 P 0 
P 4.58268002 1.96615 5 P 0 0;2=3,4=1
P 0.27165 2.43701004 7 P 0 0;2=4,4=0
L 0.27165 2.43701004 0.3003 2.46566004 1 P 0 
L 0.3003 2.46566004 0.3003 2.49235 1 P 0 
L 0.3003 2.49235 0.32698996 2.51903996 1 P 0 
L 0.32698996 2.51903996 0.3729 2.51903996 1 P 0 
L 0.3729 2.51903996 0.4017 2.51396004 1 P 0 
L 0.4017 2.51396004 0.61046004 2.36778002 1 P 0 
L 0.61046004 2.36778002 0.68 2.26846998 1 P 0 
L 0.68 2.26846998 1.27641998 1.85086004 1 P 0 
L 1.27641998 1.85086004 1.70691004 1.23598002 1 P 0 
L 1.70691004 1.23598002 2.01871004 1.01766004 1 P 0 
L 2.01871004 1.01766004 2.23526004 0.97948002 1 P 0 
L 2.23526004 0.97948002 3.2497 1.15835 1 P 0 
L 3.2497 1.15835 4.31231004 1.9024 1 P 0 
L 4.31231004 1.9024 4.55331998 1.9449 1 P 0 
L 4.55331998 1.9449 4.57888002 1.9449 1 P 0 
L 4.57888002 1.9449 4.58268002 1.9487 1 P 0 
L 4.58268002 1.9487 4.58268002 1.96615 1 P 0 
P 4.68268002 2.06615 5 P 0 0;2=3,4=1
P 0.35038996 3.18503996 7 P 0 0;2=4,4=0
L 0.35038996 3.18503996 0.33315 3.1678 1 P 0 
L 0.33315 3.1678 0.3136 3.1678 1 P 0 
L 0.3136 3.1678 0.3078 3.1736 1 P 0 
L 0.3078 3.1736 0.3078 3.1979 1 P 0 
L 0.3078 3.1979 0.3301 3.2202 1 P 0 
L 0.3301 3.2202 0.37223996 3.2202 1 P 0 
L 0.37223996 3.2202 0.39093002 3.2169 1 P 0 
L 0.39093002 3.2169 0.41458002 3.20033002 1 P 0 
L 0.41458002 3.20033002 0.60971998 2.92168996 1 P 0 
L 0.60971998 2.92168996 0.64816998 2.70366004 1 P 0 
L 0.64816998 2.70366004 0.91106004 2.3282 1 P 0 
L 0.91106004 2.3282 1.44373996 1.95521998 1 P 0 
L 1.44373996 1.95521998 1.91511998 1.28198996 1 P 0 
L 1.91511998 1.28198996 2.09506998 1.156 1 P 0 
L 2.09506998 1.156 2.2409 1.13028002 1 P 0 
L 2.2409 1.13028002 3.2045 1.30018996 1 P 0 
L 3.2045 1.30018996 4.34258002 2.09706998 1 P 0 
L 4.34258002 2.09706998 4.57133002 2.1374 1 P 0 
L 4.57133002 2.1374 4.65023002 2.1374 1 P 0 
L 4.65023002 2.1374 4.65393002 2.1337 1 P 0 
L 4.65393002 2.1337 4.65393002 2.09548996 1 P 0 
L 4.65393002 2.09548996 4.66201998 2.0874 1 P 0 
L 4.66201998 2.0874 4.67898002 2.0874 1 P 0 
L 4.67898002 2.0874 4.68268002 2.0837 1 P 0 
L 4.68268002 2.0837 4.68268002 2.06615 1 P 0 
P 4.58268002 1.91615 5 P 0 0;2=3,4=1
P 0.35038996 2.47638002 7 P 0 0;2=4,4=0
L 4.58268002 1.91615 4.58268002 1.9337 1 P 0 
L 4.58268002 1.9337 4.57898002 1.9374 1 P 0 
L 4.57898002 1.9374 4.554 1.9374 1 P 0 
L 4.554 1.9374 4.31525 1.8953 1 P 0 
L 4.31525 1.8953 3.25263996 1.15125 1 P 0 
L 3.25263996 1.15125 2.23526004 0.97186004 1 P 0 
L 2.23526004 0.97186004 2.01576998 1.01056004 1 P 0 
L 2.01576998 1.01056004 1.70151998 1.23058996 1 P 0 
L 1.70151998 1.23058996 1.27103002 1.84546998 1 P 0 
L 1.27103002 1.84546998 0.67461004 2.26308002 1 P 0 
L 0.67461004 2.26308002 0.60506998 2.36238996 1 P 0 
L 0.60506998 2.36238996 0.39876004 2.50686004 1 P 0 
L 0.39876004 2.50686004 0.37223996 2.51153996 1 P 0 
L 0.37223996 2.51153996 0.3301 2.51153996 1 P 0 
L 0.3301 2.51153996 0.3078 2.48923996 1 P 0 
L 0.3078 2.48923996 0.3078 2.46493996 1 P 0 
L 0.3078 2.46493996 0.3136 2.45913996 1 P 0 
L 0.3136 2.45913996 0.33315 2.45913996 1 P 0 
L 0.33315 2.45913996 0.35038996 2.47638002 1 P 0 
P 0.27165 2.27953002 7 P 0 0;2=4,4=0
P 4.63268002 1.91615 5 P 0 0;2=3,4=1
L 0.27165 2.27953002 0.3003 2.30818002 1 P 0 
L 0.3003 2.30818002 0.3003 2.33486998 1 P 0 
L 0.3003 2.33486998 0.32698996 2.36156004 1 P 0 
L 0.32698996 2.36156004 0.36068002 2.36156004 1 P 0 
L 0.36068002 2.36156004 0.49366998 2.33811004 1 P 0 
L 0.49366998 2.33811004 1.24031998 1.8153 1 P 0 
L 1.24031998 1.8153 1.66318002 1.21135 1 P 0 
L 1.66318002 1.21135 1.98976998 0.98268996 1 P 0 
L 1.98976998 0.98268996 2.23935 0.93868996 1 P 0 
L 2.23935 0.93868996 3.27485 1.12126998 1 P 0 
L 3.27485 1.12126998 4.1585 1.74001998 1 P 0 
L 4.1585 1.74001998 4.5494 1.80893002 1 P 0 
L 4.5494 1.80893002 4.5983 1.84316998 1 P 0 
L 4.5983 1.84316998 4.60393002 1.8488 1 P 0 
L 4.60393002 1.8488 4.60393002 1.88681004 1 P 0 
L 4.60393002 1.88681004 4.61201998 1.8949 1 P 0 
L 4.61201998 1.8949 4.62898002 1.8949 1 P 0 
L 4.62898002 1.8949 4.63268002 1.8986 1 P 0 
L 4.63268002 1.8986 4.63268002 1.91615 1 P 0 
P 4.68268002 2.11615 5 P 0 0;2=3,4=1
P 0.27165 3.14566998 7 P 0 0;2=4,4=0
L 0.27165 3.14566998 0.3003 3.17431998 1 P 0 
L 0.3003 3.17431998 0.3003 3.20101004 1 P 0 
L 0.3003 3.20101004 0.32698996 3.2277 1 P 0 
L 0.32698996 3.2277 0.3729 3.2277 1 P 0 
L 0.3729 3.2277 0.39386998 3.224 1 P 0 
L 0.39386998 3.224 0.41996998 3.20571998 1 P 0 
L 0.41996998 3.20571998 0.61681998 2.92463002 1 P 0 
L 0.61681998 2.92463002 0.65526998 2.7066 1 P 0 
L 0.65526998 2.7066 0.91645 2.33358996 1 P 0 
L 0.91645 2.33358996 1.44913002 1.96061004 1 P 0 
L 1.44913002 1.96061004 1.92051004 1.28738002 1 P 0 
L 1.92051004 1.28738002 2.09801004 1.1631 1 P 0 
L 2.09801004 1.1631 2.2409 1.1379 1 P 0 
L 2.2409 1.1379 3.20156004 1.30728996 1 P 0 
L 3.20156004 1.30728996 4.33963996 2.10416998 1 P 0 
L 4.33963996 2.10416998 4.57066998 2.1449 1 P 0 
L 4.57066998 2.1449 4.65333996 2.1449 1 P 0 
L 4.65333996 2.1449 4.66143002 2.13681004 1 P 0 
L 4.66143002 2.13681004 4.66143002 2.0986 1 P 0 
L 4.66143002 2.0986 4.66513002 2.0949 1 P 0 
L 4.66513002 2.0949 4.67898002 2.0949 1 P 0 
L 4.67898002 2.0949 4.68268002 2.0986 1 P 0 
L 4.68268002 2.0986 4.68268002 2.11615 1 P 0 
P 4.68268002 1.91615 5 P 0 0;2=3,4=1
P 0.35038996 2.16141998 7 P 0 0;2=4,4=0
L 4.68268002 1.91615 4.68268002 1.9337 1 P 0 
L 4.68268002 1.9337 4.67898002 1.9374 1 P 0 
L 4.67898002 1.9374 4.66513002 1.9374 1 P 0 
L 4.66513002 1.9374 4.66143002 1.9337 1 P 0 
L 4.66143002 1.9337 4.66143002 1.85573996 1 P 0 
L 4.66143002 1.85573996 4.65761998 1.83408996 1 P 0 
L 4.65761998 1.83408996 4.64176998 1.81145 1 P 0 
L 4.64176998 1.81145 4.57656004 1.7658 1 P 0 
L 4.57656004 1.7658 4.17806004 1.69551004 1 P 0 
L 4.17806004 1.69551004 3.29316004 1.07588002 1 P 0 
L 3.29316004 1.07588002 2.2381 0.88983996 1 P 0 
L 2.2381 0.88983996 1.97338002 0.93651004 1 P 0 
L 1.97338002 0.93651004 1.58516004 1.20835 1 P 0 
L 1.58516004 1.20835 1.17193996 1.79851004 1 P 0 
L 1.17193996 1.79851004 0.67488002 2.14653996 1 P 0 
L 0.67488002 2.14653996 0.39113002 2.19658002 1 P 0 
L 0.39113002 2.19658002 0.3301 2.19658002 1 P 0 
L 0.3301 2.19658002 0.3078 2.17428002 1 P 0 
L 0.3078 2.17428002 0.3078 2.14998002 1 P 0 
L 0.3078 2.14998002 0.3136 2.14418002 1 P 0 
L 0.3136 2.14418002 0.33315 2.14418002 1 P 0 
L 0.33315 2.14418002 0.35038996 2.16141998 1 P 0 
P 4.68268002 1.96615 5 P 0 0;2=3,4=1
P 0.27165 2.12205 7 P 0 0;2=4,4=0
L 4.68268002 1.96615 4.68268002 1.9486 1 P 0 
L 4.68268002 1.9486 4.67898002 1.9449 1 P 0 
L 4.67898002 1.9449 4.66201998 1.9449 1 P 0 
L 4.66201998 1.9449 4.65393002 1.93681004 1 P 0 
L 4.65393002 1.93681004 4.65393002 1.8564 1 P 0 
L 4.65393002 1.8564 4.65051998 1.83703002 1 P 0 
L 4.65051998 1.83703002 4.63638002 1.81683996 1 P 0 
L 4.63638002 1.81683996 4.57361998 1.7729 1 P 0 
L 4.57361998 1.7729 4.17511998 1.70261004 1 P 0 
L 4.17511998 1.70261004 3.29021998 1.08298002 1 P 0 
L 3.29021998 1.08298002 2.2381 0.89746004 1 P 0 
L 2.2381 0.89746004 1.97631998 0.94361004 1 P 0 
L 1.97631998 0.94361004 1.59055 1.21373996 1 P 0 
L 1.59055 1.21373996 1.17733002 1.8039 1 P 0 
L 1.17733002 1.8039 0.67781998 2.15363996 1 P 0 
L 0.67781998 2.15363996 0.39178996 2.20408002 1 P 0 
L 0.39178996 2.20408002 0.32698996 2.20408002 1 P 0 
L 0.32698996 2.20408002 0.3003 2.17738996 1 P 0 
L 0.3003 2.17738996 0.3003 2.1507 1 P 0 
L 0.3003 2.1507 0.27165 2.12205 1 P 0 
L 4.68268002 2.41615 4.68268002 2.3986 1 P 0 
L 4.68268002 2.3986 4.67898002 2.3949 1 P 0 
L 4.67898002 2.3949 4.66201998 2.3949 1 P 0 
L 4.66201998 2.3949 4.65393002 2.38681004 1 P 0 
L 4.65393002 2.38681004 4.65393002 2.3488 1 P 0 
L 4.65393002 2.3488 4.65003002 2.3449 1 P 0 
L 4.65003002 2.3449 4.52421998 2.3449 1 P 0 
L 4.52421998 2.3449 4.29698002 2.30483996 1 P 0 
L 4.29698002 2.30483996 3.77818996 1.94156998 1 P 0 
L 3.77818996 1.94156998 3.54626998 1.90068002 1 P 0 
L 3.54626998 1.90068002 2.42483996 1.70293002 1 P 0 
L 2.42483996 1.70293002 2.23846004 1.73578996 1 P 0 
L 2.23846004 1.73578996 2.15061004 1.7203 1 P 0 
L 2.15061004 1.7203 1.96776004 1.75253002 1 P 0 
L 1.96776004 1.75253002 1.83161998 1.84786998 1 P 0 
L 1.83161998 1.84786998 1.40698002 2.4543 1 P 0 
L 1.40698002 2.4543 1.37521004 2.63446004 1 P 0 
L 1.37521004 2.63446004 0.5327 3.83768996 1 P 0 
L 0.5327 3.83768996 0.39961998 3.93086998 1 P 0 
L 0.39961998 3.93086998 0.3634 3.93726004 1 P 0 
L 0.3634 3.93726004 0.3345 3.93726004 1 P 0 
L 0.3345 3.93726004 0.31036998 3.96138996 1 P 0 
L 0.31036998 3.96138996 0.31036998 3.98706004 1 P 0 
L 0.31036998 3.98706004 0.31506998 3.99176004 1 P 0 
L 0.31506998 3.99176004 0.33106998 3.99176004 1 P 0 
L 0.33106998 3.99176004 0.35038996 3.97243996 1 P 0 
P 0.35038996 3.97243996 7 P 0 0;2=4,4=0
P 4.68268002 2.41615 5 P 0 0;2=3,4=1
P 4.73268002 2.46615 5 P 0 0;2=3,4=1
P 0.35038996 4.44488002 7 P 0 0;2=4,4=0
L 4.73268002 2.46615 4.73268002 2.4486 1 P 0 
L 4.73268002 2.4486 4.72898002 2.4449 1 P 0 
L 4.72898002 2.4449 4.71513002 2.4449 1 P 0 
L 4.71513002 2.4449 4.71143002 2.4486 1 P 0 
L 4.71143002 2.4486 4.71143002 2.48681004 1 P 0 
L 4.71143002 2.48681004 4.70333996 2.4949 1 P 0 
L 4.70333996 2.4949 4.55673996 2.4949 1 P 0 
L 4.55673996 2.4949 4.29691998 2.4491 1 P 0 
L 4.29691998 2.4491 3.68376004 2.01975 1 P 0 
L 3.68376004 2.01975 2.3771 1.78933996 1 P 0 
L 2.3771 1.78933996 2.2401 1.8135 1 P 0 
L 2.2401 1.8135 2.14638996 1.79698002 1 P 0 
L 2.14638996 1.79698002 2.02256004 1.81881998 1 P 0 
L 2.02256004 1.81881998 1.98393002 1.84586998 1 P 0 
L 1.98393002 1.84586998 1.57183996 2.43438996 1 P 0 
L 1.57183996 2.43438996 1.49726004 2.85736004 1 P 0 
L 1.49726004 2.85736004 0.43371004 4.37626998 1 P 0 
L 0.43371004 4.37626998 0.39356998 4.40438002 1 P 0 
L 0.39356998 4.40438002 0.3634 4.4097 1 P 0 
L 0.3634 4.4097 0.3345 4.4097 1 P 0 
L 0.3345 4.4097 0.31036998 4.43383002 1 P 0 
L 0.31036998 4.43383002 0.31036998 4.4595 1 P 0 
L 0.31036998 4.4595 0.31506998 4.4642 1 P 0 
L 0.31506998 4.4642 0.33106998 4.4642 1 P 0 
L 0.33106998 4.4642 0.35038996 4.44488002 1 P 0 
P 4.63268002 2.46615 5 P 0 0;2=3,4=1
P 0.35038996 4.2874 7 P 0 0;2=4,4=0
L 4.63268002 2.46615 4.63268002 2.4486 1 P 0 
L 4.63268002 2.4486 4.62898002 2.4449 1 P 0 
L 4.62898002 2.4449 4.54703002 2.4449 1 P 0 
L 4.54703002 2.4449 4.29493996 2.40045 1 P 0 
L 4.29493996 2.40045 3.71466998 1.99413996 1 P 0 
L 3.71466998 1.99413996 3.53618002 1.96266998 1 P 0 
L 3.53618002 1.96266998 2.39186998 1.76093002 1 P 0 
L 2.39186998 1.76093002 2.24101998 1.78751998 1 P 0 
L 2.24101998 1.78751998 2.14846998 1.7712 1 P 0 
L 2.14846998 1.7712 2.01248996 1.79518002 1 P 0 
L 2.01248996 1.79518002 1.89831004 1.87511998 1 P 0 
L 1.89831004 1.87511998 1.52351998 2.4104 1 P 0 
L 1.52351998 2.4104 1.46286004 2.75435 1 P 0 
L 1.46286004 2.75435 0.43383996 4.22396998 1 P 0 
L 0.43383996 4.22396998 0.40361004 4.24513002 1 P 0 
L 0.40361004 4.24513002 0.3634 4.25221998 1 P 0 
L 0.3634 4.25221998 0.3345 4.25221998 1 P 0 
L 0.3345 4.25221998 0.31036998 4.27635 1 P 0 
L 0.31036998 4.27635 0.31036998 4.30201998 1 P 0 
L 0.31036998 4.30201998 0.31506998 4.30671998 1 P 0 
L 0.31506998 4.30671998 0.33106998 4.30671998 1 P 0 
L 0.33106998 4.30671998 0.35038996 4.2874 1 P 0 
L 4.58268002 2.41615 4.58268002 2.3986 1 P 0 
L 4.58268002 2.3986 4.57898002 2.3949 1 P 0 
L 4.57898002 2.3949 4.5205 2.3949 1 P 0 
L 4.5205 2.3949 4.29718002 2.35551998 1 P 0 
L 4.29718002 2.35551998 3.74513002 1.96898002 1 P 0 
L 3.74513002 1.96898002 3.54138996 1.93306004 1 P 0 
L 3.54138996 1.93306004 2.40423002 1.73258002 1 P 0 
L 2.40423002 1.73258002 2.24068002 1.76141004 1 P 0 
L 2.24068002 1.76141004 2.1495 1.74533002 1 P 0 
L 2.1495 1.74533002 1.9988 1.7719 1 P 0 
L 1.9988 1.7719 1.86531004 1.86536004 1 P 0 
L 1.86531004 1.86536004 1.46496004 2.43711998 1 P 0 
L 1.46496004 2.43711998 1.42131998 2.68465 1 P 0 
L 1.42131998 2.68465 0.4613 4.0557 1 P 0 
L 0.4613 4.0557 0.41971998 4.08481004 1 P 0 
L 0.41971998 4.08481004 0.3634 4.09473996 1 P 0 
L 0.3634 4.09473996 0.3345 4.09473996 1 P 0 
L 0.3345 4.09473996 0.31036998 4.11886998 1 P 0 
L 0.31036998 4.11886998 0.31036998 4.14453996 1 P 0 
L 0.31036998 4.14453996 0.31506998 4.14923996 1 P 0 
L 0.31506998 4.14923996 0.33106998 4.14923996 1 P 0 
L 0.33106998 4.14923996 0.35038996 4.12991998 1 P 0 
P 0.35038996 4.12991998 7 P 0 0;2=4,4=0
P 4.58268002 2.41615 5 P 0 0;2=3,4=1
P 4.68268002 2.26615 5 P 0 0;2=3,4=1
P 0.35038996 3.5 7 P 0 0;2=4,4=0
L 0.35038996 3.5 0.33106998 3.51931998 1 P 0 
L 0.33106998 3.51931998 0.31506998 3.51931998 1 P 0 
L 0.31506998 3.51931998 0.31036998 3.51461998 1 P 0 
L 0.31036998 3.51461998 0.31036998 3.48895 1 P 0 
L 0.31036998 3.48895 0.3345 3.46481998 1 P 0 
L 0.3345 3.46481998 0.3634 3.46481998 1 P 0 
L 0.3634 3.46481998 0.40951998 3.45668996 1 P 0 
L 0.40951998 3.45668996 0.48676998 3.4026 1 P 0 
L 0.48676998 3.4026 0.66875 3.14271004 1 P 0 
L 0.66875 3.14271004 0.73221998 2.78271998 1 P 0 
L 0.73221998 2.78271998 1.00428996 2.39416998 1 P 0 
L 1.00428996 2.39416998 1.48685 2.05628002 1 P 0 
L 1.48685 2.05628002 2.00586004 1.31506004 1 P 0 
L 2.00586004 1.31506004 2.13996998 1.22116004 1 P 0 
L 2.13996998 1.22116004 2.23806998 1.20386004 1 P 0 
L 2.23806998 1.20386004 3.17591004 1.36923002 1 P 0 
L 3.17591004 1.36923002 4.30205 2.15775 1 P 0 
L 4.30205 2.15775 4.51273002 2.1949 1 P 0 
L 4.51273002 2.1949 4.59148996 2.1949 1 P 0 
L 4.59148996 2.1949 4.60393002 2.20733996 1 P 0 
L 4.60393002 2.20733996 4.60393002 2.23681004 1 P 0 
L 4.60393002 2.23681004 4.61201998 2.2449 1 P 0 
L 4.61201998 2.2449 4.67898002 2.2449 1 P 0 
L 4.67898002 2.2449 4.68268002 2.2486 1 P 0 
L 4.68268002 2.2486 4.68268002 2.26615 1 P 0 
P 4.73268002 2.31615 5 P 0 0;2=3,4=1
P 0.35038996 3.34251998 7 P 0 0;2=4,4=0
L 0.35038996 3.34251998 0.33106998 3.36183996 1 P 0 
L 0.33106998 3.36183996 0.31506998 3.36183996 1 P 0 
L 0.31506998 3.36183996 0.31036998 3.35713996 1 P 0 
L 0.31036998 3.35713996 0.31036998 3.33146998 1 P 0 
L 0.31036998 3.33146998 0.3345 3.30733996 1 P 0 
L 0.3345 3.30733996 0.3634 3.30733996 1 P 0 
L 0.3634 3.30733996 0.39196998 3.3023 1 P 0 
L 0.39196998 3.3023 0.43063996 3.27521998 1 P 0 
L 0.43063996 3.27521998 0.65708002 2.95183996 1 P 0 
L 0.65708002 2.95183996 0.6944 2.74016998 1 P 0 
L 0.6944 2.74016998 0.95653996 2.36578996 1 P 0 
L 0.95653996 2.36578996 1.47588996 2.00213996 1 P 0 
L 1.47588996 2.00213996 1.96358002 1.30566004 1 P 0 
L 1.96358002 1.30566004 2.12451004 1.19296998 1 P 0 
L 2.12451004 1.19296998 2.24458996 1.17178996 1 P 0 
L 2.24458996 1.17178996 2.5713 1.2294 1 P 0 
L 2.5713 1.2294 3.18748002 1.33805 1 P 0 
L 3.18748002 1.33805 4.31588996 2.12811998 1 P 0 
L 4.31588996 2.12811998 4.55283996 2.1699 1 P 0 
L 4.55283996 2.1699 4.59366004 2.1699 1 P 0 
L 4.59366004 2.1699 4.61866004 2.1949 1 P 0 
L 4.61866004 2.1949 4.70003002 2.1949 1 P 0 
L 4.70003002 2.1949 4.70393002 2.1988 1 P 0 
L 4.70393002 2.1988 4.70393002 2.28681004 1 P 0 
L 4.70393002 2.28681004 4.71201998 2.2949 1 P 0 
L 4.71201998 2.2949 4.72898002 2.2949 1 P 0 
L 4.72898002 2.2949 4.73268002 2.2986 1 P 0 
L 4.73268002 2.2986 4.73268002 2.31615 1 P 0 
P 4.63268002 2.31615 5 P 0 0;2=3,4=1
P 0.35038996 3.81496004 7 P 0 0;2=4,4=0
L 4.63268002 2.31615 4.63268002 2.2986 1 P 0 
L 4.63268002 2.2986 4.62898002 2.2949 1 P 0 
L 4.62898002 2.2949 4.55563996 2.2949 1 P 0 
L 4.55563996 2.2949 4.28658996 2.24746004 1 P 0 
L 4.28658996 2.24746004 3.13478002 1.44096998 1 P 0 
L 3.13478002 1.44096998 2.24383996 1.28388002 1 P 0 
L 2.24383996 1.28388002 2.1615 1.2984 1 P 0 
L 2.1615 1.2984 2.06141004 1.36848002 1 P 0 
L 2.06141004 1.36848002 1.36258002 2.36653002 1 P 0 
L 1.36258002 2.36653002 1.31941004 2.61135 1 P 0 
L 1.31941004 2.61135 0.59465 3.64641998 1 P 0 
L 0.59465 3.64641998 0.41791004 3.77016998 1 P 0 
L 0.41791004 3.77016998 0.3634 3.77978002 1 P 0 
L 0.3634 3.77978002 0.3345 3.77978002 1 P 0 
L 0.3345 3.77978002 0.31036998 3.80391004 1 P 0 
L 0.31036998 3.80391004 0.31036998 3.82958002 1 P 0 
L 0.31036998 3.82958002 0.31506998 3.83428002 1 P 0 
L 0.31506998 3.83428002 0.33106998 3.83428002 1 P 0 
L 0.33106998 3.83428002 0.35038996 3.81496004 1 P 0 
P 4.58268002 2.26615 5 P 0 0;2=3,4=1
P 0.35038996 3.65748002 7 P 0 0;2=4,4=0
L 0.35038996 3.65748002 0.33106998 3.6768 1 P 0 
L 0.33106998 3.6768 0.31506998 3.6768 1 P 0 
L 0.31506998 3.6768 0.31036998 3.6721 1 P 0 
L 0.31036998 3.6721 0.31036998 3.64643002 1 P 0 
L 0.31036998 3.64643002 0.3345 3.6223 1 P 0 
L 0.3345 3.6223 0.3634 3.6223 1 P 0 
L 0.3634 3.6223 0.40311004 3.6153 1 P 0 
L 0.40311004 3.6153 0.69003002 3.41438996 1 P 0 
L 0.69003002 3.41438996 1.25975 2.60076004 1 P 0 
L 1.25975 2.60076004 1.29626004 2.39368996 1 P 0 
L 1.29626004 2.39368996 2.03348996 1.34081998 1 P 0 
L 2.03348996 1.34081998 2.15141998 1.25823002 1 P 0 
L 2.15141998 1.25823002 2.24401998 1.2419 1 P 0 
L 2.24401998 1.2419 3.14873002 1.40143002 1 P 0 
L 3.14873002 1.40143002 4.28596998 2.19771998 1 P 0 
L 4.28596998 2.19771998 4.55353996 2.2449 1 P 0 
L 4.55353996 2.2449 4.57898002 2.2449 1 P 0 
L 4.57898002 2.2449 4.58268002 2.2486 1 P 0 
L 4.58268002 2.2486 4.58268002 2.26615 1 P 0 
P 0.35038996 1.9252 7 P 0 0;2=4,4=0
L 4.73268002 1.91615 4.73268002 1.8986 1 P 0 
L 4.73268002 1.8986 4.72898002 1.8949 1 P 0 
L 4.72898002 1.8949 4.71201998 1.8949 1 P 0 
L 4.71201998 1.8949 4.70393002 1.88681004 1 P 0 
L 4.70393002 1.88681004 4.70393002 1.85608996 1 P 0 
L 4.70393002 1.85608996 4.70145 1.8419 1 P 0 
L 4.70145 1.8419 4.6613 1.78458002 1 P 0 
L 4.6613 1.78458002 4.58508996 1.73121004 1 P 0 
L 4.58508996 1.73121004 4.18805 1.66121004 1 P 0 
L 4.18805 1.66121004 3.31083002 1.04696998 1 P 0 
L 3.31083002 1.04696998 2.2381 0.85781998 1 P 0 
L 2.2381 0.85781998 1.96101998 0.90666998 1 P 0 
L 1.96101998 0.90666998 1.52741004 1.21028002 1 P 0 
L 1.52741004 1.21028002 1.16146998 1.7329 1 P 0 
L 1.16146998 1.7329 0.88013002 1.9299 1 P 0 
L 0.88013002 1.9299 0.6786 1.96543996 1 P 0 
L 0.6786 1.96543996 0.49121998 1.9324 1 P 0 
L 0.49121998 1.9324 0.45335 1.90588002 1 P 0 
L 0.45335 1.90588002 0.3634 1.89001998 1 P 0 
L 0.3634 1.89001998 0.3345 1.89001998 1 P 0 
L 0.3345 1.89001998 0.31036998 1.91415 1 P 0 
L 0.31036998 1.91415 0.31036998 1.93981998 1 P 0 
L 0.31036998 1.93981998 0.31506998 1.94451998 1 P 0 
L 0.31506998 1.94451998 0.33106998 1.94451998 1 P 0 
L 0.33106998 1.94451998 0.35038996 1.9252 1 P 0 
P 4.73268002 1.91615 5 P 0 0;2=3,4=1
P 4.73268002 1.86615 5 P 0 0;2=3,4=1
P 0.27165 1.96456998 7 P 0 0;2=4,4=0
L 4.73268002 1.86615 4.73268002 1.8837 1 P 0 
L 4.73268002 1.8837 4.72898002 1.8874 1 P 0 
L 4.72898002 1.8874 4.71513002 1.8874 1 P 0 
L 4.71513002 1.8874 4.71143002 1.8837 1 P 0 
L 4.71143002 1.8837 4.71143002 1.85543002 1 P 0 
L 4.71143002 1.85543002 4.70855 1.83896004 1 P 0 
L 4.70855 1.83896004 4.66668996 1.77918996 1 P 0 
L 4.66668996 1.77918996 4.58803002 1.72411004 1 P 0 
L 4.58803002 1.72411004 4.19098996 1.65411004 1 P 0 
L 4.19098996 1.65411004 3.31376998 1.03986998 1 P 0 
L 3.31376998 1.03986998 2.2381 0.8502 1 P 0 
L 2.2381 0.8502 1.95808002 0.89956998 1 P 0 
L 1.95808002 0.89956998 1.52201998 1.20488996 1 P 0 
L 1.52201998 1.20488996 1.15608002 1.72751004 1 P 0 
L 1.15608002 1.72751004 0.87718996 1.9228 1 P 0 
L 0.87718996 1.9228 0.6786 1.95781998 1 P 0 
L 0.6786 1.95781998 0.49416004 1.9253 1 P 0 
L 0.49416004 1.9253 0.45628996 1.89878002 1 P 0 
L 0.45628996 1.89878002 0.36406004 1.88251998 1 P 0 
L 0.36406004 1.88251998 0.33138996 1.88251998 1 P 0 
L 0.33138996 1.88251998 0.30286998 1.91103996 1 P 0 
L 0.30286998 1.91103996 0.30286998 1.93335 1 P 0 
L 0.30286998 1.93335 0.27165 1.96456998 1 P 0 
P 4.58268002 2.21615 5 P 0 0;2=3,4=1
P 0.27165 3.69685 7 P 0 0;2=4,4=0
L 0.27165 3.69685 0.30286998 3.66563002 1 P 0 
L 0.30286998 3.66563002 0.30286998 3.64331998 1 P 0 
L 0.30286998 3.64331998 0.33138996 3.6148 1 P 0 
L 0.33138996 3.6148 0.36273996 3.6148 1 P 0 
L 0.36273996 3.6148 0.40016998 3.6082 1 P 0 
L 0.40016998 3.6082 0.68463996 3.409 1 P 0 
L 0.68463996 3.409 1.25265 2.59781998 1 P 0 
L 1.25265 2.59781998 1.28916004 2.39075 1 P 0 
L 1.28916004 2.39075 2.0281 1.33543002 1 P 0 
L 2.0281 1.33543002 2.14848002 1.25113002 1 P 0 
L 2.14848002 1.25113002 2.24401998 1.23428002 1 P 0 
L 2.24401998 1.23428002 3.15166998 1.39433002 1 P 0 
L 3.15166998 1.39433002 4.28891004 2.19061998 1 P 0 
L 4.28891004 2.19061998 4.5542 2.2374 1 P 0 
L 4.5542 2.2374 4.57898002 2.2374 1 P 0 
L 4.57898002 2.2374 4.58268002 2.2337 1 P 0 
L 4.58268002 2.2337 4.58268002 2.21615 1 P 0 
P 4.73268002 2.06615 5 P 0 0;2=3,4=1
P 0.27165 2.67323002 7 P 0 0;2=4,4=0
L 4.73268002 2.06615 4.73268002 2.0486 1 P 0 
L 4.73268002 2.0486 4.72898002 2.0449 1 P 0 
L 4.72898002 2.0449 4.66201998 2.0449 1 P 0 
L 4.66201998 2.0449 4.65393002 2.03681004 1 P 0 
L 4.65393002 2.03681004 4.65393002 1.9988 1 P 0 
L 4.65393002 1.9988 4.65003002 1.9949 1 P 0 
L 4.65003002 1.9949 4.5564 1.9949 1 P 0 
L 4.5564 1.9949 4.32105 1.9534 1 P 0 
L 4.32105 1.9534 3.23673996 1.19416998 1 P 0 
L 3.23673996 1.19416998 2.59453996 1.08093002 1 P 0 
L 2.59453996 1.08093002 2.2297 1.0166 1 P 0 
L 2.2297 1.0166 2.05101004 1.04811004 1 P 0 
L 2.05101004 1.04811004 1.76211998 1.25038996 1 P 0 
L 1.76211998 1.25038996 1.32701998 1.87181998 1 P 0 
L 1.32701998 1.87181998 0.80041004 2.24056004 1 P 0 
L 0.80041004 2.24056004 0.48978002 2.6842 1 P 0 
L 0.48978002 2.6842 0.3935 2.75163002 1 P 0 
L 0.3935 2.75163002 0.3729 2.75526004 1 P 0 
L 0.3729 2.75526004 0.32698996 2.75526004 1 P 0 
L 0.32698996 2.75526004 0.3003 2.72856998 1 P 0 
L 0.3003 2.72856998 0.3003 2.70188002 1 P 0 
L 0.3003 2.70188002 0.27165 2.67323002 1 P 0 
P 4.73268002 2.01615 5 P 0 0;2=3,4=1
P 0.35038996 2.7126 7 P 0 0;2=4,4=0
L 4.73268002 2.01615 4.73268002 2.0337 1 P 0 
L 4.73268002 2.0337 4.72898002 2.0374 1 P 0 
L 4.72898002 2.0374 4.66513002 2.0374 1 P 0 
L 4.66513002 2.0374 4.66143002 2.0337 1 P 0 
L 4.66143002 2.0337 4.66143002 1.99568996 1 P 0 
L 4.66143002 1.99568996 4.65313996 1.9874 1 P 0 
L 4.65313996 1.9874 4.55706004 1.9874 1 P 0 
L 4.55706004 1.9874 4.32398996 1.9463 1 P 0 
L 4.32398996 1.9463 3.23968002 1.18706998 1 P 0 
L 3.23968002 1.18706998 2.59583996 1.07353996 1 P 0 
L 2.59583996 1.07353996 2.2297 1.00898002 1 P 0 
L 2.2297 1.00898002 2.04806998 1.04101004 1 P 0 
L 2.04806998 1.04101004 1.75673002 1.245 1 P 0 
L 1.75673002 1.245 1.32163002 1.86643002 1 P 0 
L 1.32163002 1.86643002 0.79501998 2.23516998 1 P 0 
L 0.79501998 2.23516998 0.48438996 2.67881004 1 P 0 
L 0.48438996 2.67881004 0.39056004 2.74453002 1 P 0 
L 0.39056004 2.74453002 0.37223996 2.74776004 1 P 0 
L 0.37223996 2.74776004 0.3301 2.74776004 1 P 0 
L 0.3301 2.74776004 0.3078 2.72546004 1 P 0 
L 0.3078 2.72546004 0.3078 2.70116004 1 P 0 
L 0.3078 2.70116004 0.3136 2.69536004 1 P 0 
L 0.3136 2.69536004 0.33315 2.69536004 1 P 0 
L 0.33315 2.69536004 0.35038996 2.7126 1 P 0 
P 4.63268002 2.01615 5 P 0 0;2=3,4=1
P 0.35038996 2.87008002 7 P 0 0;2=4,4=0
L 4.63268002 2.01615 4.63268002 2.0337 1 P 0 
L 4.63268002 2.0337 4.62898002 2.0374 1 P 0 
L 4.62898002 2.0374 4.5526 2.0374 1 P 0 
L 4.5526 2.0374 4.33493002 1.99901998 1 P 0 
L 4.33493002 1.99901998 3.23138002 1.22633996 1 P 0 
L 3.23138002 1.22633996 2.59083996 1.1134 1 P 0 
L 2.59083996 1.1134 2.2357 1.05078002 1 P 0 
L 2.2357 1.05078002 2.06821004 1.08031998 1 P 0 
L 2.06821004 1.08031998 1.80876004 1.26195 1 P 0 
L 1.80876004 1.26195 1.37216998 1.88551004 1 P 0 
L 1.37216998 1.88551004 0.8364 2.26066998 1 P 0 
L 0.8364 2.26066998 0.56793996 2.64408002 1 P 0 
L 0.56793996 2.64408002 0.54511998 2.77346998 1 P 0 
L 0.54511998 2.77346998 0.49328996 2.84746998 1 P 0 
L 0.49328996 2.84746998 0.42376998 2.89615 1 P 0 
L 0.42376998 2.89615 0.37223996 2.90523996 1 P 0 
L 0.37223996 2.90523996 0.3301 2.90523996 1 P 0 
L 0.3301 2.90523996 0.3078 2.88293996 1 P 0 
L 0.3078 2.88293996 0.3078 2.85863996 1 P 0 
L 0.3078 2.85863996 0.3136 2.85283996 1 P 0 
L 0.3136 2.85283996 0.33315 2.85283996 1 P 0 
L 0.33315 2.85283996 0.35038996 2.87008002 1 P 0 
P 4.63268002 2.06615 5 P 0 0;2=3,4=1
P 0.27165 2.83071004 7 P 0 0;2=4,4=0
L 4.63268002 2.06615 4.63268002 2.0486 1 P 0 
L 4.63268002 2.0486 4.62898002 2.0449 1 P 0 
L 4.62898002 2.0449 4.55193996 2.0449 1 P 0 
L 4.55193996 2.0449 4.33198996 2.00611998 1 P 0 
L 4.33198996 2.00611998 3.22843996 1.23343996 1 P 0 
L 3.22843996 1.23343996 2.58953996 1.12078996 1 P 0 
L 2.58953996 1.12078996 2.2357 1.0584 1 P 0 
L 2.2357 1.0584 2.07115 1.08741998 1 P 0 
L 2.07115 1.08741998 1.81415 1.26733996 1 P 0 
L 1.81415 1.26733996 1.37756004 1.8909 1 P 0 
L 1.37756004 1.8909 0.84178996 2.26606004 1 P 0 
L 0.84178996 2.26606004 0.57503996 2.64701998 1 P 0 
L 0.57503996 2.64701998 0.55221998 2.77641004 1 P 0 
L 0.55221998 2.77641004 0.49868002 2.85286004 1 P 0 
L 0.49868002 2.85286004 0.42671004 2.90325 1 P 0 
L 0.42671004 2.90325 0.3729 2.91273996 1 P 0 
L 0.3729 2.91273996 0.32698996 2.91273996 1 P 0 
L 0.32698996 2.91273996 0.3003 2.88605 1 P 0 
L 0.3003 2.88605 0.3003 2.85936004 1 P 0 
L 0.3003 2.85936004 0.27165 2.83071004 1 P 0 
P 1.025 -0.25 7 P 0 0;2=0,4=0
L 3.05 -0.375 3.05 -0.4155 2 P 0 
L 3.05 -0.4155 3.0455 -0.42 2 P 0 
L 3.0455 -0.42 2.9981 -0.42 2 P 0 
L 2.9981 -0.42 2.9936 -0.4155 2 P 0 
L 2.9936 -0.4155 2.9936 -0.1945 2 P 0 
L 2.9936 -0.1945 2.9891 -0.19 2 P 0 
L 2.9891 -0.19 2.9386 -0.19 2 P 0 
L 2.9386 -0.19 2.9341 -0.1945 2 P 0 
L 2.9341 -0.1945 2.9341 -0.4155 2 P 0 
L 2.9341 -0.4155 2.9296 -0.42 2 P 0 
L 2.9296 -0.42 2.8791 -0.42 2 P 0 
L 2.8791 -0.42 2.8746 -0.4155 2 P 0 
L 2.8746 -0.4155 2.8746 -0.1945 2 P 0 
L 2.8746 -0.1945 2.8701 -0.19 2 P 0 
L 2.8701 -0.19 2.8196 -0.19 2 P 0 
L 2.8196 -0.19 2.8151 -0.1945 2 P 0 
L 2.8151 -0.1945 2.8151 -0.4155 2 P 0 
L 2.8151 -0.4155 2.8106 -0.42 2 P 0 
L 2.8106 -0.42 2.7601 -0.42 2 P 0 
L 2.7601 -0.42 2.7556 -0.4155 2 P 0 
L 2.7556 -0.4155 2.7556 -0.1945 2 P 0 
L 2.7556 -0.1945 2.7511 -0.19 2 P 0 
L 2.7511 -0.19 2.7006 -0.19 2 P 0 
L 2.7006 -0.19 2.6961 -0.1945 2 P 0 
L 2.6961 -0.1945 2.6961 -0.4155 2 P 0 
L 2.6961 -0.4155 2.6916 -0.42 2 P 0 
L 2.6916 -0.42 2.6411 -0.42 2 P 0 
L 2.6411 -0.42 2.6366 -0.4155 2 P 0 
L 2.6366 -0.4155 2.6366 -0.1945 2 P 0 
L 2.6366 -0.1945 2.6321 -0.19 2 P 0 
L 2.6321 -0.19 2.5816 -0.19 2 P 0 
L 2.5816 -0.19 2.5771 -0.1945 2 P 0 
L 2.5771 -0.1945 2.5771 -0.4155 2 P 0 
L 2.5771 -0.4155 2.5726 -0.42 2 P 0 
L 2.5726 -0.42 2.5221 -0.42 2 P 0 
L 2.5221 -0.42 2.5176 -0.4155 2 P 0 
L 2.5176 -0.4155 2.5176 -0.1945 2 P 0 
L 2.5176 -0.1945 2.5131 -0.19 2 P 0 
L 2.5131 -0.19 2.4626 -0.19 2 P 0 
L 2.4626 -0.19 2.4581 -0.1945 2 P 0 
L 2.4581 -0.1945 2.4581 -0.4155 2 P 0 
L 2.4581 -0.4155 2.4536 -0.42 2 P 0 
L 2.4536 -0.42 2.4031 -0.42 2 P 0 
L 2.4031 -0.42 2.3986 -0.4155 2 P 0 
L 2.3986 -0.4155 2.3986 -0.1945 2 P 0 
L 2.3986 -0.1945 2.3941 -0.19 2 P 0 
L 2.3941 -0.19 2.3436 -0.19 2 P 0 
L 2.3436 -0.19 2.3391 -0.1945 2 P 0 
L 2.3391 -0.1945 2.3391 -0.4155 2 P 0 
L 2.3391 -0.4155 2.3346 -0.42 2 P 0 
L 2.3346 -0.42 2.2841 -0.42 2 P 0 
L 2.2841 -0.42 2.2796 -0.4155 2 P 0 
L 2.2796 -0.4155 2.2796 -0.1945 2 P 0 
L 2.2796 -0.1945 2.2751 -0.19 2 P 0 
L 2.2751 -0.19 2.2246 -0.19 2 P 0 
L 2.2246 -0.19 2.2201 -0.1945 2 P 0 
L 2.2201 -0.1945 2.2201 -0.4155 2 P 0 
L 2.2201 -0.4155 2.2156 -0.42 2 P 0 
L 2.2156 -0.42 2.1651 -0.42 2 P 0 
L 2.1651 -0.42 2.1606 -0.4155 2 P 0 
L 2.1606 -0.4155 2.1606 -0.1945 2 P 0 
L 2.1606 -0.1945 2.1561 -0.19 2 P 0 
L 2.1561 -0.19 2.1056 -0.19 2 P 0 
L 2.1056 -0.19 2.1011 -0.1945 2 P 0 
L 2.1011 -0.1945 2.1011 -0.4155 2 P 0 
L 2.1011 -0.4155 2.0966 -0.42 2 P 0 
L 2.0966 -0.42 2.0461 -0.42 2 P 0 
L 2.0461 -0.42 2.0416 -0.4155 2 P 0 
L 2.0416 -0.4155 2.0416 -0.1945 2 P 0 
L 2.0416 -0.1945 2.0371 -0.19 2 P 0 
L 2.0371 -0.19 1.9866 -0.19 2 P 0 
L 1.9866 -0.19 1.9821 -0.1945 2 P 0 
L 1.9821 -0.1945 1.9821 -0.4155 2 P 0 
L 1.9821 -0.4155 1.9776 -0.42 2 P 0 
L 1.9776 -0.42 1.9271 -0.42 2 P 0 
L 1.9271 -0.42 1.9226 -0.4155 2 P 0 
L 1.9226 -0.4155 1.9226 -0.1945 2 P 0 
L 1.9226 -0.1945 1.9181 -0.19 2 P 0 
L 1.9181 -0.19 1.8676 -0.19 2 P 0 
L 1.8676 -0.19 1.8631 -0.1945 2 P 0 
L 1.8631 -0.1945 1.8631 -0.4155 2 P 0 
L 1.8631 -0.4155 1.8586 -0.42 2 P 0 
L 1.8586 -0.42 1.8081 -0.42 2 P 0 
L 1.8081 -0.42 1.8036 -0.4155 2 P 0 
L 1.8036 -0.4155 1.8036 -0.1945 2 P 0 
L 1.8036 -0.1945 1.7991 -0.19 2 P 0 
L 1.7991 -0.19 1.7486 -0.19 2 P 0 
L 1.7486 -0.19 1.7441 -0.1945 2 P 0 
L 1.7441 -0.1945 1.7441 -0.4155 2 P 0 
L 1.7441 -0.4155 1.7396 -0.42 2 P 0 
L 1.7396 -0.42 1.6891 -0.42 2 P 0 
L 1.6891 -0.42 1.6846 -0.4155 2 P 0 
L 1.6846 -0.4155 1.6846 -0.1945 2 P 0 
L 1.6846 -0.1945 1.6801 -0.19 2 P 0 
L 1.6801 -0.19 1.6296 -0.19 2 P 0 
L 1.6296 -0.19 1.6251 -0.1945 2 P 0 
L 1.6251 -0.1945 1.6251 -0.4155 2 P 0 
L 1.6251 -0.4155 1.6206 -0.42 2 P 0 
L 1.6206 -0.42 1.5701 -0.42 2 P 0 
L 1.5701 -0.42 1.5656 -0.4155 2 P 0 
L 1.5656 -0.4155 1.5656 -0.1945 2 P 0 
L 1.5656 -0.1945 1.5611 -0.19 2 P 0 
L 1.5611 -0.19 1.5106 -0.19 2 P 0 
L 1.5106 -0.19 1.5061 -0.1945 2 P 0 
L 1.5061 -0.1945 1.5061 -0.4155 2 P 0 
L 1.5061 -0.4155 1.5016 -0.42 2 P 0 
L 1.5016 -0.42 1.46 -0.42 2 P 0 
L 1.46 -0.42 1.445 -0.405 2 P 0 
L 1.445 -0.405 1.445 -0.31 2 P 0 
L 1.445 -0.31 1.435 -0.3 2 P 0 
L 1.435 -0.3 1.075 -0.3 2 P 0 
L 1.075 -0.3 1.025 -0.25 2 P 0 
P 12.81495 2.51575 7 P 0 0;2=4,4=0
P 10.26 1.66445 5 P 0 0;2=3,4=1
L 10.26 1.66445 10.27695 1.6814 1 P 0 
L 10.27695 1.6814 10.29883996 1.6814 1 P 0 
L 10.29883996 1.6814 10.29951004 1.68128002 1 P 0 
L 10.29951004 1.68128002 10.36286004 1.69246004 1 P 0 
L 10.36286004 1.69246004 10.38571004 1.68841998 1 P 0 
L 10.38571004 1.68841998 10.41241998 1.66971004 1 P 0 
L 10.41241998 1.66971004 10.5216 1.51376004 1 P 0 
L 10.5216 1.51376004 10.53568996 1.43381998 1 P 0 
L 10.53568996 1.43381998 10.6243 1.30726004 1 P 0 
L 10.6243 1.30726004 10.71836004 1.2414 1 P 0 
L 10.71836004 1.2414 10.85708996 1.21693002 1 P 0 
L 10.85708996 1.21693002 11.62106998 1.35165 1 P 0 
L 11.62106998 1.35165 11.76793996 1.45448996 1 P 0 
L 11.76793996 1.45448996 12.06836004 1.88356004 1 P 0 
L 12.06836004 1.88356004 12.10265 2.07786998 1 P 0 
L 12.10265 2.07786998 12.35381004 2.43626004 1 P 0 
L 12.35381004 2.43626004 12.40446998 2.47173002 1 P 0 
L 12.40446998 2.47173002 12.47908002 2.48488002 1 P 0 
L 12.47908002 2.48488002 12.55363996 2.47173996 1 P 0 
L 12.55363996 2.47173996 12.56278002 2.47173996 1 P 0 
L 12.56278002 2.47173996 12.57658996 2.4693 1 P 0 
L 12.57658996 2.4693 12.62366004 2.43633996 1 P 0 
L 12.62366004 2.43633996 12.63841004 2.43373996 1 P 0 
L 12.63841004 2.43373996 12.75831004 2.43373996 1 P 0 
L 12.75831004 2.43373996 12.7863 2.46173002 1 P 0 
L 12.7863 2.46173002 12.7863 2.4871 1 P 0 
L 12.7863 2.4871 12.81495 2.51575 1 P 0 
P 9.975 2.4709 5 P 0 0;2=3,4=1
P 12.73621004 4.20866004 7 P 0 0;2=4,4=0
L 12.73621004 4.20866004 12.75653002 4.18833996 1 P 0 
L 12.75653002 4.18833996 12.76988996 4.18833996 1 P 0 
L 12.76988996 4.18833996 12.77623002 4.19468002 1 P 0 
L 12.77623002 4.19468002 12.77623002 4.22651004 1 P 0 
L 12.77623002 4.22651004 12.7582 4.24453996 1 P 0 
L 12.7582 4.24453996 12.6429 4.24453996 1 P 0 
L 12.6429 4.24453996 12.62506004 4.2414 1 P 0 
L 12.62506004 4.2414 12.57663002 4.20746004 1 P 0 
L 12.57663002 4.20746004 12.56913002 4.20613996 1 P 0 
L 12.56913002 4.20613996 12.54463002 4.20613996 1 P 0 
L 12.54463002 4.20613996 12.50161004 4.17601998 1 P 0 
L 12.50161004 4.17601998 12.44333002 4.09278002 1 P 0 
L 12.44333002 4.09278002 12.28591998 3.98256004 1 P 0 
L 12.28591998 3.98256004 11.96718996 3.92636998 1 P 0 
L 11.96718996 3.92636998 11.31428996 4.0415 1 P 0 
L 11.31428996 4.0415 10.83553996 3.95708002 1 P 0 
L 10.83553996 3.95708002 10.6912 3.98253002 1 P 0 
L 10.6912 3.98253002 10.54511004 3.95678002 1 P 0 
L 10.54511004 3.95678002 10.4941 3.92105 1 P 0 
L 10.4941 3.92105 10.44148996 3.84596004 1 P 0 
L 10.44148996 3.84596004 10.24571004 2.74318996 1 P 0 
L 10.24571004 2.74318996 10.19293002 2.66783002 1 P 0 
L 10.19293002 2.66783002 10.13053002 2.62413002 1 P 0 
L 10.13053002 2.62413002 10.0766 2.61463002 1 P 0 
L 10.0766 2.61463002 10.0641 2.60586004 1 P 0 
L 10.0641 2.60586004 10.0576 2.59658002 1 P 0 
L 10.0576 2.59658002 10.04288996 2.51318996 1 P 0 
L 10.04288996 2.51318996 10.03348996 2.49976998 1 P 0 
L 10.03348996 2.49976998 10.0206 2.49075 1 P 0 
L 10.0206 2.49075 10.00416004 2.48785 1 P 0 
L 10.00416004 2.48785 9.99195 2.48785 1 P 0 
L 9.99195 2.48785 9.975 2.4709 1 P 0 
P 12.73621004 2.47638002 7 P 0 0;2=4,4=0
P 10.26 1.70445 5 P 0 0;2=3,4=1
L 10.26 1.70445 10.27555 1.6889 1 P 0 
L 10.27555 1.6889 10.2995 1.6889 1 P 0 
L 10.2995 1.6889 10.36286004 1.70008002 1 P 0 
L 10.36286004 1.70008002 10.38865 1.69551998 1 P 0 
L 10.38865 1.69551998 10.41781004 1.6751 1 P 0 
L 10.41781004 1.6751 10.5287 1.5167 1 P 0 
L 10.5287 1.5167 10.54278996 1.43676004 1 P 0 
L 10.54278996 1.43676004 10.62968996 1.31265 1 P 0 
L 10.62968996 1.31265 10.7213 1.2485 1 P 0 
L 10.7213 1.2485 10.85708996 1.22455 1 P 0 
L 10.85708996 1.22455 11.61813002 1.35875 1 P 0 
L 11.61813002 1.35875 11.76255 1.45988002 1 P 0 
L 11.76255 1.45988002 12.06126004 1.8865 1 P 0 
L 12.06126004 1.8865 12.09555 2.08081004 1 P 0 
L 12.09555 2.08081004 12.34841998 2.44165 1 P 0 
L 12.34841998 2.44165 12.40153002 2.47883002 1 P 0 
L 12.40153002 2.47883002 12.47908002 2.4925 1 P 0 
L 12.47908002 2.4925 12.5543 2.47923996 1 P 0 
L 12.5543 2.47923996 12.56343996 2.47923996 1 P 0 
L 12.56343996 2.47923996 12.57953002 2.4764 1 P 0 
L 12.57953002 2.4764 12.6266 2.44343996 1 P 0 
L 12.6266 2.44343996 12.63906998 2.44123996 1 P 0 
L 12.63906998 2.44123996 12.7552 2.44123996 1 P 0 
L 12.7552 2.44123996 12.7788 2.46483996 1 P 0 
L 12.7788 2.46483996 12.7788 2.48906004 1 P 0 
L 12.7788 2.48906004 12.7751 2.49276004 1 P 0 
L 12.7751 2.49276004 12.75258996 2.49276004 1 P 0 
L 12.75258996 2.49276004 12.73621004 2.47638002 1 P 0 
P 12.73621004 2.87008002 7 P 0 0;2=4,4=0
P 10.225 1.96645 5 P 0 0;2=3,4=1
L 10.225 1.96645 10.24135 1.9501 1 P 0 
L 10.24135 1.9501 10.26876004 1.9501 1 P 0 
L 10.26876004 1.9501 10.28813996 1.94668002 1 P 0 
L 10.28813996 1.94668002 10.30693996 1.93351998 1 P 0 
L 10.30693996 1.93351998 10.58196004 1.54075 1 P 0 
L 10.58196004 1.54075 10.59458002 1.46916004 1 P 0 
L 10.59458002 1.46916004 10.67438996 1.35518996 1 P 0 
L 10.67438996 1.35518996 10.74243002 1.30753996 1 P 0 
L 10.74243002 1.30753996 10.85291004 1.28806004 1 P 0 
L 10.85291004 1.28806004 10.98206004 1.31083002 1 P 0 
L 10.98206004 1.31083002 11.505 1.677 1 P 0 
L 11.505 1.677 11.65798996 1.70398002 1 P 0 
L 11.65798996 1.70398002 11.7712 1.78325 1 P 0 
L 11.7712 1.78325 12.29963996 2.53795 1 P 0 
L 12.29963996 2.53795 12.31391998 2.6189 1 P 0 
L 12.31391998 2.6189 12.45946998 2.82676998 1 P 0 
L 12.45946998 2.82676998 12.46538002 2.83268002 1 P 0 
L 12.46538002 2.83268002 12.46538002 2.83278002 1 P 0 
L 12.46538002 2.83278002 12.46795 2.83535 1 P 0 
L 12.46795 2.83535 12.51601998 2.86901004 1 P 0 
L 12.51601998 2.86901004 12.53833996 2.87293996 1 P 0 
L 12.53833996 2.87293996 12.56343996 2.87293996 1 P 0 
L 12.56343996 2.87293996 12.57953002 2.8701 1 P 0 
L 12.57953002 2.8701 12.6266 2.83713996 1 P 0 
L 12.6266 2.83713996 12.63906998 2.83493996 1 P 0 
L 12.63906998 2.83493996 12.7552 2.83493996 1 P 0 
L 12.7552 2.83493996 12.7788 2.85853996 1 P 0 
L 12.7788 2.85853996 12.7788 2.88276004 1 P 0 
L 12.7788 2.88276004 12.7751 2.88646004 1 P 0 
L 12.7751 2.88646004 12.75258996 2.88646004 1 P 0 
L 12.75258996 2.88646004 12.73621004 2.87008002 1 P 0 
P 12.73621004 3.02756004 7 P 0 0;2=4,4=0
P 10.09 2.05655 5 P 0 0;2=3,4=1
L 10.09 2.05655 10.10615 2.0404 1 P 0 
L 10.10615 2.0404 10.14166004 2.0404 1 P 0 
L 10.14166004 2.0404 10.26478996 2.01868996 1 P 0 
L 10.26478996 2.01868996 10.29678996 1.99628002 1 P 0 
L 10.29678996 1.99628002 10.40473002 1.84211004 1 P 0 
L 10.40473002 1.84211004 10.56598996 1.72921004 1 P 0 
L 10.56598996 1.72921004 10.6869 1.70788996 1 P 0 
L 10.6869 1.70788996 10.83133996 1.73336998 1 P 0 
L 10.83133996 1.73336998 10.98696998 1.70591998 1 P 0 
L 10.98696998 1.70591998 11.13686004 1.73235 1 P 0 
L 11.13686004 1.73235 11.22253002 1.79233996 1 P 0 
L 11.22253002 1.79233996 11.57905 1.8552 1 P 0 
L 11.57905 1.8552 11.6523 1.90648002 1 P 0 
L 11.6523 1.90648002 11.76598002 1.92653002 1 P 0 
L 11.76598002 1.92653002 11.86088996 1.99298996 1 P 0 
L 11.86088996 1.99298996 12.25533002 2.5563 1 P 0 
L 12.25533002 2.5563 12.28663996 2.73388002 1 P 0 
L 12.28663996 2.73388002 12.46795 2.99283002 1 P 0 
L 12.46795 2.99283002 12.51601998 3.02648996 1 P 0 
L 12.51601998 3.02648996 12.53833996 3.03041998 1 P 0 
L 12.53833996 3.03041998 12.56343996 3.03041998 1 P 0 
L 12.56343996 3.03041998 12.57953002 3.02758002 1 P 0 
L 12.57953002 3.02758002 12.6266 2.99461998 1 P 0 
L 12.6266 2.99461998 12.63906998 2.99241998 1 P 0 
L 12.63906998 2.99241998 12.7552 2.99241998 1 P 0 
L 12.7552 2.99241998 12.7788 3.01601998 1 P 0 
L 12.7788 3.01601998 12.7788 3.04023996 1 P 0 
L 12.7788 3.04023996 12.7751 3.04393996 1 P 0 
L 12.7751 3.04393996 12.75258996 3.04393996 1 P 0 
L 12.75258996 3.04393996 12.73621004 3.02756004 1 P 0 
P 12.81495 4.01181004 7 P 0 0;2=4,4=0
P 10.09 2.57845 5 P 0 0;2=3,4=1
L 10.09 2.57845 10.10555 2.5629 1 P 0 
L 10.10555 2.5629 10.1317 2.5629 1 P 0 
L 10.1317 2.5629 10.15248002 2.56656004 1 P 0 
L 10.15248002 2.56656004 10.17611998 2.58311004 1 P 0 
L 10.17611998 2.58311004 10.2538 2.69403996 1 P 0 
L 10.2538 2.69403996 10.45595 3.84066998 1 P 0 
L 10.45595 3.84066998 10.50506998 3.91078002 1 P 0 
L 10.50506998 3.91078002 10.54931998 3.94176998 1 P 0 
L 10.54931998 3.94176998 10.69351004 3.96718996 1 P 0 
L 10.69351004 3.96718996 10.83638996 3.94198996 1 P 0 
L 10.83638996 3.94198996 11.29081004 4.02211004 1 P 0 
L 11.29081004 4.02211004 11.96256004 3.90368002 1 P 0 
L 11.96256004 3.90368002 12.18806998 3.94345 1 P 0 
L 12.18806998 3.94345 12.18806998 3.94346004 1 P 0 
L 12.18806998 3.94346004 12.41356004 3.98321004 1 P 0 
L 12.41356004 3.98321004 12.51123996 4.05161004 1 P 0 
L 12.51123996 4.05161004 12.53703996 4.05616004 1 P 0 
L 12.53703996 4.05616004 12.56846998 4.05616004 1 P 0 
L 12.56846998 4.05616004 12.57368996 4.05708002 1 P 0 
L 12.57368996 4.05708002 12.62211998 4.09101998 1 P 0 
L 12.62211998 4.09101998 12.64223996 4.09456004 1 P 0 
L 12.64223996 4.09456004 12.76131004 4.09456004 1 P 0 
L 12.76131004 4.09456004 12.78373002 4.07213996 1 P 0 
L 12.78373002 4.07213996 12.78373002 4.04303002 1 P 0 
L 12.78373002 4.04303002 12.81495 4.01181004 1 P 0 
P 12.73621004 2.7126 7 P 0 0;2=4,4=0
P 10.26025 1.86845 5 P 0 0;2=3,4=1
L 10.26025 1.86845 10.276 1.8527 1 P 0 
L 10.276 1.8527 10.3025 1.8527 1 P 0 
L 10.3025 1.8527 10.31885 1.84981998 1 P 0 
L 10.31885 1.84981998 10.34285 1.83301004 1 P 0 
L 10.34285 1.83301004 10.55643002 1.52795 1 P 0 
L 10.55643002 1.52795 10.5689 1.4572 1 P 0 
L 10.5689 1.4572 10.65551004 1.33351004 1 P 0 
L 10.65551004 1.33351004 10.73173996 1.28013002 1 P 0 
L 10.73173996 1.28013002 10.8599 1.25753002 1 P 0 
L 10.8599 1.25753002 11.08423002 1.29708002 1 P 0 
L 11.08423002 1.29708002 11.34403002 1.47898996 1 P 0 
L 11.34403002 1.47898996 11.56741004 1.51838996 1 P 0 
L 11.56741004 1.51838996 11.65233996 1.57786004 1 P 0 
L 11.65233996 1.57786004 11.78625 1.60146998 1 P 0 
L 11.78625 1.60146998 11.81903996 1.62443002 1 P 0 
L 11.81903996 1.62443002 12.04683002 1.94973996 1 P 0 
L 12.04683002 1.94973996 12.0726 2.09585 1 P 0 
L 12.0726 2.09585 12.49083996 2.69313002 1 P 0 
L 12.49083996 2.69313002 12.51748996 2.71178996 1 P 0 
L 12.51748996 2.71178996 12.53833996 2.71546004 1 P 0 
L 12.53833996 2.71546004 12.56343996 2.71546004 1 P 0 
L 12.56343996 2.71546004 12.57953002 2.71261998 1 P 0 
L 12.57953002 2.71261998 12.6266 2.67966004 1 P 0 
L 12.6266 2.67966004 12.63906998 2.67746004 1 P 0 
L 12.63906998 2.67746004 12.7552 2.67746004 1 P 0 
L 12.7552 2.67746004 12.7788 2.70106004 1 P 0 
L 12.7788 2.70106004 12.7788 2.72528002 1 P 0 
L 12.7788 2.72528002 12.7751 2.72898002 1 P 0 
L 12.7751 2.72898002 12.75258996 2.72898002 1 P 0 
L 12.75258996 2.72898002 12.73621004 2.7126 1 P 0 
P 12.73621004 3.18503996 7 P 0 0;2=4,4=0
P 10.09 2.17095 5 P 0 0;2=3,4=1
L 10.09 2.17095 10.10615 2.1548 1 P 0 
L 10.10615 2.1548 10.14166004 2.1548 1 P 0 
L 10.14166004 2.1548 10.19198002 2.14593002 1 P 0 
L 10.19198002 2.14593002 10.2489 2.10608002 1 P 0 
L 10.2489 2.10608002 10.42301004 1.85743002 1 P 0 
L 10.42301004 1.85743002 10.57373002 1.7519 1 P 0 
L 10.57373002 1.7519 10.69081998 1.73126004 1 P 0 
L 10.69081998 1.73126004 10.83656998 1.75696004 1 P 0 
L 10.83656998 1.75696004 10.98711998 1.7304 1 P 0 
L 10.98711998 1.7304 11.12588996 1.75488002 1 P 0 
L 11.12588996 1.75488002 11.2483 1.8406 1 P 0 
L 11.2483 1.8406 11.44606998 1.97908002 1 P 0 
L 11.44606998 1.97908002 11.58906004 2.0043 1 P 0 
L 11.58906004 2.0043 11.66858996 2.05998996 1 P 0 
L 11.66858996 2.05998996 11.83848002 2.08993996 1 P 0 
L 11.83848002 2.08993996 11.93151004 2.15508996 1 P 0 
L 11.93151004 2.15508996 12.2212 2.5688 1 P 0 
L 12.2212 2.5688 12.28375 2.9235 1 P 0 
L 12.28375 2.9235 12.43246998 3.13591004 1 P 0 
L 12.43246998 3.13591004 12.49608002 3.18045 1 P 0 
L 12.49608002 3.18045 12.53833996 3.1879 1 P 0 
L 12.53833996 3.1879 12.56343996 3.1879 1 P 0 
L 12.56343996 3.1879 12.57953002 3.18506004 1 P 0 
L 12.57953002 3.18506004 12.6266 3.1521 1 P 0 
L 12.6266 3.1521 12.63906998 3.1499 1 P 0 
L 12.63906998 3.1499 12.7552 3.1499 1 P 0 
L 12.7552 3.1499 12.7788 3.1735 1 P 0 
L 12.7788 3.1735 12.7788 3.19771998 1 P 0 
L 12.7788 3.19771998 12.7751 3.20141998 1 P 0 
L 12.7751 3.20141998 12.75258996 3.20141998 1 P 0 
L 12.75258996 3.20141998 12.73621004 3.18503996 1 P 0 
P 12.81495 2.90945 7 P 0 0;2=4,4=0
P 10.225 1.92645 5 P 0 0;2=3,4=1
L 10.225 1.92645 10.24115 1.9426 1 P 0 
L 10.24115 1.9426 10.2681 1.9426 1 P 0 
L 10.2681 1.9426 10.2852 1.93958002 1 P 0 
L 10.2852 1.93958002 10.30155 1.92813002 1 P 0 
L 10.30155 1.92813002 10.57486004 1.53781004 1 P 0 
L 10.57486004 1.53781004 10.58748002 1.46621998 1 P 0 
L 10.58748002 1.46621998 10.669 1.3498 1 P 0 
L 10.669 1.3498 10.73948996 1.30043996 1 P 0 
L 10.73948996 1.30043996 10.85291004 1.28043996 1 P 0 
L 10.85291004 1.28043996 10.85421004 1.28066004 1 P 0 
L 10.85421004 1.28066004 10.85421004 1.28066998 1 P 0 
L 10.85421004 1.28066998 10.985 1.30373002 1 P 0 
L 10.985 1.30373002 11.50793996 1.6699 1 P 0 
L 11.50793996 1.6699 11.66093002 1.69688002 1 P 0 
L 11.66093002 1.69688002 11.77658996 1.77786004 1 P 0 
L 11.77658996 1.77786004 12.30673996 2.53501004 1 P 0 
L 12.30673996 2.53501004 12.32101998 2.61596004 1 P 0 
L 12.32101998 2.61596004 12.46521998 2.8219 1 P 0 
L 12.46521998 2.8219 12.47068996 2.82736998 1 P 0 
L 12.47068996 2.82736998 12.47075 2.82736998 1 P 0 
L 12.47075 2.82736998 12.47333996 2.82996004 1 P 0 
L 12.47333996 2.82996004 12.51896004 2.86191004 1 P 0 
L 12.51896004 2.86191004 12.539 2.86543996 1 P 0 
L 12.539 2.86543996 12.56278002 2.86543996 1 P 0 
L 12.56278002 2.86543996 12.57658996 2.863 1 P 0 
L 12.57658996 2.863 12.62366004 2.83003996 1 P 0 
L 12.62366004 2.83003996 12.63841004 2.82743996 1 P 0 
L 12.63841004 2.82743996 12.75831004 2.82743996 1 P 0 
L 12.75831004 2.82743996 12.7863 2.85543002 1 P 0 
L 12.7863 2.85543002 12.7863 2.8808 1 P 0 
L 12.7863 2.8808 12.81495 2.90945 1 P 0 
L 9.91 4.433 9.91 3.021 2 P 0 
L 9.91 3.021 9.995 2.936 2 P 0 
P 9.91 4.433 6 P 0 0;2=2,4=1
P 9.995 2.936 6 P 0 0;2=1,4=1
P 12.81495 3.06693002 7 P 0 0;2=4,4=0
P 10.09 2.01655 5 P 0 0;2=3,4=1
L 10.09 2.01655 10.10635 2.0329 1 P 0 
L 10.10635 2.0329 10.141 2.0329 1 P 0 
L 10.141 2.0329 10.26185 2.01158996 1 P 0 
L 10.26185 2.01158996 10.2914 1.99088996 1 P 0 
L 10.2914 1.99088996 10.39933996 1.83671998 1 P 0 
L 10.39933996 1.83671998 10.56305 1.72211004 1 P 0 
L 10.56305 1.72211004 10.6869 1.70026998 1 P 0 
L 10.6869 1.70026998 10.6882 1.70048996 1 P 0 
L 10.6882 1.70048996 10.6882 1.7005 1 P 0 
L 10.6882 1.7005 10.83133996 1.72575 1 P 0 
L 10.83133996 1.72575 10.98696998 1.6983 1 P 0 
L 10.98696998 1.6983 11.1398 1.72525 1 P 0 
L 11.1398 1.72525 11.22546998 1.78523996 1 P 0 
L 11.22546998 1.78523996 11.58198996 1.8481 1 P 0 
L 11.58198996 1.8481 11.65523996 1.89938002 1 P 0 
L 11.65523996 1.89938002 11.76891998 1.91943002 1 P 0 
L 11.76891998 1.91943002 11.86628002 1.9876 1 P 0 
L 11.86628002 1.9876 12.26243002 2.55336004 1 P 0 
L 12.26243002 2.55336004 12.29373996 2.73093996 1 P 0 
L 12.29373996 2.73093996 12.47333996 2.98743996 1 P 0 
L 12.47333996 2.98743996 12.51896004 3.01938996 1 P 0 
L 12.51896004 3.01938996 12.539 3.02291998 1 P 0 
L 12.539 3.02291998 12.56278002 3.02291998 1 P 0 
L 12.56278002 3.02291998 12.57658996 3.02048002 1 P 0 
L 12.57658996 3.02048002 12.62366004 2.98751998 1 P 0 
L 12.62366004 2.98751998 12.63841004 2.98491998 1 P 0 
L 12.63841004 2.98491998 12.75831004 2.98491998 1 P 0 
L 12.75831004 2.98491998 12.7863 3.01291004 1 P 0 
L 12.7863 3.01291004 12.7863 3.03828002 1 P 0 
L 12.7863 3.03828002 12.81495 3.06693002 1 P 0 
P 12.73621004 2.3189 7 P 0 0;2=4,4=0
P 10.38371998 1.49328002 5 P 0 0;2=3,4=1
L 10.38371998 1.49328002 10.38371998 1.51651998 1 P 0 
L 10.38371998 1.51651998 10.3948 1.5276 1 P 0 
L 10.3948 1.5276 10.3948 1.52758996 1 P 0 
L 10.3948 1.52758996 10.41783002 1.54371004 1 P 0 
L 10.41783002 1.54371004 10.43293996 1.54638002 1 P 0 
L 10.43293996 1.54638002 10.46068996 1.5415 1 P 0 
L 10.46068996 1.5415 10.47645 1.53043996 1 P 0 
L 10.47645 1.53043996 10.49483002 1.50418002 1 P 0 
L 10.49483002 1.50418002 10.5102 1.41701004 1 P 0 
L 10.5102 1.41701004 10.60491998 1.28171998 1 P 0 
L 10.60491998 1.28171998 10.7062 1.2108 1 P 0 
L 10.7062 1.2108 10.85491998 1.18458002 1 P 0 
L 10.85491998 1.18458002 11.62206998 1.31985 1 P 0 
L 11.62206998 1.31985 11.79716004 1.44246004 1 P 0 
L 11.79716004 1.44246004 12.09878996 1.87321998 1 P 0 
L 12.09878996 1.87321998 12.10003996 1.87446998 1 P 0 
L 12.10003996 1.87446998 12.10003996 1.87623002 1 P 0 
L 12.10003996 1.87623002 12.1366 2.08358996 1 P 0 
L 12.1366 2.08358996 12.37256998 2.42056004 1 P 0 
L 12.37256998 2.42056004 12.41003996 2.4468 1 P 0 
L 12.41003996 2.4468 12.43196004 2.45066004 1 P 0 
L 12.43196004 2.45066004 12.46005 2.44571004 1 P 0 
L 12.46005 2.44571004 12.48018002 2.43161004 1 P 0 
L 12.48018002 2.43161004 12.49045 2.41695 1 P 0 
L 12.49045 2.41695 12.5005 2.35991998 1 P 0 
L 12.5005 2.35991998 12.52223996 2.32883996 1 P 0 
L 12.52223996 2.32883996 12.54055 2.31605 1 P 0 
L 12.54055 2.31605 12.55898996 2.3128 1 P 0 
L 12.55898996 2.3128 12.57001004 2.31475 1 P 0 
L 12.57001004 2.31475 12.62275 2.35166004 1 P 0 
L 12.62275 2.35166004 12.63933996 2.3546 1 P 0 
L 12.63933996 2.3546 12.75796998 2.3546 1 P 0 
L 12.75796998 2.3546 12.76876004 2.3438 1 P 0 
L 12.76876004 2.3438 12.7712 2.34136004 1 P 0 
L 12.7712 2.34136004 12.7712 2.3244 1 P 0 
L 12.7712 2.3244 12.7657 2.3189 1 P 0 
L 12.7657 2.3189 12.73621004 2.3189 1 P 0 
L 4.125 2.682 4.0045 2.8025 2 P 0 
L 4.0045 2.8025 4.0045 4.2905 2 P 0 
L 4.0045 4.2905 3.94 4.355 2 P 0 
L 3.94 4.355 3.94 4.42 2 P 0 
P 4.125 2.682 6 P 0 0;2=1,4=1
P 3.94 4.42 6 P 0 0;2=2,4=1
P 5.37968996 2.8 6 P 0 0;2=1,4=1
P 5.387 2.725 6 P 0 0;2=2,4=1
P 5.5822 2.785 6 P 0 0;2=1,4=1
P 5.5822 2.905 6 P 0 0;2=1,4=1
P 7.2426 4.69351004 6 P 0 0;2=1,4=1
P 7.2926 4.60351004 6 P 0 0;2=1,4=1
S P 0
OB 5.36 2.7 I
OS 5.34 2.72
OS 5.34 2.895
OS 5.36 2.915
OS 5.62 2.915
OS 5.64 2.895
OS 5.64 2.831
OS 5.676 2.795
OS 5.9 2.795
OS 6.485 3.38
OS 6.485 4.415
OS 6.72 4.65
OS 6.96 4.65
OS 7.045 4.735
OS 7.31 4.735
OS 7.325 4.72
OS 7.325 4.62
OS 7.13 4.425
OS 6.875 4.425
OS 6.73 4.28
OS 6.73 3.27
OS 6.16 2.7
OS 5.5361 2.7
OC 5.534519980315 2.7 5.53531003937 2.6825 N
OS 5.36 2.7
OE
OB 6.85783996063 4.555 H
OC 6.870530314961 4.547749015748 6.872084744094 4.5652 N
OC 6.8843 4.55263996063 6.87208523622 4.5652 N
OC 6.889880019685 4.55263996063 6.887090059055 4.549769980315 Y
OC 6.889880019685 4.57776003937 6.90208996063 4.5652 N
OC 6.8843 4.57776003937 6.887090059055 4.580630019685 Y
OC 6.870530314961 4.582650984252 6.87208523622 4.5652 N
OC 6.85783996063 4.5754 6.872084744094 4.5652 N
OC 6.85133996063 4.5754 6.85458996063 4.577719980315 Y
OC 6.85133996063 4.555 6.83708996063 4.5652 N
OC 6.85783996063 4.555 6.85458996063 4.552680019685 Y
OE
OB 6.74783996063 4.555 H
OC 6.77633996063 4.555 6.76208996063 4.5652 N
OC 6.78283996063 4.555 6.77958996063 4.552680019685 Y
OC 6.78283996063 4.5754 6.79708996063 4.5652 N
OC 6.77633996063 4.5754 6.77958996063 4.577719980315 Y
OC 6.74783996063 4.5754 6.76208996063 4.5652 N
OC 6.74133996063 4.5754 6.74458996063 4.577719980315 Y
OC 6.74133996063 4.555 6.72708996063 4.5652 N
OC 6.74783996063 4.555 6.74458996063 4.552680019685 Y
OE
OB 5.509730019685 2.73 H
OC 5.509730019685 2.73 5.49221003937 2.73 N
OE
OB 5.599719980315 2.855 H
OC 5.599719980315 2.855 5.5822 2.855 N
OE
OB 7.260119980315 4.60351003937 H
OC 7.260119980315 4.60351003937 7.2426 4.60351003937 N
OE
OB 7.310119980315 4.69351003937 H
OC 7.310119980315 4.69351003937 7.2926 4.69351003937 N
OE
SE
P 10.07286004 2.82336998 6 P 0 0;2=1,4=1
P 10.03 4.61 6 P 0 0;2=1,4=1
L 10.07286004 2.82336998 9.97763996 2.82336998 6 P 0 
L 9.97763996 2.82336998 9.865 2.93601004 6 P 0 
L 9.865 2.93601004 9.865 4.545 6 P 0 
L 9.865 4.545 9.93 4.61 6 P 0 
L 9.93 4.61 10.03 4.61 6 P 0 
P 12.73621004 4.36613996 7 P 0 0;2=4,4=0
P 9.975 2.66445 5 P 0 0;2=3,4=1
L 9.975 2.66445 9.99055 2.6489 1 P 0 
L 9.99055 2.6489 10.04421004 2.6489 1 P 0 
L 10.04421004 2.6489 10.1308 2.66416998 1 P 0 
L 10.1308 2.66416998 10.17148002 2.69265 1 P 0 
L 10.17148002 2.69265 10.21743002 2.75826004 1 P 0 
L 10.21743002 2.75826004 10.41176004 3.86001004 1 P 0 
L 10.41176004 3.86001004 10.46718002 3.93918002 1 P 0 
L 10.46718002 3.93918002 10.53303002 3.98526998 1 P 0 
L 10.53303002 3.98526998 10.68988996 4.01293996 1 P 0 
L 10.68988996 4.01293996 10.83533996 3.98728996 1 P 0 
L 10.83533996 3.98728996 11.52361004 4.10861004 1 P 0 
L 11.52361004 4.10861004 11.95628002 4.41158002 1 P 0 
L 11.95628002 4.41158002 12.11096998 4.43886004 1 P 0 
L 12.11096998 4.43886004 12.31295 4.40323996 1 P 0 
L 12.31295 4.40323996 12.45141004 4.30631004 1 P 0 
L 12.45141004 4.30631004 12.54113996 4.2905 1 P 0 
L 12.54113996 4.2905 12.55513996 4.2905 1 P 0 
L 12.55513996 4.2905 12.56861004 4.29288002 1 P 0 
L 12.56861004 4.29288002 12.61753996 4.32713996 1 P 0 
L 12.61753996 4.32713996 12.6406 4.3312 1 P 0 
L 12.6406 4.3312 12.75928996 4.3312 1 P 0 
L 12.75928996 4.3312 12.7686 4.34051004 1 P 0 
L 12.7686 4.34051004 12.7686 4.3579 1 P 0 
L 12.7686 4.3579 12.76036004 4.36613996 1 P 0 
L 12.76036004 4.36613996 12.73621004 4.36613996 1 P 0 
P 8.45 3.41615 5 P 0 0;2=3,4=1
P 8.18811004 5.0535 5 P 0 0;2=3,4=1
L 8.18811004 5.0535 8.17596004 5.0535 1 P 0 
A 8.17596004 5.0535 8.17226004 5.0498 8.17596004 5.0498 1 P 0 N
L 8.17226004 5.0498 8.17226004 5.01728002 1 P 0 
L 8.17226004 5.01728002 8.18331004 4.95468002 1 P 0 
L 8.18331004 4.95468002 8.16218996 4.83496998 1 P 0 
L 8.16218996 4.83496998 8.17033996 4.78871998 1 P 0 
L 8.17033996 4.78871998 8.15801998 4.71891998 1 P 0 
L 8.15801998 4.71891998 8.12946998 4.67815 1 P 0 
L 8.12946998 4.67815 8.12221004 4.63703002 1 P 0 
L 8.12221004 4.63703002 8.12778996 4.60538996 1 P 0 
A 8.12778996 4.60538996 8.12967933 4.59983799 8.14678002 4.60875492 1 P 0 N
A 8.12967933 4.59983799 8.13315 4.59511004 8.14678002 4.60875335 1 P 0 N
L 8.13315 4.59511004 8.16293996 4.56531998 1 P 0 
A 8.16293996 4.56531998 8.17204272 4.55169843 8.13325 4.53562707 1 P 0 Y
A 8.17204272 4.55169843 8.17523996 4.53563002 8.13325 4.53562726 1 P 0 Y
L 8.17523996 4.53563002 8.17523996 4.52591998 1 P 0 
L 8.17523996 4.52591998 8.1642 4.46325 1 P 0 
A 8.1642 4.46325 8.16338996 4.45918002 8.07463996 4.47895935 1 P 0 Y
A 8.16338996 4.45918002 8.1543311 4.43519941 8.07463996 4.47900463 1 P 0 Y
A 8.1543311 4.43519941 8.13893996 4.4147 8.07463996 4.47900463 1 P 0 Y
L 8.13893996 4.4147 8.12153996 4.3973 1 P 0 
A 8.12153996 4.3973 8.10002077 4.38292756 8.07463671 4.44423002 1 P 0 Y
A 8.10002077 4.38292756 8.07463996 4.37788002 8.07463711 4.44423002 1 P 0 Y
L 8.07463996 4.37788002 8.07458002 4.37788002 1 P 0 
A 8.07458002 4.37788002 8.05653199 4.38146959 8.07458268 4.42506004 1 P 0 Y
A 8.05653199 4.38146959 8.04123002 4.39168996 8.07458238 4.42506004 1 P 0 Y
L 8.04123002 4.39168996 8.03875 4.39416998 1 P 0 
A 8.03875 4.39416998 8.03409341 4.39728425 8.02859213 4.38401998 1 P 0 N
A 8.03409341 4.39728425 8.0286 4.39838002 8.02859163 4.38401998 1 P 0 N
L 8.0286 4.39838002 8.02506998 4.39838002 1 P 0 
A 8.02506998 4.39838002 8.0139 4.39373996 8.02508878 4.38256998 1 P 0 N
L 8.0139 4.39373996 8.00805 4.38788996 1 P 0 
A 8.00805 4.38788996 8.00805 4.36788996 8.01805 4.37788996 1 P 0 N
L 8.00805 4.36788996 8.02508996 4.35085 1 P 0 
A 8.02508996 4.35085 8.04260699 4.32199961 7.97486998 4.30061496 1 P 0 Y
A 8.04260699 4.32199961 8.04483002 4.28831998 7.97486998 4.30061545 1 P 0 Y
L 8.04483002 4.28831998 8.04481998 4.28831998 1 P 0 
L 8.04481998 4.28831998 8.03551998 4.23546998 1 P 0 
L 8.03551998 4.23546998 8.03551998 4.23543996 1 P 0 
A 8.03551998 4.23543996 8.05397913 4.14266142 8.27795 4.23544813 1 P 0 N
A 8.05397913 4.14266142 8.10653996 4.06401004 8.27795 4.23544744 1 P 0 N
L 8.10653996 4.06401004 8.10766998 4.06286998 1 P 0 
A 8.10766998 4.06286998 8.16654203 4.02409793 8.2357062 4.1932 1 P 0 N
A 8.16654203 4.02409793 8.23571004 4.0105 8.23570689 4.1932 1 P 0 N
L 8.23571004 4.0105 8.26093002 4.0105 1 P 0 
A 8.26093002 4.0105 8.38233002 4.06078996 8.26091959 4.1822 1 P 0 N
L 8.38233002 4.06078996 8.38235 4.06081004 1 P 0 
A 8.38235 4.06081004 8.42558996 4.06081004 8.40396998 4.03918996 1 P 0 Y
L 8.42558996 4.06081004 8.45926998 4.02713002 1 P 0 
A 8.45926998 4.02713002 8.46775157 4.02091181 8.48372274 4.05158996 1 P 0 N
A 8.46775157 4.02091181 8.47771004 4.01753002 8.48372303 4.05158996 1 P 0 N
L 8.47771004 4.01753002 8.5388 4.00673996 1 P 0 
A 8.5388 4.00673996 8.56714272 3.99571811 8.52526417 3.92998002 1 P 0 Y
A 8.56714272 3.99571811 8.58911004 3.97468996 8.52526329 3.92998002 1 P 0 Y
L 8.58911004 3.97468996 8.65551004 3.87983002 1 P 0 
L 8.65551004 3.87983002 8.68418002 3.71713996 1 P 0 
L 8.68418002 3.71713996 8.65226004 3.53615 1 P 0 
A 8.65226004 3.53615 8.62178996 3.47763002 8.54421998 3.55521152 1 P 0 Y
L 8.62178996 3.47763002 8.60545 3.46128996 1 P 0 
A 8.60545 3.46128996 8.57898573 3.44360906 8.5477685 3.51898002 1 P 0 Y
A 8.57898573 3.44360906 8.54776998 3.4374 8.5477685 3.51898002 1 P 0 Y
L 8.54776998 3.4374 8.4537 3.4374 1 P 0 
A 8.4537 3.4374 8.45 3.4337 8.4537 3.4337 1 P 0 N
L 8.45 3.4337 8.45 3.41615 1 P 0 
P 8.45 3.46615 5 P 0 0;2=3,4=1
P 8.14811004 5.0535 5 P 0 0;2=3,4=1
L 8.14811004 5.0535 8.16106004 5.0535 1 P 0 
A 8.16106004 5.0535 8.16476004 5.0498 8.16106004 5.0498 1 P 0 Y
L 8.16476004 5.0498 8.16476004 5.01661998 1 P 0 
L 8.16476004 5.01661998 8.17568996 4.95468002 1 P 0 
L 8.17568996 4.95468002 8.16656004 4.90293996 1 P 0 
L 8.16656004 4.90293996 8.16063996 4.89878996 1 P 0 
L 8.16063996 4.89878996 8.1587 4.88785 1 P 0 
L 8.1587 4.88785 8.16286004 4.88193996 1 P 0 
L 8.16286004 4.88193996 8.16091998 4.87098002 1 P 0 
L 8.16091998 4.87098002 8.155 4.86683002 1 P 0 
L 8.155 4.86683002 8.15306004 4.85588996 1 P 0 
L 8.15306004 4.85588996 8.15721998 4.84998002 1 P 0 
L 8.15721998 4.84998002 8.15456998 4.83496998 1 P 0 
L 8.15456998 4.83496998 8.16271998 4.78871998 1 P 0 
L 8.16271998 4.78871998 8.15091998 4.72186004 1 P 0 
L 8.15091998 4.72186004 8.12236998 4.68108996 1 P 0 
L 8.12236998 4.68108996 8.11458996 4.63703002 1 P 0 
L 8.11458996 4.63703002 8.1204 4.60408996 1 P 0 
A 8.1204 4.60408996 8.12302077 4.59637274 8.14678996 4.60874833 1 P 0 N
A 8.12302077 4.59637274 8.12783996 4.5898 8.14678996 4.60874744 1 P 0 N
L 8.12783996 4.5898 8.15763002 4.56001004 1 P 0 
A 8.15763002 4.56001004 8.16511191 4.54882116 8.13326004 4.53561811 1 P 0 Y
A 8.16511191 4.54882116 8.16773996 4.53561998 8.13326004 4.53561801 1 P 0 Y
L 8.16773996 4.53561998 8.16773996 4.52658002 1 P 0 
L 8.16773996 4.52658002 8.15681004 4.46455 1 P 0 
A 8.15681004 4.46455 8.15606998 4.46083002 8.07463996 4.47896348 1 P 0 Y
L 8.15606998 4.46083002 8.15606004 4.46081998 1 P 0 
A 8.15606004 4.46081998 8.13363002 4.42001004 8.07463996 4.47900118 1 P 0 Y
L 8.13363002 4.42001004 8.11623002 4.40261004 1 P 0 
A 8.11623002 4.40261004 8.0971435 4.38985837 8.07462756 4.44421998 1 P 0 Y
A 8.0971435 4.38985837 8.07463002 4.38538002 8.07462785 4.44421998 1 P 0 Y
L 8.07463002 4.38538002 8.07458996 4.38538002 1 P 0 
A 8.07458996 4.38538002 8.05940925 4.38840039 8.07459193 4.42505 1 P 0 Y
A 8.05940925 4.38840039 8.04653996 4.397 8.07459163 4.42505 1 P 0 Y
L 8.04653996 4.397 8.04406004 4.39948002 1 P 0 
A 8.04406004 4.39948002 8.03697156 4.40421575 8.02860522 4.38401998 1 P 0 N
A 8.03697156 4.40421575 8.02861004 4.40588002 8.02860541 4.38401998 1 P 0 N
L 8.02861004 4.40588002 8.02506004 4.40588002 1 P 0 
A 8.02506004 4.40588002 8.00858996 4.39903996 8.02508947 4.38256004 1 P 0 N
L 8.00858996 4.39903996 8.00858996 4.39905 1 P 0 
L 8.00858996 4.39905 8.00273996 4.3932 1 P 0 
A 8.00273996 4.3932 8.00273996 4.36258002 8.01805 4.37789006 1 P 0 N
L 8.00273996 4.36258002 8.01978002 4.34553996 1 P 0 
A 8.01978002 4.34553996 8.03544626 4.31973415 7.97486998 4.30061762 1 P 0 Y
A 8.03544626 4.31973415 8.03743002 4.28961004 7.97486998 4.30061762 1 P 0 Y
L 8.03743002 4.28961004 8.02801998 4.23613002 1 P 0 
L 8.02801998 4.23613002 8.02801998 4.23543002 1 P 0 
A 8.02801998 4.23543002 8.10123002 4.0587 8.27796004 4.23543858 1 P 0 N
L 8.10123002 4.0587 8.10123002 4.05868996 1 P 0 
A 8.10123002 4.05868996 8.10241004 4.05751998 8.2345065 4.19193002 1 P 0 N
A 8.10241004 4.05751998 8.16369547 4.01715748 8.23570276 4.1932 1 P 0 N
A 8.16369547 4.01715748 8.2357 4.003 8.23570295 4.1932 1 P 0 N
L 8.2357 4.003 8.26093002 4.003 1 P 0 
A 8.26093002 4.003 8.38763996 4.05548002 8.26092874 4.18221004 1 P 0 N
L 8.38763996 4.05548002 8.38766004 4.0555 1 P 0 
A 8.38766004 4.0555 8.42028002 4.0555 8.40397008 4.03918996 1 P 0 Y
L 8.42028002 4.0555 8.45396004 4.02181998 1 P 0 
A 8.45396004 4.02181998 8.47641004 4.01013996 8.48371181 4.05158996 1 P 0 N
L 8.47641004 4.01013996 8.5375 3.99935 1 P 0 
A 8.5375 3.99935 8.56311122 3.98938553 8.52525453 3.92998002 1 P 0 Y
A 8.56311122 3.98938553 8.58296004 3.97038002 8.52525305 3.92998002 1 P 0 Y
L 8.58296004 3.97038002 8.64841004 3.87688996 1 P 0 
L 8.64841004 3.87688996 8.67656004 3.71713996 1 P 0 
L 8.67656004 3.71713996 8.64486998 3.53745 1 P 0 
A 8.64486998 3.53745 8.63486929 3.50801043 8.54421998 3.55522264 1 P 0 Y
A 8.63486929 3.50801043 8.61648002 3.48293996 8.54421998 3.55522244 1 P 0 Y
L 8.61648002 3.48293996 8.60013996 3.4666 1 P 0 
A 8.60013996 3.4666 8.54778002 3.4449 8.54775915 3.51896998 1 P 0 Y
L 8.54778002 3.4449 8.4537 3.4449 1 P 0 
A 8.4537 3.4449 8.45 3.4486 8.4537 3.4486 1 P 0 Y
L 8.45 3.4486 8.45 3.46615 1 P 0 
P 8.45 3.26615 5 P 0 0;2=3,4=1
P 8.40071004 5.115 5 P 0 0;2=3,4=1
L 8.40071004 5.115 8.3883 5.115 1 P 0 
A 8.3883 5.115 8.3846 5.1113 8.3883 5.1113 1 P 0 N
L 8.3846 5.1113 8.3846 5.03666004 1 P 0 
L 8.3846 5.03666004 8.38073002 5.01468996 1 P 0 
L 8.38073002 5.01468996 8.32346004 4.93288996 1 P 0 
L 8.32346004 4.93288996 8.31546004 4.88745 1 P 0 
L 8.31546004 4.88745 8.32308002 4.84425 1 P 0 
L 8.32308002 4.84425 8.32285 4.84293996 1 P 0 
L 8.32285 4.84293996 8.32285 4.84295 1 P 0 
L 8.32285 4.84295 8.31218996 4.7825 1 P 0 
L 8.31218996 4.7825 8.32688002 4.69918996 1 P 0 
L 8.32688002 4.69918996 8.34466004 4.67381004 1 P 0 
L 8.34466004 4.67381004 8.40738002 4.62986998 1 P 0 
A 8.40738002 4.62986998 8.42160581 4.61363691 8.38131998 4.59268248 1 P 0 Y
A 8.42160581 4.61363691 8.42673002 4.59266998 8.38131998 4.59268159 1 P 0 Y
L 8.42673002 4.59266998 8.42673002 4.56673996 1 P 0 
L 8.42673002 4.56673996 8.42398996 4.55116998 1 P 0 
L 8.42398996 4.55116998 8.41405 4.53696004 1 P 0 
A 8.41405 4.53696004 8.40453996 4.514 8.43701004 4.51400049 1 P 0 N
A 8.40453996 4.514 8.42471004 4.49383002 8.42470994 4.514 1 P 0 N
L 8.42471004 4.49383002 8.45191998 4.49383002 1 P 0 
L 8.45191998 4.49383002 8.48956004 4.50046998 1 P 0 
L 8.48956004 4.50046998 8.49765 4.50046998 1 P 0 
A 8.49765 4.50046998 8.52694232 4.4935626 8.49767215 4.435 1 P 0 Y
A 8.52694232 4.4935626 8.55005 4.47428002 8.49767293 4.435 1 P 0 Y
L 8.55005 4.47428002 8.55006004 4.47426998 1 P 0 
L 8.55006004 4.47426998 8.6789 4.29026004 1 P 0 
A 8.6789 4.29026004 8.68076004 4.28576998 8.6697 4.2838186 1 P 0 Y
L 8.68076004 4.28576998 8.70456998 4.15066998 1 P 0 
L 8.70456998 4.15066998 8.70456998 4.15061998 1 P 0 
A 8.70456998 4.15061998 8.69577205 4.11468602 8.62678002 4.15062175 1 P 0 Y
A 8.69577205 4.11468602 8.67136998 4.08688002 8.62678002 4.15062175 1 P 0 Y
L 8.67136998 4.08688002 8.65986004 4.07881998 1 P 0 
L 8.65986004 4.07881998 8.65368002 4.07265 1 P 0 
A 8.65368002 4.07265 8.64353996 4.04816998 8.67816004 4.04816978 1 P 0 N
L 8.64353996 4.04816998 8.64353996 4.04168002 1 P 0 
A 8.64353996 4.04168002 8.64514754 4.03123681 8.67828002 4.04168238 1 P 0 N
A 8.64514754 4.03123681 8.64981998 4.02176004 8.67828002 4.04168228 1 P 0 N
L 8.64981998 4.02176004 8.72018996 3.92125 1 P 0 
L 8.72018996 3.92125 8.75578002 3.71941004 1 P 0 
L 8.75578002 3.71941004 8.70216998 3.4154 1 P 0 
A 8.70216998 3.4154 8.69691348 3.39990128 8.64918996 3.42472776 1 P 0 Y
A 8.69691348 3.39990128 8.68723996 3.3867 8.64918996 3.42472677 1 P 0 Y
L 8.68723996 3.3867 8.63351998 3.33298002 1 P 0 
A 8.63351998 3.33298002 8.58303396 3.2992436 8.52349282 3.44298996 1 P 0 Y
A 8.58303396 3.2992436 8.52348002 3.2874 8.52349222 3.44298996 1 P 0 Y
L 8.52348002 3.2874 8.4537 3.2874 1 P 0 
A 8.4537 3.2874 8.45 3.2837 8.4537 3.2837 1 P 0 N
L 8.45 3.2837 8.45 3.26615 1 P 0 
P 8.45 3.31615 5 P 0 0;2=3,4=1
P 8.36071004 5.115 5 P 0 0;2=3,4=1
L 8.36071004 5.115 8.3734 5.115 1 P 0 
A 8.3734 5.115 8.3771 5.1113 8.3734 5.1113 1 P 0 Y
L 8.3771 5.1113 8.3771 5.03731998 1 P 0 
L 8.3771 5.03731998 8.37363002 5.01763002 1 P 0 
L 8.37363002 5.01763002 8.35606998 4.99255 1 P 0 
L 8.35606998 4.99255 8.34931004 4.99136004 1 P 0 
L 8.34931004 4.99136004 8.34293002 4.98223996 1 P 0 
L 8.34293002 4.98223996 8.34413002 4.9755 1 P 0 
L 8.34413002 4.9755 8.33775 4.96638996 1 P 0 
L 8.33775 4.96638996 8.33098996 4.9652 1 P 0 
L 8.33098996 4.9652 8.32461004 4.95608002 1 P 0 
L 8.32461004 4.95608002 8.32581998 4.94933996 1 P 0 
L 8.32581998 4.94933996 8.31636004 4.93583002 1 P 0 
L 8.31636004 4.93583002 8.30783996 4.88745 1 P 0 
L 8.30783996 4.88745 8.30806004 4.88615 1 P 0 
L 8.30806004 4.88615 8.30806998 4.88615 1 P 0 
L 8.30806998 4.88615 8.31546004 4.84425 1 P 0 
L 8.31546004 4.84425 8.30456998 4.7825 1 P 0 
L 8.30456998 4.7825 8.31978002 4.69625 1 P 0 
L 8.31978002 4.69625 8.33926998 4.66841998 1 P 0 
L 8.33926998 4.66841998 8.40306998 4.62371998 1 P 0 
A 8.40306998 4.62371998 8.41923002 4.59266998 8.38131998 4.59266988 1 P 0 Y
L 8.41923002 4.59266998 8.41923002 4.5674 1 P 0 
L 8.41923002 4.5674 8.41688996 4.55411004 1 P 0 
L 8.41688996 4.55411004 8.40825 4.54176004 1 P 0 
A 8.40825 4.54176004 8.39994252 4.52897008 8.437 4.51399301 1 P 0 N
A 8.39994252 4.52897008 8.39703002 4.514 8.437 4.51399203 1 P 0 N
A 8.39703002 4.514 8.42471004 4.48633002 8.4247 4.514 1 P 0 N
L 8.42471004 4.48633002 8.45258002 4.48633002 1 P 0 
L 8.45258002 4.48633002 8.49021998 4.49296998 1 P 0 
L 8.49021998 4.49296998 8.49766004 4.49296998 1 P 0 
A 8.49766004 4.49296998 8.54403996 4.46976998 8.49765994 4.43501004 1 P 0 Y
L 8.54403996 4.46976998 8.54415 4.46963002 1 P 0 
L 8.54415 4.46963002 8.67275 4.28595 1 P 0 
A 8.67275 4.28595 8.67314075 4.2852439 8.66971004 4.2838065 1 P 0 Y
A 8.67314075 4.2852439 8.67336998 4.28446998 8.66971004 4.28380679 1 P 0 Y
L 8.67336998 4.28446998 8.69706004 4.15003002 1 P 0 
A 8.69706004 4.15003002 8.68897431 4.11789154 8.62678002 4.15062539 1 P 0 Y
A 8.68897431 4.11789154 8.66706004 4.09303002 8.62678002 4.15062392 1 P 0 Y
L 8.66706004 4.09303002 8.65501998 4.08458996 1 P 0 
L 8.65501998 4.08458996 8.64836998 4.07796004 1 P 0 
A 8.64836998 4.07796004 8.63924183 4.06429114 8.67816004 4.04818376 1 P 0 N
A 8.63924183 4.06429114 8.63603996 4.04816998 8.67816004 4.04818297 1 P 0 N
L 8.63603996 4.04816998 8.63603996 4.04166998 1 P 0 
A 8.63603996 4.04166998 8.63799232 4.02897333 8.67828996 4.04166831 1 P 0 N
A 8.63799232 4.02897333 8.64366998 4.01745 8.67828996 4.04166801 1 P 0 N
L 8.64366998 4.01745 8.71308996 3.91831004 1 P 0 
L 8.71308996 3.91831004 8.74816004 3.71941004 1 P 0 
L 8.74816004 3.71941004 8.69478002 3.4167 1 P 0 
A 8.69478002 3.4167 8.69025492 3.40336654 8.6492 3.42473435 1 P 0 Y
A 8.69025492 3.40336654 8.68193002 3.39201004 8.6492 3.42473238 1 P 0 Y
L 8.68193002 3.39201004 8.62821004 3.33828996 1 P 0 
A 8.62821004 3.33828996 8.52348002 3.2949 8.52347923 3.44298996 1 P 0 Y
L 8.52348002 3.2949 8.4537 3.2949 1 P 0 
A 8.4537 3.2949 8.45 3.2986 8.4537 3.2986 1 P 0 Y
L 8.45 3.2986 8.45 3.31615 1 P 0 
P 8.35 3.26615 5 P 0 0;2=3,4=1
P 8.40071004 4.742 5 P 0 0;2=3,4=1
L 8.40071004 4.742 8.3883 4.742 1 P 0 
A 8.3883 4.742 8.3846 4.7383 8.3883 4.7383 1 P 0 N
L 8.3846 4.7383 8.3846 4.70265 1 P 0 
A 8.3846 4.70265 8.41525 4.672 8.41525 4.70265 1 P 0 N
L 8.41525 4.672 8.42021004 4.672 1 P 0 
A 8.42021004 4.672 8.45733002 4.68371004 8.42021909 4.73666004 1 P 0 N
L 8.45733002 4.68371004 8.50495 4.71706998 1 P 0 
A 8.50495 4.71706998 8.51884016 4.72425315 8.53427776 4.67738002 1 P 0 Y
A 8.51884016 4.72425315 8.53428002 4.72673002 8.53427815 4.67738002 1 P 0 Y
L 8.53428002 4.72673002 8.53433996 4.72673002 1 P 0 
A 8.53433996 4.72673002 8.5621 4.71523996 8.53433967 4.68745 1 P 0 Y
L 8.5621 4.71523996 8.56213002 4.71521004 1 P 0 
A 8.56213002 4.71521004 8.57653996 4.6804 8.52728996 4.6804001 1 P 0 Y
L 8.57653996 4.6804 8.57653996 4.67268002 1 P 0 
A 8.57653996 4.67268002 8.56543996 4.64588996 8.53866004 4.67268032 1 P 0 Y
L 8.56543996 4.64588996 8.56186004 4.64231004 1 P 0 
L 8.56186004 4.64231004 8.5617 4.64231004 1 P 0 
L 8.5617 4.64231004 8.45933996 4.57061998 1 P 0 
A 8.45933996 4.57061998 8.45140354 4.56157057 8.47386998 4.54987215 1 P 0 N
A 8.45140354 4.56157057 8.44853996 4.54988002 8.47386998 4.54987146 1 P 0 N
A 8.44853996 4.54988002 8.47453002 4.52388996 8.47453002 4.54988002 1 P 0 N
L 8.47453002 4.52388996 8.48345 4.52388996 1 P 0 
L 8.48345 4.52388996 8.51025 4.52861004 1 P 0 
A 8.51025 4.52861004 8.53367274 4.52707667 8.51882864 4.47998996 1 P 0 Y
A 8.53367274 4.52707667 8.55373996 4.5149 8.51882874 4.47998996 1 P 0 Y
L 8.55373996 4.5149 8.55423002 4.5144 1 P 0 
L 8.55423002 4.5144 8.62698996 4.4105 1 P 0 
L 8.62698996 4.4105 8.627 4.4105 1 P 0 
L 8.627 4.4105 8.69936004 4.30715 1 P 0 
A 8.69936004 4.30715 8.70541998 4.29253002 8.66943002 4.28617815 1 P 0 Y
L 8.70541998 4.29253002 8.73263996 4.13806998 1 P 0 
L 8.73263996 4.13806998 8.73263996 4.13738002 1 P 0 
A 8.73263996 4.13738002 8.7249437 4.10548986 8.66278002 4.13736604 1 P 0 Y
A 8.7249437 4.10548986 8.70353996 4.08063002 8.66278002 4.13736732 1 P 0 Y
L 8.70353996 4.08063002 8.70351998 4.0806 1 P 0 
L 8.70351998 4.0806 8.68391004 4.06681004 1 P 0 
A 8.68391004 4.06681004 8.67481811 4.05640906 8.70066998 4.04298514 1 P 0 N
A 8.67481811 4.05640906 8.67153996 4.04298996 8.70066998 4.04298376 1 P 0 N
A 8.67153996 4.04298996 8.67351132 4.03018268 8.71416004 4.04299488 1 P 0 N
A 8.67351132 4.03018268 8.67923996 4.01856004 8.71416004 4.04299478 1 P 0 N
L 8.67923996 4.01856004 8.7495 3.91823002 1 P 0 
L 8.7495 3.91823002 8.78536998 3.71481998 1 P 0 
L 8.78536998 3.71481998 8.72863996 3.39313996 1 P 0 
L 8.72863996 3.39313996 8.65773996 3.29188002 1 P 0 
L 8.65773996 3.29188002 8.62243002 3.26713002 1 P 0 
A 8.62243002 3.26713002 8.5282 3.2374 8.52819911 3.4016 1 P 0 Y
L 8.5282 3.2374 8.38558996 3.2374 1 P 0 
A 8.38558996 3.2374 8.37125 3.25173996 8.38558996 3.25173996 1 P 0 Y
L 8.37125 3.25173996 8.37125 3.2833 1 P 0 
A 8.37125 3.2833 8.36715 3.2874 8.36715 3.2833 1 P 0 N
L 8.36715 3.2874 8.3537 3.2874 1 P 0 
A 8.3537 3.2874 8.35 3.2837 8.3537 3.2837 1 P 0 N
L 8.35 3.2837 8.35 3.26615 1 P 0 
P 8.35 3.31615 5 P 0 0;2=3,4=1
P 8.36071004 4.742 5 P 0 0;2=3,4=1
L 8.36071004 4.742 8.3734 4.742 1 P 0 
A 8.3734 4.742 8.3771 4.7383 8.3734 4.7383 1 P 0 Y
L 8.3771 4.7383 8.3771 4.70265 1 P 0 
A 8.3771 4.70265 8.41525 4.6645 8.41525 4.70265 1 P 0 N
L 8.41525 4.6645 8.4202 4.6645 1 P 0 
A 8.4202 4.6645 8.44192598 4.6678375 8.42023278 4.73666998 1 P 0 N
A 8.44192598 4.6678375 8.46163996 4.67756004 8.42023366 4.73666998 1 P 0 N
L 8.46163996 4.67756004 8.51028002 4.71163002 1 P 0 
L 8.51028002 4.71163002 8.51028002 4.71165 1 P 0 
A 8.51028002 4.71165 8.52170148 4.71728888 8.53429724 4.67738996 1 P 0 Y
A 8.52170148 4.71728888 8.53428996 4.71923002 8.53429774 4.67738996 1 P 0 Y
L 8.53428996 4.71923002 8.53433002 4.71923002 1 P 0 
A 8.53433002 4.71923002 8.54648455 4.7168123 8.53432618 4.68745 1 P 0 Y
A 8.54648455 4.7168123 8.55678996 4.70993002 8.53432628 4.68745 1 P 0 Y
L 8.55678996 4.70993002 8.55681998 4.7099 1 P 0 
A 8.55681998 4.7099 8.56903002 4.6804 8.52728996 4.68040069 1 P 0 Y
L 8.56903002 4.6804 8.56903996 4.68041004 1 P 0 
L 8.56903996 4.68041004 8.56903996 4.67268002 1 P 0 
A 8.56903996 4.67268002 8.56013002 4.6512 8.53866998 4.67268957 1 P 0 Y
L 8.56013002 4.6512 8.5574 4.64846998 1 P 0 
L 8.5574 4.64846998 8.55741004 4.64846998 1 P 0 
L 8.55741004 4.64846998 8.45503002 4.57676004 1 P 0 
L 8.45503002 4.57676004 8.45503002 4.57676998 1 P 0 
A 8.45503002 4.57676998 8.44474154 4.56503691 8.47386998 4.54987215 1 P 0 N
A 8.44474154 4.56503691 8.44103002 4.54988002 8.47386998 4.54987126 1 P 0 N
A 8.44103002 4.54988002 8.47453002 4.51638996 8.47452008 4.54988002 1 P 0 N
L 8.47453002 4.51638996 8.48411004 4.51638996 1 P 0 
L 8.48411004 4.51638996 8.51155 4.52121998 1 P 0 
A 8.51155 4.52121998 8.53139833 4.51992559 8.51882697 4.47998002 1 P 0 Y
A 8.53139833 4.51992559 8.54841004 4.50961998 8.51882687 4.47998002 1 P 0 Y
L 8.54841004 4.50961998 8.5484 4.50961998 1 P 0 
L 8.5484 4.50961998 8.54846004 4.50956004 1 P 0 
L 8.54846004 4.50956004 8.69321004 4.30283996 1 P 0 
A 8.69321004 4.30283996 8.69625581 4.29729902 8.66943996 4.28616634 1 P 0 Y
A 8.69625581 4.29729902 8.69803002 4.29123002 8.66943996 4.28616585 1 P 0 Y
L 8.69803002 4.29123002 8.72513996 4.13741004 1 P 0 
L 8.72513996 4.13741004 8.72513996 4.13736998 1 P 0 
A 8.72513996 4.13736998 8.71813219 4.10864675 8.66278996 4.13736535 1 P 0 Y
A 8.71813219 4.10864675 8.69868002 4.08638002 8.66278996 4.13736348 1 P 0 Y
L 8.69868002 4.08638002 8.69866998 4.08636998 1 P 0 
L 8.69866998 4.08636998 8.67958996 4.07295 1 P 0 
A 8.67958996 4.07295 8.66815384 4.0598686 8.70066998 4.04298159 1 P 0 N
A 8.66815384 4.0598686 8.66403002 4.04298996 8.70066998 4.0429811 1 P 0 N
A 8.66403002 4.04298996 8.66634941 4.02792293 8.71416004 4.04299488 1 P 0 N
A 8.66634941 4.02792293 8.67308996 4.01425 8.71416004 4.04299488 1 P 0 N
L 8.67308996 4.01425 8.7424 3.91528996 1 P 0 
L 8.7424 3.91528996 8.77775 3.71481998 1 P 0 
L 8.77775 3.71481998 8.72153996 3.39608002 1 P 0 
L 8.72153996 3.39608002 8.69995 3.36525 1 P 0 
L 8.69995 3.36525 8.69056004 3.3636 1 P 0 
L 8.69056004 3.3636 8.68418002 3.3545 1 P 0 
L 8.68418002 3.3545 8.68585 3.34511998 1 P 0 
L 8.68585 3.34511998 8.67946998 3.33601004 1 P 0 
L 8.67946998 3.33601004 8.67008002 3.33436004 1 P 0 
L 8.67008002 3.33436004 8.6637 3.32526004 1 P 0 
L 8.6637 3.32526004 8.66536998 3.31586998 1 P 0 
L 8.66536998 3.31586998 8.65235 3.29726998 1 P 0 
L 8.65235 3.29726998 8.61811998 3.27328002 1 P 0 
A 8.61811998 3.27328002 8.57534518 3.25216614 8.52818219 3.4016 1 P 0 Y
A 8.57534518 3.25216614 8.5282 3.2449 8.5281815 3.4016 1 P 0 Y
L 8.5282 3.2449 8.38558996 3.2449 1 P 0 
A 8.38558996 3.2449 8.37875 3.25173996 8.38558996 3.25173996 1 P 0 Y
L 8.37875 3.25173996 8.37875 3.2833 1 P 0 
A 8.37875 3.2833 8.36715 3.2949 8.36715 3.2833 1 P 0 N
L 8.36715 3.2949 8.3537 3.2949 1 P 0 
A 8.3537 3.2949 8.35 3.2986 8.3537 3.2986 1 P 0 Y
L 8.35 3.2986 8.35 3.31615 1 P 0 
P 8.05 3.31615 5 P 0 0;2=3,4=1
P 7.58118996 5.169 5 P 0 0;2=3,4=1
L 7.58118996 5.169 7.59301998 5.169 1 P 0 
A 7.59301998 5.169 7.59671998 5.1653 7.59301998 5.1653 1 P 0 Y
L 7.59671998 5.1653 7.59671998 5.04251004 1 P 0 
L 7.59671998 5.04251004 7.60221998 5.01131004 1 P 0 
L 7.60221998 5.01131004 7.72285 4.83905 1 P 0 
L 7.72285 4.83905 7.72691998 4.81598002 1 P 0 
L 7.72691998 4.81598002 7.72451998 4.80235 1 P 0 
L 7.72451998 4.80235 7.7304 4.76878002 1 P 0 
L 7.7304 4.76878002 7.71666998 4.69086998 1 P 0 
L 7.71666998 4.69086998 7.64745 4.59203002 1 P 0 
L 7.64745 4.59203002 7.58268002 4.52726004 1 P 0 
A 7.58268002 4.52726004 7.54967116 4.50722569 7.52524537 4.58468002 1 P 0 Y
A 7.54967116 4.50722569 7.51113996 4.5047 7.52524567 4.58468002 1 P 0 Y
L 7.51113996 4.5047 7.46316004 4.51316004 1 P 0 
A 7.46316004 4.51316004 7.41457087 4.50997785 7.44536801 4.41228002 1 P 0 N
A 7.41457087 4.50997785 7.37293996 4.48471998 7.44536752 4.41228002 1 P 0 N
L 7.37293996 4.48471998 7.36168002 4.47346004 1 P 0 
A 7.36168002 4.47346004 7.32041004 4.34256998 7.46678002 4.36837047 1 P 0 N
L 7.32041004 4.34256998 7.42763996 3.73426998 1 P 0 
A 7.42763996 3.73426998 7.47261998 3.62566004 7.69501004 3.78138032 1 P 0 N
L 7.47261998 3.62566004 7.50838002 3.5746 1 P 0 
L 7.50838002 3.5746 7.50838996 3.57458996 1 P 0 
L 7.50838996 3.57458996 7.61641998 3.42033002 1 P 0 
L 7.61641998 3.42033002 7.69493996 3.36535 1 P 0 
L 7.69493996 3.36535 7.94205 3.32178996 1 P 0 
L 7.94205 3.32178996 8.03061998 3.3374 1 P 0 
L 8.03061998 3.3374 8.04653996 3.3374 1 P 0 
L 8.04653996 3.3374 8.04671998 3.33738002 1 P 0 
A 8.04671998 3.33738002 8.04906201 3.33616476 8.04629675 3.3337 1 P 0 Y
A 8.04906201 3.33616476 8.05 3.3337 8.0463 3.33370276 1 P 0 Y
L 8.05 3.3337 8.05 3.31615 1 P 0 
P 8.05 3.36615 5 P 0 0;2=3,4=1
P 7.62118996 5.169 5 P 0 0;2=3,4=1
L 7.62118996 5.169 7.60791998 5.169 1 P 0 
A 7.60791998 5.169 7.60421998 5.1653 7.60791998 5.1653 1 P 0 N
L 7.60421998 5.1653 7.60421998 5.11758996 1 P 0 
L 7.60421998 5.11758996 7.60853996 5.11326998 1 P 0 
L 7.60853996 5.11326998 7.60853996 5.10216998 1 P 0 
L 7.60853996 5.10216998 7.60421998 5.09785 1 P 0 
L 7.60421998 5.09785 7.60421998 5.08675 1 P 0 
L 7.60421998 5.08675 7.60853996 5.08243002 1 P 0 
L 7.60853996 5.08243002 7.60853996 5.07133002 1 P 0 
L 7.60853996 5.07133002 7.60421998 5.06701004 1 P 0 
L 7.60421998 5.06701004 7.60421998 5.04316998 1 P 0 
L 7.60421998 5.04316998 7.60931998 5.01425 1 P 0 
L 7.60931998 5.01425 7.72995 4.84198996 1 P 0 
L 7.72995 4.84198996 7.73453996 4.81598002 1 P 0 
L 7.73453996 4.81598002 7.73213996 4.80235 1 P 0 
L 7.73213996 4.80235 7.73801998 4.76878002 1 P 0 
L 7.73801998 4.76878002 7.72376998 4.68793002 1 P 0 
L 7.72376998 4.68793002 7.65321998 4.58718996 1 P 0 
L 7.65321998 4.58718996 7.58798996 4.52195 1 P 0 
A 7.58798996 4.52195 7.55192972 4.50006713 7.52525285 4.58468002 1 P 0 Y
A 7.55192972 4.50006713 7.50983996 4.49731004 7.52525197 4.58468002 1 P 0 Y
L 7.50983996 4.49731004 7.46186004 4.50576998 1 P 0 
A 7.46186004 4.50576998 7.41683071 4.50281811 7.44537795 4.41226998 1 P 0 N
A 7.41683071 4.50281811 7.37825 4.47941004 7.44537736 4.41226998 1 P 0 N
L 7.37825 4.47941004 7.36698996 4.46815 1 P 0 
A 7.36698996 4.46815 7.33219114 4.41080384 7.46678002 4.36836398 1 P 0 N
A 7.33219114 4.41080384 7.3278 4.34386998 7.46678002 4.36836329 1 P 0 N
L 7.3278 4.34386998 7.43503002 3.73556998 1 P 0 
A 7.43503002 3.73556998 7.45111624 3.68037441 7.69501004 3.78139675 1 P 0 N
A 7.45111624 3.68037441 7.47876998 3.62996998 7.69501004 3.78139547 1 P 0 N
L 7.47876998 3.62996998 7.62181004 3.42571998 1 P 0 
L 7.62181004 3.42571998 7.69788002 3.37245 1 P 0 
L 7.69788002 3.37245 7.94205 3.32941004 1 P 0 
L 7.94205 3.32941004 8.02996004 3.3449 1 P 0 
L 8.02996004 3.3449 8.0463 3.3449 1 P 0 
L 8.0463 3.3449 8.04671998 3.34491998 1 P 0 
A 8.04671998 3.34491998 8.04906201 3.34613524 8.04629675 3.3486 1 P 0 N
A 8.04906201 3.34613524 8.05 3.3486 8.0463 3.34859724 1 P 0 N
L 8.05 3.3486 8.05 3.36615 1 P 0 
P 10.82676998 5.49685 8 P 0 0;2=5,4=0
P 10.99213002 5.49685 8 P 0 0;2=5,4=0
P 11.15748002 5.49685 8 P 0 0;2=5,4=0
P 11.32283996 5.49685 8 P 0 0;2=5,4=0
P 11.48818996 5.49685 8 P 0 0;2=5,4=0
P 11.65353996 5.49685 8 P 0 0;2=5,4=0
P 11.8189 5.49685 8 P 0 0;2=5,4=0
P 11.98425 5.49685 8 P 0 0;2=5,4=0
P 12.14961004 5.49685 8 P 0 0;2=6,4=0
P 10.80498996 5.56656004 6 P 0 0;2=1,4=1
P 10.84498996 5.56656004 6 P 0 0;2=1,4=1
P 10.80498996 5.42656004 6 P 0 0;2=1,4=1
P 10.84498996 5.42656004 6 P 0 0;2=1,4=1
P 11.01035 5.42656004 6 P 0 0;2=1,4=1
P 10.97035 5.42656004 6 P 0 0;2=1,4=1
P 11.01035 5.56656004 6 P 0 0;2=1,4=1
P 10.97035 5.56656004 6 P 0 0;2=1,4=1
P 11.17571004 5.42656004 6 P 0 0;2=1,4=1
P 11.13571004 5.42656004 6 P 0 0;2=1,4=1
P 11.17571004 5.56656004 6 P 0 0;2=1,4=1
P 11.13571004 5.56656004 6 P 0 0;2=1,4=1
P 11.34106998 5.42656004 6 P 0 0;2=1,4=1
P 11.30106998 5.42656004 6 P 0 0;2=1,4=1
P 11.34106998 5.56656004 6 P 0 0;2=1,4=1
P 11.30106998 5.56656004 6 P 0 0;2=1,4=1
P 11.50643002 5.42656004 6 P 0 0;2=1,4=1
P 11.46643002 5.42656004 6 P 0 0;2=1,4=1
P 11.50643002 5.56656004 6 P 0 0;2=1,4=1
P 11.46643002 5.56656004 6 P 0 0;2=1,4=1
P 11.67178996 5.42656004 6 P 0 0;2=1,4=1
P 11.63178996 5.42656004 6 P 0 0;2=1,4=1
P 11.67178996 5.56656004 6 P 0 0;2=1,4=1
P 11.63178996 5.56656004 6 P 0 0;2=1,4=1
P 11.83715 5.42656004 6 P 0 0;2=1,4=1
P 11.79715 5.42656004 6 P 0 0;2=1,4=1
P 11.83715 5.56656004 6 P 0 0;2=1,4=1
P 11.79715 5.56656004 6 P 0 0;2=1,4=1
P 12.00251004 5.42656004 6 P 0 0;2=1,4=1
P 11.96251004 5.42656004 6 P 0 0;2=1,4=1
P 12.00251004 5.56656004 6 P 0 0;2=1,4=1
P 11.96251004 5.56656004 6 P 0 0;2=1,4=1
P 12.16786998 5.42656004 6 P 0 0;2=1,4=1
P 12.12786998 5.42656004 6 P 0 0;2=1,4=1
P 12.16786998 5.56656004 6 P 0 0;2=1,4=1
P 12.12786998 5.56656004 6 P 0 0;2=1,4=1
S P 0
OB 10.78 5.565 I
OS 10.8 5.585
OS 12.19 5.585
OS 12.205 5.57
OS 12.205 5.42
OS 12.19 5.405
OS 10.8 5.405
OS 10.78 5.425
OS 10.78 5.565
OE
SE
P 8.2 3.26615 5 P 0 0;2=3,4=1
P 7.65203996 5.0535 5 P 0 0;2=3,4=1
L 8.2 3.26615 8.2 3.2837 1 P 0 
A 8.2 3.2837 8.19906201 3.28616476 8.1963 3.28370276 1 P 0 N
A 8.19906201 3.28616476 8.19671998 3.28738002 8.19629675 3.2837 1 P 0 N
L 8.19671998 3.28738002 8.19653996 3.2874 1 P 0 
L 8.19653996 3.2874 8.18591998 3.2874 1 P 0 
A 8.18591998 3.2874 8.17125 3.30206998 8.18591998 3.30206998 1 P 0 Y
L 8.17125 3.30206998 8.17125 3.3796 1 P 0 
A 8.17125 3.3796 8.16345 3.3874 8.16345 3.3796 1 P 0 N
L 8.16345 3.3874 8.0472 3.3874 1 P 0 
A 8.0472 3.3874 8.04197963 3.38654685 8.04720679 3.37096004 1 P 0 N
A 8.04197963 3.38654685 8.0373 3.38408002 8.0472061 3.37096004 1 P 0 N
A 8.0373 3.38408002 8.03556998 3.38256998 8.047219 3.37096998 1 P 0 N
L 8.03556998 3.38256998 8.03556004 3.38256998 1 P 0 
L 8.03556004 3.38256998 8.02226004 3.36926998 1 P 0 
A 8.02226004 3.36926998 8.0115 3.36366998 8.00800118 3.38353002 1 P 0 Y
L 8.0115 3.36366998 7.93636004 3.35043996 1 P 0 
L 7.93636004 3.35043996 7.69786998 3.39246998 1 P 0 
L 7.69786998 3.39246998 7.63298002 3.4379 1 P 0 
L 7.63298002 3.4379 7.48851998 3.64421998 1 P 0 
A 7.48851998 3.64421998 7.46579803 3.68564203 7.66626998 3.76866732 1 P 0 Y
A 7.46579803 3.68564203 7.45258002 3.731 7.66626998 3.76866762 1 P 0 Y
L 7.45258002 3.731 7.35151004 4.30416004 1 P 0 
A 7.35151004 4.30416004 7.34686998 4.35728996 7.65333996 4.3572877 1 P 0 Y
A 7.34686998 4.35728996 7.39046998 4.46255 7.49573002 4.35729016 1 P 0 Y
L 7.39046998 4.46255 7.39686004 4.46893996 1 P 0 
A 7.39686004 4.46893996 7.42034272 4.48462549 7.44802628 4.41776004 1 P 0 Y
A 7.42034272 4.48462549 7.44803996 4.49013002 7.44802707 4.41776004 1 P 0 Y
L 7.44803996 4.49013002 7.44871004 4.49013002 1 P 0 
L 7.44871004 4.49013002 7.52415 4.47685 1 P 0 
A 7.52415 4.47685 7.56017785 4.47922205 7.53731654 4.55166004 1 P 0 N
A 7.56017785 4.47922205 7.59103996 4.49796004 7.53731644 4.55166004 1 P 0 N
L 7.59103996 4.49796004 7.64993996 4.55686004 1 P 0 
L 7.64993996 4.55686004 7.64995 4.55686004 1 P 0 
L 7.64995 4.55686004 7.73871004 4.68361004 1 P 0 
L 7.73871004 4.68361004 7.75336004 4.76666998 1 P 0 
L 7.75336004 4.76666998 7.74731004 4.80111004 1 P 0 
L 7.74731004 4.80111004 7.75193002 4.82736998 1 P 0 
L 7.75193002 4.82736998 7.73363996 4.93108002 1 P 0 
L 7.73363996 4.93108002 7.66756998 5.02541998 1 P 0 
L 7.66756998 5.02541998 7.66756998 5.04846998 1 P 0 
A 7.66756998 5.04846998 7.66253996 5.0535 7.66253996 5.04846998 1 P 0 N
L 7.66253996 5.0535 7.65203996 5.0535 1 P 0 
P 7.69203996 5.0535 5 P 0 0;2=3,4=1
P 8.2 3.31615 5 P 0 0;2=3,4=1
L 8.2 3.31615 8.2 3.2986 1 P 0 
A 8.2 3.2986 8.19906201 3.29613524 8.1963 3.29859724 1 P 0 Y
A 8.19906201 3.29613524 8.19671998 3.29491998 8.19629675 3.2986 1 P 0 Y
L 8.19671998 3.29491998 8.1963 3.2949 1 P 0 
L 8.1963 3.2949 8.18591998 3.2949 1 P 0 
A 8.18591998 3.2949 8.17875 3.30206998 8.18591998 3.30206998 1 P 0 Y
L 8.17875 3.30206998 8.17875 3.3796 1 P 0 
A 8.17875 3.3796 8.16345 3.3949 8.16345 3.3796 1 P 0 N
L 8.16345 3.3949 8.04718996 3.3949 1 P 0 
A 8.04718996 3.3949 8.03278002 3.39006998 8.0471999 3.37096004 1 P 0 N
L 8.03278002 3.39006998 8.03245 3.39006998 1 P 0 
L 8.03245 3.39006998 8.01695 3.37458002 1 P 0 
A 8.01695 3.37458002 8.0102 3.37106004 8.00798996 3.38353002 1 P 0 Y
L 8.0102 3.37106004 7.93636004 3.35806004 1 P 0 
L 7.93636004 3.35806004 7.70081004 3.39956998 1 P 0 
L 7.70081004 3.39956998 7.63836998 3.44328996 1 P 0 
L 7.63836998 3.44328996 7.49466998 3.64853002 1 P 0 
A 7.49466998 3.64853002 7.47273337 3.68851506 7.66626998 3.76868327 1 P 0 Y
A 7.47273337 3.68851506 7.45996998 3.7323 7.66626998 3.76868406 1 P 0 Y
L 7.45996998 3.7323 7.3589 4.30546004 1 P 0 
A 7.3589 4.30546004 7.35438002 4.35728996 7.65335 4.35725049 1 P 0 Y
A 7.35438002 4.35728996 7.36514016 4.41138238 7.49573996 4.35728691 1 P 0 Y
A 7.36514016 4.41138238 7.39578002 4.45723996 7.49573996 4.35728661 1 P 0 Y
L 7.39578002 4.45723996 7.40216998 4.46363002 1 P 0 
A 7.40216998 4.46363002 7.44803996 4.48263002 7.44803996 4.41776004 1 P 0 Y
L 7.44803996 4.48263002 7.44805 4.48263002 1 P 0 
L 7.44805 4.48263002 7.52285 4.46946004 1 P 0 
A 7.52285 4.46946004 7.56243652 4.47206339 7.53732313 4.55166004 1 P 0 N
A 7.56243652 4.47206339 7.59635 4.49265 7.53732382 4.55166004 1 P 0 N
L 7.59635 4.49265 7.65571998 4.55201998 1 P 0 
L 7.65571998 4.55201998 7.74581004 4.68066998 1 P 0 
L 7.74581004 4.68066998 7.76075 4.76536998 1 P 0 
L 7.76075 4.76536998 7.76075 4.76536004 1 P 0 
L 7.76075 4.76536004 7.76098002 4.76666998 1 P 0 
L 7.76098002 4.76666998 7.75493002 4.80111004 1 P 0 
L 7.75493002 4.80111004 7.75955 4.82736998 1 P 0 
L 7.75955 4.82736998 7.74073996 4.93401998 1 P 0 
L 7.74073996 4.93401998 7.7315 4.94725 1 P 0 
L 7.7315 4.94725 7.73253002 4.95303002 1 P 0 
L 7.73253002 4.95303002 7.72615 4.96213002 1 P 0 
L 7.72615 4.96213002 7.72036004 4.96315 1 P 0 
L 7.72036004 4.96315 7.71398002 4.97225 1 P 0 
L 7.71398002 4.97225 7.71501004 4.97803002 1 P 0 
L 7.71501004 4.97803002 7.70863002 4.98713002 1 P 0 
L 7.70863002 4.98713002 7.70283996 4.98815 1 P 0 
L 7.70283996 4.98815 7.67506998 5.02778996 1 P 0 
L 7.67506998 5.02778996 7.67506998 5.0498 1 P 0 
A 7.67506998 5.0498 7.67876998 5.0535 7.67876998 5.0498 1 P 0 Y
L 7.67876998 5.0535 7.69203996 5.0535 1 P 0 
P 8.2 3.41615 5 P 0 0;2=3,4=1
P 7.86465 5.169 5 P 0 0;2=3,4=1
L 8.2 3.41615 8.2 3.4337 1 P 0 
A 8.2 3.4337 8.19906201 3.43616476 8.1963 3.43370276 1 P 0 N
A 8.19906201 3.43616476 8.19671998 3.43738002 8.19629675 3.4337 1 P 0 N
L 8.19671998 3.43738002 8.19653996 3.4374 1 P 0 
L 8.19653996 3.4374 8.13936998 3.4374 1 P 0 
A 8.13936998 3.4374 8.12125 3.45551998 8.13936998 3.45551998 1 P 0 Y
L 8.12125 3.45551998 8.12125 3.46998996 1 P 0 
A 8.12125 3.46998996 8.11693996 3.48036998 8.10656998 3.46997923 1 P 0 N
L 8.11693996 3.48036998 8.11398996 3.48331998 1 P 0 
A 8.11398996 3.48331998 8.10948071 3.4863373 8.10414813 3.47348996 1 P 0 N
A 8.10948071 3.4863373 8.10416004 3.4874 8.10414823 3.47348996 1 P 0 N
L 8.10416004 3.4874 8.0361 3.4874 1 P 0 
A 8.0361 3.4874 8.02875 3.48005 8.0361 3.48005 1 P 0 N
L 8.02875 3.48005 8.02875 3.46033002 1 P 0 
A 8.02875 3.46033002 8.02755069 3.45431201 8.01301998 3.46033632 1 P 0 Y
A 8.02755069 3.45431201 8.02413996 3.44921004 8.01301998 3.46033494 1 P 0 Y
L 8.02413996 3.44921004 8.01773002 3.4428 1 P 0 
A 8.01773002 3.4428 8.01174685 3.43880305 8.00469222 3.45583996 1 P 0 Y
A 8.01174685 3.43880305 8.00468996 3.4374 8.00469163 3.45583996 1 P 0 Y
L 8.00468996 3.4374 7.94983002 3.4374 1 P 0 
L 7.94983002 3.4374 7.79615 3.4645 1 P 0 
L 7.79615 3.4645 7.55968996 3.63006004 1 P 0 
L 7.55968996 3.63006004 7.55921004 3.63053002 1 P 0 
A 7.55921004 3.63053002 7.50193996 3.74056004 7.70506998 3.7763688 1 P 0 Y
L 7.50193996 3.74056004 7.4398 4.09286998 1 P 0 
L 7.4398 4.09286998 7.4398 4.1129 1 P 0 
L 7.4398 4.1129 7.44011004 4.11321004 1 P 0 
A 7.44011004 4.11321004 7.44438376 4.12786663 7.48568002 4.10787362 1 P 0 Y
A 7.44438376 4.12786663 7.45323002 4.14031004 7.48568002 4.10787451 1 P 0 Y
L 7.45323002 4.14031004 7.45323996 4.14031004 1 P 0 
A 7.45323996 4.14031004 7.49473002 4.1575 7.49474006 4.09881004 1 P 0 Y
L 7.49473002 4.1575 7.50291998 4.1575 1 P 0 
A 7.50291998 4.1575 7.55116496 4.17505453 7.5029247 4.23256004 1 P 0 N
A 7.55116496 4.17505453 7.57683996 4.21951004 7.50293002 4.23255423 1 P 0 N
L 7.57683996 4.21951004 7.60803996 4.39646004 1 P 0 
L 7.60803996 4.39646004 7.60803002 4.39646004 1 P 0 
L 7.60803002 4.39646004 7.60803996 4.39646998 1 P 0 
A 7.60803996 4.39646998 7.62653996 4.44113002 7.7181 4.37704035 1 P 0 Y
L 7.62653996 4.44113002 7.80571004 4.69696998 1 P 0 
L 7.80571004 4.69696998 7.84056998 4.72138002 1 P 0 
L 7.84056998 4.72138002 7.8541 4.72376998 1 P 0 
L 7.8541 4.72376998 7.86176004 4.72913002 1 P 0 
L 7.86176004 4.72913002 7.86893002 4.7394 1 P 0 
L 7.86893002 4.7394 7.88895 4.85283002 1 P 0 
L 7.88895 4.85283002 7.87738002 4.91841998 1 P 0 
L 7.87738002 4.91841998 7.88966998 4.98811004 1 P 0 
L 7.88966998 4.98811004 7.87278996 5.08375 1 P 0 
L 7.87278996 5.08375 7.88018002 5.12566004 1 P 0 
L 7.88018002 5.12566004 7.88018002 5.1653 1 P 0 
A 7.88018002 5.1653 7.87648002 5.169 7.87648002 5.1653 1 P 0 N
L 7.87648002 5.169 7.86465 5.169 1 P 0 
P 2.34606004 3.26615 5 P 0 0;2=3,4=1
P 2.39716998 4.742 5 P 0 0;2=3,4=1
L 2.39716998 4.742 2.38476004 4.742 1 P 0 
A 2.38476004 4.742 2.38106004 4.7383 2.38476004 4.7383 1 P 0 N
L 2.38106004 4.7383 2.38106004 4.70265 1 P 0 
A 2.38106004 4.70265 2.41171004 4.672 2.41171004 4.70265 1 P 0 N
L 2.41171004 4.672 2.41666998 4.672 1 P 0 
A 2.41666998 4.672 2.45378996 4.68371004 2.41667904 4.73666004 1 P 0 N
L 2.45378996 4.68371004 2.50141004 4.71706998 1 P 0 
A 2.50141004 4.71706998 2.5153001 4.72425305 2.5307375 4.67738002 1 P 0 Y
A 2.5153001 4.72425305 2.53073996 4.72673002 2.53073839 4.67738002 1 P 0 Y
L 2.53073996 4.72673002 2.5308 4.72673002 1 P 0 
A 2.5308 4.72673002 2.55856004 4.71523996 2.5307997 4.68745 1 P 0 Y
L 2.55856004 4.71523996 2.55858996 4.71521004 1 P 0 
A 2.55858996 4.71521004 2.573 4.6804 2.52375 4.6804 1 P 0 Y
L 2.573 4.6804 2.573 4.67268002 1 P 0 
A 2.573 4.67268002 2.5619 4.64588996 2.53511998 4.67268041 1 P 0 Y
L 2.5619 4.64588996 2.55831998 4.64231004 1 P 0 
L 2.55831998 4.64231004 2.55816004 4.64231004 1 P 0 
L 2.55816004 4.64231004 2.4558 4.57061998 1 P 0 
A 2.4558 4.57061998 2.44786358 4.56157057 2.47033002 4.54987215 1 P 0 N
A 2.44786358 4.56157057 2.445 4.54988002 2.47033002 4.54987146 1 P 0 N
A 2.445 4.54988002 2.47098996 4.52388996 2.47098996 4.54987992 1 P 0 N
L 2.47098996 4.52388996 2.47991004 4.52388996 1 P 0 
L 2.47991004 4.52388996 2.50671004 4.52861004 1 P 0 
A 2.50671004 4.52861004 2.53013278 4.52707667 2.51528868 4.47998996 1 P 0 Y
A 2.53013278 4.52707667 2.5502 4.5149 2.51528878 4.47998996 1 P 0 Y
L 2.5502 4.5149 2.55068996 4.5144 1 P 0 
L 2.55068996 4.5144 2.62345 4.4105 1 P 0 
L 2.62345 4.4105 2.62346004 4.4105 1 P 0 
L 2.62346004 4.4105 2.69581998 4.30715 1 P 0 
A 2.69581998 4.30715 2.70188002 4.29253002 2.66588996 4.28617795 1 P 0 Y
L 2.70188002 4.29253002 2.7291 4.13806998 1 P 0 
L 2.7291 4.13806998 2.7291 4.13738002 1 P 0 
A 2.7291 4.13738002 2.72140374 4.10548986 2.65923996 4.13736604 1 P 0 Y
A 2.72140374 4.10548986 2.7 4.08063002 2.65923996 4.13736742 1 P 0 Y
L 2.7 4.08063002 2.69998002 4.0806 1 P 0 
L 2.69998002 4.0806 2.68036998 4.06681004 1 P 0 
A 2.68036998 4.06681004 2.67127815 4.05640906 2.69713002 4.04298533 1 P 0 N
A 2.67127815 4.05640906 2.668 4.04298996 2.69713002 4.04298376 1 P 0 N
A 2.668 4.04298996 2.66997136 4.03018268 2.71061998 4.04299488 1 P 0 N
A 2.66997136 4.03018268 2.6757 4.01856004 2.71061998 4.04299469 1 P 0 N
L 2.6757 4.01856004 2.74596004 3.91823002 1 P 0 
L 2.74596004 3.91823002 2.78183002 3.71481998 1 P 0 
L 2.78183002 3.71481998 2.7251 3.39313996 1 P 0 
L 2.7251 3.39313996 2.6542 3.29188002 1 P 0 
L 2.6542 3.29188002 2.61888996 3.26713002 1 P 0 
A 2.61888996 3.26713002 2.52466004 3.2374 2.52465906 3.4016 1 P 0 Y
L 2.52466004 3.2374 2.38205 3.2374 1 P 0 
A 2.38205 3.2374 2.36731004 3.25213996 2.38205 3.25213996 1 P 0 Y
L 2.36731004 3.25213996 2.36731004 3.2837 1 P 0 
A 2.36731004 3.2837 2.36361004 3.2874 2.36361004 3.2837 1 P 0 N
L 2.36361004 3.2874 2.34976004 3.2874 1 P 0 
A 2.34976004 3.2874 2.34606004 3.2837 2.34976004 3.2837 1 P 0 N
L 2.34606004 3.2837 2.34606004 3.26615 1 P 0 
P 8.2 3.46615 5 P 0 0;2=3,4=1
P 7.90465 5.169 5 P 0 0;2=3,4=1
L 8.2 3.46615 8.2 3.4486 1 P 0 
A 8.2 3.4486 8.19906201 3.44613524 8.1963 3.44859724 1 P 0 Y
A 8.19906201 3.44613524 8.19671998 3.44491998 8.19629675 3.4486 1 P 0 Y
L 8.19671998 3.44491998 8.1963 3.4449 1 P 0 
L 8.1963 3.4449 8.13936998 3.4449 1 P 0 
A 8.13936998 3.4449 8.12875 3.45551998 8.13936998 3.45551998 1 P 0 Y
L 8.12875 3.45551998 8.12875 3.47 1 P 0 
A 8.12875 3.47 8.12705463 3.4784873 8.10656998 3.46998238 1 P 0 N
A 8.12705463 3.4784873 8.12223996 3.48568002 8.10656998 3.46998307 1 P 0 N
L 8.12223996 3.48568002 8.1193 3.48861998 1 P 0 
A 8.1193 3.48861998 8.11235915 3.49326417 8.10415217 3.47348996 1 P 0 N
A 8.11235915 3.49326417 8.10416998 3.4949 8.10415118 3.47348996 1 P 0 N
L 8.10416998 3.4949 8.0361 3.4949 1 P 0 
A 8.0361 3.4949 8.02125 3.48005 8.0361 3.48005 1 P 0 N
L 8.02125 3.48005 8.02125 3.46033996 1 P 0 
A 8.02125 3.46033996 8.01883002 3.45451998 8.01301998 3.46034892 1 P 0 Y
L 8.01883002 3.45451998 8.01241998 3.44811004 1 P 0 
A 8.01241998 3.44811004 8.00887884 3.4457377 8.00468287 3.45583002 1 P 0 Y
A 8.00887884 3.4457377 8.0047 3.4449 8.00468228 3.45583002 1 P 0 Y
L 8.0047 3.4449 7.95048996 3.4449 1 P 0 
L 7.95048996 3.4449 7.79908996 3.4716 1 P 0 
L 7.79908996 3.4716 7.56451998 3.63583996 1 P 0 
A 7.56451998 3.63583996 7.50933002 3.74186004 7.70506998 3.77637972 1 P 0 Y
L 7.50933002 3.74186004 7.4473 4.09353002 1 P 0 
L 7.4473 4.09353002 7.4473 4.10786998 1 P 0 
L 7.4473 4.10786998 7.44731004 4.10786004 1 P 0 
A 7.44731004 4.10786004 7.44756998 4.11233996 7.48568996 4.10788061 1 P 0 Y
A 7.44756998 4.11233996 7.45853996 4.135 7.48568996 4.10787096 1 P 0 Y
A 7.45853996 4.135 7.47514764 4.14610079 7.4947436 4.09881004 1 P 0 Y
A 7.47514764 4.14610079 7.49473996 4.15 7.4947435 4.09881004 1 P 0 Y
L 7.49473996 4.15 7.50293002 4.15 1 P 0 
A 7.50293002 4.15 7.55599193 4.16931211 7.50292726 4.23256004 1 P 0 N
A 7.55599193 4.16931211 7.58423002 4.21821004 7.50293002 4.23255738 1 P 0 N
L 7.58423002 4.21821004 7.61535 4.39471998 1 P 0 
A 7.61535 4.39471998 7.63268996 4.43681998 7.7181 4.37702067 1 P 0 Y
L 7.63268996 4.43681998 7.8111 4.69158002 1 P 0 
L 7.8111 4.69158002 7.84351004 4.71428002 1 P 0 
L 7.84351004 4.71428002 7.85703996 4.71666998 1 P 0 
L 7.85703996 4.71666998 7.86606004 4.72298002 1 P 0 
L 7.86606004 4.72298002 7.86606004 4.72296998 1 P 0 
L 7.86606004 4.72296998 7.86716004 4.72373996 1 P 0 
L 7.86716004 4.72373996 7.87603996 4.73646004 1 P 0 
L 7.87603996 4.73646004 7.89656998 4.85283002 1 P 0 
L 7.89656998 4.85283002 7.89336998 4.87098996 1 P 0 
L 7.89336998 4.87098996 7.89751004 4.8769 1 P 0 
L 7.89751004 4.8769 7.89556998 4.88785 1 P 0 
L 7.89556998 4.88785 7.88966998 4.89196998 1 P 0 
L 7.88966998 4.89196998 7.885 4.91841998 1 P 0 
L 7.885 4.91841998 7.88931998 4.94288996 1 P 0 
L 7.88931998 4.94288996 7.89405 4.94618002 1 P 0 
L 7.89405 4.94618002 7.89598996 4.95713002 1 P 0 
L 7.89598996 4.95713002 7.89266004 4.96185 1 P 0 
L 7.89266004 4.96185 7.89728996 4.98811004 1 P 0 
L 7.89728996 4.98811004 7.88041004 5.08375 1 P 0 
L 7.88041004 5.08375 7.88768002 5.125 1 P 0 
L 7.88768002 5.125 7.88768002 5.1653 1 P 0 
A 7.88768002 5.1653 7.89138002 5.169 7.89138002 5.1653 1 P 0 Y
L 7.89138002 5.169 7.90465 5.169 1 P 0 
P 2.34606004 3.31615 5 P 0 0;2=3,4=1
P 2.35716998 4.742 5 P 0 0;2=3,4=1
L 2.35716998 4.742 2.36986004 4.742 1 P 0 
A 2.36986004 4.742 2.37356004 4.7383 2.36986004 4.7383 1 P 0 Y
L 2.37356004 4.7383 2.37356004 4.70265 1 P 0 
A 2.37356004 4.70265 2.41171004 4.6645 2.41171004 4.70265 1 P 0 N
L 2.41171004 4.6645 2.41666004 4.6645 1 P 0 
A 2.41666004 4.6645 2.43838602 4.6678375 2.41669282 4.73666998 1 P 0 N
A 2.43838602 4.6678375 2.4581 4.67756004 2.4166937 4.73666998 1 P 0 N
L 2.4581 4.67756004 2.50673996 4.71163002 1 P 0 
L 2.50673996 4.71163002 2.50673996 4.71165 1 P 0 
A 2.50673996 4.71165 2.51816142 4.71728888 2.53075719 4.67738996 1 P 0 Y
A 2.51816142 4.71728888 2.53075 4.71923002 2.53075768 4.67738996 1 P 0 Y
L 2.53075 4.71923002 2.53078996 4.71923002 1 P 0 
A 2.53078996 4.71923002 2.54294459 4.7168124 2.53078652 4.68745 1 P 0 Y
A 2.54294459 4.7168124 2.55325 4.70993002 2.53078602 4.68745 1 P 0 Y
L 2.55325 4.70993002 2.55328002 4.7099 1 P 0 
A 2.55328002 4.7099 2.56548996 4.6804 2.52375 4.68040079 1 P 0 Y
L 2.56548996 4.6804 2.5655 4.68041004 1 P 0 
L 2.5655 4.68041004 2.5655 4.67268002 1 P 0 
A 2.5655 4.67268002 2.55658996 4.6512 2.53513002 4.67268967 1 P 0 Y
L 2.55658996 4.6512 2.55386004 4.64846998 1 P 0 
L 2.55386004 4.64846998 2.55386998 4.64846998 1 P 0 
L 2.55386998 4.64846998 2.45148996 4.57676004 1 P 0 
L 2.45148996 4.57676004 2.45148996 4.57676998 1 P 0 
A 2.45148996 4.57676998 2.44120148 4.56503691 2.47033002 4.54987205 1 P 0 N
A 2.44120148 4.56503691 2.43748996 4.54988002 2.47033002 4.54987126 1 P 0 N
A 2.43748996 4.54988002 2.47098996 4.51638996 2.47098002 4.54988002 1 P 0 N
L 2.47098996 4.51638996 2.48056998 4.51638996 1 P 0 
L 2.48056998 4.51638996 2.50801004 4.52121998 1 P 0 
A 2.50801004 4.52121998 2.52785827 4.51992559 2.51528691 4.47998002 1 P 0 Y
A 2.52785827 4.51992559 2.54486998 4.50961998 2.51528681 4.47998002 1 P 0 Y
L 2.54486998 4.50961998 2.54486004 4.50961998 1 P 0 
L 2.54486004 4.50961998 2.54491998 4.50956004 1 P 0 
L 2.54491998 4.50956004 2.68966998 4.30283996 1 P 0 
A 2.68966998 4.30283996 2.69271575 4.29729902 2.6659 4.28616644 1 P 0 Y
A 2.69271575 4.29729902 2.69448996 4.29123002 2.6659 4.28616585 1 P 0 Y
L 2.69448996 4.29123002 2.7216 4.13741004 1 P 0 
L 2.7216 4.13741004 2.7216 4.13736998 1 P 0 
A 2.7216 4.13736998 2.71459222 4.10864675 2.65925 4.13736535 1 P 0 Y
A 2.71459222 4.10864675 2.69513996 4.08638002 2.65925 4.13736368 1 P 0 Y
L 2.69513996 4.08638002 2.69513002 4.08636998 1 P 0 
L 2.69513002 4.08636998 2.67605 4.07295 1 P 0 
A 2.67605 4.07295 2.66461388 4.0598687 2.69713002 4.0429815 1 P 0 N
A 2.66461388 4.0598687 2.66048996 4.04298996 2.69713002 4.042981 1 P 0 N
A 2.66048996 4.04298996 2.66280935 4.02792293 2.71061998 4.04299488 1 P 0 N
A 2.66280935 4.02792293 2.66955 4.01425 2.71061998 4.04299518 1 P 0 N
L 2.66955 4.01425 2.73886004 3.91528996 1 P 0 
L 2.73886004 3.91528996 2.77421004 3.71481998 1 P 0 
L 2.77421004 3.71481998 2.718 3.39608002 1 P 0 
L 2.718 3.39608002 2.69641004 3.36525 1 P 0 
L 2.69641004 3.36525 2.68701998 3.3636 1 P 0 
L 2.68701998 3.3636 2.68063996 3.3545 1 P 0 
L 2.68063996 3.3545 2.68231004 3.34511998 1 P 0 
L 2.68231004 3.34511998 2.67593002 3.33601004 1 P 0 
L 2.67593002 3.33601004 2.66653996 3.33436004 1 P 0 
L 2.66653996 3.33436004 2.66016004 3.32526004 1 P 0 
L 2.66016004 3.32526004 2.66183002 3.31586998 1 P 0 
L 2.66183002 3.31586998 2.64881004 3.29726998 1 P 0 
L 2.64881004 3.29726998 2.61458002 3.27328002 1 P 0 
A 2.61458002 3.27328002 2.57180522 3.25216614 2.52464222 3.4016 1 P 0 Y
A 2.57180522 3.25216614 2.52466004 3.2449 2.52464154 3.4016 1 P 0 Y
L 2.52466004 3.2449 2.38205 3.2449 1 P 0 
A 2.38205 3.2449 2.37481004 3.25213996 2.38205 3.25213996 1 P 0 Y
L 2.37481004 3.25213996 2.37481004 3.2837 1 P 0 
A 2.37481004 3.2837 2.36361004 3.2949 2.36361004 3.2837 1 P 0 N
L 2.36361004 3.2949 2.34976004 3.2949 1 P 0 
A 2.34976004 3.2949 2.34606004 3.2986 2.34976004 3.2986 1 P 0 Y
L 2.34606004 3.2986 2.34606004 3.31615 1 P 0 
P 8 3.46615 5 P 0 0;2=3,4=1
P 7.93551004 5.0535 5 P 0 0;2=3,4=1
L 8 3.46615 8 3.4837 1 P 0 
A 8 3.4837 7.99906201 3.48616476 7.9963 3.48370276 1 P 0 N
A 7.99906201 3.48616476 7.99671998 3.48738002 7.99629675 3.4837 1 P 0 N
L 7.99671998 3.48738002 7.9963 3.4874 1 P 0 
L 7.9963 3.4874 7.93361004 3.4874 1 P 0 
L 7.93361004 3.4874 7.87861998 3.47768996 1 P 0 
L 7.87861998 3.47768996 7.80293996 3.49103996 1 P 0 
L 7.80293996 3.49103996 7.62545 3.6153 1 P 0 
A 7.62545 3.6153 7.61485148 3.62738573 7.64485 3.64300276 1 P 0 Y
A 7.61485148 3.62738573 7.61103002 3.643 7.64485 3.64300236 1 P 0 Y
A 7.61103002 3.643 7.61362421 3.6560377 7.6451 3.64299783 1 P 0 Y
A 7.61362421 3.6560377 7.62101004 3.66708996 7.6451 3.64299754 1 P 0 Y
L 7.62101004 3.66708996 7.62923002 3.67531004 1 P 0 
A 7.62923002 3.67531004 7.63522559 3.68808976 7.61453996 3.68999813 1 P 0 N
A 7.63522559 3.68808976 7.63166998 3.70175 7.61453996 3.68999843 1 P 0 N
A 7.63166998 3.70175 7.61241004 3.7095 7.61240079 3.68166998 1 P 0 N
L 7.61241004 3.7095 7.57466998 3.7095 1 P 0 
A 7.57466998 3.7095 7.55873809 3.71266762 7.57466811 3.75113996 1 P 0 Y
A 7.55873809 3.71266762 7.54523002 3.72168996 7.57466742 3.75113996 1 P 0 Y
A 7.54523002 3.72168996 7.53581614 3.73578543 7.57596998 3.75241142 1 P 0 Y
A 7.53581614 3.73578543 7.53251004 3.75241004 7.57596998 3.75241181 1 P 0 Y
L 7.53251004 3.75241004 7.53251004 3.75248996 1 P 0 
A 7.53251004 3.75248996 7.54106004 3.77313996 7.56171998 3.75249085 1 P 0 Y
L 7.54106004 3.77313996 7.54106998 3.77315 1 P 0 
A 7.54106998 3.77315 7.55529272 3.7826562 7.57209134 3.74213002 1 P 0 Y
A 7.55529272 3.7826562 7.57206998 3.786 7.57209163 3.74213002 1 P 0 Y
L 7.57206998 3.786 7.57208996 3.786 1 P 0 
A 7.57208996 3.786 7.59615157 3.79070167 7.57209783 3.84988002 1 P 0 N
A 7.59615157 3.79070167 7.61666998 3.80411998 7.57209774 3.84988002 1 P 0 N
L 7.61666998 3.80411998 7.61761998 3.80505 1 P 0 
A 7.61761998 3.80505 7.62304498 3.81893868 7.60323002 3.81867461 1 P 0 N
A 7.62304498 3.81893868 7.61725 3.83268002 7.60323002 3.8186749 1 P 0 N
L 7.61725 3.83268002 7.61623996 3.83368996 1 P 0 
L 7.61623996 3.83368996 7.61623002 3.83368996 1 P 0 
A 7.61623002 3.83368996 7.60199459 3.84320659 7.5851939 3.80266998 1 P 0 N
A 7.60199459 3.84320659 7.5852 3.84655 7.58519459 3.80266998 1 P 0 N
L 7.5852 3.84655 7.58466004 3.84655 1 P 0 
A 7.58466004 3.84655 7.52106998 3.87408996 7.58768081 3.94071004 1 P 0 Y
L 7.52106998 3.87408996 7.51741998 3.87773996 1 P 0 
L 7.51741998 3.87773996 7.51741998 3.87775 1 P 0 
L 7.51741998 3.87775 7.51703996 3.87806998 1 P 0 
A 7.51703996 3.87806998 7.50008996 3.91426004 7.5472 3.91426014 1 P 0 Y
L 7.50008996 3.91426004 7.50008996 3.91953996 1 P 0 
A 7.50008996 3.91953996 7.51353996 3.952 7.54601004 3.91952923 1 P 0 Y
L 7.51353996 3.952 7.51911004 3.95756004 1 P 0 
A 7.51911004 3.95756004 7.55153996 3.971 7.55155 3.92513002 1 P 0 Y
L 7.55153996 3.971 7.55358002 3.971 1 P 0 
A 7.55358002 3.971 7.56561112 3.97339419 7.55357726 4.00243996 1 P 0 N
A 7.56561112 3.97339419 7.57581004 3.98021004 7.55357697 4.00243996 1 P 0 N
A 7.57581004 3.98021004 7.58303002 4.001 7.54948996 4.00099921 1 P 0 N
A 7.58303002 4.001 7.57508996 4.02018002 7.55586998 4.00098986 1 P 0 N
L 7.57508996 4.02018002 7.57506998 4.0202 1 P 0 
A 7.57506998 4.0202 7.55383996 4.029 7.55383937 3.99898996 1 P 0 N
L 7.55383996 4.029 7.54383002 4.029 1 P 0 
A 7.54383002 4.029 7.5125 4.03523179 7.54382785 4.11086004 1 P 0 Y
A 7.5125 4.03523179 7.48593996 4.05298002 7.54382707 4.11086004 1 P 0 Y
L 7.48593996 4.05298002 7.48591998 4.053 1 P 0 
A 7.48591998 4.053 7.47490758 4.06948002 7.52183996 4.08892215 1 P 0 Y
A 7.47490758 4.06948002 7.47103996 4.08891998 7.52183996 4.08892205 1 P 0 Y
A 7.47103996 4.08891998 7.47436339 4.10563652 7.51473002 4.08892254 1 P 0 Y
A 7.47436339 4.10563652 7.48383002 4.11981004 7.51473002 4.08892343 1 P 0 Y
L 7.48383002 4.11981004 7.48413002 4.12008996 1 P 0 
L 7.48413002 4.12008996 7.48415 4.12011004 1 P 0 
L 7.48415 4.12011004 7.48715 4.12258002 1 P 0 
A 7.48715 4.12258002 7.51898996 4.134 7.51899124 4.0839 1 P 0 Y
L 7.51898996 4.134 7.54008002 4.134 1 P 0 
A 7.54008002 4.134 7.54410886 4.13479724 7.54008169 4.14456998 1 P 0 N
A 7.54410886 4.13479724 7.54753002 4.13706998 7.54008209 4.14456998 1 P 0 N
L 7.54753002 4.13706998 7.59001004 4.17946004 1 P 0 
A 7.59001004 4.17946004 7.59483996 4.18866004 7.57806004 4.19160148 1 P 0 N
L 7.59483996 4.18866004 7.63113996 4.39458996 1 P 0 
A 7.63113996 4.39458996 7.63442648 4.40588445 7.68433996 4.38523504 1 P 0 Y
A 7.63442648 4.40588445 7.64008002 4.4162 7.68433996 4.38523583 1 P 0 Y
L 7.64008002 4.4162 7.82783996 4.68441998 1 P 0 
L 7.82783996 4.68441998 7.84918996 4.69935 1 P 0 
L 7.84918996 4.69935 7.86398996 4.70195 1 P 0 
L 7.86398996 4.70195 7.90453002 4.73035 1 P 0 
L 7.90453002 4.73035 7.95136004 4.79693002 1 P 0 
L 7.95136004 4.79693002 7.96271998 4.86138996 1 P 0 
L 7.96271998 4.86138996 7.94328002 4.97166998 1 P 0 
L 7.94328002 4.97166998 7.95103996 5.01566004 1 P 0 
L 7.95103996 5.01566004 7.95103996 5.049 1 P 0 
A 7.95103996 5.049 7.94653996 5.0535 7.94653996 5.049 1 P 0 N
L 7.94653996 5.0535 7.93551004 5.0535 1 P 0 
P 2.25855 4.667 5 P 0 0;2=3,4=1
P 2.39606004 3.31615 5 P 0 0;2=3,4=1
L 2.39606004 3.31615 2.39606004 3.3337 1 P 0 
A 2.39606004 3.3337 2.39976004 3.3374 2.39976004 3.3337 1 P 0 Y
L 2.39976004 3.3374 2.41046998 3.3374 1 P 0 
A 2.41046998 3.3374 2.42481004 3.35173996 2.41047008 3.35173996 1 P 0 N
L 2.42481004 3.35173996 2.42481004 3.38146998 1 P 0 
A 2.42481004 3.38146998 2.43073996 3.3874 2.43073996 3.38147008 1 P 0 Y
L 2.43073996 3.3874 2.58231004 3.3874 1 P 0 
A 2.58231004 3.3874 2.60169961 3.39125187 2.58232146 3.43806998 1 P 0 N
A 2.60169961 3.39125187 2.61813996 3.40223002 2.58232205 3.43806998 1 P 0 N
L 2.61813996 3.40223002 2.61816004 3.40225 1 P 0 
A 2.61816004 3.40225 2.64789724 3.44280689 2.5013 3.51911476 1 P 0 N
A 2.64789724 3.44280689 2.66406004 3.49043002 2.5013 3.51911476 1 P 0 N
L 2.66406004 3.49043002 2.68415 3.60438996 1 P 0 
L 2.68415 3.60438996 2.68413996 3.60438996 1 P 0 
L 2.68413996 3.60438996 2.70445 3.71963996 1 P 0 
L 2.70445 3.71963996 2.67353002 3.89511004 1 P 0 
L 2.67353002 3.89511004 2.61108996 3.98433002 1 P 0 
A 2.61108996 3.98433002 2.54001998 4.02961004 2.52090925 3.9212 1 P 0 N
L 2.54001998 4.02961004 2.48301004 4.03966998 1 P 0 
A 2.48301004 4.03966998 2.46651319 4.04919843 2.48785315 4.0671 1 P 0 Y
A 2.46651319 4.04919843 2.46 4.0671 2.48785 4.06709715 1 P 0 Y
A 2.46 4.0671 2.4874 4.0945 2.4874 4.0671 1 P 0 Y
L 2.4874 4.0945 2.51858996 4.0945 1 P 0 
A 2.51858996 4.0945 2.54733307 4.10021801 2.51858829 4.16961004 1 P 0 N
A 2.54733307 4.10021801 2.5717 4.1165 2.51858858 4.16961004 1 P 0 N
L 2.5717 4.1165 2.57171004 4.11651004 1 P 0 
A 2.57171004 4.11651004 2.57171004 4.15263002 2.55365 4.13457008 1 P 0 N
L 2.57171004 4.15263002 2.57168996 4.15265 1 P 0 
A 2.57168996 4.15265 2.55838327 4.16240098 2.53335413 4.11428996 1 P 0 N
A 2.55838327 4.16240098 2.54276004 4.1677 2.53335492 4.11428996 1 P 0 N
L 2.54276004 4.1677 2.51096004 4.1733 1 P 0 
A 2.51096004 4.1733 2.50891004 4.17346998 2.50896122 4.16163996 1 P 0 N
L 2.50891004 4.17346998 2.50588996 4.17348002 1 P 0 
A 2.50588996 4.17348002 2.49014341 4.17924724 2.50589341 4.19786998 1 P 0 Y
A 2.49014341 4.17924724 2.48183996 4.19381998 2.5059 4.19787726 1 P 0 Y
L 2.48183996 4.19381998 2.48178996 4.20286004 1 P 0 
A 2.48178996 4.20286004 2.48391348 4.21373268 2.51 4.20299409 1 P 0 Y
A 2.48391348 4.21373268 2.49006004 4.22295 2.51 4.20299498 1 P 0 Y
L 2.49006004 4.22295 2.49006004 4.22296004 1 P 0 
L 2.49006004 4.22296004 2.49006998 4.22296004 1 P 0 
A 2.49006998 4.22296004 2.50553002 4.23101004 2.51058051 4.20243996 1 P 0 Y
L 2.50553002 4.23101004 2.56298996 4.24113002 1 P 0 
A 2.56298996 4.24113002 2.57435807 4.24498484 2.55615394 4.27998002 1 P 0 N
A 2.57435807 4.24498484 2.58403996 4.25208002 2.55615325 4.27998002 1 P 0 N
L 2.58403996 4.25208002 2.58405 4.25208996 1 P 0 
A 2.58405 4.25208996 2.5985 4.28698996 2.54913002 4.28698967 1 P 0 N
L 2.5985 4.28698996 2.5985 4.28853002 1 P 0 
A 2.5985 4.28853002 2.58564291 4.32252274 2.54713002 4.28852815 1 P 0 N
A 2.58564291 4.32252274 2.55351004 4.3395 2.54713159 4.28853002 1 P 0 N
L 2.55351004 4.3395 2.54853002 4.34011998 1 P 0 
L 2.54853002 4.34011998 2.49083996 4.35028996 1 P 0 
A 2.49083996 4.35028996 2.4804878 4.35626112 2.4938628 4.36748996 1 P 0 Y
A 2.4804878 4.35626112 2.4764 4.36748996 2.49386004 4.3674877 1 P 0 Y
L 2.4764 4.36748996 2.4764 4.37293002 1 P 0 
A 2.4764 4.37293002 2.47550079 4.38030906 2.44596004 4.37296486 1 P 0 N
A 2.47550079 4.38030906 2.47283996 4.38725 2.44596004 4.37296506 1 P 0 N
L 2.47283996 4.38725 2.47281998 4.38728002 1 P 0 
A 2.47281998 4.38728002 2.4519 4.41553002 2.36773002 4.33132864 1 P 0 N
A 2.4519 4.41553002 2.42771654 4.42554921 2.42771506 4.39135 1 P 0 N
A 2.42771654 4.42554921 2.40353002 4.41553002 2.42771496 4.39135 1 P 0 N
L 2.40353002 4.41553002 2.39998996 4.41198996 1 P 0 
A 2.39998996 4.41198996 2.39129419 4.40632943 2.38227785 4.42968996 1 P 0 Y
A 2.39129419 4.40632943 2.38105 4.40468002 2.38227805 4.42968996 1 P 0 Y
A 2.38105 4.40468002 2.35421004 4.41578996 2.3810311 4.44261004 1 P 0 Y
L 2.35421004 4.41578996 2.3542 4.4158 1 P 0 
A 2.3542 4.4158 2.3279377 4.4333439 2.29697776 4.35856998 1 P 0 N
A 2.3279377 4.4333439 2.29696004 4.4395 2.29697756 4.35856998 1 P 0 N
L 2.29696004 4.4395 2.28573002 4.4395 1 P 0 
A 2.28573002 4.4395 2.24667343 4.44726939 2.2857373 4.54158996 1 P 0 Y
A 2.24667343 4.44726939 2.21356004 4.46938996 2.28573671 4.54158996 1 P 0 Y
L 2.21356004 4.46938996 2.20801004 4.47731004 1 P 0 
A 2.20801004 4.47731004 2.20771998 4.47781004 2.21143002 4.47962815 1 P 0 Y
A 2.20771998 4.47781004 2.20236299 4.49524449 2.25983996 4.50336486 1 P 0 Y
A 2.20236299 4.49524449 2.20268002 4.51348002 2.25983996 4.50336575 1 P 0 Y
L 2.20268002 4.51348002 2.20766004 4.54165 1 P 0 
L 2.20766004 4.54165 2.20766004 4.54166004 1 P 0 
L 2.20766004 4.54166004 2.23303002 4.57815 1 P 0 
L 2.23303002 4.57815 2.24243996 4.63133996 1 P 0 
L 2.24243996 4.63133996 2.24243996 4.6633 1 P 0 
A 2.24243996 4.6633 2.24613996 4.667 2.24613996 4.6633 1 P 0 Y
L 2.24613996 4.667 2.25855 4.667 1 P 0 
P 8 3.51615 5 P 0 0;2=3,4=1
P 7.97551004 5.0535 5 P 0 0;2=3,4=1
L 8 3.51615 8 3.4986 1 P 0 
A 8 3.4986 7.99906201 3.49613524 7.9963 3.49859724 1 P 0 Y
A 7.99906201 3.49613524 7.99671998 3.49491998 7.99629675 3.4986 1 P 0 Y
L 7.99671998 3.49491998 7.99653996 3.4949 1 P 0 
L 7.99653996 3.4949 7.93295 3.4949 1 P 0 
L 7.93295 3.4949 7.87861998 3.48531004 1 P 0 
L 7.87861998 3.48531004 7.84223996 3.49173002 1 P 0 
L 7.84223996 3.49173002 7.84225 3.49173002 1 P 0 
L 7.84225 3.49173002 7.80588002 3.49813996 1 P 0 
L 7.80588002 3.49813996 7.62976004 3.62145 1 P 0 
A 7.62976004 3.62145 7.62151358 3.63085207 7.64485 3.64300266 1 P 0 Y
A 7.62151358 3.63085207 7.61853996 3.643 7.64485 3.64300236 1 P 0 Y
A 7.61853996 3.643 7.6205623 3.65316388 7.6451 3.64299843 1 P 0 Y
A 7.6205623 3.65316388 7.62631998 3.66178002 7.6451 3.64299852 1 P 0 Y
L 7.62631998 3.66178002 7.63453996 3.67 1 P 0 
A 7.63453996 3.67 7.64270295 3.68740089 7.61453996 3.68999734 1 P 0 N
A 7.64270295 3.68740089 7.63786004 3.706 7.61453996 3.68999774 1 P 0 N
A 7.63786004 3.706 7.63741004 3.70663996 7.6145 3.69005217 1 P 0 N
L 7.63741004 3.70663996 7.6374 3.70665 1 P 0 
A 7.6374 3.70665 7.62593957 3.71430925 7.61241565 3.68166998 1 P 0 N
A 7.62593957 3.71430925 7.61241998 3.717 7.61241594 3.68166998 1 P 0 N
L 7.61241998 3.717 7.57468002 3.717 1 P 0 
A 7.57468002 3.717 7.55053996 3.727 7.5746812 3.75113996 1 P 0 Y
A 7.55053996 3.727 7.54001004 3.75241998 7.57596004 3.75242087 1 P 0 Y
L 7.54001004 3.75241998 7.54001004 3.75248002 1 P 0 
A 7.54001004 3.75248002 7.54166348 3.7607877 7.56171998 3.75247756 1 P 0 Y
A 7.54166348 3.7607877 7.54636998 3.76783002 7.56171998 3.75247746 1 P 0 Y
L 7.54636998 3.76783002 7.54638002 3.76783996 1 P 0 
A 7.54638002 3.76783996 7.57208002 3.7785 7.57210089 3.74213996 1 P 0 Y
L 7.57208002 3.7785 7.57213996 3.7785 1 P 0 
L 7.57213996 3.7785 7.57218002 3.7785 1 P 0 
A 7.57218002 3.7785 7.62253996 3.79936004 7.57217963 3.84971998 1 P 0 N
L 7.62253996 3.79936004 7.62255 3.79936004 1 P 0 
A 7.62255 3.79936004 7.62255 3.838 7.60323996 3.81868002 1 P 0 N
L 7.62255 3.838 7.62153996 3.839 1 P 0 
A 7.62153996 3.839 7.60487195 3.85013809 7.58520768 3.80266998 1 P 0 N
A 7.60487195 3.85013809 7.58521004 3.85405 7.58520768 3.80266998 1 P 0 N
L 7.58521004 3.85405 7.58478996 3.85405 1 P 0 
A 7.58478996 3.85405 7.55317352 3.86116939 7.58769429 3.94071004 1 P 0 Y
A 7.55317352 3.86116939 7.52638002 3.8794 7.58769498 3.94071004 1 P 0 Y
L 7.52638002 3.8794 7.5223 3.88348002 1 P 0 
L 7.5223 3.88348002 7.52226004 3.88348002 1 P 0 
L 7.52226004 3.88348002 7.52185 3.88383996 1 P 0 
A 7.52185 3.88383996 7.50758996 3.91426004 7.54718996 3.91427096 1 P 0 Y
L 7.50758996 3.91426004 7.50758996 3.91953002 1 P 0 
A 7.50758996 3.91953002 7.51051457 3.93422884 7.54601004 3.91952598 1 P 0 Y
A 7.51051457 3.93422884 7.51883996 3.94668996 7.54601004 3.91952569 1 P 0 Y
L 7.51883996 3.94668996 7.52441004 3.95225 1 P 0 
L 7.52441004 3.95225 7.52441998 3.95225 1 P 0 
A 7.52441998 3.95225 7.55155 3.9635 7.55155925 3.92513996 1 P 0 Y
L 7.55155 3.9635 7.55358996 3.9635 1 P 0 
A 7.55358996 3.9635 7.58111004 3.9749 7.55358061 4.00243996 1 P 0 N
L 7.58111004 3.9749 7.5817 3.97548996 1 P 0 
L 7.5817 3.97548996 7.5817 3.97555 1 P 0 
A 7.5817 3.97555 7.58826732 3.98752923 7.54948996 4.00099813 1 P 0 N
A 7.58826732 3.98752923 7.59053996 4.001 7.54948996 4.00099843 1 P 0 N
A 7.59053996 4.001 7.5804 4.02548996 7.55586998 4.00098917 1 P 0 N
L 7.5804 4.02548996 7.58038002 4.02551004 1 P 0 
A 7.58038002 4.02551004 7.56820344 4.03364616 7.55385335 3.99898996 1 P 0 N
A 7.56820344 4.03364616 7.55383996 4.0365 7.55385246 3.99898996 1 P 0 N
L 7.55383996 4.0365 7.54381998 4.0365 1 P 0 
A 7.54381998 4.0365 7.51536801 4.04216644 7.54383711 4.11085 1 P 0 Y
A 7.51536801 4.04216644 7.49125 4.05828996 7.54383622 4.11085 1 P 0 Y
L 7.49125 4.05828996 7.49123002 4.05831004 1 P 0 
A 7.49123002 4.05831004 7.48184035 4.07235276 7.52183002 4.0889313 1 P 0 Y
A 7.48184035 4.07235276 7.47853996 4.08891998 7.52183002 4.0889315 1 P 0 Y
L 7.47853996 4.08891998 7.47855 4.08891998 1 P 0 
A 7.47855 4.08891998 7.48901004 4.11438002 7.51473996 4.08893041 1 P 0 Y
L 7.48901004 4.11438002 7.48911004 4.11446998 1 P 0 
L 7.48911004 4.11446998 7.49191998 4.11678996 1 P 0 
A 7.49191998 4.11678996 7.50461063 4.12399833 7.51899419 4.0839 1 P 0 Y
A 7.50461063 4.12399833 7.51898996 4.1265 7.51899409 4.0839 1 P 0 Y
L 7.51898996 4.1265 7.54006998 4.1265 1 P 0 
A 7.54006998 4.1265 7.54697037 4.12785915 7.54009478 4.14456998 1 P 0 N
A 7.54697037 4.12785915 7.55283002 4.13175 7.54009587 4.14456998 1 P 0 N
L 7.55283002 4.13175 7.59526998 4.17411004 1 P 0 
A 7.59526998 4.17411004 7.59978524 4.18019134 7.57806998 4.19159764 1 P 0 N
A 7.59978524 4.18019134 7.60223002 4.18736004 7.57806998 4.19159823 1 P 0 N
L 7.60223002 4.18736004 7.63853002 4.39328996 1 P 0 
A 7.63853002 4.39328996 7.64623002 4.41188996 7.68433996 4.38521949 1 P 0 Y
L 7.64623002 4.41188996 7.83323002 4.67903002 1 P 0 
L 7.83323002 4.67903002 7.85213002 4.69225 1 P 0 
L 7.85213002 4.69225 7.86693002 4.69485 1 P 0 
L 7.86693002 4.69485 7.90991004 4.72496004 1 P 0 
L 7.90991004 4.72496004 7.95846004 4.79398002 1 P 0 
L 7.95846004 4.79398002 7.97033996 4.86138996 1 P 0 
L 7.97033996 4.86138996 7.96863996 4.87101004 1 P 0 
L 7.96863996 4.87101004 7.97236004 4.87628002 1 P 0 
L 7.97236004 4.87628002 7.97041998 4.88723002 1 P 0 
L 7.97041998 4.88723002 7.96513996 4.89091998 1 P 0 
L 7.96513996 4.89091998 7.95765 4.93336998 1 P 0 
L 7.95765 4.93336998 7.96136998 4.93863002 1 P 0 
L 7.96136998 4.93863002 7.95943002 4.94958002 1 P 0 
L 7.95943002 4.94958002 7.95415 4.95328002 1 P 0 
L 7.95415 4.95328002 7.9509 4.97166998 1 P 0 
L 7.9509 4.97166998 7.95853996 5.015 1 P 0 
L 7.95853996 5.015 7.95853996 5.0498 1 P 0 
A 7.95853996 5.0498 7.96223996 5.0535 7.96223996 5.0498 1 P 0 Y
L 7.96223996 5.0535 7.97551004 5.0535 1 P 0 
P 2.21855 4.667 5 P 0 0;2=3,4=1
P 2.39606004 3.36615 5 P 0 0;2=3,4=1
L 2.39606004 3.36615 2.39606004 3.3486 1 P 0 
A 2.39606004 3.3486 2.39976004 3.3449 2.39976004 3.3486 1 P 0 N
L 2.39976004 3.3449 2.41046998 3.3449 1 P 0 
A 2.41046998 3.3449 2.41731004 3.35173996 2.41047008 3.35173996 1 P 0 N
L 2.41731004 3.35173996 2.41731004 3.38146998 1 P 0 
A 2.41731004 3.38146998 2.43073996 3.3949 2.43073996 3.38147008 1 P 0 Y
L 2.43073996 3.3949 2.58231004 3.3949 1 P 0 
A 2.58231004 3.3949 2.59882697 3.39818533 2.58230846 3.43806998 1 P 0 N
A 2.59882697 3.39818533 2.61283002 3.40753996 2.58230846 3.43806998 1 P 0 N
L 2.61283002 3.40753996 2.61285 3.40756004 1 P 0 
A 2.61285 3.40756004 2.64123819 3.44627215 2.5013 3.51912618 1 P 0 N
A 2.64123819 3.44627215 2.65666998 3.49173002 2.5013 3.51912589 1 P 0 N
L 2.65666998 3.49173002 2.69683002 3.71963996 1 P 0 
L 2.69683002 3.71963996 2.66643002 3.89216998 1 P 0 
L 2.66643002 3.89216998 2.60493996 3.98001998 1 P 0 
A 2.60493996 3.98001998 2.53871998 4.02221998 2.52089931 3.9212 1 P 0 N
L 2.53871998 4.02221998 2.48171004 4.03228002 1 P 0 
A 2.48171004 4.03228002 2.46076988 4.0443753 2.48785915 4.0671 1 P 0 Y
A 2.46076988 4.0443753 2.4525 4.0671 2.48786004 4.06710098 1 P 0 Y
A 2.4525 4.0671 2.4874 4.102 2.4874 4.0671 1 P 0 Y
L 2.4874 4.102 2.51858002 4.102 1 P 0 
A 2.51858002 4.102 2.54445581 4.10714961 2.5185751 4.16961004 1 P 0 N
A 2.54445581 4.10714961 2.56638996 4.12181004 2.5185747 4.16961004 1 P 0 N
L 2.56638996 4.12181004 2.5664 4.12181998 1 P 0 
A 2.5664 4.12181998 2.5664 4.14731998 2.55365 4.13456998 1 P 0 N
L 2.5664 4.14731998 2.56638002 4.14733996 1 P 0 
A 2.56638002 4.14733996 2.55491801 4.15574193 2.53334301 4.11428996 1 P 0 N
A 2.55491801 4.15574193 2.54146004 4.16031004 2.5333435 4.11428996 1 P 0 N
L 2.54146004 4.16031004 2.50968002 4.16591004 1 P 0 
A 2.50968002 4.16591004 2.50893996 4.16596998 2.50896171 4.16163996 1 P 0 N
L 2.50893996 4.16596998 2.50891004 4.16596004 1 P 0 
L 2.50891004 4.16596004 2.50588002 4.16596998 1 P 0 
A 2.50588002 4.16596998 2.48515069 4.17363829 2.50589764 4.19786998 1 P 0 Y
A 2.48515069 4.17363829 2.47438002 4.19293996 2.5059 4.19787274 1 P 0 Y
L 2.47438002 4.19293996 2.47433996 4.19296004 1 P 0 
L 2.47433996 4.19296004 2.47428996 4.20281998 1 P 0 
A 2.47428996 4.20281998 2.47697234 4.2165877 2.51 4.20300768 1 P 0 Y
A 2.47697234 4.2165877 2.48475 4.22826004 2.51 4.20300768 1 P 0 Y
L 2.48475 4.22826004 2.48476004 4.22826998 1 P 0 
A 2.48476004 4.22826998 2.50423002 4.2384 2.51056939 4.20243996 1 P 0 Y
L 2.50423002 4.2384 2.56168996 4.24851998 1 P 0 
A 2.56168996 4.24851998 2.57089282 4.25164331 2.55614764 4.27996998 1 P 0 N
A 2.57089282 4.25164331 2.57873002 4.25738996 2.55614764 4.27996998 1 P 0 N
L 2.57873002 4.25738996 2.57873996 4.2574 1 P 0 
A 2.57873996 4.2574 2.58781309 4.27098081 2.54913002 4.28700315 1 P 0 N
A 2.58781309 4.27098081 2.591 4.287 2.54913002 4.28700315 1 P 0 N
L 2.591 4.287 2.591 4.28853002 1 P 0 
A 2.591 4.28853002 2.58002037 4.3175562 2.54713996 4.28852894 1 P 0 N
A 2.58002037 4.3175562 2.55258002 4.33205 2.54714104 4.28853002 1 P 0 N
L 2.55258002 4.33205 2.54741004 4.3327 1 P 0 
L 2.54741004 4.3327 2.48953996 4.3429 1 P 0 
A 2.48953996 4.3429 2.47474439 4.35143799 2.4938687 4.36748996 1 P 0 Y
A 2.47474439 4.35143799 2.4689 4.36748996 2.49386998 4.36749134 1 P 0 Y
L 2.4689 4.36748996 2.4689 4.37293996 1 P 0 
A 2.4689 4.37293996 2.46825935 4.37833071 2.44596004 4.37294715 1 P 0 N
A 2.46825935 4.37833071 2.46636998 4.38341998 2.44596004 4.37294754 1 P 0 N
L 2.46636998 4.38341998 2.46636998 4.38343002 1 P 0 
L 2.46636998 4.38343002 2.46618996 4.38375 1 P 0 
A 2.46618996 4.38375 2.44658996 4.41021998 2.36771998 4.33132825 1 P 0 N
A 2.44658996 4.41021998 2.42771644 4.41803967 2.42771506 4.39135 1 P 0 N
A 2.42771644 4.41803967 2.40883996 4.41021998 2.42771486 4.39135 1 P 0 N
L 2.40883996 4.41021998 2.4053 4.40668002 1 P 0 
A 2.4053 4.40668002 2.39408494 4.39935689 2.38227667 4.42968996 1 P 0 Y
A 2.39408494 4.39935689 2.38086998 4.39716998 2.38227677 4.42968996 1 P 0 Y
A 2.38086998 4.39716998 2.36356722 4.40065935 2.38102844 4.4426 1 P 0 Y
A 2.36356722 4.40065935 2.3489 4.41048002 2.38102785 4.4426 1 P 0 Y
L 2.3489 4.41048002 2.34888996 4.41048996 1 P 0 
A 2.34888996 4.41048996 2.32506427 4.42641043 2.29696476 4.35856998 1 P 0 N
A 2.32506427 4.42641043 2.29696004 4.432 2.29696368 4.35856998 1 P 0 N
L 2.29696004 4.432 2.28571998 4.432 1 P 0 
A 2.28571998 4.432 2.24348809 4.44046545 2.2857251 4.5416 1 P 0 Y
A 2.24348809 4.44046545 2.20778002 4.46455 2.28572539 4.5416 1 P 0 Y
L 2.20778002 4.46455 2.20186004 4.47301004 1 P 0 
L 2.20186004 4.47301004 2.20183996 4.47303996 1 P 0 
A 2.20183996 4.47303996 2.20098002 4.4745 2.21141004 4.47965984 1 P 0 Y
A 2.20098002 4.4745 2.19528996 4.51478996 2.25983996 4.50335945 1 P 0 Y
L 2.19528996 4.51478996 2.20056004 4.54458996 1 P 0 
L 2.20056004 4.54458996 2.20841998 4.5559 1 P 0 
L 2.20841998 4.5559 2.20841998 4.55591998 1 P 0 
L 2.20841998 4.55591998 2.20713996 4.56301004 1 P 0 
L 2.20713996 4.56301004 2.21348996 4.57215 1 P 0 
L 2.21348996 4.57215 2.22056998 4.57341004 1 P 0 
L 2.22056998 4.57341004 2.22593002 4.58111998 1 P 0 
L 2.22593002 4.58111998 2.22761998 4.59066004 1 P 0 
L 2.22761998 4.59066004 2.22378996 4.5961 1 P 0 
L 2.22378996 4.5961 2.22573002 4.60705 1 P 0 
L 2.22573002 4.60705 2.23118996 4.61086998 1 P 0 
L 2.23118996 4.61086998 2.23493996 4.632 1 P 0 
L 2.23493996 4.632 2.23493996 4.6633 1 P 0 
A 2.23493996 4.6633 2.23123996 4.667 2.23123996 4.6633 1 P 0 N
L 2.23123996 4.667 2.21855 4.667 1 P 0 
P 8.11725 5.169 5 P 0 0;2=3,4=1
P 8.4 3.46615 5 P 0 0;2=3,4=1
L 8.4 3.46615 8.4 3.4837 1 P 0 
A 8.4 3.4837 8.4037 3.4874 8.4037 3.4837 1 P 0 Y
L 8.4037 3.4874 8.40618002 3.4874 1 P 0 
A 8.40618002 3.4874 8.41211152 3.48857923 8.40618346 3.50288996 1 P 0 N
A 8.41211152 3.48857923 8.41713996 3.49193996 8.40618425 3.50288996 1 P 0 N
L 8.41713996 3.49193996 8.42546004 3.50026004 1 P 0 
A 8.42546004 3.50026004 8.42789341 3.50389813 8.41753002 3.50819695 1 P 0 N
A 8.42789341 3.50389813 8.42875 3.50818996 8.41753002 3.50819793 1 P 0 N
L 8.42875 3.50818996 8.42875 3.57848996 1 P 0 
A 8.42875 3.57848996 8.43766004 3.5874 8.43766004 3.57848996 1 P 0 Y
L 8.43766004 3.5874 8.52473002 3.5874 1 P 0 
A 8.52473002 3.5874 8.54488268 3.5914 8.52475512 3.64003996 1 P 0 N
A 8.54488268 3.5914 8.56196998 3.60281004 8.5247565 3.64003996 1 P 0 N
L 8.56196998 3.60281004 8.57063996 3.61148002 1 P 0 
A 8.57063996 3.61148002 8.58796624 3.63741191 8.51411998 3.66799774 1 P 0 N
A 8.58796624 3.63741191 8.59405 3.668 8.51411998 3.66799843 1 P 0 N
A 8.59405 3.668 8.58991732 3.68877618 8.53975 3.66799803 1 P 0 N
A 8.58991732 3.68877618 8.57815 3.70638996 8.53975 3.66799823 1 P 0 N
L 8.57815 3.70638996 8.57085 3.71368996 1 P 0 
A 8.57085 3.71368996 8.57085 3.76568996 8.59685 3.73968996 1 P 0 Y
L 8.57085 3.76568996 8.57085 3.7657 1 P 0 
L 8.57085 3.7657 8.57518996 3.77005 1 P 0 
A 8.57518996 3.77005 8.58100423 3.7787439 8.55623996 3.78901447 1 P 0 N
A 8.58100423 3.7787439 8.58305 3.789 8.55623996 3.78901565 1 P 0 N
A 8.58305 3.789 8.581575 3.79639882 8.56371998 3.78899291 1 P 0 N
A 8.581575 3.79639882 8.57738002 3.80266998 8.56371998 3.7889937 1 P 0 N
L 8.57738002 3.80266998 8.56858002 3.81148002 1 P 0 
A 8.56858002 3.81148002 8.56796043 3.81230069 8.5712 3.81410226 1 P 0 Y
A 8.56796043 3.81230069 8.56758996 3.81326004 8.5712 3.81410295 1 P 0 Y
L 8.56758996 3.81326004 8.56515 3.82373996 1 P 0 
A 8.56515 3.82373996 8.56505 3.82458996 8.56876998 3.82459675 1 P 0 Y
L 8.56505 3.82458996 8.56503996 3.8292 1 P 0 
L 8.56503996 3.8292 8.56503996 3.86131004 1 P 0 
A 8.56503996 3.86131004 8.54522569 3.91577136 8.48028002 3.86130758 1 P 0 N
A 8.54522569 3.91577136 8.49505 3.94476998 8.48028258 3.86131004 1 P 0 N
L 8.49505 3.94476998 8.43656004 3.95511004 1 P 0 
L 8.43656004 3.95511004 8.43648996 3.95511998 1 P 0 
L 8.43648996 3.95511998 8.4365 3.95511998 1 P 0 
L 8.4365 3.95511998 8.43593002 3.95521998 1 P 0 
L 8.43593002 3.95521998 8.43315 3.95521998 1 P 0 
A 8.43315 3.95521998 8.43051998 3.95631004 8.43315089 3.95893996 1 P 0 Y
L 8.43051998 3.95631004 8.41983996 3.967 1 P 0 
A 8.41983996 3.967 8.38223996 3.967 8.40103996 3.9482 1 P 0 N
A 8.38223996 3.967 8.29701998 3.9317 8.2970189 4.05221998 1 P 0 Y
L 8.29701998 3.9317 8.27036004 3.9317 1 P 0 
A 8.27036004 3.9317 8.14127362 3.95737785 8.2703626 4.26901998 1 P 0 Y
A 8.14127362 3.95737785 8.03183996 4.0305 8.2703623 4.26901998 1 P 0 Y
L 8.03183996 4.0305 8.03183002 4.0305 1 P 0 
L 8.03183002 4.0305 8.01028996 4.05203996 1 P 0 
A 8.01028996 4.05203996 7.96615 4.1601 8.12041998 4.16007057 1 P 0 Y
L 7.96615 4.1601 7.96613996 4.16008996 1 P 0 
L 7.96613996 4.16008996 7.96613996 4.16011004 1 P 0 
A 7.96613996 4.16011004 7.94235 4.1839 7.94235 4.16011004 1 P 0 N
L 7.94235 4.1839 7.94103002 4.1839 1 P 0 
A 7.94103002 4.1839 7.8608 4.21713996 7.94104075 4.29736998 1 P 0 Y
L 7.8608 4.21713996 7.84623996 4.2317 1 P 0 
A 7.84623996 4.2317 7.83351063 4.25074921 7.88776004 4.27322283 1 P 0 Y
A 7.83351063 4.25074921 7.82903996 4.27321998 7.88776004 4.27322254 1 P 0 Y
L 7.82903996 4.27321998 7.82903996 4.29011004 1 P 0 
A 7.82903996 4.29011004 7.84083996 4.3186 7.86933002 4.29011132 1 P 0 Y
A 7.84083996 4.3186 7.86256998 4.3276 7.8625687 4.29686998 1 P 0 Y
L 7.86256998 4.3276 7.86825 4.3276 1 P 0 
A 7.86825 4.3276 7.87664961 4.32927156 7.86824803 4.34955 1 P 0 N
A 7.87664961 4.32927156 7.88376998 4.33403002 7.86824793 4.34955 1 P 0 N
A 7.88376998 4.33403002 7.88376998 4.37626998 7.86265 4.35515 1 P 0 N
L 7.88376998 4.37626998 7.88113996 4.3789 1 P 0 
A 7.88113996 4.3789 7.88113996 4.4044 7.89388996 4.39165 1 P 0 Y
L 7.88113996 4.4044 7.88773996 4.411 1 P 0 
A 7.88773996 4.411 7.89203228 4.41742313 7.87373996 4.42500138 1 P 0 N
A 7.89203228 4.41742313 7.89353996 4.425 7.87373996 4.42500148 1 P 0 N
A 7.89353996 4.425 7.90536998 4.45353002 7.93386004 4.42499892 1 P 0 Y
L 7.90536998 4.45353002 7.91433002 4.46248002 1 P 0 
A 7.91433002 4.46248002 7.92638848 4.4805189 7.87505 4.5017873 1 P 0 N
A 7.92638848 4.4805189 7.93061998 4.5018 7.87505 4.50178819 1 P 0 N
L 7.93061998 4.5018 7.96246004 4.68213996 1 P 0 
L 7.96246004 4.68213996 8.02313996 4.76866004 1 P 0 
L 8.02313996 4.76866004 8.0301 4.80823996 1 P 0 
L 8.0301 4.80823996 8.09036004 4.89431004 1 P 0 
L 8.09036004 4.89431004 8.10623002 4.98428002 1 P 0 
L 8.10623002 4.98428002 8.09151004 5.06791998 1 P 0 
L 8.09151004 5.06791998 8.10028002 5.11765 1 P 0 
L 8.10028002 5.11765 8.10028002 5.1653 1 P 0 
A 8.10028002 5.1653 8.10398002 5.169 8.10398002 5.1653 1 P 0 Y
L 8.10398002 5.169 8.11725 5.169 1 P 0 
P 2.44606004 3.26615 5 P 0 0;2=3,4=1
P 2.39716998 5.115 5 P 0 0;2=3,4=1
L 2.39716998 5.115 2.38476004 5.115 1 P 0 
A 2.38476004 5.115 2.38106004 5.1113 2.38476004 5.1113 1 P 0 N
L 2.38106004 5.1113 2.38106004 5.03666004 1 P 0 
L 2.38106004 5.03666004 2.37718996 5.01468996 1 P 0 
L 2.37718996 5.01468996 2.31991998 4.93288996 1 P 0 
L 2.31991998 4.93288996 2.31191998 4.88745 1 P 0 
L 2.31191998 4.88745 2.31953996 4.84425 1 P 0 
L 2.31953996 4.84425 2.31931004 4.84293996 1 P 0 
L 2.31931004 4.84293996 2.31931004 4.84295 1 P 0 
L 2.31931004 4.84295 2.30865 4.7825 1 P 0 
L 2.30865 4.7825 2.32333996 4.69918996 1 P 0 
L 2.32333996 4.69918996 2.34111998 4.67381004 1 P 0 
L 2.34111998 4.67381004 2.40383996 4.62986998 1 P 0 
A 2.40383996 4.62986998 2.41806575 4.61363691 2.37778002 4.59268248 1 P 0 Y
A 2.41806575 4.61363691 2.42318996 4.59266998 2.37778002 4.59268169 1 P 0 Y
L 2.42318996 4.59266998 2.42318996 4.56673996 1 P 0 
L 2.42318996 4.56673996 2.42045 4.55116998 1 P 0 
L 2.42045 4.55116998 2.41051004 4.53696004 1 P 0 
A 2.41051004 4.53696004 2.401 4.514 2.43346998 4.51400049 1 P 0 N
A 2.401 4.514 2.42116998 4.49383002 2.42116998 4.514 1 P 0 N
L 2.42116998 4.49383002 2.44838002 4.49383002 1 P 0 
L 2.44838002 4.49383002 2.48601998 4.50046998 1 P 0 
L 2.48601998 4.50046998 2.49411004 4.50046998 1 P 0 
A 2.49411004 4.50046998 2.52340236 4.4935626 2.49413219 4.435 1 P 0 Y
A 2.52340236 4.4935626 2.54651004 4.47428002 2.49413297 4.435 1 P 0 Y
L 2.54651004 4.47428002 2.54651998 4.47426998 1 P 0 
L 2.54651998 4.47426998 2.67536004 4.29026004 1 P 0 
A 2.67536004 4.29026004 2.67721998 4.28576998 2.66616004 4.2838188 1 P 0 Y
L 2.67721998 4.28576998 2.70103002 4.15066998 1 P 0 
L 2.70103002 4.15066998 2.70103002 4.15061998 1 P 0 
A 2.70103002 4.15061998 2.69223209 4.11468602 2.62323996 4.15062175 1 P 0 Y
A 2.69223209 4.11468602 2.66783002 4.08688002 2.62323996 4.15062185 1 P 0 Y
L 2.66783002 4.08688002 2.65631998 4.07881998 1 P 0 
L 2.65631998 4.07881998 2.65013996 4.07265 1 P 0 
A 2.65013996 4.07265 2.64 4.04816998 2.67461998 4.04816998 1 P 0 N
L 2.64 4.04816998 2.64 4.04168002 1 P 0 
A 2.64 4.04168002 2.64160758 4.03123681 2.67473996 4.04168238 1 P 0 N
A 2.64160758 4.03123681 2.64628002 4.02176004 2.67473996 4.04168219 1 P 0 N
L 2.64628002 4.02176004 2.71665 3.92125 1 P 0 
L 2.71665 3.92125 2.75223996 3.71941004 1 P 0 
L 2.75223996 3.71941004 2.69863002 3.4154 1 P 0 
A 2.69863002 3.4154 2.69337352 3.39990128 2.64565 3.42472776 1 P 0 Y
A 2.69337352 3.39990128 2.6837 3.3867 2.64565 3.42472677 1 P 0 Y
L 2.6837 3.3867 2.62998002 3.33298002 1 P 0 
A 2.62998002 3.33298002 2.5794939 3.2992436 2.51995295 3.44298996 1 P 0 Y
A 2.5794939 3.2992436 2.51993996 3.2874 2.51995217 3.44298996 1 P 0 Y
L 2.51993996 3.2874 2.44976004 3.2874 1 P 0 
A 2.44976004 3.2874 2.44606004 3.2837 2.44976004 3.2837 1 P 0 N
L 2.44606004 3.2837 2.44606004 3.26615 1 P 0 
P 8.07725 5.169 5 P 0 0;2=3,4=1
P 8.4 3.51615 5 P 0 0;2=3,4=1
L 8.4 3.51615 8.4 3.4986 1 P 0 
A 8.4 3.4986 8.4037 3.4949 8.4037 3.4986 1 P 0 N
L 8.4037 3.4949 8.40618996 3.4949 1 P 0 
A 8.40618996 3.4949 8.40924341 3.49551388 8.40617402 3.50288002 1 P 0 N
A 8.40924341 3.49551388 8.41183002 3.49725 8.4061752 3.50288002 1 P 0 N
L 8.41183002 3.49725 8.42015 3.50556998 1 P 0 
L 8.42015 3.50556998 8.42016004 3.50556998 1 P 0 
A 8.42016004 3.50556998 8.42125 3.5082 8.41753002 3.50820079 1 P 0 N
L 8.42125 3.5082 8.42125 3.57848996 1 P 0 
A 8.42125 3.57848996 8.43766004 3.5949 8.43766004 3.57848996 1 P 0 Y
L 8.43766004 3.5949 8.52473996 3.5949 1 P 0 
A 8.52473996 3.5949 8.54201457 3.59833533 8.52474203 3.64003996 1 P 0 N
A 8.54201457 3.59833533 8.55666004 3.60811998 8.52474301 3.64003996 1 P 0 N
L 8.55666004 3.60811998 8.56533002 3.61678996 1 P 0 
A 8.56533002 3.61678996 8.58653996 3.668 8.51411004 3.66800138 1 P 0 N
A 8.58653996 3.668 8.57283996 3.70108002 8.53975 3.66799902 1 P 0 N
L 8.57283996 3.70108002 8.56553996 3.70838002 1 P 0 
A 8.56553996 3.70838002 8.56553996 3.771 8.59685 3.73969006 1 P 0 Y
L 8.56553996 3.771 8.56988002 3.77535 1 P 0 
A 8.56988002 3.77535 8.57406732 3.7816124 8.55623002 3.78900807 1 P 0 N
A 8.57406732 3.7816124 8.57553996 3.789 8.55623002 3.78900866 1 P 0 N
A 8.57553996 3.789 8.57208002 3.79736004 8.56371004 3.789 1 P 0 N
L 8.57208002 3.79736004 8.57206998 3.79736004 1 P 0 
L 8.57206998 3.79736004 8.56326998 3.80616998 1 P 0 
A 8.56326998 3.80616998 8.56028002 3.81155 8.5712 3.81409793 1 P 0 Y
L 8.56028002 3.81155 8.55783996 3.82203996 1 P 0 
L 8.55783996 3.82203996 8.55783002 3.82203996 1 P 0 
A 8.55783002 3.82203996 8.55755 3.82456998 8.56878002 3.82453238 1 P 0 Y
L 8.55755 3.82456998 8.55753996 3.82918996 1 P 0 
L 8.55753996 3.82918996 8.55753996 3.86131004 1 P 0 
A 8.55753996 3.86131004 8.49373996 3.93738002 8.48028996 3.86130984 1 P 0 N
L 8.49373996 3.93738002 8.43525 3.94771998 1 P 0 
L 8.43525 3.94771998 8.43315 3.94771998 1 P 0 
A 8.43315 3.94771998 8.42885276 3.94857539 8.43315167 3.95895 1 P 0 Y
A 8.42885276 3.94857539 8.42521004 3.95101004 8.43315177 3.95895 1 P 0 Y
L 8.42521004 3.95101004 8.41453002 3.9617 1 P 0 
A 8.41453002 3.9617 8.40103947 3.9672812 8.40104508 3.9482 1 P 0 N
A 8.40103947 3.9672812 8.38755 3.96168996 8.40104488 3.9482 1 P 0 N
A 8.38755 3.96168996 8.34601811 3.9339436 8.29702835 4.05223002 1 P 0 Y
A 8.34601811 3.9339436 8.29703002 3.9242 8.29702825 4.05223002 1 P 0 Y
L 8.29703002 3.9242 8.27035 3.9242 1 P 0 
A 8.27035 3.9242 8.13839636 3.95044705 8.27035325 4.26903002 1 P 0 Y
A 8.13839636 3.95044705 8.02653002 4.02518996 8.27035315 4.26903002 1 P 0 Y
L 8.02653002 4.02518996 8.00601004 4.04571004 1 P 0 
L 8.00601004 4.04571004 8.006 4.04571004 1 P 0 
A 8.006 4.04571004 8.00493002 4.04678996 8.12038996 4.16011703 1 P 0 Y
A 8.00493002 4.04678996 7.95863996 4.1601 8.12041998 4.16008091 1 P 0 Y
L 7.95863996 4.1601 7.95863996 4.16011004 1 P 0 
A 7.95863996 4.16011004 7.94235 4.1764 7.94235 4.16011004 1 P 0 N
L 7.94235 4.1764 7.94103002 4.1764 1 P 0 
A 7.94103002 4.1764 7.89473652 4.18560748 7.94102776 4.29736998 1 P 0 Y
A 7.89473652 4.18560748 7.85548996 4.21183002 7.94102687 4.29736998 1 P 0 Y
L 7.85548996 4.21183002 7.84093002 4.22638996 1 P 0 
A 7.84093002 4.22638996 7.82153996 4.27321004 7.88776004 4.27320925 1 P 0 Y
L 7.82153996 4.27321004 7.82153996 4.2901 1 P 0 
A 7.82153996 4.2901 7.82517106 4.30839656 7.86933002 4.29012421 1 P 0 Y
A 7.82517106 4.30839656 7.83553002 4.32391004 7.86933002 4.2901252 1 P 0 Y
A 7.83553002 4.32391004 7.8479373 4.33219469 7.86255492 4.29686998 1 P 0 Y
A 7.8479373 4.33219469 7.86256998 4.3351 7.86255581 4.29686998 1 P 0 Y
L 7.86256998 4.3351 7.86823996 4.3351 1 P 0 
A 7.86823996 4.3351 7.87377224 4.33620305 7.86823494 4.34955 1 P 0 N
A 7.87377224 4.33620305 7.87846004 4.33933996 7.86823435 4.34955 1 P 0 N
A 7.87846004 4.33933996 7.87846004 4.37096004 7.86265 4.35515 1 P 0 N
L 7.87846004 4.37096004 7.87583002 4.37358996 1 P 0 
A 7.87583002 4.37358996 7.87583002 4.40971004 7.89388996 4.39165 1 P 0 Y
L 7.87583002 4.40971004 7.88243002 4.41631004 1 P 0 
A 7.88243002 4.41631004 7.88603002 4.425 7.87373996 4.42500079 1 P 0 N
A 7.88603002 4.425 7.8896815 4.44331762 7.93386004 4.42498819 1 P 0 Y
A 7.8896815 4.44331762 7.90006998 4.45883996 7.93386004 4.42498809 1 P 0 Y
L 7.90006998 4.45883996 7.90903002 4.46778996 1 P 0 
A 7.90903002 4.46778996 7.92311004 4.5018 7.87503996 4.5017813 1 P 0 N
L 7.92311004 4.5018 7.92311004 4.50246004 1 P 0 
L 7.92311004 4.50246004 7.95536004 4.68508002 1 P 0 
L 7.95536004 4.68508002 8.01603996 4.7716 1 P 0 
L 8.01603996 4.7716 8.023 4.81118002 1 P 0 
L 8.023 4.81118002 8.02863996 4.81925 1 P 0 
L 8.02863996 4.81925 8.02863996 4.81923996 1 P 0 
L 8.02863996 4.81923996 8.03333996 4.82595 1 P 0 
L 8.03333996 4.82595 8.03205 4.83316998 1 P 0 
L 8.03205 4.83316998 8.03843002 4.84226998 1 P 0 
L 8.03843002 4.84226998 8.04563996 4.84351998 1 P 0 
L 8.04563996 4.84351998 8.05201998 4.85263002 1 P 0 
L 8.05201998 4.85263002 8.05073002 4.85985 1 P 0 
L 8.05073002 4.85985 8.05711004 4.86895 1 P 0 
L 8.05711004 4.86895 8.06431998 4.8702 1 P 0 
L 8.06431998 4.8702 8.08326004 4.89725 1 P 0 
L 8.08326004 4.89725 8.09861004 4.98428002 1 P 0 
L 8.09861004 4.98428002 8.08388996 5.06791998 1 P 0 
L 8.08388996 5.06791998 8.09278002 5.11831004 1 P 0 
L 8.09278002 5.11831004 8.09278002 5.1653 1 P 0 
A 8.09278002 5.1653 8.08908002 5.169 8.08908002 5.1653 1 P 0 N
L 8.08908002 5.169 8.07725 5.169 1 P 0 
P 2.44606004 3.31615 5 P 0 0;2=3,4=1
P 2.35716998 5.115 5 P 0 0;2=3,4=1
L 2.35716998 5.115 2.36986004 5.115 1 P 0 
A 2.36986004 5.115 2.37356004 5.1113 2.36986004 5.1113 1 P 0 Y
L 2.37356004 5.1113 2.37356004 5.03731998 1 P 0 
L 2.37356004 5.03731998 2.37008996 5.01763002 1 P 0 
L 2.37008996 5.01763002 2.35253002 4.99255 1 P 0 
L 2.35253002 4.99255 2.34576998 4.99136004 1 P 0 
L 2.34576998 4.99136004 2.33938996 4.98223996 1 P 0 
L 2.33938996 4.98223996 2.34058996 4.9755 1 P 0 
L 2.34058996 4.9755 2.33421004 4.96638996 1 P 0 
L 2.33421004 4.96638996 2.32745 4.9652 1 P 0 
L 2.32745 4.9652 2.32106998 4.95608002 1 P 0 
L 2.32106998 4.95608002 2.32228002 4.94933996 1 P 0 
L 2.32228002 4.94933996 2.31281998 4.93583002 1 P 0 
L 2.31281998 4.93583002 2.3043 4.88745 1 P 0 
L 2.3043 4.88745 2.30451998 4.88615 1 P 0 
L 2.30451998 4.88615 2.30453002 4.88615 1 P 0 
L 2.30453002 4.88615 2.31191998 4.84425 1 P 0 
L 2.31191998 4.84425 2.30103002 4.7825 1 P 0 
L 2.30103002 4.7825 2.31623996 4.69625 1 P 0 
L 2.31623996 4.69625 2.33573002 4.66841998 1 P 0 
L 2.33573002 4.66841998 2.39953002 4.62371998 1 P 0 
A 2.39953002 4.62371998 2.41568996 4.59266998 2.37778002 4.59266998 1 P 0 Y
L 2.41568996 4.59266998 2.41568996 4.5674 1 P 0 
L 2.41568996 4.5674 2.41335 4.55411004 1 P 0 
L 2.41335 4.55411004 2.40471004 4.54176004 1 P 0 
A 2.40471004 4.54176004 2.39640246 4.52897008 2.43346004 4.51399272 1 P 0 N
A 2.39640246 4.52897008 2.39348996 4.514 2.43346004 4.51399203 1 P 0 N
A 2.39348996 4.514 2.42116998 4.48633002 2.42115994 4.514 1 P 0 N
L 2.42116998 4.48633002 2.44903996 4.48633002 1 P 0 
L 2.44903996 4.48633002 2.48668002 4.49296998 1 P 0 
L 2.48668002 4.49296998 2.49411998 4.49296998 1 P 0 
A 2.49411998 4.49296998 2.5405 4.46976998 2.49411998 4.43501004 1 P 0 Y
L 2.5405 4.46976998 2.54061004 4.46963002 1 P 0 
L 2.54061004 4.46963002 2.66921004 4.28595 1 P 0 
A 2.66921004 4.28595 2.66960079 4.2852439 2.66616998 4.2838065 1 P 0 Y
A 2.66960079 4.2852439 2.66983002 4.28446998 2.66616998 4.28380679 1 P 0 Y
L 2.66983002 4.28446998 2.69351998 4.15003002 1 P 0 
A 2.69351998 4.15003002 2.68543425 4.11789154 2.62323996 4.15062539 1 P 0 Y
A 2.68543425 4.11789154 2.66351998 4.09303002 2.62323996 4.15062392 1 P 0 Y
L 2.66351998 4.09303002 2.65148002 4.08458996 1 P 0 
L 2.65148002 4.08458996 2.64483002 4.07796004 1 P 0 
A 2.64483002 4.07796004 2.63570187 4.06429114 2.67461998 4.04818376 1 P 0 N
A 2.63570187 4.06429114 2.6325 4.04816998 2.67461998 4.04818297 1 P 0 N
L 2.6325 4.04816998 2.6325 4.04166998 1 P 0 
A 2.6325 4.04166998 2.63445236 4.02897333 2.67475 4.04166831 1 P 0 N
A 2.63445236 4.02897333 2.64013002 4.01745 2.67475 4.04166801 1 P 0 N
L 2.64013002 4.01745 2.70955 3.91831004 1 P 0 
L 2.70955 3.91831004 2.74461998 3.71941004 1 P 0 
L 2.74461998 3.71941004 2.69123996 3.4167 1 P 0 
A 2.69123996 3.4167 2.68671486 3.40336654 2.64566004 3.42473425 1 P 0 Y
A 2.68671486 3.40336654 2.67838996 3.39201004 2.64566004 3.42473228 1 P 0 Y
L 2.67838996 3.39201004 2.62466998 3.33828996 1 P 0 
A 2.62466998 3.33828996 2.51993996 3.2949 2.51993917 3.44298996 1 P 0 Y
L 2.51993996 3.2949 2.44976004 3.2949 1 P 0 
A 2.44976004 3.2949 2.44606004 3.2986 2.44976004 3.2986 1 P 0 Y
L 2.44606004 3.2986 2.44606004 3.31615 1 P 0 
P 8.5 3.46615 5 P 0 0;2=3,4=1
P 8.07206998 4.66688996 5 P 0 0;2=3,4=1
L 8.5 3.46615 8.5 3.4837 1 P 0 
A 8.5 3.4837 8.5037 3.4874 8.5037 3.4837 1 P 0 Y
L 8.5037 3.4874 8.54761004 3.4874 1 P 0 
A 8.54761004 3.4874 8.59938996 3.50885 8.54761122 3.56061998 1 P 0 N
L 8.59938996 3.50885 8.61126998 3.52073002 1 P 0 
A 8.61126998 3.52073002 8.62501654 3.53947697 8.55723996 3.57476201 1 P 0 N
A 8.62501654 3.53947697 8.63248996 3.56148996 8.55723996 3.5747623 1 P 0 N
L 8.63248996 3.56148996 8.65983996 3.71668996 1 P 0 
L 8.65983996 3.71668996 8.63196998 3.87468996 1 P 0 
L 8.63196998 3.87468996 8.57226004 3.95998996 1 P 0 
A 8.57226004 3.95998996 8.54833937 3.97772864 8.50330364 3.892 1 P 0 N
A 8.54833937 3.97772864 8.52016004 3.98736004 8.50330256 3.892 1 P 0 N
L 8.52016004 3.98736004 8.47073996 3.99608996 1 P 0 
A 8.47073996 3.99608996 8.44508996 4.00945 8.47910876 4.04346004 1 P 0 Y
L 8.44508996 4.00945 8.41953996 4.035 1 P 0 
A 8.41953996 4.035 8.38753996 4.035 8.40353996 4.019 1 P 0 N
L 8.38753996 4.035 8.38751998 4.03498002 1 P 0 
A 8.38751998 4.03498002 8.33216093 3.99798976 8.26685866 4.15563996 1 P 0 Y
A 8.33216093 3.99798976 8.26686004 3.985 8.26685846 4.15563996 1 P 0 Y
L 8.26686004 3.985 8.24388996 3.985 1 P 0 
A 8.24388996 3.985 8.15948986 4.00178996 8.24389449 4.20555 1 P 0 Y
A 8.15948986 4.00178996 8.08793996 4.0496 8.24389498 4.20555 1 P 0 Y
L 8.08793996 4.0496 8.08653996 4.051 1 P 0 
A 8.08653996 4.051 8.03753091 4.12035738 8.26373996 4.2282064 1 P 0 Y
A 8.03753091 4.12035738 8.0145 4.2021 8.26373996 4.22820738 1 P 0 Y
L 8.0145 4.2021 8.0145 4.20278002 1 P 0 
A 8.0145 4.20278002 8.0124315 4.2131815 7.98731998 4.2027812 1 P 0 N
A 8.0124315 4.2131815 8.00653996 4.222 7.98731998 4.20278209 1 P 0 N
L 8.00653996 4.222 8.00513996 4.2234 1 P 0 
A 8.00513996 4.2234 7.97953996 4.234 7.97954124 4.19778996 1 P 0 N
L 7.97953996 4.234 7.96591998 4.234 1 P 0 
A 7.96591998 4.234 7.94893691 4.23737923 7.96592283 4.27838002 1 P 0 Y
A 7.94893691 4.23737923 7.93453996 4.247 7.96592264 4.27838002 1 P 0 Y
A 7.93453996 4.247 7.92768829 4.26354646 7.95108996 4.26354498 1 P 0 Y
A 7.92768829 4.26354646 7.93453996 4.28008996 7.95108996 4.26354498 1 P 0 Y
L 7.93453996 4.28008996 7.93455 4.2801 1 P 0 
A 7.93455 4.2801 7.96326998 4.292 7.96327126 4.25138996 1 P 0 Y
L 7.96326998 4.292 7.98823002 4.292 1 P 0 
A 7.98823002 4.292 7.99868071 4.29407963 7.98822776 4.31931004 1 P 0 N
A 7.99868071 4.29407963 8.00753996 4.3 7.98822776 4.31931004 1 P 0 N
A 8.00753996 4.3 8.00753996 4.33218002 7.99145 4.31609006 1 P 0 N
L 8.00753996 4.33218002 8.00753002 4.33218996 1 P 0 
A 8.00753002 4.33218996 7.98345 4.35248002 7.87671998 4.20138002 1 P 0 N
L 7.98345 4.35248002 7.96986998 4.36196998 1 P 0 
L 7.96986998 4.36196998 7.96583002 4.366 1 P 0 
A 7.96583002 4.366 7.95355 4.39568996 7.99556004 4.3956811 1 P 0 Y
L 7.95355 4.39568996 7.95353996 4.39568002 1 P 0 
L 7.95353996 4.39568002 7.95353996 4.40366004 1 P 0 
A 7.95353996 4.40366004 7.99188996 4.44198996 7.99186988 4.40366004 1 P 0 Y
A 7.99188996 4.44198996 7.99711112 4.44095344 7.99189163 4.42833002 1 P 0 Y
A 7.99711112 4.44095344 8.00153996 4.438 7.99189213 4.42833002 1 P 0 Y
L 8.00153996 4.438 8.00635 4.43318996 1 P 0 
A 8.00635 4.43318996 8.01709045 4.42601496 8.02974213 4.45658002 1 P 0 N
A 8.01709045 4.42601496 8.02976004 4.4235 8.02974213 4.45658002 1 P 0 N
L 8.02976004 4.4235 8.03751998 4.4235 1 P 0 
A 8.03751998 4.4235 8.05805 4.44401004 8.03753986 4.44401004 1 P 0 N
A 8.05805 4.44401004 8.05611998 4.45369774 8.03273002 4.44400177 1 P 0 N
A 8.05611998 4.45369774 8.05063002 4.46191004 8.03273002 4.44400256 1 P 0 N
L 8.05063002 4.46191004 8.01076004 4.50178002 1 P 0 
A 8.01076004 4.50178002 8.0057877 4.50922234 8.02698996 4.51800571 1 P 0 Y
A 8.0057877 4.50922234 8.00403996 4.518 8.02698996 4.51800679 1 P 0 Y
L 8.00403996 4.518 8.00403996 4.52 1 P 0 
A 8.00403996 4.52 8.0216 4.53756004 8.0216 4.52 1 P 0 Y
L 8.0216 4.53756004 8.02161998 4.53756004 1 P 0 
A 8.02161998 4.53756004 8.05279961 4.53135591 8.02161811 4.4561 1 P 0 Y
A 8.05279961 4.53135591 8.07923002 4.51368996 8.02161811 4.4561 1 P 0 Y
L 8.07923002 4.51368996 8.08743996 4.50548002 1 P 0 
A 8.08743996 4.50548002 8.13063996 4.50548002 8.10903996 4.52708002 1 P 0 N
L 8.13063996 4.50548002 8.13535 4.51018996 1 P 0 
A 8.13535 4.51018996 8.14342362 4.52968652 8.11585 4.52968494 1 P 0 N
A 8.14342362 4.52968652 8.13535 4.54918002 8.11585 4.52968504 1 P 0 N
L 8.13535 4.54918002 8.13318996 4.55133996 1 P 0 
L 8.13318996 4.55133996 8.08281998 4.58676998 1 P 0 
L 8.08281998 4.58676998 8.05826998 4.62178996 1 P 0 
L 8.05826998 4.62178996 8.05596004 4.63488996 1 P 0 
L 8.05596004 4.63488996 8.05596004 4.66318996 1 P 0 
A 8.05596004 4.66318996 8.05966004 4.66688996 8.05966004 4.66318996 1 P 0 Y
L 8.05966004 4.66688996 8.07206998 4.66688996 1 P 0 
P 2.25543996 4.78291998 5 P 0 0;2=3,4=1
P 2.49606004 3.31615 5 P 0 0;2=3,4=1
L 2.25543996 4.78291998 2.24303002 4.78291998 1 P 0 
A 2.24303002 4.78291998 2.23933002 4.77921998 2.24303002 4.77921998 1 P 0 N
L 2.23933002 4.77921998 2.23933002 4.752 1 P 0 
L 2.23933002 4.752 2.24136004 4.74046998 1 P 0 
L 2.24136004 4.74046998 2.24973002 4.7285 1 P 0 
L 2.24973002 4.7285 2.30065 4.69286004 1 P 0 
L 2.30065 4.69286004 2.3381 4.6394 1 P 0 
L 2.3381 4.6394 2.39035 4.60283996 1 P 0 
A 2.39035 4.60283996 2.39637402 4.59437726 2.37313996 4.58421388 1 P 0 Y
A 2.39637402 4.59437726 2.3985 4.58421004 2.37313996 4.58421309 1 P 0 Y
L 2.3985 4.58421004 2.3985 4.57483002 1 P 0 
A 2.3985 4.57483002 2.35983002 4.54238002 2.3655497 4.57483002 1 P 0 Y
L 2.35983002 4.54238002 2.28351004 4.55581004 1 P 0 
A 2.28351004 4.55581004 2.25436998 4.55046998 2.2840127 4.47088996 1 P 0 N
A 2.25436998 4.55046998 2.24702539 4.5467877 2.2678436 4.51443002 1 P 0 N
A 2.24702539 4.5467877 2.24063002 4.54163002 2.26784341 4.51443002 1 P 0 N
L 2.24063002 4.54163002 2.2406 4.5416 1 P 0 
A 2.2406 4.5416 2.23805994 4.53856132 2.2563 4.52589528 1 P 0 N
A 2.23805994 4.53856132 2.2361 4.53511998 2.2563 4.52589429 1 P 0 N
L 2.2361 4.53511998 2.23185 4.52578002 1 P 0 
A 2.23185 4.52578002 2.22918002 4.51026998 2.26006004 4.51293898 1 P 0 N
A 2.22918002 4.51026998 2.22926004 4.50771998 2.27073996 4.51029793 1 P 0 N
A 2.22926004 4.50771998 2.23974409 4.48258209 2.27075 4.5102687 1 P 0 N
A 2.23974409 4.48258209 2.26353996 4.46933002 2.27075167 4.51026998 1 P 0 N
L 2.26353996 4.46933002 2.35396998 4.45338996 1 P 0 
L 2.35396998 4.45338996 2.48885 4.47716998 1 P 0 
L 2.48885 4.47716998 2.48953002 4.47716998 1 P 0 
A 2.48953002 4.47716998 2.52016004 4.4645 2.48955876 4.43388002 1 P 0 Y
L 2.52016004 4.4645 2.52018996 4.46446998 1 P 0 
A 2.52018996 4.46446998 2.52864272 4.45182077 2.49263002 4.43690433 1 P 0 Y
A 2.52864272 4.45182077 2.53161004 4.4369 2.49263002 4.43690344 1 P 0 Y
A 2.53161004 4.4369 2.52853691 4.42146467 2.49128002 4.436906 1 P 0 Y
A 2.52853691 4.42146467 2.51978996 4.40838002 2.49128002 4.43690453 1 P 0 Y
L 2.51978996 4.40838002 2.51978002 4.40838002 1 P 0 
L 2.51978002 4.40838002 2.51241004 4.401 1 P 0 
L 2.51241004 4.401 2.51241004 4.40098996 1 P 0 
A 2.51241004 4.40098996 2.51241004 4.37551004 2.52515 4.38825 1 P 0 N
L 2.51241004 4.37551004 2.51276998 4.37515 1 P 0 
A 2.51276998 4.37515 2.51814203 4.37116083 2.52892234 4.39128996 1 P 0 N
A 2.51814203 4.37116083 2.52443996 4.3689 2.52892274 4.39128996 1 P 0 N
L 2.52443996 4.3689 2.53101004 4.36758996 1 P 0 
L 2.53101004 4.36758996 2.53126998 4.36755 1 P 0 
L 2.53126998 4.36755 2.58471998 4.35811998 1 P 0 
A 2.58471998 4.35811998 2.59543504 4.35448209 2.57826211 4.3215 1 P 0 Y
A 2.59543504 4.35448209 2.60456004 4.34778996 2.57826289 4.3215 1 P 0 Y
L 2.60456004 4.34778996 2.61193002 4.34043002 1 P 0 
L 2.61193002 4.34043002 2.65066998 4.2851 1 P 0 
A 2.65066998 4.2851 2.65238632 4.28182894 2.6388 4.27678593 1 P 0 Y
A 2.65238632 4.28182894 2.65321998 4.27823002 2.6388 4.27678573 1 P 0 Y
A 2.65321998 4.27823002 2.65415 4.26371998 2.37168996 4.25290059 1 P 0 Y
A 2.65415 4.26371998 2.64468051 4.24008435 2.61516998 4.26562234 1 P 0 Y
A 2.64468051 4.24008435 2.62265 4.22731998 2.61517224 4.26561998 1 P 0 Y
L 2.62265 4.22731998 2.60218996 4.22731998 1 P 0 
A 2.60218996 4.22731998 2.578 4.2173 2.60219016 4.19311004 1 P 0 N
L 2.578 4.2173 2.57726004 4.21656004 1 P 0 
A 2.57726004 4.21656004 2.5697 4.1983 2.59553002 4.19830089 1 P 0 N
A 2.5697 4.1983 2.5863 4.1817 2.5863 4.1983 1 P 0 N
L 2.5863 4.1817 2.62943996 4.1817 1 P 0 
A 2.62943996 4.1817 2.64262805 4.17907815 2.62944183 4.14723002 1 P 0 Y
A 2.64262805 4.17907815 2.65381004 4.17161004 2.62944252 4.14723002 1 P 0 Y
A 2.65381004 4.17161004 2.65381004 4.11518996 2.6256 4.1434 1 P 0 Y
L 2.65381004 4.11518996 2.64493996 4.10631998 1 P 0 
A 2.64493996 4.10631998 2.57333002 4.07563996 2.57079026 4.18048002 1 P 0 Y
L 2.57333002 4.07563996 2.57321004 4.07563996 1 P 0 
A 2.57321004 4.07563996 2.56381388 4.07376614 2.57322293 4.05108002 1 P 0 N
A 2.56381388 4.07376614 2.55585 4.06843996 2.57322313 4.05108002 1 P 0 N
L 2.55585 4.06843996 2.5544 4.06698996 1 P 0 
A 2.5544 4.06698996 2.5511313 4.0590935 2.5623 4.05909498 1 P 0 N
A 2.5511313 4.0590935 2.5544 4.0512 2.5623 4.05909488 1 P 0 N
L 2.5544 4.0512 2.55441998 4.05118002 1 P 0 
A 2.55441998 4.05118002 2.55848002 4.04846112 2.5632936 4.06003996 1 P 0 N
A 2.55848002 4.04846112 2.56326998 4.0475 2.56329478 4.06003996 1 P 0 N
L 2.56326998 4.0475 2.57296004 4.0475 1 P 0 
A 2.57296004 4.0475 2.60576004 4.0339 2.57296122 4.00115 1 P 0 Y
L 2.60576004 4.0339 2.61388996 4.02576998 1 P 0 
L 2.61388996 4.02576998 2.69495 3.91001004 1 P 0 
L 2.69495 3.91001004 2.72883996 3.71788002 1 P 0 
L 2.72883996 3.71788002 2.6805 3.44365 1 P 0 
A 2.6805 3.44365 2.67218888 3.41915935 2.59676004 3.4584123 1 P 0 Y
A 2.67218888 3.41915935 2.6569 3.3983 2.59676004 3.4584123 1 P 0 Y
L 2.6569 3.3983 2.63083002 3.37221998 1 P 0 
A 2.63083002 3.37221998 2.59225394 3.34644518 2.54677274 3.45626998 1 P 0 Y
A 2.59225394 3.34644518 2.54675 3.3374 2.54677224 3.45626998 1 P 0 Y
L 2.54675 3.3374 2.49976004 3.3374 1 P 0 
A 2.49976004 3.3374 2.49606004 3.3337 2.49976004 3.3337 1 P 0 N
L 2.49606004 3.3337 2.49606004 3.31615 1 P 0 
P 8.5 3.51615 5 P 0 0;2=3,4=1
P 8.03206998 4.66688996 5 P 0 0;2=3,4=1
L 8.5 3.51615 8.5 3.4986 1 P 0 
A 8.5 3.4986 8.5037 3.4949 8.5037 3.4986 1 P 0 N
L 8.5037 3.4949 8.54761998 3.4949 1 P 0 
A 8.54761998 3.4949 8.57276535 3.49990994 8.54759774 3.56061998 1 P 0 N
A 8.57276535 3.49990994 8.59408002 3.51416004 8.54759793 3.56061998 1 P 0 N
L 8.59408002 3.51416004 8.60596004 3.52603996 1 P 0 
A 8.60596004 3.52603996 8.61835758 3.54294222 8.55723996 3.57477313 1 P 0 N
A 8.61835758 3.54294222 8.6251 3.56278996 8.55723996 3.57477343 1 P 0 N
L 8.6251 3.56278996 8.65221998 3.71668996 1 P 0 
L 8.65221998 3.71668996 8.62486998 3.87175 1 P 0 
L 8.62486998 3.87175 8.56648002 3.95516004 1 P 0 
A 8.56648002 3.95516004 8.54457323 3.97122894 8.50330453 3.892 1 P 0 N
A 8.54457323 3.97122894 8.51885 3.97996998 8.50330354 3.892 1 P 0 N
L 8.51885 3.97996998 8.46943996 3.9887 1 P 0 
A 8.46943996 3.9887 8.45342205 3.99413819 8.47910266 4.04346998 1 P 0 Y
A 8.45342205 3.99413819 8.43978002 4.00413996 8.47910256 4.04346998 1 P 0 Y
L 8.43978002 4.00413996 8.41423002 4.02968996 1 P 0 
A 8.41423002 4.02968996 8.39285 4.02968996 8.40354006 4.019 1 P 0 N
L 8.39285 4.02968996 8.39283002 4.02966998 1 P 0 
A 8.39283002 4.02966998 8.33503819 3.99105817 8.26687254 4.15563996 1 P 0 Y
A 8.33503819 3.99105817 8.26686998 3.9775 8.26687165 4.15563996 1 P 0 Y
L 8.26686998 3.9775 8.24388002 3.9775 1 P 0 
A 8.24388002 3.9775 8.08263002 4.04428996 8.2438814 4.20555 1 P 0 Y
L 8.08263002 4.04428996 8.08123002 4.04568996 1 P 0 
A 8.08123002 4.04568996 8.03075768 4.11712234 8.26373996 4.22819439 1 P 0 Y
A 8.03075768 4.11712234 8.00703996 4.20131004 8.26373996 4.2281939 1 P 0 Y
L 8.00703996 4.20131004 8.007 4.20135 1 P 0 
L 8.007 4.20135 8.007 4.20278996 1 P 0 
L 8.007 4.20278996 8.00698996 4.20278002 1 P 0 
A 8.00698996 4.20278002 8.00549341 4.21030768 7.98731998 4.20278209 1 P 0 N
A 8.00549341 4.21030768 8.00123002 4.21668996 7.98731998 4.20278287 1 P 0 N
L 8.00123002 4.21668996 7.99983002 4.21808996 1 P 0 
A 7.99983002 4.21808996 7.99052579 4.22431004 7.97952776 4.19778996 1 P 0 N
A 7.99052579 4.22431004 7.97955 4.2265 7.97952795 4.19778996 1 P 0 N
L 7.97955 4.2265 7.96591004 4.2265 1 P 0 
A 7.96591004 4.2265 7.92923002 4.24168996 7.96590935 4.27838002 1 P 0 Y
A 7.92923002 4.24168996 7.92017884 4.26354646 7.95108996 4.26354498 1 P 0 Y
A 7.92017884 4.26354646 7.92923002 4.2854 7.95108996 4.26354498 1 P 0 Y
L 7.92923002 4.2854 7.92923996 4.28541004 1 P 0 
A 7.92923996 4.28541004 7.94484882 4.29583858 7.96325748 4.25138996 1 P 0 Y
A 7.94484882 4.29583858 7.96326004 4.2995 7.96325797 4.25138996 1 P 0 Y
L 7.96326004 4.2995 7.98821998 4.2995 1 P 0 
A 7.98821998 4.2995 7.99580797 4.30100925 7.98822382 4.31931004 1 P 0 N
A 7.99580797 4.30100925 8.00223996 4.30531004 7.9882249 4.31931004 1 P 0 N
L 8.00223996 4.30531004 8.00223002 4.30531004 1 P 0 
A 8.00223002 4.30531004 8.00223002 4.32686998 7.99145 4.31609006 1 P 0 N
L 8.00223002 4.32686998 8.00221998 4.32688002 1 P 0 
A 8.00221998 4.32688002 7.97913996 4.34633996 7.87668593 4.20141004 1 P 0 N
L 7.97913996 4.34633996 7.96503002 4.3562 1 P 0 
L 7.96503002 4.3562 7.96053002 4.36068996 1 P 0 
A 7.96053002 4.36068996 7.94980532 4.37674961 7.99555 4.3956873 1 P 0 Y
A 7.94980532 4.37674961 7.94603996 4.39568996 7.99555 4.39568809 1 P 0 Y
L 7.94603996 4.39568996 7.94603996 4.40366004 1 P 0 
A 7.94603996 4.40366004 7.99188002 4.4495 7.99187992 4.40366004 1 P 0 Y
A 7.99188002 4.4495 7.99998032 4.44789419 7.99189459 4.42833996 1 P 0 Y
A 7.99998032 4.44789419 8.00685 4.44331004 7.99189606 4.42833996 1 P 0 Y
L 8.00685 4.44331004 8.01166004 4.4385 1 P 0 
A 8.01166004 4.4385 8.01996388 4.43294843 8.02975522 4.45658002 1 P 0 N
A 8.01996388 4.43294843 8.02976004 4.431 8.029756 4.45658002 1 P 0 N
L 8.02976004 4.431 8.03753002 4.431 1 P 0 
A 8.03753002 4.431 8.05053996 4.44401004 8.03753002 4.44400994 1 P 0 N
A 8.05053996 4.44401004 8.04918189 4.45082382 8.03273002 4.44400256 1 P 0 N
A 8.04918189 4.45082382 8.04531998 4.4566 8.03273002 4.44400335 1 P 0 N
L 8.04531998 4.4566 8.00545 4.49646998 1 P 0 
A 8.00545 4.49646998 7.99885689 4.50634498 8.027 4.51799646 1 P 0 Y
A 7.99885689 4.50634498 7.99653996 4.51798996 8.027 4.51799744 1 P 0 Y
L 7.99653996 4.51798996 7.99653996 4.52 1 P 0 
A 7.99653996 4.52 8.0216 4.54506004 8.0216 4.52 1 P 0 Y
L 8.0216 4.54506004 8.02163002 4.54506004 1 P 0 
A 8.02163002 4.54506004 8.05567697 4.53828671 8.02162746 4.45608996 1 P 0 Y
A 8.05567697 4.53828671 8.08453996 4.519 8.02162707 4.45608996 1 P 0 Y
L 8.08453996 4.519 8.09275 4.51078996 1 P 0 
A 8.09275 4.51078996 8.12533002 4.51078996 8.10904006 4.52708002 1 P 0 N
L 8.12533002 4.51078996 8.13003996 4.5155 1 P 0 
A 8.13003996 4.5155 8.13591407 4.52968652 8.11585 4.52968494 1 P 0 N
A 8.13591407 4.52968652 8.13003996 4.54386998 8.11585 4.52968504 1 P 0 N
L 8.13003996 4.54386998 8.12833996 4.54558002 1 P 0 
L 8.12833996 4.54558002 8.12253002 4.54966004 1 P 0 
L 8.12253002 4.54966004 8.12253996 4.54966004 1 P 0 
L 8.12253996 4.54966004 8.10956004 4.55878996 1 P 0 
L 8.10956004 4.55878996 8.10271004 4.55758002 1 P 0 
L 8.10271004 4.55758002 8.09361998 4.56398002 1 P 0 
L 8.09361998 4.56398002 8.09243002 4.57083002 1 P 0 
L 8.09243002 4.57083002 8.07743002 4.58138996 1 P 0 
L 8.07743002 4.58138996 8.06943996 4.59278002 1 P 0 
L 8.06943996 4.59278002 8.062 4.59408002 1 P 0 
L 8.062 4.59408002 8.05561998 4.60318996 1 P 0 
L 8.05561998 4.60318996 8.05693996 4.61061004 1 P 0 
L 8.05693996 4.61061004 8.05116998 4.61885 1 P 0 
L 8.05116998 4.61885 8.04846004 4.63423002 1 P 0 
L 8.04846004 4.63423002 8.04846004 4.66318996 1 P 0 
A 8.04846004 4.66318996 8.04476004 4.66688996 8.04476004 4.66318996 1 P 0 N
L 8.04476004 4.66688996 8.03206998 4.66688996 1 P 0 
L 4.02 4.42 4.04325 4.39675 2 P 0 
L 4.04325 4.39675 4.04325 2.82868996 2 P 0 
L 4.04325 2.82868996 4.10578996 2.76615 2 P 0 
L 4.10578996 2.76615 4.58268002 2.76615 2 P 0 
P 4.02 4.42 6 P 0 0;2=2,4=1
P 4.58268002 2.76615 5 P 0 0;2=3,4=1
P 2.21543996 4.78291998 5 P 0 0;2=3,4=1
P 2.49606004 3.36615 5 P 0 0;2=3,4=1
L 2.21543996 4.78291998 2.22813002 4.78291998 1 P 0 
A 2.22813002 4.78291998 2.23183002 4.77921998 2.22813002 4.77921998 1 P 0 Y
L 2.23183002 4.77921998 2.23183002 4.75133996 1 P 0 
L 2.23183002 4.75133996 2.23425 4.73753002 1 P 0 
L 2.23425 4.73753002 2.24433996 4.72311004 1 P 0 
L 2.24433996 4.72311004 2.29526004 4.68746998 1 P 0 
L 2.29526004 4.68746998 2.31305 4.66206004 1 P 0 
L 2.31305 4.66206004 2.31191998 4.6557 1 P 0 
L 2.31191998 4.6557 2.3183 4.64658996 1 P 0 
L 2.3183 4.64658996 2.32466998 4.64546998 1 P 0 
L 2.32466998 4.64546998 2.33271004 4.634 1 P 0 
L 2.33271004 4.634 2.34661998 4.62426998 1 P 0 
L 2.34661998 4.62426998 2.34751998 4.61908996 1 P 0 
L 2.34751998 4.61908996 2.35663002 4.61271004 1 P 0 
L 2.35663002 4.61271004 2.36178996 4.61365 1 P 0 
L 2.36178996 4.61365 2.3618 4.61365 1 P 0 
L 2.3618 4.61365 2.38558996 4.59701004 1 P 0 
A 2.38558996 4.59701004 2.38958543 4.5911562 2.37313002 4.58421516 1 P 0 Y
A 2.38958543 4.5911562 2.39098996 4.58421004 2.37313002 4.58421378 1 P 0 Y
L 2.39098996 4.58421004 2.391 4.58421998 1 P 0 
L 2.391 4.58421998 2.391 4.57483002 1 P 0 
A 2.391 4.57483002 2.38190738 4.55533504 2.36555 4.57483219 1 P 0 Y
A 2.38190738 4.55533504 2.36113002 4.54976998 2.36555187 4.57483002 1 P 0 Y
L 2.36113002 4.54976998 2.28416004 4.56331998 1 P 0 
L 2.28416004 4.56331998 2.28403002 4.56331998 1 P 0 
A 2.28403002 4.56331998 2.25175 4.5575 2.28403022 4.47088996 1 P 0 N
A 2.25175 4.5575 2.23531998 4.54693996 2.26783012 4.51441998 1 P 0 N
L 2.23531998 4.54693996 2.23528996 4.54691004 1 P 0 
A 2.23528996 4.54691004 2.22926998 4.53823996 2.2563 4.52589695 1 P 0 N
L 2.22926998 4.53823996 2.22501998 4.52888002 1 P 0 
A 2.22501998 4.52888002 2.22213819 4.51958268 2.26006004 4.51292372 1 P 0 N
A 2.22213819 4.51958268 2.22168002 4.50986004 2.26006004 4.51292352 1 P 0 N
A 2.22168002 4.50986004 2.22176998 4.50726004 2.27075 4.5102563 1 P 0 N
A 2.22176998 4.50726004 2.23414744 4.47758356 2.27075 4.51026919 1 P 0 N
A 2.23414744 4.47758356 2.26223996 4.46193996 2.27075108 4.51026998 1 P 0 N
L 2.26223996 4.46193996 2.35396998 4.44576998 1 P 0 
L 2.35396998 4.44576998 2.48951004 4.46966998 1 P 0 
L 2.48951004 4.46966998 2.48953996 4.46966998 1 P 0 
A 2.48953996 4.46966998 2.5032377 4.46694734 2.48954557 4.43388002 1 P 0 Y
A 2.5032377 4.46694734 2.51485 4.45918996 2.48954488 4.43388002 1 P 0 Y
L 2.51485 4.45918996 2.51488002 4.45916004 1 P 0 
A 2.51488002 4.45916004 2.5241 4.4369 2.49261998 4.43690059 1 P 0 Y
A 2.5241 4.4369 2.52159813 4.42433848 2.49126998 4.43690886 1 P 0 Y
A 2.52159813 4.42433848 2.51448002 4.41368996 2.49126998 4.43690827 1 P 0 Y
L 2.51448002 4.41368996 2.5071 4.4063 1 P 0 
A 2.5071 4.4063 2.5071 4.3702 2.52515 4.38825 1 P 0 N
L 2.5071 4.3702 2.50746004 4.36983996 1 P 0 
A 2.50746004 4.36983996 2.52296004 4.36153996 2.52891841 4.39128996 1 P 0 N
L 2.52296004 4.36153996 2.52298002 4.36153996 1 P 0 
L 2.52298002 4.36153996 2.52971004 4.3602 1 P 0 
L 2.52971004 4.3602 2.58341998 4.35073002 1 P 0 
A 2.58341998 4.35073002 2.59925 4.34248002 2.57825118 4.3215 1 P 0 Y
L 2.59925 4.34248002 2.60098002 4.34075 1 P 0 
L 2.60098002 4.34075 2.60616998 4.33558002 1 P 0 
L 2.60616998 4.33558002 2.64451998 4.28078996 1 P 0 
A 2.64451998 4.28078996 2.6453438 4.27922815 2.6388 4.27677461 1 P 0 Y
A 2.6453438 4.27922815 2.64575 4.27751004 2.6388 4.27677402 1 P 0 Y
A 2.64575 4.27751004 2.64601998 4.27421004 2.37165 4.25342431 1 P 0 Y
A 2.64601998 4.27421004 2.64663996 4.26376998 2.3717 4.2526812 1 P 0 Y
A 2.64663996 4.26376998 2.63912726 4.24513179 2.61516998 4.26562175 1 P 0 Y
A 2.63912726 4.24513179 2.62188002 4.23481998 2.61517146 4.26561998 1 P 0 Y
L 2.62188002 4.23481998 2.60218002 4.23481998 1 P 0 
A 2.60218002 4.23481998 2.58622116 4.23164734 2.60217717 4.19311004 1 P 0 N
A 2.58622116 4.23164734 2.57268996 4.22261004 2.60217608 4.19311004 1 P 0 N
L 2.57268996 4.22261004 2.57195 4.22186998 1 P 0 
A 2.57195 4.22186998 2.56218996 4.1983 2.59553002 4.1983 1 P 0 N
A 2.56218996 4.1983 2.5863 4.1742 2.58628996 4.1983 1 P 0 N
L 2.5863 4.1742 2.62943002 4.1742 1 P 0 
A 2.62943002 4.1742 2.6485 4.1663 2.62942864 4.14723002 1 P 0 Y
L 2.6485 4.1663 2.6485 4.16631004 1 P 0 
A 2.6485 4.16631004 2.65798898 4.14340354 2.6256 4.14340512 1 P 0 Y
A 2.65798898 4.14340354 2.6485 4.1205 2.6256 4.14340492 1 P 0 Y
L 2.6485 4.1205 2.63963002 4.11163002 1 P 0 
A 2.63963002 4.11163002 2.57323002 4.08313996 2.570781 4.18046998 1 P 0 Y
L 2.57323002 4.08313996 2.57321004 4.08313996 1 P 0 
A 2.57321004 4.08313996 2.55053996 4.07375 2.57320955 4.05108002 1 P 0 N
L 2.55053996 4.07375 2.54908996 4.0723 1 P 0 
A 2.54908996 4.0723 2.54362175 4.0590935 2.5623 4.05909498 1 P 0 N
A 2.54362175 4.0590935 2.54908996 4.04588996 2.5623 4.05909498 1 P 0 N
L 2.54908996 4.04588996 2.54911004 4.04586998 1 P 0 
A 2.54911004 4.04586998 2.55560197 4.04153032 2.56328533 4.06005 1 P 0 N
A 2.55560197 4.04153032 2.56326004 4.04 2.56328474 4.06005 1 P 0 N
L 2.56326004 4.04 2.57296004 4.04 1 P 0 
A 2.57296004 4.04 2.58783996 4.03703652 2.57295778 4.00115 1 P 0 Y
A 2.58783996 4.03703652 2.60045 4.0286 2.57295787 4.00115 1 P 0 Y
L 2.60045 4.0286 2.60811998 4.02093002 1 P 0 
L 2.60811998 4.02093002 2.68785 3.90706998 1 P 0 
L 2.68785 3.90706998 2.72121998 3.71788002 1 P 0 
L 2.72121998 3.71788002 2.67311004 3.44495 1 P 0 
A 2.67311004 3.44495 2.65158996 3.40361004 2.59676998 3.4584186 1 P 0 Y
L 2.65158996 3.40361004 2.62551998 3.37753002 1 P 0 
A 2.62551998 3.37753002 2.54675 3.3449 2.54675896 3.45626998 1 P 0 Y
L 2.54675 3.3449 2.49976004 3.3449 1 P 0 
A 2.49976004 3.3449 2.49606004 3.3486 2.49976004 3.3486 1 P 0 Y
L 2.49606004 3.3486 2.49606004 3.36615 1 P 0 
P 8.35 3.41615 5 P 0 0;2=3,4=1
P 8.11725 4.78291998 5 P 0 0;2=3,4=1
L 8.11725 4.78291998 8.10533996 4.78291998 1 P 0 
A 8.10533996 4.78291998 8.101 4.77858002 8.10533996 4.77858002 1 P 0 N
L 8.101 4.77858002 8.101 4.75081004 1 P 0 
L 8.101 4.75081004 8.09871998 4.73788002 1 P 0 
L 8.09871998 4.73788002 8.08838996 4.72313996 1 P 0 
L 8.08838996 4.72313996 8.07876998 4.7164 1 P 0 
L 8.07876998 4.7164 8.01008002 4.70431004 1 P 0 
L 8.01008002 4.70431004 8.00151998 4.69831998 1 P 0 
L 8.00151998 4.69831998 7.98663002 4.67701998 1 P 0 
L 7.98663002 4.67701998 7.97831998 4.62983996 1 P 0 
A 7.97831998 4.62983996 7.98045689 4.61910236 8.00638002 4.62984282 1 P 0 N
A 7.98045689 4.61910236 7.98653996 4.61 8.00638002 4.62984282 1 P 0 N
L 7.98653996 4.61 7.99606004 4.60048002 1 P 0 
A 7.99606004 4.60048002 8.00453996 4.58 7.97556998 4.5800003 1 P 0 Y
A 8.00453996 4.58 7.99818002 4.56463002 7.98281004 4.57999075 1 P 0 Y
L 7.99818002 4.56463002 7.99608996 4.56253996 1 P 0 
A 7.99608996 4.56253996 7.99216683 4.55992037 7.98753799 4.5711 1 P 0 Y
A 7.99216683 4.55992037 7.98753996 4.559 7.98753799 4.5711 1 P 0 Y
A 7.98753996 4.559 7.96453996 4.536 7.98753996 4.536 1 P 0 N
L 7.96453996 4.536 7.96453996 4.52843002 1 P 0 
A 7.96453996 4.52843002 7.96486998 4.52435 7.98971004 4.5284126 1 P 0 N
A 7.96486998 4.52435 7.97366998 4.5072 7.99591998 4.52944961 1 P 0 N
L 7.97366998 4.5072 7.98696004 4.49391004 1 P 0 
A 7.98696004 4.49391004 7.98868248 4.49168907 7.97901004 4.48596614 1 P 0 Y
A 7.98868248 4.49168907 7.9898 4.48911004 7.97901004 4.48596624 1 P 0 Y
A 7.9898 4.48911004 7.98998032 4.47811959 7.96981004 4.48328533 1 P 0 Y
A 7.98998032 4.47811959 7.98453996 4.46856998 7.96981004 4.48328602 1 P 0 Y
A 7.98453996 4.46856998 7.97507116 4.46223533 7.96385837 4.48923996 1 P 0 Y
A 7.97507116 4.46223533 7.9639 4.46 7.96385837 4.48923996 1 P 0 Y
L 7.9639 4.46 7.95353996 4.46 1 P 0 
A 7.95353996 4.46 7.94486929 4.45827382 7.95354203 4.43735 1 P 0 N
A 7.94486929 4.45827382 7.93751998 4.45336004 7.95354163 4.43735 1 P 0 N
L 7.93751998 4.45336004 7.92883996 4.44468002 1 P 0 
A 7.92883996 4.44468002 7.91653996 4.41501998 7.9585 4.41499961 1 P 0 N
L 7.91653996 4.41501998 7.91653996 4.404 1 P 0 
A 7.91653996 4.404 7.93131998 4.36831998 7.967 4.40400118 1 P 0 N
L 7.93131998 4.36831998 7.95211998 4.34751998 1 P 0 
A 7.95211998 4.34751998 7.95211998 4.32138002 7.93905 4.33445 1 P 0 Y
A 7.95211998 4.32138002 7.91498002 4.306 7.9149813 4.35853002 1 P 0 Y
L 7.91498002 4.306 7.88585 4.306 1 P 0 
A 7.88585 4.306 7.87539921 4.30392037 7.88585217 4.27868996 1 P 0 N
A 7.87539921 4.30392037 7.86653996 4.298 7.88585207 4.27868996 1 P 0 N
L 7.86653996 4.298 7.86653002 4.298 1 P 0 
A 7.86653002 4.298 7.86653996 4.24656998 7.89226004 4.27228996 1 P 0 N
L 7.86653996 4.24656998 7.86656004 4.24655 1 P 0 
A 7.86656004 4.24655 7.89374045 4.22638927 7.94815295 4.32815 1 P 0 N
A 7.89374045 4.22638927 7.9256 4.21498002 7.94815472 4.32815 1 P 0 N
L 7.9256 4.21498002 7.96031004 4.20806998 1 P 0 
A 7.96031004 4.20806998 7.96103996 4.208 7.96103022 4.21173996 1 P 0 N
L 7.96103996 4.208 7.97453996 4.208 1 P 0 
A 7.97453996 4.208 7.99153996 4.191 7.97453996 4.191 1 P 0 Y
A 7.99153996 4.191 8.05023002 4.04931004 8.19191998 4.1910002 1 P 0 N
L 8.05023002 4.04931004 8.05953996 4.04 1 P 0 
A 8.05953996 4.04 8.25508996 3.959 8.25509075 4.23555 1 P 0 N
L 8.25508996 3.959 8.27673996 3.959 1 P 0 
A 8.27673996 3.959 8.33697126 3.97098632 8.27672687 4.11638996 1 P 0 N
A 8.33697126 3.97098632 8.38803002 4.00511004 8.27672687 4.11638996 1 P 0 N
L 8.38803002 4.00511004 8.38803996 4.00511998 1 P 0 
A 8.38803996 4.00511998 8.41643002 4.00511004 8.40223002 3.99093996 1 P 0 Y
L 8.41643002 4.00511004 8.43993996 3.9816 1 P 0 
L 8.43993996 3.9816 8.43993996 3.98158996 1 P 0 
A 8.43993996 3.98158996 8.44547687 3.97752766 8.45589341 3.99753002 1 P 0 N
A 8.44547687 3.97752766 8.45198002 3.97531998 8.4558935 3.99753002 1 P 0 N
L 8.45198002 3.97531998 8.50711998 3.9656 1 P 0 
A 8.50711998 3.9656 8.53126516 3.95740413 8.49255591 3.88303002 1 P 0 Y
A 8.53126516 3.95740413 8.55183002 3.94233002 8.49255581 3.88303002 1 P 0 Y
L 8.55183002 3.94233002 8.55773996 3.93641998 1 P 0 
A 8.55773996 3.93641998 8.58571555 3.89454931 8.46646998 3.84515738 1 P 0 Y
A 8.58571555 3.89454931 8.59553996 3.84516004 8.46646998 3.84515748 1 P 0 Y
L 8.59553996 3.84516004 8.59553996 3.837 1 P 0 
A 8.59553996 3.837 8.59792805 3.82499114 8.62691998 3.83699833 1 P 0 N
A 8.59792805 3.82499114 8.60473002 3.81481004 8.62691998 3.83699783 1 P 0 N
L 8.60473002 3.81481004 8.60953996 3.81 1 P 0 
A 8.60953996 3.81 8.60953996 3.775 8.59203996 3.7925 1 P 0 Y
L 8.60953996 3.775 8.60281004 3.76826004 1 P 0 
A 8.60281004 3.76826004 8.59628002 3.75251004 8.61856004 3.75250128 1 P 0 N
L 8.59628002 3.75251004 8.59628002 3.7422 1 P 0 
A 8.59628002 3.7422 8.6055 3.71993996 8.62776004 3.74219941 1 P 0 N
L 8.6055 3.71993996 8.61473996 3.7107 1 P 0 
A 8.61473996 3.7107 8.62813996 3.67835 8.58238996 3.6783497 1 P 0 Y
L 8.62813996 3.67835 8.62813996 3.6783 1 P 0 
A 8.62813996 3.6783 8.58491004 3.57393996 8.48056004 3.67829951 1 P 0 Y
L 8.58491004 3.57393996 8.55653002 3.54556998 1 P 0 
A 8.55653002 3.54556998 8.53678002 3.53738996 8.536781 3.56531998 1 P 0 Y
L 8.53678002 3.53738996 8.5235 3.53738996 1 P 0 
L 8.5235 3.53738996 8.52348996 3.5374 1 P 0 
L 8.52348996 3.5374 8.48716998 3.5374 1 P 0 
A 8.48716998 3.5374 8.47875 3.52898002 8.48716998 3.52898002 1 P 0 N
L 8.47875 3.52898002 8.47875 3.50383002 1 P 0 
A 8.47875 3.50383002 8.46231998 3.4874 8.46231998 3.50383002 1 P 0 Y
L 8.46231998 3.4874 8.44853996 3.4874 1 P 0 
A 8.44853996 3.4874 8.42875 3.46761004 8.44853996 3.46761004 1 P 0 N
L 8.42875 3.46761004 8.42875 3.45378002 1 P 0 
A 8.42875 3.45378002 8.41236998 3.4374 8.41236998 3.45378002 1 P 0 Y
L 8.41236998 3.4374 8.3537 3.4374 1 P 0 
A 8.3537 3.4374 8.35 3.4337 8.3537 3.4337 1 P 0 N
L 8.35 3.4337 8.35 3.41615 1 P 0 
P 2.11371004 4.78291998 5 P 0 0;2=3,4=1
P 2.34606004 3.41615 5 P 0 0;2=3,4=1
L 2.34606004 3.41615 2.34606004 3.4337 1 P 0 
A 2.34606004 3.4337 2.34976004 3.4374 2.34976004 3.4337 1 P 0 Y
L 2.34976004 3.4374 2.40883002 3.4374 1 P 0 
A 2.40883002 3.4374 2.42481004 3.45338002 2.40883002 3.45338002 1 P 0 N
L 2.42481004 3.45338002 2.42481004 3.46956004 1 P 0 
A 2.42481004 3.46956004 2.42936998 3.48056998 2.44038002 3.46956073 1 P 0 Y
L 2.42936998 3.48056998 2.42938996 3.48058996 1 P 0 
L 2.42938996 3.48058996 2.42938002 3.48058996 1 P 0 
L 2.42938002 3.48058996 2.43343002 3.48463996 1 P 0 
A 2.43343002 3.48463996 2.4401 3.4874 2.4401002 3.47796004 1 P 0 Y
L 2.4401 3.4874 2.45878002 3.4874 1 P 0 
A 2.45878002 3.4874 2.47481004 3.50343002 2.45878002 3.50343002 1 P 0 N
L 2.47481004 3.50343002 2.47481004 3.52858002 1 P 0 
A 2.47481004 3.52858002 2.48363002 3.5374 2.48363002 3.52858002 1 P 0 Y
L 2.48363002 3.5374 2.51995 3.5374 1 P 0 
L 2.51995 3.5374 2.51996004 3.53738996 1 P 0 
L 2.51996004 3.53738996 2.54016998 3.53738996 1 P 0 
A 2.54016998 3.53738996 2.54446191 3.53824656 2.54016211 3.54861004 1 P 0 N
A 2.54446191 3.53824656 2.5481 3.54068002 2.5401628 3.54861004 1 P 0 N
L 2.5481 3.54068002 2.58136998 3.57393996 1 P 0 
A 2.58136998 3.57393996 2.6246 3.6783 2.47701998 3.67829961 1 P 0 N
L 2.6246 3.6783 2.6246 3.67835 1 P 0 
A 2.6246 3.67835 2.6112 3.7107 2.57885 3.6783497 1 P 0 N
L 2.6112 3.7107 2.60196004 3.71993996 1 P 0 
A 2.60196004 3.71993996 2.59273996 3.7422 2.62421998 3.74219951 1 P 0 Y
L 2.59273996 3.7422 2.59273996 3.75251004 1 P 0 
A 2.59273996 3.75251004 2.59926998 3.76826004 2.61501998 3.75250128 1 P 0 Y
L 2.59926998 3.76826004 2.606 3.775 1 P 0 
A 2.606 3.775 2.606 3.81 2.5885 3.7925 1 P 0 N
L 2.606 3.81 2.60118996 3.81481004 1 P 0 
A 2.60118996 3.81481004 2.59438809 3.82499124 2.62338002 3.83699744 1 P 0 Y
A 2.59438809 3.82499124 2.592 3.837 2.62338002 3.83699843 1 P 0 Y
L 2.592 3.837 2.592 3.84516004 1 P 0 
A 2.592 3.84516004 2.58217559 3.89454931 2.46293002 3.84515748 1 P 0 N
A 2.58217559 3.89454931 2.5542 3.93641998 2.46293002 3.84515738 1 P 0 N
L 2.5542 3.93641998 2.54828996 3.94233002 1 P 0 
A 2.54828996 3.94233002 2.5277251 3.95740413 2.48901575 3.88303002 1 P 0 N
A 2.5277251 3.95740413 2.50358002 3.9656 2.48901585 3.88303002 1 P 0 N
L 2.50358002 3.9656 2.44843996 3.97531998 1 P 0 
A 2.44843996 3.97531998 2.44193691 3.97752766 2.45235364 3.99753002 1 P 0 Y
A 2.44193691 3.97752766 2.4364 3.98158996 2.45235344 3.99753002 1 P 0 Y
L 2.4364 3.98158996 2.4364 3.9816 1 P 0 
L 2.4364 3.9816 2.41288996 4.00511004 1 P 0 
A 2.41288996 4.00511004 2.3845 4.00511998 2.39869006 3.99093996 1 P 0 N
L 2.3845 4.00511998 2.38448996 4.00511004 1 P 0 
A 2.38448996 4.00511004 2.3334312 3.97098632 2.27318681 4.11638996 1 P 0 Y
A 2.3334312 3.97098632 2.2732 3.959 2.27318681 4.11638996 1 P 0 Y
L 2.2732 3.959 2.25155 3.959 1 P 0 
A 2.25155 3.959 2.056 4.04 2.25155079 4.23555 1 P 0 Y
L 2.056 4.04 2.04668996 4.04931004 1 P 0 
A 2.04668996 4.04931004 1.988 4.191 2.18838002 4.1910001 1 P 0 Y
A 1.988 4.191 1.971 4.208 1.971 4.191 1 P 0 N
L 1.971 4.208 1.9575 4.208 1 P 0 
A 1.9575 4.208 1.95676998 4.20806998 1.95749016 4.21173996 1 P 0 Y
L 1.95676998 4.20806998 1.92206004 4.21498002 1 P 0 
A 1.92206004 4.21498002 1.89020049 4.22638917 1.94461447 4.32815 1 P 0 Y
A 1.89020049 4.22638917 1.86301998 4.24655 1.94461309 4.32815 1 P 0 Y
L 1.86301998 4.24655 1.863 4.24656998 1 P 0 
A 1.863 4.24656998 1.86298996 4.298 1.88871998 4.27229006 1 P 0 Y
L 1.86298996 4.298 1.863 4.298 1 P 0 
A 1.863 4.298 1.87185925 4.30392037 1.88231211 4.27868996 1 P 0 Y
A 1.87185925 4.30392037 1.88231004 4.306 1.8823122 4.27868996 1 P 0 Y
L 1.88231004 4.306 1.91143996 4.306 1 P 0 
A 1.91143996 4.306 1.93153917 4.30999685 1.91144104 4.35853002 1 P 0 N
A 1.93153917 4.30999685 1.94858002 4.32138002 1.91144173 4.35853002 1 P 0 N
A 1.94858002 4.32138002 1.94858002 4.34751998 1.93551004 4.33445 1 P 0 N
L 1.94858002 4.34751998 1.92778002 4.36831998 1 P 0 
A 1.92778002 4.36831998 1.913 4.404 1.96346004 4.40400118 1 P 0 Y
L 1.913 4.404 1.913 4.41501998 1 P 0 
A 1.913 4.41501998 1.9253 4.44468002 1.95496004 4.41499961 1 P 0 Y
L 1.9253 4.44468002 1.93398002 4.45336004 1 P 0 
A 1.93398002 4.45336004 1.94132933 4.45827382 1.95000167 4.43735 1 P 0 Y
A 1.94132933 4.45827382 1.95 4.46 1.95000207 4.43735 1 P 0 Y
L 1.95 4.46 1.96036004 4.46 1 P 0 
A 1.96036004 4.46 1.9715312 4.46223533 1.96031841 4.48923996 1 P 0 N
A 1.9715312 4.46223533 1.981 4.46856998 1.96031841 4.48923996 1 P 0 N
A 1.981 4.46856998 1.98644035 4.47811959 1.96626998 4.48328602 1 P 0 N
A 1.98644035 4.47811959 1.98626004 4.48911004 1.96626998 4.48328533 1 P 0 N
A 1.98626004 4.48911004 1.98514242 4.49168907 1.97546998 4.48596585 1 P 0 N
A 1.98514242 4.49168907 1.98341998 4.49391004 1.97546998 4.48596614 1 P 0 N
L 1.98341998 4.49391004 1.97013002 4.5072 1 P 0 
A 1.97013002 4.5072 1.96133002 4.52435 1.99238002 4.52944961 1 P 0 Y
A 1.96133002 4.52435 1.961 4.52843002 1.98616998 4.5284126 1 P 0 Y
L 1.961 4.52843002 1.961 4.536 1 P 0 
A 1.961 4.536 1.984 4.559 1.984 4.536 1 P 0 Y
A 1.984 4.559 1.98862687 4.55992037 1.98399803 4.5711 1 P 0 N
A 1.98862687 4.55992037 1.99255 4.56253996 1.98399803 4.5711 1 P 0 N
L 1.99255 4.56253996 1.99463996 4.56463002 1 P 0 
A 1.99463996 4.56463002 2.001 4.58 1.97926998 4.57999094 1 P 0 N
A 2.001 4.58 1.99251998 4.60048002 1.97203002 4.5800002 1 P 0 N
L 1.99251998 4.60048002 1.983 4.61 1 P 0 
A 1.983 4.61 1.97691693 4.61910236 2.00283996 4.62984282 1 P 0 Y
A 1.97691693 4.61910236 1.97478002 4.62983996 2.00283996 4.62984282 1 P 0 Y
L 1.97478002 4.62983996 1.98308996 4.67701998 1 P 0 
L 1.98308996 4.67701998 1.99798002 4.69831998 1 P 0 
L 1.99798002 4.69831998 2.00653996 4.70431004 1 P 0 
L 2.00653996 4.70431004 2.07523002 4.7164 1 P 0 
L 2.07523002 4.7164 2.08485 4.72313996 1 P 0 
L 2.08485 4.72313996 2.09518002 4.73788002 1 P 0 
L 2.09518002 4.73788002 2.09746004 4.75081004 1 P 0 
L 2.09746004 4.75081004 2.09746004 4.77858002 1 P 0 
A 2.09746004 4.77858002 2.1018 4.78291998 2.1018 4.77858002 1 P 0 Y
L 2.1018 4.78291998 2.11371004 4.78291998 1 P 0 
P 8.35 3.46615 5 P 0 0;2=3,4=1
P 8.07725 4.78291998 5 P 0 0;2=3,4=1
L 8.07725 4.78291998 8.08943996 4.78291998 1 P 0 
A 8.08943996 4.78291998 8.0935 4.77886004 8.08944006 4.77886004 1 P 0 Y
L 8.0935 4.77886004 8.0935 4.75146998 1 P 0 
L 8.0935 4.75146998 8.09161998 4.74081998 1 P 0 
L 8.09161998 4.74081998 8.083 4.72853002 1 P 0 
L 8.083 4.72853002 8.07583002 4.7235 1 P 0 
L 8.07583002 4.7235 8.04273996 4.71768996 1 P 0 
L 8.04273996 4.71768996 8.03611004 4.72235 1 P 0 
L 8.03611004 4.72235 8.02516004 4.72041004 1 P 0 
L 8.02516004 4.72041004 8.02051004 4.71378002 1 P 0 
L 8.02051004 4.71378002 8.00713996 4.71141004 1 P 0 
L 8.00713996 4.71141004 7.99613002 4.70371004 1 P 0 
L 7.99613002 4.70371004 7.97953002 4.67996004 1 P 0 
L 7.97953002 4.67996004 7.97081998 4.63053002 1 P 0 
A 7.97081998 4.63053002 7.98123002 4.60468996 8.00638002 4.62983898 1 P 0 N
L 7.98123002 4.60468996 7.99075 4.59516998 1 P 0 
A 7.99075 4.59516998 7.99540266 4.58821033 7.97556998 4.57998681 1 P 0 Y
A 7.99540266 4.58821033 7.99703996 4.58 7.97556998 4.57998691 1 P 0 Y
A 7.99703996 4.58 7.99595532 4.57455502 7.98281004 4.58000413 1 P 0 Y
A 7.99595532 4.57455502 7.99286998 4.56993996 7.98281004 4.58000423 1 P 0 Y
L 7.99286998 4.56993996 7.99078002 4.56785 1 P 0 
A 7.99078002 4.56785 7.98753996 4.56651004 7.98753888 4.5711 1 P 0 Y
A 7.98753996 4.56651004 7.95703996 4.536 7.98753996 4.53600994 1 P 0 N
L 7.95703996 4.536 7.95703996 4.52843002 1 P 0 
A 7.95703996 4.52843002 7.95746004 4.52313002 7.98971998 4.52835364 1 P 0 N
A 7.95746004 4.52313002 7.96124331 4.51165492 7.99591004 4.52944557 1 P 0 N
A 7.96124331 4.51165492 7.96836004 4.50188996 7.99591004 4.52944429 1 P 0 N
L 7.96836004 4.50188996 7.98165 4.4886 1 P 0 
A 7.98165 4.4886 7.98221998 4.48786388 7.97901004 4.48596713 1 P 0 Y
A 7.98221998 4.48786388 7.98258996 4.48701004 7.97901004 4.48596585 1 P 0 Y
A 7.98258996 4.48701004 7.98270856 4.47998041 7.96981004 4.48327864 1 P 0 Y
A 7.98270856 4.47998041 7.97923002 4.47386998 7.96981004 4.48327795 1 P 0 Y
A 7.97923002 4.47386998 7.97219262 4.4691623 7.96385492 4.48923996 1 P 0 Y
A 7.97219262 4.4691623 7.96388996 4.4675 7.96385502 4.48923996 1 P 0 Y
L 7.96388996 4.4675 7.95353996 4.4675 1 P 0 
A 7.95353996 4.4675 7.94199656 4.46520728 7.95352884 4.43735 1 P 0 N
A 7.94199656 4.46520728 7.93221004 4.45866998 7.95352825 4.43735 1 P 0 N
L 7.93221004 4.45866998 7.92353002 4.44998996 1 P 0 
A 7.92353002 4.44998996 7.90903996 4.41501004 7.95851004 4.41500876 1 P 0 N
L 7.90903996 4.41501004 7.90903996 4.404 1 P 0 
A 7.90903996 4.404 7.91344803 4.38181732 7.967 4.40398829 1 P 0 N
A 7.91344803 4.38181732 7.92601004 4.36301004 7.967 4.4039875 1 P 0 N
L 7.92601004 4.36301004 7.94681004 4.34221004 1 P 0 
A 7.94681004 4.34221004 7.94681004 4.32668996 7.93905 4.33445 1 P 0 Y
A 7.94681004 4.32668996 7.93221112 4.3169315 7.91497274 4.35851998 1 P 0 Y
A 7.93221112 4.3169315 7.91498996 4.3135 7.91497175 4.35851998 1 P 0 Y
L 7.91498996 4.3135 7.88583996 4.3135 1 P 0 
A 7.88583996 4.3135 7.86123002 4.30331004 7.88583878 4.27868996 1 P 0 N
A 7.86123002 4.30331004 7.84838061 4.27228356 7.89226004 4.27228514 1 P 0 N
A 7.84838061 4.27228356 7.86123002 4.24126004 7.89226004 4.27228494 1 P 0 N
L 7.86123002 4.24126004 7.86125 4.24123996 1 P 0 
A 7.86125 4.24123996 7.89019843 4.21976959 7.94814537 4.32815 1 P 0 N
A 7.89019843 4.21976959 7.92413002 4.20761998 7.94814626 4.32815 1 P 0 N
L 7.92413002 4.20761998 7.95885 4.20071004 1 P 0 
A 7.95885 4.20071004 7.96105 4.2005 7.96101309 4.21173996 1 P 0 N
L 7.96105 4.2005 7.97453996 4.2005 1 P 0 
A 7.97453996 4.2005 7.98403996 4.191 7.97453996 4.191 1 P 0 Y
A 7.98403996 4.191 7.99985965 4.11144528 8.19191998 4.1909873 1 P 0 N
A 7.99985965 4.11144528 8.04491998 4.044 8.19191998 4.19098612 1 P 0 N
L 8.04491998 4.044 8.05423002 4.03468996 1 P 0 
A 8.05423002 4.03468996 8.14639094 3.97311604 8.25507687 4.23555 1 P 0 N
A 8.14639094 3.97311604 8.2551 3.9515 8.25507776 4.23555 1 P 0 N
L 8.2551 3.9515 8.27673996 3.9515 1 P 0 
A 8.27673996 3.9515 8.39333996 3.9998 8.27674026 4.11638996 1 P 0 N
L 8.39333996 3.9998 8.39335 3.99981004 1 P 0 
A 8.39335 3.99981004 8.40223652 4.00349173 8.40223494 3.99093002 1 P 0 Y
A 8.40223652 4.00349173 8.41111998 3.99981004 8.40223504 3.99093002 1 P 0 Y
L 8.41111998 3.99981004 8.43463002 3.97628996 1 P 0 
A 8.43463002 3.97628996 8.44201073 3.97087343 8.45589547 3.99753002 1 P 0 N
A 8.44201073 3.97087343 8.45068002 3.96793002 8.45589547 3.99753002 1 P 0 N
L 8.45068002 3.96793002 8.50581998 3.95821004 1 P 0 
A 8.50581998 3.95821004 8.5277999 3.95074518 8.49254478 3.88303002 1 P 0 Y
A 8.5277999 3.95074518 8.54651998 3.93701998 8.492544 3.88303002 1 P 0 Y
L 8.54651998 3.93701998 8.55243002 3.93111004 1 P 0 
A 8.55243002 3.93111004 8.57878484 3.89167195 8.46648002 3.84514833 1 P 0 Y
A 8.57878484 3.89167195 8.58803996 3.84515 8.46648002 3.84514833 1 P 0 Y
L 8.58803996 3.84515 8.58803996 3.83701004 1 P 0 
A 8.58803996 3.83701004 8.59099262 3.82212313 8.62691998 3.83698524 1 P 0 N
A 8.59099262 3.82212313 8.59941998 3.8095 8.62691998 3.83698396 1 P 0 N
L 8.59941998 3.8095 8.60423002 3.80468996 1 P 0 
A 8.60423002 3.80468996 8.60928278 3.7924935 8.59203996 3.79249498 1 P 0 Y
A 8.60928278 3.7924935 8.60423002 3.7803 8.59203996 3.79249498 1 P 0 Y
L 8.60423002 3.7803 8.5975 3.77356998 1 P 0 
A 8.5975 3.77356998 8.59104734 3.76391152 8.61856004 3.75251545 1 P 0 N
A 8.59104734 3.76391152 8.58878002 3.75251998 8.61856004 3.75251407 1 P 0 N
L 8.58878002 3.75251998 8.58878002 3.74221004 1 P 0 
A 8.58878002 3.74221004 8.59174075 3.72728504 8.62776004 3.74218652 1 P 0 N
A 8.59174075 3.72728504 8.60018996 3.71463002 8.62776004 3.74218543 1 P 0 N
L 8.60018996 3.71463002 8.60943002 3.70538996 1 P 0 
A 8.60943002 3.70538996 8.61772579 3.69298032 8.58238996 3.67833622 1 P 0 Y
A 8.61772579 3.69298032 8.62063996 3.67833996 8.58238996 3.67833652 1 P 0 Y
L 8.62063996 3.67833996 8.62063996 3.6783 1 P 0 
A 8.62063996 3.6783 8.60997136 3.62469301 8.48056004 3.67831289 1 P 0 Y
A 8.60997136 3.62469301 8.5796 3.57925 8.48056004 3.67831299 1 P 0 Y
L 8.5796 3.57925 8.57166998 3.57131004 1 P 0 
L 8.57166998 3.57131004 8.56811998 3.57131998 1 P 0 
L 8.56811998 3.57131998 8.56458002 3.57131998 1 P 0 
L 8.56458002 3.57131998 8.55671004 3.56346004 1 P 0 
L 8.55671004 3.56346004 8.55671998 3.55991004 1 P 0 
L 8.55671998 3.55991004 8.55671998 3.55636998 1 P 0 
L 8.55671998 3.55636998 8.55121998 3.55088002 1 P 0 
A 8.55121998 3.55088002 8.54459577 3.54644921 8.53676742 3.56531998 1 P 0 Y
A 8.54459577 3.54644921 8.53678002 3.54488996 8.53676762 3.56531998 1 P 0 Y
L 8.53678002 3.54488996 8.52661004 3.54488996 1 P 0 
L 8.52661004 3.54488996 8.5266 3.5449 1 P 0 
L 8.5266 3.5449 8.48716998 3.5449 1 P 0 
A 8.48716998 3.5449 8.47125 3.52898002 8.48716998 3.52898002 1 P 0 N
L 8.47125 3.52898002 8.47125 3.50383002 1 P 0 
A 8.47125 3.50383002 8.46231998 3.4949 8.46231998 3.50383002 1 P 0 Y
L 8.46231998 3.4949 8.44853996 3.4949 1 P 0 
A 8.44853996 3.4949 8.42125 3.46761004 8.44853996 3.46761004 1 P 0 N
L 8.42125 3.46761004 8.42125 3.45378002 1 P 0 
A 8.42125 3.45378002 8.41236998 3.4449 8.41236998 3.45378002 1 P 0 Y
L 8.41236998 3.4449 8.3537 3.4449 1 P 0 
A 8.3537 3.4449 8.35 3.4486 8.3537 3.4486 1 P 0 Y
L 8.35 3.4486 8.35 3.46615 1 P 0 
P 2.07371004 4.78291998 5 P 0 0;2=3,4=1
P 2.34606004 3.46615 5 P 0 0;2=3,4=1
L 2.34606004 3.46615 2.34606004 3.4486 1 P 0 
A 2.34606004 3.4486 2.34976004 3.4449 2.34976004 3.4486 1 P 0 N
L 2.34976004 3.4449 2.40883002 3.4449 1 P 0 
A 2.40883002 3.4449 2.41731004 3.45338002 2.40883002 3.45338002 1 P 0 N
L 2.41731004 3.45338002 2.41731004 3.46956004 1 P 0 
A 2.41731004 3.46956004 2.42406004 3.48588002 2.44038996 3.46956998 1 P 0 Y
L 2.42406004 3.48588002 2.42406004 3.48588996 1 P 0 
L 2.42406004 3.48588996 2.42811998 3.48995 1 P 0 
A 2.42811998 3.48995 2.43361811 3.49361614 2.44008622 3.47796004 1 P 0 Y
A 2.43361811 3.49361614 2.4401 3.4949 2.4400872 3.47796004 1 P 0 Y
L 2.4401 3.4949 2.45878002 3.4949 1 P 0 
A 2.45878002 3.4949 2.46731004 3.50343002 2.45878002 3.50343002 1 P 0 N
L 2.46731004 3.50343002 2.46731004 3.52858002 1 P 0 
A 2.46731004 3.52858002 2.48363002 3.5449 2.48363002 3.52858002 1 P 0 Y
L 2.48363002 3.5449 2.52306004 3.5449 1 P 0 
L 2.52306004 3.5449 2.52306998 3.54488996 1 P 0 
L 2.52306998 3.54488996 2.54016004 3.54488996 1 P 0 
A 2.54016004 3.54488996 2.54158346 3.54517274 2.5401628 3.5486 1 P 0 N
A 2.54158346 3.54517274 2.54278996 3.54598002 2.54016358 3.5486 1 P 0 N
L 2.54278996 3.54598002 2.54278996 3.54598996 1 P 0 
L 2.54278996 3.54598996 2.55318002 3.55636998 1 P 0 
L 2.55318002 3.55636998 2.55318002 3.55991004 1 P 0 
L 2.55318002 3.55991004 2.55316998 3.56346004 1 P 0 
L 2.55316998 3.56346004 2.56103996 3.57131998 1 P 0 
L 2.56103996 3.57131998 2.56458002 3.57131998 1 P 0 
L 2.56458002 3.57131998 2.56813002 3.57131004 1 P 0 
L 2.56813002 3.57131004 2.57606004 3.57925 1 P 0 
A 2.57606004 3.57925 2.6064314 3.62469301 2.47701998 3.67831309 1 P 0 N
A 2.6064314 3.62469301 2.6171 3.6783 2.47701998 3.67831289 1 P 0 N
L 2.6171 3.6783 2.6171 3.67833996 1 P 0 
A 2.6171 3.67833996 2.61418573 3.69298032 2.57885 3.67833622 1 P 0 N
A 2.61418573 3.69298032 2.60588996 3.70538996 2.57885 3.67833622 1 P 0 N
L 2.60588996 3.70538996 2.59665 3.71463002 1 P 0 
A 2.59665 3.71463002 2.58820069 3.72728504 2.62421998 3.74218563 1 P 0 Y
A 2.58820069 3.72728504 2.58523996 3.74221004 2.62421998 3.74218652 1 P 0 Y
L 2.58523996 3.74221004 2.58523996 3.75251998 1 P 0 
A 2.58523996 3.75251998 2.58750728 3.76391152 2.61501998 3.75251407 1 P 0 Y
A 2.58750728 3.76391152 2.59396004 3.77356998 2.61501998 3.75251516 1 P 0 Y
L 2.59396004 3.77356998 2.60068996 3.7803 1 P 0 
A 2.60068996 3.7803 2.60574272 3.7924935 2.5885 3.79249488 1 P 0 N
A 2.60574272 3.7924935 2.60068996 3.80468996 2.5885 3.79249508 1 P 0 N
L 2.60068996 3.80468996 2.59588002 3.8095 1 P 0 
A 2.59588002 3.8095 2.58745266 3.82212313 2.62338002 3.83698396 1 P 0 Y
A 2.58745266 3.82212313 2.5845 3.83701004 2.62338002 3.83698524 1 P 0 Y
L 2.5845 3.83701004 2.5845 3.84515 1 P 0 
A 2.5845 3.84515 2.57524478 3.89167195 2.46293996 3.84514813 1 P 0 N
A 2.57524478 3.89167195 2.54888996 3.93111004 2.46293996 3.84514833 1 P 0 N
L 2.54888996 3.93111004 2.54298002 3.93701998 1 P 0 
A 2.54298002 3.93701998 2.52425994 3.95074518 2.48900404 3.88303002 1 P 0 N
A 2.52425994 3.95074518 2.50228002 3.95821004 2.48900482 3.88303002 1 P 0 N
L 2.50228002 3.95821004 2.44713996 3.96793002 1 P 0 
A 2.44713996 3.96793002 2.43847067 3.97087343 2.45235541 3.99753002 1 P 0 Y
A 2.43847067 3.97087343 2.43108996 3.97628996 2.45235541 3.99753002 1 P 0 Y
L 2.43108996 3.97628996 2.40758002 3.99981004 1 P 0 
A 2.40758002 3.99981004 2.39869656 4.00349173 2.39869508 3.99093002 1 P 0 N
A 2.39869656 4.00349173 2.38981004 3.99981004 2.39869498 3.99093002 1 P 0 N
L 2.38981004 3.99981004 2.3898 3.9998 1 P 0 
A 2.3898 3.9998 2.2732 3.9515 2.2732003 4.11638996 1 P 0 Y
L 2.2732 3.9515 2.25156004 3.9515 1 P 0 
A 2.25156004 3.9515 2.14285098 3.97311594 2.2515375 4.23555 1 P 0 Y
A 2.14285098 3.97311594 2.05068996 4.03468996 2.25153691 4.23555 1 P 0 Y
L 2.05068996 4.03468996 2.04138002 4.044 1 P 0 
A 2.04138002 4.044 1.99631969 4.11144528 2.18838002 4.19098612 1 P 0 Y
A 1.99631969 4.11144528 1.9805 4.191 2.18838002 4.1909873 1 P 0 Y
A 1.9805 4.191 1.971 4.2005 1.971 4.191 1 P 0 N
L 1.971 4.2005 1.95751004 4.2005 1 P 0 
A 1.95751004 4.2005 1.95531004 4.20071004 1.95747313 4.21173996 1 P 0 Y
L 1.95531004 4.20071004 1.92058996 4.20761998 1 P 0 
A 1.92058996 4.20761998 1.88665846 4.21976959 1.9446064 4.32815 1 P 0 Y
A 1.88665846 4.21976959 1.85771004 4.24123996 1.94460541 4.32815 1 P 0 Y
L 1.85771004 4.24123996 1.85768996 4.24126004 1 P 0 
A 1.85768996 4.24126004 1.84484055 4.27228356 1.88871998 4.27228494 1 P 0 Y
A 1.84484055 4.27228356 1.85768996 4.30331004 1.88871998 4.27228514 1 P 0 Y
A 1.85768996 4.30331004 1.8823 4.3135 1.88229872 4.27868996 1 P 0 Y
L 1.8823 4.3135 1.91145 4.3135 1 P 0 
A 1.91145 4.3135 1.92867116 4.3169315 1.91143179 4.35851998 1 P 0 N
A 1.92867116 4.3169315 1.94326998 4.32668996 1.91143258 4.35851998 1 P 0 N
A 1.94326998 4.32668996 1.94326998 4.34221004 1.93551004 4.33445 1 P 0 N
L 1.94326998 4.34221004 1.92246998 4.36301004 1 P 0 
A 1.92246998 4.36301004 1.90990797 4.38181732 1.96346004 4.4039876 1 P 0 Y
A 1.90990797 4.38181732 1.9055 4.404 1.96346004 4.40398809 1 P 0 Y
L 1.9055 4.404 1.9055 4.41501004 1 P 0 
A 1.9055 4.41501004 1.91998996 4.44998996 1.95496998 4.41500886 1 P 0 Y
L 1.91998996 4.44998996 1.92866998 4.45866998 1 P 0 
A 1.92866998 4.45866998 1.93845659 4.46520728 1.94998809 4.43735 1 P 0 Y
A 1.93845659 4.46520728 1.95 4.4675 1.94998888 4.43735 1 P 0 Y
L 1.95 4.4675 1.96035 4.4675 1 P 0 
A 1.96035 4.4675 1.96865266 4.4691623 1.96031506 4.48923996 1 P 0 N
A 1.96865266 4.4691623 1.97568996 4.47386998 1.96031476 4.48923996 1 P 0 N
A 1.97568996 4.47386998 1.9791686 4.47998032 1.96626998 4.48327815 1 P 0 N
A 1.9791686 4.47998032 1.97905 4.48701004 1.96626998 4.48327854 1 P 0 N
A 1.97905 4.48701004 1.97867992 4.48786388 1.97546998 4.48596545 1 P 0 N
A 1.97867992 4.48786388 1.97811004 4.4886 1.97546998 4.48596742 1 P 0 N
L 1.97811004 4.4886 1.96481998 4.50188996 1 P 0 
A 1.96481998 4.50188996 1.95770325 4.51165492 1.99236998 4.52944429 1 P 0 Y
A 1.95770325 4.51165492 1.95391998 4.52313002 1.99236998 4.52944557 1 P 0 Y
A 1.95391998 4.52313002 1.9535 4.52843002 1.98618002 4.52835295 1 P 0 Y
L 1.9535 4.52843002 1.9535 4.536 1 P 0 
A 1.9535 4.536 1.984 4.56651004 1.984 4.53600994 1 P 0 Y
A 1.984 4.56651004 1.98723996 4.56785 1.98399882 4.5711 1 P 0 N
L 1.98723996 4.56785 1.98933002 4.56993996 1 P 0 
A 1.98933002 4.56993996 1.99241535 4.57455502 1.97926998 4.58000433 1 P 0 N
A 1.99241535 4.57455502 1.9935 4.58 1.97926998 4.58000413 1 P 0 N
A 1.9935 4.58 1.9918627 4.58821033 1.97203002 4.57998691 1 P 0 N
A 1.9918627 4.58821033 1.98721004 4.59516998 1.97203002 4.57998681 1 P 0 N
L 1.98721004 4.59516998 1.97768996 4.60468996 1 P 0 
A 1.97768996 4.60468996 1.96728002 4.63053002 2.00283996 4.62983878 1 P 0 Y
L 1.96728002 4.63053002 1.97598996 4.67996004 1 P 0 
L 1.97598996 4.67996004 1.99258996 4.70371004 1 P 0 
L 1.99258996 4.70371004 2.0036 4.71141004 1 P 0 
L 2.0036 4.71141004 2.01696998 4.71378002 1 P 0 
L 2.01696998 4.71378002 2.02161998 4.72041004 1 P 0 
L 2.02161998 4.72041004 2.03256998 4.72235 1 P 0 
L 2.03256998 4.72235 2.0392 4.71768996 1 P 0 
L 2.0392 4.71768996 2.07228996 4.7235 1 P 0 
L 2.07228996 4.7235 2.07946004 4.72853002 1 P 0 
L 2.07946004 4.72853002 2.08808002 4.74081998 1 P 0 
L 2.08808002 4.74081998 2.08996004 4.75146998 1 P 0 
L 2.08996004 4.75146998 2.08996004 4.77886004 1 P 0 
A 2.08996004 4.77886004 2.0859 4.78291998 2.0859001 4.77886004 1 P 0 N
L 2.0859 4.78291998 2.07371004 4.78291998 1 P 0 
P 2.18456998 5.0535 5 P 0 0;2=3,4=1
P 2.44606004 3.41615 5 P 0 0;2=3,4=1
L 2.44606004 3.41615 2.44606004 3.4337 1 P 0 
A 2.44606004 3.4337 2.44976004 3.4374 2.44976004 3.4337 1 P 0 Y
L 2.44976004 3.4374 2.54423996 3.4374 1 P 0 
A 2.54423996 3.4374 2.57545039 3.44361102 2.54422835 3.51898002 1 P 0 N
A 2.57545039 3.44361102 2.60191004 3.46128996 2.54422864 3.51898002 1 P 0 N
L 2.60191004 3.46128996 2.61825 3.47763002 1 P 0 
A 2.61825 3.47763002 2.64871998 3.53615 2.54068002 3.55521132 1 P 0 N
L 2.64871998 3.53615 2.68063996 3.71713996 1 P 0 
L 2.68063996 3.71713996 2.65196998 3.87983002 1 P 0 
L 2.65196998 3.87983002 2.58418996 3.97666998 1 P 0 
A 2.58418996 3.97666998 2.56336732 3.99660738 2.52365541 3.93428996 1 P 0 N
A 2.56336732 3.99660738 2.5365 4.00706004 2.52365591 3.93428996 1 P 0 N
L 2.5365 4.00706004 2.4726 4.01833996 1 P 0 
A 2.4726 4.01833996 2.4647751 4.02100157 2.47734744 4.04513002 1 P 0 Y
A 2.4647751 4.02100157 2.45811004 4.02588996 2.47734656 4.04513002 1 P 0 Y
L 2.45811004 4.02588996 2.42318996 4.06081004 1 P 0 
A 2.42318996 4.06081004 2.37881004 4.06081004 2.401 4.03861998 1 P 0 N
L 2.37881004 4.06081004 2.37878996 4.06078996 1 P 0 
A 2.37878996 4.06078996 2.25738996 4.0105 2.25737953 4.1822 1 P 0 Y
L 2.25738996 4.0105 2.23216998 4.0105 1 P 0 
A 2.23216998 4.0105 2.16300207 4.02409803 2.23216722 4.1932 1 P 0 Y
A 2.16300207 4.02409803 2.10413002 4.06286998 2.23216594 4.1932 1 P 0 Y
L 2.10413002 4.06286998 2.103 4.06401004 1 P 0 
A 2.103 4.06401004 2.05043917 4.14266142 2.27441004 4.23544744 1 P 0 Y
A 2.05043917 4.14266142 2.03198002 4.23543996 2.27441004 4.23544813 1 P 0 Y
L 2.03198002 4.23543996 2.03198002 4.23546998 1 P 0 
L 2.03198002 4.23546998 2.04128002 4.28831998 1 P 0 
L 2.04128002 4.28831998 2.04128996 4.28831998 1 P 0 
A 2.04128996 4.28831998 2.03906703 4.32199951 1.97133002 4.30061555 1 P 0 N
A 2.03906703 4.32199951 2.02155 4.35085 1.97133002 4.30061506 1 P 0 N
L 2.02155 4.35085 2.00451004 4.36788996 1 P 0 
A 2.00451004 4.36788996 2.00451004 4.38788996 2.01451004 4.37788996 1 P 0 Y
L 2.00451004 4.38788996 2.01036004 4.39373996 1 P 0 
A 2.01036004 4.39373996 2.02153002 4.39838002 2.02154882 4.38256998 1 P 0 Y
L 2.02153002 4.39838002 2.02506004 4.39838002 1 P 0 
A 2.02506004 4.39838002 2.03055344 4.39728425 2.02505167 4.38401998 1 P 0 Y
A 2.03055344 4.39728425 2.03521004 4.39416998 2.02505217 4.38401998 1 P 0 Y
L 2.03521004 4.39416998 2.03768996 4.39168996 1 P 0 
A 2.03768996 4.39168996 2.05299193 4.38146959 2.07104232 4.42506004 1 P 0 N
A 2.05299193 4.38146959 2.07103996 4.37788002 2.07104262 4.42506004 1 P 0 N
L 2.07103996 4.37788002 2.0711 4.37788002 1 P 0 
A 2.0711 4.37788002 2.09648081 4.38292756 2.07109715 4.44423002 1 P 0 N
A 2.09648081 4.38292756 2.118 4.3973 2.07109675 4.44423002 1 P 0 N
L 2.118 4.3973 2.1354 4.4147 1 P 0 
A 2.1354 4.4147 2.15079114 4.43519941 2.0711 4.47900463 1 P 0 N
A 2.15079114 4.43519941 2.15985 4.45918002 2.0711 4.47900463 1 P 0 N
A 2.15985 4.45918002 2.16066004 4.46325 2.0711 4.47895935 1 P 0 N
L 2.16066004 4.46325 2.1717 4.52591998 1 P 0 
L 2.1717 4.52591998 2.1717 4.53563002 1 P 0 
A 2.1717 4.53563002 2.16850276 4.55169843 2.12971004 4.53562726 1 P 0 N
A 2.16850276 4.55169843 2.1594 4.56531998 2.12971004 4.53562707 1 P 0 N
L 2.1594 4.56531998 2.12961004 4.59511004 1 P 0 
A 2.12961004 4.59511004 2.12613937 4.59983799 2.14323996 4.60875325 1 P 0 Y
A 2.12613937 4.59983799 2.12425 4.60538996 2.14323996 4.60875492 1 P 0 Y
L 2.12425 4.60538996 2.11866998 4.63703002 1 P 0 
L 2.11866998 4.63703002 2.12593002 4.67815 1 P 0 
L 2.12593002 4.67815 2.15448002 4.71891998 1 P 0 
L 2.15448002 4.71891998 2.1668 4.78871998 1 P 0 
L 2.1668 4.78871998 2.15865 4.83496998 1 P 0 
L 2.15865 4.83496998 2.17976998 4.95468002 1 P 0 
L 2.17976998 4.95468002 2.16871998 5.01728002 1 P 0 
L 2.16871998 5.01728002 2.16871998 5.0498 1 P 0 
A 2.16871998 5.0498 2.17241998 5.0535 2.17241998 5.0498 1 P 0 Y
L 2.17241998 5.0535 2.18456998 5.0535 1 P 0 
P 2.14456998 5.0535 5 P 0 0;2=3,4=1
P 2.44606004 3.46615 5 P 0 0;2=3,4=1
L 2.44606004 3.46615 2.44606004 3.4486 1 P 0 
A 2.44606004 3.4486 2.44976004 3.4449 2.44976004 3.4486 1 P 0 N
L 2.44976004 3.4449 2.54423002 3.4449 1 P 0 
A 2.54423002 3.4449 2.5966 3.4666 2.54421919 3.51896998 1 P 0 N
L 2.5966 3.4666 2.61293996 3.48293996 1 P 0 
A 2.61293996 3.48293996 2.63132933 3.50801043 2.54068002 3.55522274 1 P 0 N
A 2.63132933 3.50801043 2.64133002 3.53745 2.54068002 3.55522264 1 P 0 N
L 2.64133002 3.53745 2.67301998 3.71713996 1 P 0 
L 2.67301998 3.71713996 2.64486998 3.87688996 1 P 0 
L 2.64486998 3.87688996 2.57803996 3.97236004 1 P 0 
A 2.57803996 3.97236004 2.55933573 3.9902747 2.52364557 3.93428996 1 P 0 N
A 2.55933573 3.9902747 2.5352 3.99966998 2.52364616 3.93428996 1 P 0 N
L 2.5352 3.99966998 2.47128996 4.01095 1 P 0 
A 2.47128996 4.01095 2.4528 4.02058002 2.47733898 4.04513002 1 P 0 Y
L 2.4528 4.02058002 2.41788002 4.0555 1 P 0 
A 2.41788002 4.0555 2.38411998 4.0555 2.401 4.03861998 1 P 0 N
L 2.38411998 4.0555 2.3841 4.05548002 1 P 0 
A 2.3841 4.05548002 2.25738996 4.003 2.25738878 4.18221004 1 P 0 Y
L 2.25738996 4.003 2.23216004 4.003 1 P 0 
A 2.23216004 4.003 2.16015541 4.01715738 2.2321626 4.1932 1 P 0 Y
A 2.16015541 4.01715738 2.09886998 4.05751998 2.23216299 4.1932 1 P 0 Y
A 2.09886998 4.05751998 2.09768996 4.05868996 2.23096644 4.19193002 1 P 0 Y
L 2.09768996 4.05868996 2.09768996 4.0587 1 P 0 
A 2.09768996 4.0587 2.04350837 4.13978406 2.27441998 4.23543819 1 P 0 Y
A 2.04350837 4.13978406 2.02448002 4.23543002 2.27441998 4.23543868 1 P 0 Y
L 2.02448002 4.23543002 2.02448002 4.23613002 1 P 0 
L 2.02448002 4.23613002 2.03388996 4.28961004 1 P 0 
A 2.03388996 4.28961004 2.0319062 4.31973415 1.97133002 4.30061762 1 P 0 N
A 2.0319062 4.31973415 2.01623996 4.34553996 1.97133002 4.30061772 1 P 0 N
L 2.01623996 4.34553996 1.9992 4.36258002 1 P 0 
A 1.9992 4.36258002 1.9992 4.3932 2.01451004 4.37789006 1 P 0 Y
L 1.9992 4.3932 2.00505 4.39905 1 P 0 
L 2.00505 4.39905 2.00505 4.39903996 1 P 0 
A 2.00505 4.39903996 2.02151998 4.40588002 2.02154951 4.38256004 1 P 0 Y
L 2.02151998 4.40588002 2.02506998 4.40588002 1 P 0 
A 2.02506998 4.40588002 2.0334315 4.40421575 2.02506535 4.38401998 1 P 0 Y
A 2.0334315 4.40421575 2.04051998 4.39948002 2.02506516 4.38401998 1 P 0 Y
L 2.04051998 4.39948002 2.043 4.397 1 P 0 
A 2.043 4.397 2.05586929 4.38840039 2.07105167 4.42505 1 P 0 N
A 2.05586929 4.38840039 2.07105 4.38538002 2.07105197 4.42505 1 P 0 N
L 2.07105 4.38538002 2.07108996 4.38538002 1 P 0 
A 2.07108996 4.38538002 2.09360344 4.38985837 2.0710878 4.44421998 1 P 0 N
A 2.09360344 4.38985837 2.11268996 4.40261004 2.0710875 4.44421998 1 P 0 N
L 2.11268996 4.40261004 2.13008996 4.42001004 1 P 0 
A 2.13008996 4.42001004 2.15251998 4.46081998 2.0711 4.47900118 1 P 0 N
L 2.15251998 4.46081998 2.15253002 4.46083002 1 P 0 
A 2.15253002 4.46083002 2.15326998 4.46455 2.0711 4.47896132 1 P 0 N
L 2.15326998 4.46455 2.1642 4.52658002 1 P 0 
L 2.1642 4.52658002 2.1642 4.53561998 1 P 0 
A 2.1642 4.53561998 2.16157195 4.54882116 2.12971998 4.53561801 1 P 0 N
A 2.16157195 4.54882116 2.15408996 4.56001004 2.12971998 4.53561782 1 P 0 N
L 2.15408996 4.56001004 2.1243 4.5898 1 P 0 
A 2.1243 4.5898 2.11948081 4.59637274 2.14325 4.60874744 1 P 0 Y
A 2.11948081 4.59637274 2.11686004 4.60408996 2.14325 4.60874833 1 P 0 Y
L 2.11686004 4.60408996 2.11105 4.63703002 1 P 0 
L 2.11105 4.63703002 2.11883002 4.68108996 1 P 0 
L 2.11883002 4.68108996 2.14738002 4.72186004 1 P 0 
L 2.14738002 4.72186004 2.15918002 4.78871998 1 P 0 
L 2.15918002 4.78871998 2.15103002 4.83496998 1 P 0 
L 2.15103002 4.83496998 2.15368002 4.84998002 1 P 0 
L 2.15368002 4.84998002 2.14951998 4.85588996 1 P 0 
L 2.14951998 4.85588996 2.15146004 4.86683002 1 P 0 
L 2.15146004 4.86683002 2.15738002 4.87098002 1 P 0 
L 2.15738002 4.87098002 2.15931998 4.88193996 1 P 0 
L 2.15931998 4.88193996 2.15516004 4.88785 1 P 0 
L 2.15516004 4.88785 2.1571 4.89878996 1 P 0 
L 2.1571 4.89878996 2.16301998 4.90293996 1 P 0 
L 2.16301998 4.90293996 2.17215 4.95468002 1 P 0 
L 2.17215 4.95468002 2.16121998 5.01661998 1 P 0 
L 2.16121998 5.01661998 2.16121998 5.0498 1 P 0 
A 2.16121998 5.0498 2.15751998 5.0535 2.15751998 5.0498 1 P 0 N
L 2.15751998 5.0535 2.14456998 5.0535 1 P 0 
P 8.5 3.31615 5 P 0 0;2=3,4=1
P 8.25898002 4.78291998 5 P 0 0;2=3,4=1
L 8.25898002 4.78291998 8.24656998 4.78291998 1 P 0 
A 8.24656998 4.78291998 8.24286998 4.77921998 8.24656998 4.77921998 1 P 0 N
L 8.24286998 4.77921998 8.24286998 4.752 1 P 0 
L 8.24286998 4.752 8.2449 4.74046998 1 P 0 
L 8.2449 4.74046998 8.25326998 4.7285 1 P 0 
L 8.25326998 4.7285 8.30418996 4.69286004 1 P 0 
L 8.30418996 4.69286004 8.34163996 4.6394 1 P 0 
L 8.34163996 4.6394 8.39388996 4.60283996 1 P 0 
A 8.39388996 4.60283996 8.39991398 4.59437726 8.37668002 4.58421398 1 P 0 Y
A 8.39991398 4.59437726 8.40203996 4.58421004 8.37668002 4.58421309 1 P 0 Y
L 8.40203996 4.58421004 8.40203996 4.57483002 1 P 0 
A 8.40203996 4.57483002 8.36336998 4.54238002 8.36908967 4.57483002 1 P 0 Y
L 8.36336998 4.54238002 8.28705 4.55581004 1 P 0 
A 8.28705 4.55581004 8.25791004 4.55046998 8.28755276 4.47088996 1 P 0 N
A 8.25791004 4.55046998 8.25056535 4.5467877 8.27138337 4.51443002 1 P 0 N
A 8.25056535 4.5467877 8.24416998 4.54163002 8.27138337 4.51443002 1 P 0 N
L 8.24416998 4.54163002 8.24413996 4.5416 1 P 0 
A 8.24413996 4.5416 8.2415999 4.53856132 8.25983996 4.52589528 1 P 0 N
A 8.2415999 4.53856132 8.23963996 4.53511998 8.25983996 4.52589429 1 P 0 N
L 8.23963996 4.53511998 8.23538996 4.52578002 1 P 0 
A 8.23538996 4.52578002 8.23271998 4.51026998 8.2636 4.51293898 1 P 0 N
A 8.23271998 4.51026998 8.2328 4.50771998 8.27428002 4.51029793 1 P 0 N
A 8.2328 4.50771998 8.24328406 4.48258209 8.27428996 4.5102687 1 P 0 N
A 8.24328406 4.48258209 8.26708002 4.46933002 8.27429154 4.51026998 1 P 0 N
L 8.26708002 4.46933002 8.35751004 4.45338996 1 P 0 
L 8.35751004 4.45338996 8.49238996 4.47716998 1 P 0 
L 8.49238996 4.47716998 8.49306998 4.47716998 1 P 0 
A 8.49306998 4.47716998 8.5237 4.4645 8.49309872 4.43388002 1 P 0 Y
L 8.5237 4.4645 8.52373002 4.46446998 1 P 0 
A 8.52373002 4.46446998 8.53218268 4.45182077 8.49616998 4.43690453 1 P 0 Y
A 8.53218268 4.45182077 8.53515 4.4369 8.49616998 4.43690344 1 P 0 Y
A 8.53515 4.4369 8.53207697 4.42146467 8.49481998 4.43690571 1 P 0 Y
A 8.53207697 4.42146467 8.52333002 4.40838002 8.49481998 4.43690463 1 P 0 Y
L 8.52333002 4.40838002 8.52331998 4.40838002 1 P 0 
L 8.52331998 4.40838002 8.51595 4.401 1 P 0 
L 8.51595 4.401 8.51595 4.40098996 1 P 0 
A 8.51595 4.40098996 8.51595 4.37551004 8.52868996 4.38825 1 P 0 N
L 8.51595 4.37551004 8.51631004 4.37515 1 P 0 
A 8.51631004 4.37515 8.52168209 4.37116083 8.5324624 4.39128996 1 P 0 N
A 8.52168209 4.37116083 8.52798002 4.3689 8.5324628 4.39128996 1 P 0 N
L 8.52798002 4.3689 8.53455 4.36758996 1 P 0 
L 8.53455 4.36758996 8.53481004 4.36755 1 P 0 
L 8.53481004 4.36755 8.58826004 4.35811998 1 P 0 
A 8.58826004 4.35811998 8.598975 4.35448209 8.58180207 4.3215 1 P 0 Y
A 8.598975 4.35448209 8.6081 4.34778996 8.58180285 4.3215 1 P 0 Y
L 8.6081 4.34778996 8.61546998 4.34043002 1 P 0 
L 8.61546998 4.34043002 8.65421004 4.2851 1 P 0 
A 8.65421004 4.2851 8.65592638 4.28182894 8.64233996 4.27678593 1 P 0 Y
A 8.65592638 4.28182894 8.65676004 4.27823002 8.64233996 4.27678573 1 P 0 Y
A 8.65676004 4.27823002 8.65768996 4.26371998 8.37523002 4.25290246 1 P 0 Y
A 8.65768996 4.26371998 8.64822047 4.24008435 8.61871004 4.26562234 1 P 0 Y
A 8.64822047 4.24008435 8.62618996 4.22731998 8.6187122 4.26561998 1 P 0 Y
L 8.62618996 4.22731998 8.60573002 4.22731998 1 P 0 
A 8.60573002 4.22731998 8.58153996 4.2173 8.60573012 4.19311004 1 P 0 N
L 8.58153996 4.2173 8.5808 4.21656004 1 P 0 
A 8.5808 4.21656004 8.57323996 4.1983 8.59906998 4.19830089 1 P 0 N
A 8.57323996 4.1983 8.58983996 4.1817 8.58983996 4.1983 1 P 0 N
L 8.58983996 4.1817 8.63298002 4.1817 1 P 0 
A 8.63298002 4.1817 8.64616811 4.17907815 8.63298189 4.14723002 1 P 0 Y
A 8.64616811 4.17907815 8.65735 4.17161004 8.63298228 4.14723002 1 P 0 Y
A 8.65735 4.17161004 8.65735 4.11518996 8.62913996 4.1434 1 P 0 Y
L 8.65735 4.11518996 8.64848002 4.10631998 1 P 0 
A 8.64848002 4.10631998 8.57686998 4.07563996 8.57433032 4.18048002 1 P 0 Y
L 8.57686998 4.07563996 8.57675 4.07563996 1 P 0 
A 8.57675 4.07563996 8.56735384 4.07376614 8.57676289 4.05108002 1 P 0 N
A 8.56735384 4.07376614 8.55938996 4.06843996 8.57676309 4.05108002 1 P 0 N
L 8.55938996 4.06843996 8.55793996 4.06698996 1 P 0 
A 8.55793996 4.06698996 8.55466841 4.0590935 8.56583002 4.05909508 1 P 0 N
A 8.55466841 4.0590935 8.55793996 4.0512 8.56583002 4.05909488 1 P 0 N
L 8.55793996 4.0512 8.55796004 4.05118002 1 P 0 
A 8.55796004 4.05118002 8.56202008 4.04846112 8.56683366 4.06003996 1 P 0 N
A 8.56202008 4.04846112 8.56681004 4.0475 8.56683484 4.06003996 1 P 0 N
L 8.56681004 4.0475 8.5765 4.0475 1 P 0 
A 8.5765 4.0475 8.6093 4.0339 8.57650118 4.00115 1 P 0 Y
L 8.6093 4.0339 8.61743002 4.02576998 1 P 0 
L 8.61743002 4.02576998 8.69848996 3.91001004 1 P 0 
L 8.69848996 3.91001004 8.73238002 3.71788002 1 P 0 
L 8.73238002 3.71788002 8.68403996 3.44365 1 P 0 
A 8.68403996 3.44365 8.67572884 3.41915935 8.6003 3.4584123 1 P 0 Y
A 8.67572884 3.41915935 8.66043996 3.3983 8.6003 3.4584123 1 P 0 Y
L 8.66043996 3.3983 8.63436998 3.37221998 1 P 0 
A 8.63436998 3.37221998 8.5957939 3.34644518 8.5503127 3.45626998 1 P 0 Y
A 8.5957939 3.34644518 8.55028996 3.3374 8.5503122 3.45626998 1 P 0 Y
L 8.55028996 3.3374 8.5037 3.3374 1 P 0 
A 8.5037 3.3374 8.5 3.3337 8.5037 3.3337 1 P 0 N
L 8.5 3.3337 8.5 3.31615 1 P 0 
P 2.06853002 4.66688996 5 P 0 0;2=3,4=1
P 2.49606004 3.46615 5 P 0 0;2=3,4=1
L 2.49606004 3.46615 2.49606004 3.4837 1 P 0 
A 2.49606004 3.4837 2.49976004 3.4874 2.49976004 3.4837 1 P 0 Y
L 2.49976004 3.4874 2.54406004 3.4874 1 P 0 
A 2.54406004 3.4874 2.59585 3.50885 2.54407126 3.56061998 1 P 0 N
L 2.59585 3.50885 2.60773002 3.52073002 1 P 0 
A 2.60773002 3.52073002 2.62147657 3.53947697 2.5537 3.57476201 1 P 0 N
A 2.62147657 3.53947697 2.62895 3.56148996 2.5537 3.5747623 1 P 0 N
L 2.62895 3.56148996 2.6563 3.71668996 1 P 0 
L 2.6563 3.71668996 2.62843002 3.87468996 1 P 0 
L 2.62843002 3.87468996 2.56871998 3.95998996 1 P 0 
A 2.56871998 3.95998996 2.54479931 3.97772864 2.49976358 3.892 1 P 0 N
A 2.54479931 3.97772864 2.51661998 3.98736004 2.4997625 3.892 1 P 0 N
L 2.51661998 3.98736004 2.4672 3.99608996 1 P 0 
A 2.4672 3.99608996 2.44155 4.00945 2.4755688 4.04346004 1 P 0 Y
L 2.44155 4.00945 2.416 4.035 1 P 0 
A 2.416 4.035 2.384 4.035 2.4 4.019 1 P 0 N
L 2.384 4.035 2.38398002 4.03498002 1 P 0 
A 2.38398002 4.03498002 2.26331998 3.985 2.2633186 4.15563996 1 P 0 Y
L 2.26331998 3.985 2.24035 3.985 1 P 0 
A 2.24035 3.985 2.1559499 4.00178996 2.24035453 4.20555 1 P 0 Y
A 2.1559499 4.00178996 2.0844 4.0496 2.24035502 4.20555 1 P 0 Y
L 2.0844 4.0496 2.083 4.051 1 P 0 
A 2.083 4.051 2.03399094 4.12035738 2.2602 4.2282064 1 P 0 Y
A 2.03399094 4.12035738 2.01096004 4.2021 2.2602 4.22820738 1 P 0 Y
L 2.01096004 4.2021 2.01096004 4.20278002 1 P 0 
A 2.01096004 4.20278002 2.00889154 4.2131815 1.98378002 4.2027812 1 P 0 N
A 2.00889154 4.2131815 2.003 4.222 1.98378002 4.20278209 1 P 0 N
L 2.003 4.222 2.0016 4.2234 1 P 0 
A 2.0016 4.2234 1.976 4.234 1.97600128 4.19778996 1 P 0 N
L 1.976 4.234 1.96238002 4.234 1 P 0 
A 1.96238002 4.234 1.94539695 4.23737923 1.96238287 4.27838002 1 P 0 Y
A 1.94539695 4.23737923 1.931 4.247 1.96238268 4.27838002 1 P 0 Y
A 1.931 4.247 1.92414833 4.26354646 1.94755 4.26354498 1 P 0 Y
A 1.92414833 4.26354646 1.931 4.28008996 1.94755 4.26354498 1 P 0 Y
L 1.931 4.28008996 1.93101004 4.2801 1 P 0 
A 1.93101004 4.2801 1.95973002 4.292 1.9597313 4.25138996 1 P 0 Y
L 1.95973002 4.292 1.98468996 4.292 1 P 0 
A 1.98468996 4.292 1.99514075 4.29407963 1.9846878 4.31931004 1 P 0 N
A 1.99514075 4.29407963 2.004 4.3 1.9846878 4.31931004 1 P 0 N
A 2.004 4.3 2.004 4.33218002 1.98791004 4.31609006 1 P 0 N
L 2.004 4.33218002 2.00398996 4.33218996 1 P 0 
A 2.00398996 4.33218996 1.97991004 4.35248002 1.87317943 4.20138002 1 P 0 N
L 1.97991004 4.35248002 1.96633002 4.36196998 1 P 0 
L 1.96633002 4.36196998 1.96228996 4.366 1 P 0 
A 1.96228996 4.366 1.95001004 4.39568996 1.99201998 4.395681 1 P 0 Y
L 1.95001004 4.39568996 1.95 4.39568002 1 P 0 
L 1.95 4.39568002 1.95 4.40366004 1 P 0 
A 1.95 4.40366004 1.98835 4.44198996 1.98832992 4.40366004 1 P 0 Y
A 1.98835 4.44198996 1.99357116 4.44095344 1.98835167 4.42833002 1 P 0 Y
A 1.99357116 4.44095344 1.998 4.438 1.98835217 4.42833002 1 P 0 Y
L 1.998 4.438 2.00281004 4.43318996 1 P 0 
A 2.00281004 4.43318996 2.01355039 4.42601496 2.02620236 4.45658002 1 P 0 N
A 2.01355039 4.42601496 2.02621998 4.4235 2.02620207 4.45658002 1 P 0 N
L 2.02621998 4.4235 2.03398002 4.4235 1 P 0 
A 2.03398002 4.4235 2.05451004 4.44401004 2.0339999 4.44401004 1 P 0 N
A 2.05451004 4.44401004 2.05258002 4.45369774 2.02918996 4.44400177 1 P 0 N
A 2.05258002 4.45369774 2.04708996 4.46191004 2.02918996 4.44400236 1 P 0 N
L 2.04708996 4.46191004 2.00721998 4.50178002 1 P 0 
A 2.00721998 4.50178002 2.00224764 4.50922234 2.02345 4.51800581 1 P 0 Y
A 2.00224764 4.50922234 2.0005 4.518 2.02345 4.51800659 1 P 0 Y
L 2.0005 4.518 2.0005 4.52 1 P 0 
A 2.0005 4.52 2.01806004 4.53756004 2.01806004 4.52 1 P 0 Y
L 2.01806004 4.53756004 2.01808002 4.53756004 1 P 0 
A 2.01808002 4.53756004 2.04925965 4.53135591 2.01807815 4.4561 1 P 0 Y
A 2.04925965 4.53135591 2.07568996 4.51368996 2.01807785 4.4561 1 P 0 Y
L 2.07568996 4.51368996 2.0839 4.50548002 1 P 0 
A 2.0839 4.50548002 2.1271 4.50548002 2.1055 4.52708002 1 P 0 N
L 2.1271 4.50548002 2.13181004 4.51018996 1 P 0 
A 2.13181004 4.51018996 2.13988652 4.52968652 2.11231998 4.52968484 1 P 0 N
A 2.13988652 4.52968652 2.13181004 4.54918002 2.11231998 4.52968514 1 P 0 N
L 2.13181004 4.54918002 2.12965 4.55133996 1 P 0 
L 2.12965 4.55133996 2.07928002 4.58676998 1 P 0 
L 2.07928002 4.58676998 2.05473002 4.62178996 1 P 0 
L 2.05473002 4.62178996 2.05241998 4.63488996 1 P 0 
L 2.05241998 4.63488996 2.05241998 4.66318996 1 P 0 
A 2.05241998 4.66318996 2.05611998 4.66688996 2.05611998 4.66318996 1 P 0 Y
L 2.05611998 4.66688996 2.06853002 4.66688996 1 P 0 
P 8.5 3.36615 5 P 0 0;2=3,4=1
P 8.21898002 4.78291998 5 P 0 0;2=3,4=1
L 8.21898002 4.78291998 8.23166998 4.78291998 1 P 0 
A 8.23166998 4.78291998 8.23536998 4.77921998 8.23166998 4.77921998 1 P 0 Y
L 8.23536998 4.77921998 8.23536998 4.75133996 1 P 0 
L 8.23536998 4.75133996 8.23778996 4.73753002 1 P 0 
L 8.23778996 4.73753002 8.24788002 4.72311004 1 P 0 
L 8.24788002 4.72311004 8.2988 4.68746998 1 P 0 
L 8.2988 4.68746998 8.31658996 4.66206004 1 P 0 
L 8.31658996 4.66206004 8.31546004 4.6557 1 P 0 
L 8.31546004 4.6557 8.32183996 4.64658996 1 P 0 
L 8.32183996 4.64658996 8.32821004 4.64546998 1 P 0 
L 8.32821004 4.64546998 8.33625 4.634 1 P 0 
L 8.33625 4.634 8.35016004 4.62426998 1 P 0 
L 8.35016004 4.62426998 8.35106004 4.61908996 1 P 0 
L 8.35106004 4.61908996 8.36016998 4.61271004 1 P 0 
L 8.36016998 4.61271004 8.36533002 4.61365 1 P 0 
L 8.36533002 4.61365 8.36533996 4.61365 1 P 0 
L 8.36533996 4.61365 8.38913002 4.59701004 1 P 0 
A 8.38913002 4.59701004 8.39312549 4.5911562 8.37666998 4.58421506 1 P 0 Y
A 8.39312549 4.5911562 8.39453002 4.58421004 8.37666998 4.58421378 1 P 0 Y
L 8.39453002 4.58421004 8.39453996 4.58421998 1 P 0 
L 8.39453996 4.58421998 8.39453996 4.57483002 1 P 0 
A 8.39453996 4.57483002 8.38544734 4.55533504 8.36908996 4.57483219 1 P 0 Y
A 8.38544734 4.55533504 8.36466998 4.54976998 8.36909183 4.57483002 1 P 0 Y
L 8.36466998 4.54976998 8.2877 4.56331998 1 P 0 
L 8.2877 4.56331998 8.28756998 4.56331998 1 P 0 
A 8.28756998 4.56331998 8.25528996 4.5575 8.28757018 4.47088996 1 P 0 N
A 8.25528996 4.5575 8.23886004 4.54693996 8.27137028 4.51441998 1 P 0 N
L 8.23886004 4.54693996 8.23883002 4.54691004 1 P 0 
A 8.23883002 4.54691004 8.23281004 4.53823996 8.25983996 4.52589695 1 P 0 N
L 8.23281004 4.53823996 8.22856004 4.52888002 1 P 0 
A 8.22856004 4.52888002 8.22567825 4.51958268 8.2636 4.51292382 1 P 0 N
A 8.22567825 4.51958268 8.22521998 4.50986004 8.2636 4.51292313 1 P 0 N
A 8.22521998 4.50986004 8.22531004 4.50726004 8.27428996 4.51025817 1 P 0 N
A 8.22531004 4.50726004 8.2376874 4.47758356 8.27428996 4.510269 1 P 0 N
A 8.2376874 4.47758356 8.26578002 4.46193996 8.27429104 4.51026998 1 P 0 N
L 8.26578002 4.46193996 8.35751004 4.44576998 1 P 0 
L 8.35751004 4.44576998 8.49305 4.46966998 1 P 0 
L 8.49305 4.46966998 8.49308002 4.46966998 1 P 0 
A 8.49308002 4.46966998 8.50677766 4.46694724 8.49308533 4.43388002 1 P 0 Y
A 8.50677766 4.46694724 8.51838996 4.45918996 8.49308514 4.43388002 1 P 0 Y
L 8.51838996 4.45918996 8.51841998 4.45916004 1 P 0 
A 8.51841998 4.45916004 8.52763996 4.4369 8.49616004 4.43690069 1 P 0 Y
A 8.52763996 4.4369 8.52513809 4.42433848 8.49481004 4.43690886 1 P 0 Y
A 8.52513809 4.42433848 8.51801998 4.41368996 8.49481004 4.43690817 1 P 0 Y
L 8.51801998 4.41368996 8.51063996 4.4063 1 P 0 
A 8.51063996 4.4063 8.51063996 4.3702 8.52868996 4.38825 1 P 0 N
L 8.51063996 4.3702 8.511 4.36983996 1 P 0 
A 8.511 4.36983996 8.5265 4.36153996 8.53245837 4.39128996 1 P 0 N
L 8.5265 4.36153996 8.52651998 4.36153996 1 P 0 
L 8.52651998 4.36153996 8.53325 4.3602 1 P 0 
L 8.53325 4.3602 8.58696004 4.35073002 1 P 0 
A 8.58696004 4.35073002 8.60278996 4.34248002 8.58179114 4.3215 1 P 0 Y
L 8.60278996 4.34248002 8.60451998 4.34075 1 P 0 
L 8.60451998 4.34075 8.60971004 4.33558002 1 P 0 
L 8.60971004 4.33558002 8.64806004 4.28078996 1 P 0 
A 8.64806004 4.28078996 8.64888376 4.27922815 8.64233996 4.276775 1 P 0 Y
A 8.64888376 4.27922815 8.64928996 4.27751004 8.64233996 4.27677402 1 P 0 Y
A 8.64928996 4.27751004 8.64956004 4.27421004 8.37518996 4.25341604 1 P 0 Y
A 8.64956004 4.27421004 8.65018002 4.26376998 8.37523996 4.2526812 1 P 0 Y
A 8.65018002 4.26376998 8.64266732 4.24513169 8.61871004 4.26562156 1 P 0 Y
A 8.64266732 4.24513169 8.62541998 4.23481998 8.61871171 4.26561998 1 P 0 Y
L 8.62541998 4.23481998 8.60571998 4.23481998 1 P 0 
A 8.60571998 4.23481998 8.58976122 4.23164734 8.60571722 4.19311004 1 P 0 N
A 8.58976122 4.23164734 8.57623002 4.22261004 8.60571614 4.19311004 1 P 0 N
L 8.57623002 4.22261004 8.57548996 4.22186998 1 P 0 
A 8.57548996 4.22186998 8.56573002 4.1983 8.59906998 4.1983002 1 P 0 N
A 8.56573002 4.1983 8.58983996 4.1742 8.58983002 4.1983 1 P 0 N
L 8.58983996 4.1742 8.63296998 4.1742 1 P 0 
A 8.63296998 4.1742 8.65203996 4.1663 8.6329686 4.14723002 1 P 0 Y
L 8.65203996 4.1663 8.65203996 4.16631004 1 P 0 
A 8.65203996 4.16631004 8.66152894 4.14340354 8.62913996 4.14340512 1 P 0 Y
A 8.66152894 4.14340354 8.65203996 4.1205 8.62913996 4.14340492 1 P 0 Y
L 8.65203996 4.1205 8.64316998 4.11163002 1 P 0 
A 8.64316998 4.11163002 8.57676998 4.08313996 8.57432096 4.18046998 1 P 0 Y
L 8.57676998 4.08313996 8.57675 4.08313996 1 P 0 
A 8.57675 4.08313996 8.55408002 4.07375 8.57674961 4.05108002 1 P 0 N
L 8.55408002 4.07375 8.55263002 4.0723 1 P 0 
A 8.55263002 4.0723 8.54715886 4.0590935 8.56583002 4.05909498 1 P 0 N
A 8.54715886 4.0590935 8.55263002 4.04588996 8.56583002 4.05909498 1 P 0 N
L 8.55263002 4.04588996 8.55265 4.04586998 1 P 0 
A 8.55265 4.04586998 8.55914193 4.04153032 8.5668253 4.06005 1 P 0 N
A 8.55914193 4.04153032 8.5668 4.04 8.5668247 4.06005 1 P 0 N
L 8.5668 4.04 8.5765 4.04 1 P 0 
A 8.5765 4.04 8.59137992 4.03703652 8.57649774 4.00115 1 P 0 Y
A 8.59137992 4.03703652 8.60398996 4.0286 8.57649783 4.00115 1 P 0 Y
L 8.60398996 4.0286 8.61166004 4.02093002 1 P 0 
L 8.61166004 4.02093002 8.69138996 3.90706998 1 P 0 
L 8.69138996 3.90706998 8.72476004 3.71788002 1 P 0 
L 8.72476004 3.71788002 8.67665 3.44495 1 P 0 
A 8.67665 3.44495 8.65513002 3.40361004 8.60031004 3.45841841 1 P 0 Y
L 8.65513002 3.40361004 8.62906004 3.37753002 1 P 0 
A 8.62906004 3.37753002 8.55028996 3.3449 8.55029902 3.45626998 1 P 0 Y
L 8.55028996 3.3449 8.5037 3.3449 1 P 0 
A 8.5037 3.3449 8.5 3.3486 8.5037 3.3486 1 P 0 Y
L 8.5 3.3486 8.5 3.36615 1 P 0 
P 2.02853002 4.66688996 5 P 0 0;2=3,4=1
P 2.49606004 3.51615 5 P 0 0;2=3,4=1
L 2.49606004 3.51615 2.49606004 3.4986 1 P 0 
A 2.49606004 3.4986 2.49976004 3.4949 2.49976004 3.4986 1 P 0 N
L 2.49976004 3.4949 2.54406998 3.4949 1 P 0 
A 2.54406998 3.4949 2.56922077 3.49990797 2.54405797 3.56061998 1 P 0 N
A 2.56922077 3.49990797 2.59053996 3.51416004 2.54405768 3.56061998 1 P 0 N
L 2.59053996 3.51416004 2.60241998 3.52603996 1 P 0 
A 2.60241998 3.52603996 2.61481762 3.54294213 2.5537 3.57477362 1 P 0 N
A 2.61481762 3.54294213 2.62156004 3.56278996 2.5537 3.57477323 1 P 0 N
L 2.62156004 3.56278996 2.64868002 3.71668996 1 P 0 
L 2.64868002 3.71668996 2.62133002 3.87175 1 P 0 
L 2.62133002 3.87175 2.56293996 3.95516004 1 P 0 
A 2.56293996 3.95516004 2.54103327 3.97122884 2.49976467 3.892 1 P 0 N
A 2.54103327 3.97122884 2.51531004 3.97996998 2.49976329 3.892 1 P 0 N
L 2.51531004 3.97996998 2.4659 3.9887 1 P 0 
A 2.4659 3.9887 2.44988209 3.99413819 2.4755627 4.04346998 1 P 0 Y
A 2.44988209 3.99413819 2.43623996 4.00413996 2.4755624 4.04346998 1 P 0 Y
L 2.43623996 4.00413996 2.41068996 4.02968996 1 P 0 
A 2.41068996 4.02968996 2.38931004 4.02968996 2.4 4.019 1 P 0 N
L 2.38931004 4.02968996 2.38928996 4.02966998 1 P 0 
A 2.38928996 4.02966998 2.33149813 3.99105817 2.26333248 4.15563996 1 P 0 Y
A 2.33149813 3.99105817 2.26333002 3.9775 2.26333159 4.15563996 1 P 0 Y
L 2.26333002 3.9775 2.24033996 3.9775 1 P 0 
A 2.24033996 3.9775 2.07908996 4.04428996 2.24034134 4.20555 1 P 0 Y
L 2.07908996 4.04428996 2.07768996 4.04568996 1 P 0 
A 2.07768996 4.04568996 2.02721772 4.11712234 2.2602 4.22819409 1 P 0 Y
A 2.02721772 4.11712234 2.0035 4.20131004 2.2602 4.2281939 1 P 0 Y
L 2.0035 4.20131004 2.00346004 4.20135 1 P 0 
L 2.00346004 4.20135 2.00346004 4.20278996 1 P 0 
L 2.00346004 4.20278996 2.00345 4.20278002 1 P 0 
A 2.00345 4.20278002 2.00195344 4.21030768 1.98378002 4.20278209 1 P 0 N
A 2.00195344 4.21030768 1.99768996 4.21668996 1.98378002 4.20278268 1 P 0 N
L 1.99768996 4.21668996 1.99628996 4.21808996 1 P 0 
A 1.99628996 4.21808996 1.98698573 4.22431004 1.9759877 4.19778996 1 P 0 N
A 1.98698573 4.22431004 1.97601004 4.2265 1.97598789 4.19778996 1 P 0 N
L 1.97601004 4.2265 1.96236998 4.2265 1 P 0 
A 1.96236998 4.2265 1.92568996 4.24168996 1.96236929 4.27838002 1 P 0 Y
A 1.92568996 4.24168996 1.91663888 4.26354646 1.94755 4.26354488 1 P 0 Y
A 1.91663888 4.26354646 1.92568996 4.2854 1.94755 4.26354508 1 P 0 Y
L 1.92568996 4.2854 1.9257 4.28541004 1 P 0 
A 1.9257 4.28541004 1.94130886 4.29583848 1.95971722 4.25138996 1 P 0 Y
A 1.94130886 4.29583848 1.95971998 4.2995 1.95971821 4.25138996 1 P 0 Y
L 1.95971998 4.2995 1.98468002 4.2995 1 P 0 
A 1.98468002 4.2995 1.99226801 4.30100925 1.98468386 4.31931004 1 P 0 N
A 1.99226801 4.30100925 1.9987 4.30531004 1.98468494 4.31931004 1 P 0 N
L 1.9987 4.30531004 1.99868996 4.30531004 1 P 0 
A 1.99868996 4.30531004 1.99868996 4.32686998 1.98791004 4.31609006 1 P 0 N
L 1.99868996 4.32686998 1.99868002 4.32688002 1 P 0 
A 1.99868002 4.32688002 1.9756 4.34633996 1.87314596 4.20141004 1 P 0 N
L 1.9756 4.34633996 1.96148996 4.3562 1 P 0 
L 1.96148996 4.3562 1.95698996 4.36068996 1 P 0 
A 1.95698996 4.36068996 1.94626526 4.37674961 1.99201004 4.3956873 1 P 0 Y
A 1.94626526 4.37674961 1.9425 4.39568996 1.99201004 4.39568789 1 P 0 Y
L 1.9425 4.39568996 1.9425 4.40366004 1 P 0 
A 1.9425 4.40366004 1.98833996 4.4495 1.98833996 4.40366004 1 P 0 Y
A 1.98833996 4.4495 1.99644035 4.44789429 1.98835482 4.42833996 1 P 0 Y
A 1.99644035 4.44789429 2.00331004 4.44331004 1.98835581 4.42833996 1 P 0 Y
L 2.00331004 4.44331004 2.00811998 4.4385 1 P 0 
A 2.00811998 4.4385 2.01642382 4.43294843 2.02621516 4.45658002 1 P 0 N
A 2.01642382 4.43294843 2.02621998 4.431 2.02621594 4.45658002 1 P 0 N
L 2.02621998 4.431 2.03398996 4.431 1 P 0 
A 2.03398996 4.431 2.047 4.44401004 2.03398996 4.44401004 1 P 0 N
A 2.047 4.44401004 2.04564193 4.45082382 2.02918996 4.44400246 1 P 0 N
A 2.04564193 4.45082382 2.04178002 4.4566 2.02918996 4.44400325 1 P 0 N
L 2.04178002 4.4566 2.00191004 4.49646998 1 P 0 
A 2.00191004 4.49646998 1.99531693 4.50634498 2.02346004 4.51799646 1 P 0 Y
A 1.99531693 4.50634498 1.993 4.51798996 2.02346004 4.51799744 1 P 0 Y
L 1.993 4.51798996 1.993 4.52 1 P 0 
A 1.993 4.52 2.01806004 4.54506004 2.01806004 4.52 1 P 0 Y
L 2.01806004 4.54506004 2.01808996 4.54506004 1 P 0 
A 2.01808996 4.54506004 2.05213691 4.53828671 2.0180874 4.45608996 1 P 0 Y
A 2.05213691 4.53828671 2.081 4.519 2.0180873 4.45608996 1 P 0 Y
L 2.081 4.519 2.08921004 4.51078996 1 P 0 
A 2.08921004 4.51078996 2.12178996 4.51078996 2.1055 4.52708002 1 P 0 N
L 2.12178996 4.51078996 2.1265 4.5155 1 P 0 
A 2.1265 4.5155 2.13237707 4.52968652 2.11231998 4.52968494 1 P 0 N
A 2.13237707 4.52968652 2.1265 4.54386998 2.11231998 4.52968494 1 P 0 N
L 2.1265 4.54386998 2.1248 4.54558002 1 P 0 
L 2.1248 4.54558002 2.11898996 4.54966004 1 P 0 
L 2.11898996 4.54966004 2.119 4.54966004 1 P 0 
L 2.119 4.54966004 2.10601998 4.55878996 1 P 0 
L 2.10601998 4.55878996 2.09916998 4.55758002 1 P 0 
L 2.09916998 4.55758002 2.09008002 4.56398002 1 P 0 
L 2.09008002 4.56398002 2.08888996 4.57083002 1 P 0 
L 2.08888996 4.57083002 2.07388996 4.58138996 1 P 0 
L 2.07388996 4.58138996 2.0659 4.59278002 1 P 0 
L 2.0659 4.59278002 2.05846004 4.59408002 1 P 0 
L 2.05846004 4.59408002 2.05208002 4.60318996 1 P 0 
L 2.05208002 4.60318996 2.0534 4.61061004 1 P 0 
L 2.0534 4.61061004 2.04763002 4.61885 1 P 0 
L 2.04763002 4.61885 2.04491998 4.63423002 1 P 0 
L 2.04491998 4.63423002 2.04491998 4.66318996 1 P 0 
A 2.04491998 4.66318996 2.04121998 4.66688996 2.04121998 4.66318996 1 P 0 N
L 2.04121998 4.66688996 2.02853002 4.66688996 1 P 0 
P 8.4 3.31615 5 P 0 0;2=3,4=1
P 8.26208996 4.667 5 P 0 0;2=3,4=1
L 8.26208996 4.667 8.24968002 4.667 1 P 0 
A 8.24968002 4.667 8.24598002 4.6633 8.24968002 4.6633 1 P 0 N
L 8.24598002 4.6633 8.24598002 4.63133996 1 P 0 
L 8.24598002 4.63133996 8.23656998 4.57815 1 P 0 
L 8.23656998 4.57815 8.2112 4.54166004 1 P 0 
L 8.2112 4.54166004 8.2112 4.54165 1 P 0 
L 8.2112 4.54165 8.20621998 4.51348002 1 P 0 
A 8.20621998 4.51348002 8.20590295 4.49524439 8.26338002 4.50336575 1 P 0 N
A 8.20590295 4.49524439 8.21126004 4.47781004 8.26338002 4.50336526 1 P 0 N
A 8.21126004 4.47781004 8.21155 4.47731004 8.21496998 4.47962746 1 P 0 N
L 8.21155 4.47731004 8.2171 4.46938996 1 P 0 
A 8.2171 4.46938996 8.25021339 4.44726939 8.28927667 4.54158996 1 P 0 N
A 8.25021339 4.44726939 8.28926998 4.4395 8.28927726 4.54158996 1 P 0 N
L 8.28926998 4.4395 8.3005 4.4395 1 P 0 
A 8.3005 4.4395 8.33147766 4.4333439 8.30051752 4.35856998 1 P 0 Y
A 8.33147766 4.4333439 8.35773996 4.4158 8.30051772 4.35856998 1 P 0 Y
L 8.35773996 4.4158 8.35775 4.41578996 1 P 0 
A 8.35775 4.41578996 8.38458996 4.40468002 8.38457106 4.44261004 1 P 0 N
A 8.38458996 4.40468002 8.39483415 4.40632943 8.38581801 4.42968996 1 P 0 N
A 8.39483415 4.40632943 8.40353002 4.41198996 8.38581801 4.42968996 1 P 0 N
L 8.40353002 4.41198996 8.40706998 4.41553002 1 P 0 
A 8.40706998 4.41553002 8.43125344 4.42554921 8.43125492 4.39135 1 P 0 Y
A 8.43125344 4.42554921 8.45543996 4.41553002 8.43125502 4.39135 1 P 0 Y
A 8.45543996 4.41553002 8.47636004 4.38728002 8.37126998 4.33132825 1 P 0 Y
L 8.47636004 4.38728002 8.47638002 4.38725 1 P 0 
A 8.47638002 4.38725 8.47904075 4.38030906 8.4495 4.37296545 1 P 0 Y
A 8.47904075 4.38030906 8.47993996 4.37293002 8.4495 4.37296486 1 P 0 Y
L 8.47993996 4.37293002 8.47993996 4.36748996 1 P 0 
A 8.47993996 4.36748996 8.48402776 4.35626112 8.4974 4.3674877 1 P 0 N
A 8.48402776 4.35626112 8.49438002 4.35028996 8.49740276 4.36748996 1 P 0 N
L 8.49438002 4.35028996 8.55206998 4.34011998 1 P 0 
L 8.55206998 4.34011998 8.55705 4.3395 1 P 0 
A 8.55705 4.3395 8.58918287 4.32252274 8.55067156 4.28853002 1 P 0 Y
A 8.58918287 4.32252274 8.60203996 4.28853002 8.55066998 4.28852815 1 P 0 Y
L 8.60203996 4.28853002 8.60203996 4.28698996 1 P 0 
A 8.60203996 4.28698996 8.58758996 4.25208996 8.55266998 4.28698967 1 P 0 Y
L 8.58758996 4.25208996 8.58758002 4.25208002 1 P 0 
A 8.58758002 4.25208002 8.57789813 4.24498484 8.55969331 4.27998002 1 P 0 Y
A 8.57789813 4.24498484 8.56653002 4.24113002 8.559694 4.27998002 1 P 0 Y
L 8.56653002 4.24113002 8.50906998 4.23101004 1 P 0 
A 8.50906998 4.23101004 8.49361004 4.22296004 8.51412067 4.20243996 1 P 0 N
L 8.49361004 4.22296004 8.4936 4.22296004 1 P 0 
L 8.4936 4.22296004 8.4936 4.22295 1 P 0 
A 8.4936 4.22295 8.48745354 4.21373268 8.51353996 4.20299528 1 P 0 N
A 8.48745354 4.21373268 8.48533002 4.20286004 8.51353996 4.20299409 1 P 0 N
L 8.48533002 4.20286004 8.48538002 4.19381998 1 P 0 
A 8.48538002 4.19381998 8.49368346 4.17924724 8.50943996 4.19787717 1 P 0 N
A 8.49368346 4.17924724 8.50943002 4.17348002 8.50943346 4.19786998 1 P 0 N
L 8.50943002 4.17348002 8.51245 4.17346998 1 P 0 
A 8.51245 4.17346998 8.5145 4.1733 8.51250118 4.16163996 1 P 0 Y
L 8.5145 4.1733 8.5463 4.1677 1 P 0 
A 8.5463 4.1677 8.56192323 4.16240098 8.53689488 4.11428996 1 P 0 Y
A 8.56192323 4.16240098 8.57523002 4.15265 8.53689439 4.11428996 1 P 0 Y
L 8.57523002 4.15265 8.57525 4.15263002 1 P 0 
A 8.57525 4.15263002 8.57525 4.11651004 8.55718996 4.13457008 1 P 0 Y
L 8.57525 4.11651004 8.57523996 4.1165 1 P 0 
A 8.57523996 4.1165 8.55087313 4.10021801 8.52212844 4.16961004 1 P 0 Y
A 8.55087313 4.10021801 8.52213002 4.0945 8.52212835 4.16961004 1 P 0 Y
L 8.52213002 4.0945 8.49093996 4.0945 1 P 0 
A 8.49093996 4.0945 8.46353996 4.0671 8.49093996 4.0671 1 P 0 N
A 8.46353996 4.0671 8.47005315 4.04919843 8.49138996 4.06709715 1 P 0 N
A 8.47005315 4.04919843 8.48655 4.03966998 8.49139311 4.0671 1 P 0 N
L 8.48655 4.03966998 8.54356004 4.02961004 1 P 0 
A 8.54356004 4.02961004 8.61463002 3.98433002 8.52444931 3.9212 1 P 0 Y
L 8.61463002 3.98433002 8.67706998 3.89511004 1 P 0 
L 8.67706998 3.89511004 8.70798996 3.71963996 1 P 0 
L 8.70798996 3.71963996 8.68768002 3.60438996 1 P 0 
L 8.68768002 3.60438996 8.68768996 3.60438996 1 P 0 
L 8.68768996 3.60438996 8.6676 3.49043002 1 P 0 
A 8.6676 3.49043002 8.6514372 3.44280689 8.50483996 3.51911476 1 P 0 Y
A 8.6514372 3.44280689 8.6217 3.40225 8.50483996 3.51911476 1 P 0 Y
L 8.6217 3.40225 8.62168002 3.40223002 1 P 0 
A 8.62168002 3.40223002 8.60524429 3.39125384 8.5858622 3.43806998 1 P 0 Y
A 8.60524429 3.39125384 8.58586004 3.3874 8.58586142 3.43806998 1 P 0 Y
L 8.58586004 3.3874 8.44036998 3.3874 1 P 0 
A 8.44036998 3.3874 8.42875 3.37578002 8.44036998 3.37578002 1 P 0 N
L 8.42875 3.37578002 8.42875 3.35213996 1 P 0 
A 8.42875 3.35213996 8.41401004 3.3374 8.41401004 3.35213996 1 P 0 Y
L 8.41401004 3.3374 8.4037 3.3374 1 P 0 
A 8.4037 3.3374 8.4 3.3337 8.4037 3.3337 1 P 0 N
L 8.4 3.3337 8.4 3.31615 1 P 0 
P 2.11371004 5.169 5 P 0 0;2=3,4=1
P 2.39606004 3.46615 5 P 0 0;2=3,4=1
L 2.39606004 3.46615 2.39606004 3.4837 1 P 0 
A 2.39606004 3.4837 2.39976004 3.4874 2.39976004 3.4837 1 P 0 Y
L 2.39976004 3.4874 2.40346004 3.4874 1 P 0 
A 2.40346004 3.4874 2.41293996 3.49131998 2.40346122 3.50081998 1 P 0 N
L 2.41293996 3.49131998 2.41881998 3.4972 1 P 0 
A 2.41881998 3.4972 2.42325807 3.50384882 2.40435 3.51166437 1 P 0 N
A 2.42325807 3.50384882 2.42481004 3.51168996 2.40435 3.51166535 1 P 0 N
L 2.42481004 3.51168996 2.42481004 3.57808996 1 P 0 
A 2.42481004 3.57808996 2.43411998 3.5874 2.43411998 3.57809006 1 P 0 Y
L 2.43411998 3.5874 2.52118996 3.5874 1 P 0 
A 2.52118996 3.5874 2.54134272 3.5914 2.52121516 3.64003996 1 P 0 N
A 2.54134272 3.5914 2.55843002 3.60281004 2.52121654 3.64003996 1 P 0 N
L 2.55843002 3.60281004 2.5671 3.61148002 1 P 0 
A 2.5671 3.61148002 2.58442628 3.63741191 2.51058002 3.66799774 1 P 0 N
A 2.58442628 3.63741191 2.59051004 3.668 2.51058002 3.66799843 1 P 0 N
A 2.59051004 3.668 2.58637736 3.68877618 2.53621004 3.66799803 1 P 0 N
A 2.58637736 3.68877618 2.57461004 3.70638996 2.53621004 3.66799823 1 P 0 N
L 2.57461004 3.70638996 2.56731004 3.71368996 1 P 0 
A 2.56731004 3.71368996 2.56731004 3.76568996 2.59331004 3.73968996 1 P 0 Y
L 2.56731004 3.76568996 2.56731004 3.7657 1 P 0 
L 2.56731004 3.7657 2.57165 3.77005 1 P 0 
A 2.57165 3.77005 2.57746427 3.7787439 2.5527 3.78901447 1 P 0 N
A 2.57746427 3.7787439 2.57951004 3.789 2.5527 3.78901565 1 P 0 N
A 2.57951004 3.789 2.57803494 3.79639882 2.56018002 3.78899262 1 P 0 N
A 2.57803494 3.79639882 2.57383996 3.80266998 2.56018002 3.7889937 1 P 0 N
L 2.57383996 3.80266998 2.56503996 3.81148002 1 P 0 
A 2.56503996 3.81148002 2.56442037 3.81230069 2.56766004 3.81410226 1 P 0 Y
A 2.56442037 3.81230069 2.56405 3.81326004 2.56766004 3.81410256 1 P 0 Y
L 2.56405 3.81326004 2.56161004 3.82373996 1 P 0 
A 2.56161004 3.82373996 2.56151004 3.82458996 2.56523002 3.82459675 1 P 0 Y
L 2.56151004 3.82458996 2.5615 3.8292 1 P 0 
L 2.5615 3.8292 2.5615 3.86131004 1 P 0 
A 2.5615 3.86131004 2.54168563 3.91577136 2.47673996 3.86130738 1 P 0 N
A 2.54168563 3.91577136 2.49151004 3.94476998 2.47674252 3.86131004 1 P 0 N
L 2.49151004 3.94476998 2.43301998 3.95511004 1 P 0 
L 2.43301998 3.95511004 2.43295 3.95511998 1 P 0 
L 2.43295 3.95511998 2.43296004 3.95511998 1 P 0 
L 2.43296004 3.95511998 2.43238996 3.95521998 1 P 0 
L 2.43238996 3.95521998 2.42961004 3.95521998 1 P 0 
A 2.42961004 3.95521998 2.42698002 3.95631004 2.42961093 3.95893996 1 P 0 Y
L 2.42698002 3.95631004 2.4163 3.967 1 P 0 
A 2.4163 3.967 2.3787 3.967 2.3975 3.9482 1 P 0 N
A 2.3787 3.967 2.29348002 3.9317 2.29347894 4.05221998 1 P 0 Y
L 2.29348002 3.9317 2.26681998 3.9317 1 P 0 
A 2.26681998 3.9317 2.13773356 3.95737785 2.26682254 4.26901998 1 P 0 Y
A 2.13773356 3.95737785 2.0283 4.0305 2.26682254 4.26901998 1 P 0 Y
L 2.0283 4.0305 2.02828996 4.0305 1 P 0 
L 2.02828996 4.0305 2.00675 4.05203996 1 P 0 
A 2.00675 4.05203996 1.96261004 4.1601 2.11688002 4.16007057 1 P 0 Y
L 1.96261004 4.1601 1.9626 4.16008996 1 P 0 
L 1.9626 4.16008996 1.9626 4.16011004 1 P 0 
A 1.9626 4.16011004 1.93881004 4.1839 1.93881004 4.16011004 1 P 0 N
L 1.93881004 4.1839 1.93748996 4.1839 1 P 0 
A 1.93748996 4.1839 1.85726004 4.21713996 1.93750079 4.29736998 1 P 0 Y
L 1.85726004 4.21713996 1.8427 4.2317 1 P 0 
A 1.8427 4.2317 1.82997067 4.25074921 1.88421998 4.27322274 1 P 0 Y
A 1.82997067 4.25074921 1.8255 4.27321998 1.88421998 4.27322254 1 P 0 Y
L 1.8255 4.27321998 1.8255 4.29011004 1 P 0 
A 1.8255 4.29011004 1.8373 4.3186 1.86578996 4.29011132 1 P 0 Y
A 1.8373 4.3186 1.85903002 4.3276 1.85902874 4.29686998 1 P 0 Y
L 1.85903002 4.3276 1.86471004 4.3276 1 P 0 
A 1.86471004 4.3276 1.87310965 4.32927156 1.86470807 4.34955 1 P 0 N
A 1.87310965 4.32927156 1.88023002 4.33403002 1.86470797 4.34955 1 P 0 N
A 1.88023002 4.33403002 1.88023002 4.37626998 1.85911004 4.35515 1 P 0 N
L 1.88023002 4.37626998 1.8776 4.3789 1 P 0 
A 1.8776 4.3789 1.8776 4.4044 1.89035 4.39165 1 P 0 Y
L 1.8776 4.4044 1.8842 4.411 1 P 0 
A 1.8842 4.411 1.88849232 4.41742313 1.8702 4.42500138 1 P 0 N
A 1.88849232 4.41742313 1.89 4.425 1.8702 4.42500148 1 P 0 N
A 1.89 4.425 1.90183002 4.45353002 1.93031998 4.42499892 1 P 0 Y
L 1.90183002 4.45353002 1.91078996 4.46248002 1 P 0 
A 1.91078996 4.46248002 1.92284852 4.4805189 1.87151004 4.5017876 1 P 0 N
A 1.92284852 4.4805189 1.92708002 4.5018 1.87151004 4.50178819 1 P 0 N
L 1.92708002 4.5018 1.95891998 4.68213996 1 P 0 
L 1.95891998 4.68213996 2.0196 4.76866004 1 P 0 
L 2.0196 4.76866004 2.02656004 4.80823996 1 P 0 
L 2.02656004 4.80823996 2.08681998 4.89431004 1 P 0 
L 2.08681998 4.89431004 2.10268996 4.98428002 1 P 0 
L 2.10268996 4.98428002 2.08796998 5.06791998 1 P 0 
L 2.08796998 5.06791998 2.09673996 5.11765 1 P 0 
L 2.09673996 5.11765 2.09673996 5.1653 1 P 0 
A 2.09673996 5.1653 2.10043996 5.169 2.10043996 5.1653 1 P 0 Y
L 2.10043996 5.169 2.11371004 5.169 1 P 0 
P 8.4 3.36615 5 P 0 0;2=3,4=1
P 8.22208996 4.667 5 P 0 0;2=3,4=1
L 8.22208996 4.667 8.23478002 4.667 1 P 0 
A 8.23478002 4.667 8.23848002 4.6633 8.23478002 4.6633 1 P 0 Y
L 8.23848002 4.6633 8.23848002 4.632 1 P 0 
L 8.23848002 4.632 8.23473002 4.61086998 1 P 0 
L 8.23473002 4.61086998 8.22926998 4.60705 1 P 0 
L 8.22926998 4.60705 8.22733002 4.5961 1 P 0 
L 8.22733002 4.5961 8.23116004 4.59066004 1 P 0 
L 8.23116004 4.59066004 8.22946998 4.58111998 1 P 0 
L 8.22946998 4.58111998 8.22411004 4.57341004 1 P 0 
L 8.22411004 4.57341004 8.21703002 4.57215 1 P 0 
L 8.21703002 4.57215 8.21068002 4.56301004 1 P 0 
L 8.21068002 4.56301004 8.21196004 4.55591998 1 P 0 
L 8.21196004 4.55591998 8.21196004 4.5559 1 P 0 
L 8.21196004 4.5559 8.2041 4.54458996 1 P 0 
L 8.2041 4.54458996 8.19883002 4.51478996 1 P 0 
A 8.19883002 4.51478996 8.20451998 4.4745 8.26338002 4.50335925 1 P 0 N
A 8.20451998 4.4745 8.20538002 4.47303996 8.21495 4.47966053 1 P 0 N
L 8.20538002 4.47303996 8.2054 4.47301004 1 P 0 
L 8.2054 4.47301004 8.21131998 4.46455 1 P 0 
A 8.21131998 4.46455 8.24702815 4.44046535 8.28926555 4.5416 1 P 0 N
A 8.24702815 4.44046535 8.28926004 4.432 8.28926486 4.5416 1 P 0 N
L 8.28926004 4.432 8.3005 4.432 1 P 0 
A 8.3005 4.432 8.32860423 4.42641043 8.30050364 4.35856998 1 P 0 Y
A 8.32860423 4.42641043 8.35243002 4.41048996 8.30050492 4.35856998 1 P 0 Y
L 8.35243002 4.41048996 8.35243996 4.41048002 1 P 0 
A 8.35243996 4.41048002 8.36710719 4.40065935 8.38456782 4.4426 1 P 0 N
A 8.36710719 4.40065935 8.38441004 4.39716998 8.38456841 4.4426 1 P 0 N
A 8.38441004 4.39716998 8.397625 4.39935689 8.38581683 4.42968996 1 P 0 N
A 8.397625 4.39935689 8.40883996 4.40668002 8.38581654 4.42968996 1 P 0 N
L 8.40883996 4.40668002 8.41238002 4.41021998 1 P 0 
A 8.41238002 4.41021998 8.43125354 4.41803967 8.43125492 4.39135 1 P 0 Y
A 8.43125354 4.41803967 8.45013002 4.41021998 8.43125512 4.39135 1 P 0 Y
A 8.45013002 4.41021998 8.46973002 4.38375 8.37126004 4.33132825 1 P 0 Y
L 8.46973002 4.38375 8.46991004 4.38343002 1 P 0 
L 8.46991004 4.38343002 8.46991004 4.38341998 1 P 0 
A 8.46991004 4.38341998 8.47179931 4.37833071 8.4495 4.37294793 1 P 0 Y
A 8.47179931 4.37833071 8.47243996 4.37293996 8.4495 4.37294715 1 P 0 Y
L 8.47243996 4.37293996 8.47243996 4.36748996 1 P 0 
A 8.47243996 4.36748996 8.47828445 4.35143789 8.49741004 4.36749144 1 P 0 N
A 8.47828445 4.35143789 8.49308002 4.3429 8.49740856 4.36748996 1 P 0 N
L 8.49308002 4.3429 8.55095 4.3327 1 P 0 
L 8.55095 4.3327 8.55611998 4.33205 1 P 0 
A 8.55611998 4.33205 8.58356033 4.3175562 8.550681 4.28853002 1 P 0 Y
A 8.58356033 4.3175562 8.59453996 4.28853002 8.55068002 4.28852894 1 P 0 Y
L 8.59453996 4.28853002 8.59453996 4.287 1 P 0 
A 8.59453996 4.287 8.59135315 4.27098081 8.55266998 4.28700295 1 P 0 Y
A 8.59135315 4.27098081 8.58228002 4.2574 8.55266998 4.28700325 1 P 0 Y
L 8.58228002 4.2574 8.58226998 4.25738996 1 P 0 
A 8.58226998 4.25738996 8.57443287 4.25164331 8.5596874 4.27996998 1 P 0 Y
A 8.57443287 4.25164331 8.56523002 4.24851998 8.5596877 4.27996998 1 P 0 Y
L 8.56523002 4.24851998 8.50776998 4.2384 1 P 0 
A 8.50776998 4.2384 8.4883 4.22826998 8.51410935 4.20243996 1 P 0 N
L 8.4883 4.22826998 8.48828996 4.22826004 1 P 0 
A 8.48828996 4.22826004 8.4805123 4.2165876 8.51353996 4.20300778 1 P 0 N
A 8.4805123 4.2165876 8.47783002 4.20281998 8.51353996 4.20300787 1 P 0 N
L 8.47783002 4.20281998 8.47788002 4.19296004 1 P 0 
L 8.47788002 4.19296004 8.47791998 4.19293996 1 P 0 
A 8.47791998 4.19293996 8.48869065 4.17363829 8.50943996 4.19787274 1 P 0 N
A 8.48869065 4.17363829 8.50941998 4.16596998 8.5094376 4.19786998 1 P 0 N
L 8.50941998 4.16596998 8.51245 4.16596004 1 P 0 
L 8.51245 4.16596004 8.51248002 4.16596998 1 P 0 
A 8.51248002 4.16596998 8.51321998 4.16591004 8.51250167 4.16163996 1 P 0 Y
L 8.51321998 4.16591004 8.545 4.16031004 1 P 0 
A 8.545 4.16031004 8.55845797 4.15574193 8.53688346 4.11428996 1 P 0 Y
A 8.55845797 4.15574193 8.56991998 4.14733996 8.53688297 4.11428996 1 P 0 Y
L 8.56991998 4.14733996 8.56993996 4.14731998 1 P 0 
A 8.56993996 4.14731998 8.56993996 4.12181998 8.55718996 4.13456998 1 P 0 Y
L 8.56993996 4.12181998 8.56993002 4.12181004 1 P 0 
A 8.56993002 4.12181004 8.54799577 4.10714951 8.52211457 4.16961004 1 P 0 Y
A 8.54799577 4.10714951 8.52211998 4.102 8.52211526 4.16961004 1 P 0 Y
L 8.52211998 4.102 8.49093996 4.102 1 P 0 
A 8.49093996 4.102 8.45603996 4.0671 8.49093996 4.0671 1 P 0 N
A 8.45603996 4.0671 8.46430984 4.0443753 8.4914 4.06710098 1 P 0 N
A 8.46430984 4.0443753 8.48525 4.03228002 8.49139911 4.0671 1 P 0 N
L 8.48525 4.03228002 8.54226004 4.02221998 1 P 0 
A 8.54226004 4.02221998 8.60848002 3.98001998 8.52443937 3.9212 1 P 0 Y
L 8.60848002 3.98001998 8.66996998 3.89216998 1 P 0 
L 8.66996998 3.89216998 8.70036998 3.71963996 1 P 0 
L 8.70036998 3.71963996 8.66021004 3.49173002 1 P 0 
A 8.66021004 3.49173002 8.64477825 3.44627215 8.50483996 3.51912589 1 P 0 Y
A 8.64477825 3.44627215 8.61638996 3.40756004 8.50483996 3.51912648 1 P 0 Y
L 8.61638996 3.40756004 8.61636998 3.40753996 1 P 0 
A 8.61636998 3.40753996 8.60236693 3.39818533 8.58584843 3.43806998 1 P 0 Y
A 8.60236693 3.39818533 8.58585 3.3949 8.58584843 3.43806998 1 P 0 Y
L 8.58585 3.3949 8.44036998 3.3949 1 P 0 
A 8.44036998 3.3949 8.42125 3.37578002 8.44036998 3.37578002 1 P 0 N
L 8.42125 3.37578002 8.42125 3.35213996 1 P 0 
A 8.42125 3.35213996 8.41401004 3.3449 8.41401004 3.35213996 1 P 0 Y
L 8.41401004 3.3449 8.4037 3.3449 1 P 0 
A 8.4037 3.3449 8.4 3.3486 8.4037 3.3486 1 P 0 Y
L 8.4 3.3486 8.4 3.36615 1 P 0 
P 2.07371004 5.169 5 P 0 0;2=3,4=1
P 2.39606004 3.51615 5 P 0 0;2=3,4=1
L 2.39606004 3.51615 2.39606004 3.4986 1 P 0 
A 2.39606004 3.4986 2.39976004 3.4949 2.39976004 3.4986 1 P 0 N
L 2.39976004 3.4949 2.40345 3.4949 1 P 0 
A 2.40345 3.4949 2.40571191 3.49535 2.40344793 3.50081998 1 P 0 N
A 2.40571191 3.49535 2.40763002 3.49663002 2.40344774 3.50081998 1 P 0 N
L 2.40763002 3.49663002 2.41351004 3.50251004 1 P 0 
A 2.41351004 3.50251004 2.41632274 3.50671703 2.40435 3.51167795 1 P 0 N
A 2.41632274 3.50671703 2.41731004 3.51168002 2.40435 3.51167854 1 P 0 N
L 2.41731004 3.51168002 2.41731004 3.57808996 1 P 0 
A 2.41731004 3.57808996 2.43411998 3.5949 2.43411998 3.57809006 1 P 0 Y
L 2.43411998 3.5949 2.5212 3.5949 1 P 0 
A 2.5212 3.5949 2.53847461 3.59833533 2.52120207 3.64003996 1 P 0 N
A 2.53847461 3.59833533 2.55311998 3.60811998 2.52120276 3.64003996 1 P 0 N
L 2.55311998 3.60811998 2.56178996 3.61678996 1 P 0 
A 2.56178996 3.61678996 2.5774874 3.64028573 2.51056998 3.66800138 1 P 0 N
A 2.5774874 3.64028573 2.583 3.668 2.51056998 3.66800157 1 P 0 N
A 2.583 3.668 2.5693 3.70108002 2.53621004 3.66799902 1 P 0 N
L 2.5693 3.70108002 2.562 3.70838002 1 P 0 
A 2.562 3.70838002 2.562 3.771 2.59331004 3.73969006 1 P 0 Y
L 2.562 3.771 2.56633996 3.77535 1 P 0 
A 2.56633996 3.77535 2.57052726 3.7816123 2.55268996 3.78900817 1 P 0 N
A 2.57052726 3.7816123 2.572 3.789 2.55268996 3.78900876 1 P 0 N
A 2.572 3.789 2.56853996 3.79736004 2.56016998 3.7889998 1 P 0 N
L 2.56853996 3.79736004 2.56853002 3.79736004 1 P 0 
L 2.56853002 3.79736004 2.55973002 3.80616998 1 P 0 
A 2.55973002 3.80616998 2.55673996 3.81155 2.56766004 3.81409813 1 P 0 Y
L 2.55673996 3.81155 2.5543 3.82203996 1 P 0 
L 2.5543 3.82203996 2.55428996 3.82203996 1 P 0 
A 2.55428996 3.82203996 2.55401004 3.82456998 2.56523996 3.82453199 1 P 0 Y
L 2.55401004 3.82456998 2.554 3.82918996 1 P 0 
L 2.554 3.82918996 2.554 3.86131004 1 P 0 
A 2.554 3.86131004 2.4902 3.93738002 2.47675 3.86130984 1 P 0 N
L 2.4902 3.93738002 2.43171004 3.94771998 1 P 0 
L 2.43171004 3.94771998 2.42961004 3.94771998 1 P 0 
A 2.42961004 3.94771998 2.4253127 3.94857539 2.42961161 3.95895 1 P 0 Y
A 2.4253127 3.94857539 2.42166998 3.95101004 2.42961171 3.95895 1 P 0 Y
L 2.42166998 3.95101004 2.41098996 3.9617 1 P 0 
A 2.41098996 3.9617 2.39749941 3.9672812 2.39750502 3.9482 1 P 0 N
A 2.39749941 3.9672812 2.38401004 3.96168996 2.39750492 3.9482 1 P 0 N
A 2.38401004 3.96168996 2.34247815 3.9339436 2.29348839 4.05223002 1 P 0 Y
A 2.34247815 3.9339436 2.29348996 3.9242 2.29348829 4.05223002 1 P 0 Y
L 2.29348996 3.9242 2.26681004 3.9242 1 P 0 
A 2.26681004 3.9242 2.1348563 3.95044695 2.26681299 4.26903002 1 P 0 Y
A 2.1348563 3.95044695 2.02298996 4.02518996 2.26681339 4.26903002 1 P 0 Y
L 2.02298996 4.02518996 2.00246998 4.04571004 1 P 0 
L 2.00246998 4.04571004 2.00246004 4.04571004 1 P 0 
A 2.00246004 4.04571004 2.00138996 4.04678996 2.11685 4.16012756 1 P 0 Y
A 2.00138996 4.04678996 1.9551 4.1601 2.11688002 4.16008081 1 P 0 Y
L 1.9551 4.1601 1.9551 4.16011004 1 P 0 
A 1.9551 4.16011004 1.93881004 4.1764 1.93881004 4.16011004 1 P 0 N
L 1.93881004 4.1764 1.93748996 4.1764 1 P 0 
A 1.93748996 4.1764 1.89119646 4.18560748 1.9374877 4.29736998 1 P 0 Y
A 1.89119646 4.18560748 1.85195 4.21183002 1.93748711 4.29736998 1 P 0 Y
L 1.85195 4.21183002 1.83738996 4.22638996 1 P 0 
A 1.83738996 4.22638996 1.818 4.27321004 1.88421998 4.27320915 1 P 0 Y
L 1.818 4.27321004 1.818 4.2901 1 P 0 
A 1.818 4.2901 1.8216311 4.30839656 1.86578996 4.29012431 1 P 0 Y
A 1.8216311 4.30839656 1.83198996 4.32391004 1.86578996 4.29012539 1 P 0 Y
A 1.83198996 4.32391004 1.84439734 4.33219469 1.85901467 4.29686998 1 P 0 Y
A 1.84439734 4.33219469 1.85903002 4.3351 1.85901585 4.29686998 1 P 0 Y
L 1.85903002 4.3351 1.8647 4.3351 1 P 0 
A 1.8647 4.3351 1.87023228 4.33620305 1.86469498 4.34955 1 P 0 N
A 1.87023228 4.33620305 1.87491998 4.33933996 1.86469419 4.34955 1 P 0 N
A 1.87491998 4.33933996 1.87491998 4.37096004 1.85911004 4.35515 1 P 0 N
L 1.87491998 4.37096004 1.87228996 4.37358996 1 P 0 
A 1.87228996 4.37358996 1.87228996 4.40971004 1.89035 4.39165 1 P 0 Y
L 1.87228996 4.40971004 1.87888996 4.41631004 1 P 0 
A 1.87888996 4.41631004 1.88248996 4.425 1.8702 4.42500069 1 P 0 N
A 1.88248996 4.425 1.88614154 4.44331762 1.93031998 4.42498799 1 P 0 Y
A 1.88614154 4.44331762 1.89653002 4.45883996 1.93031998 4.42498819 1 P 0 Y
L 1.89653002 4.45883996 1.90548996 4.46778996 1 P 0 
A 1.90548996 4.46778996 1.91956998 4.5018 1.8715 4.5017812 1 P 0 N
L 1.91956998 4.5018 1.91956998 4.50246004 1 P 0 
L 1.91956998 4.50246004 1.95181998 4.68508002 1 P 0 
L 1.95181998 4.68508002 2.0125 4.7716 1 P 0 
L 2.0125 4.7716 2.01946004 4.81118002 1 P 0 
L 2.01946004 4.81118002 2.0251 4.81925 1 P 0 
L 2.0251 4.81925 2.0251 4.81923996 1 P 0 
L 2.0251 4.81923996 2.0298 4.82595 1 P 0 
L 2.0298 4.82595 2.02851004 4.83316998 1 P 0 
L 2.02851004 4.83316998 2.03488996 4.84226998 1 P 0 
L 2.03488996 4.84226998 2.0421 4.84351998 1 P 0 
L 2.0421 4.84351998 2.04848002 4.85263002 1 P 0 
L 2.04848002 4.85263002 2.04718996 4.85985 1 P 0 
L 2.04718996 4.85985 2.05356998 4.86895 1 P 0 
L 2.05356998 4.86895 2.06078002 4.8702 1 P 0 
L 2.06078002 4.8702 2.07971998 4.89725 1 P 0 
L 2.07971998 4.89725 2.09506998 4.98428002 1 P 0 
L 2.09506998 4.98428002 2.08035 5.06791998 1 P 0 
L 2.08035 5.06791998 2.08923996 5.11831004 1 P 0 
L 2.08923996 5.11831004 2.08923996 5.1653 1 P 0 
A 2.08923996 5.1653 2.08553996 5.169 2.08553996 5.1653 1 P 0 N
L 2.08553996 5.169 2.07371004 5.169 1 P 0 
P 1.57765 5.169 5 P 0 0;2=3,4=1
P 2.04606004 3.31615 5 P 0 0;2=3,4=1
L 1.57765 5.169 1.58948002 5.169 1 P 0 
A 1.58948002 5.169 1.59318002 5.1653 1.58948002 5.1653 1 P 0 Y
L 1.59318002 5.1653 1.59318002 5.04251004 1 P 0 
L 1.59318002 5.04251004 1.59868002 5.01131004 1 P 0 
L 1.59868002 5.01131004 1.71931004 4.83905 1 P 0 
L 1.71931004 4.83905 1.72338002 4.81598002 1 P 0 
L 1.72338002 4.81598002 1.72098002 4.80235 1 P 0 
L 1.72098002 4.80235 1.72686004 4.76878002 1 P 0 
L 1.72686004 4.76878002 1.71313002 4.69086998 1 P 0 
L 1.71313002 4.69086998 1.64391004 4.59203002 1 P 0 
L 1.64391004 4.59203002 1.57913996 4.52726004 1 P 0 
A 1.57913996 4.52726004 1.5461311 4.50722569 1.52170532 4.58468002 1 P 0 Y
A 1.5461311 4.50722569 1.5076 4.5047 1.52170571 4.58468002 1 P 0 Y
L 1.5076 4.5047 1.45961998 4.51316004 1 P 0 
A 1.45961998 4.51316004 1.41103081 4.50997776 1.44182815 4.41228002 1 P 0 N
A 1.41103081 4.50997776 1.3694 4.48471998 1.44182736 4.41228002 1 P 0 N
L 1.3694 4.48471998 1.35813996 4.47346004 1 P 0 
A 1.35813996 4.47346004 1.31686998 4.34256998 1.46323996 4.36837047 1 P 0 N
L 1.31686998 4.34256998 1.4241 3.73426998 1 P 0 
A 1.4241 3.73426998 1.46908002 3.62566004 1.69146998 3.78138032 1 P 0 N
L 1.46908002 3.62566004 1.61288002 3.42033002 1 P 0 
L 1.61288002 3.42033002 1.69436998 3.36326998 1 P 0 
L 1.69436998 3.36326998 1.93408996 3.32101004 1 P 0 
L 1.93408996 3.32101004 2.02708002 3.3374 1 P 0 
L 2.02708002 3.3374 2.04236004 3.3374 1 P 0 
A 2.04236004 3.3374 2.04606004 3.3337 2.04236004 3.3337 1 P 0 Y
L 2.04606004 3.3337 2.04606004 3.31615 1 P 0 
P 1.61765 5.169 5 P 0 0;2=3,4=1
P 2.04606004 3.36615 5 P 0 0;2=3,4=1
L 1.61765 5.169 1.60438002 5.169 1 P 0 
A 1.60438002 5.169 1.60068002 5.1653 1.60438002 5.1653 1 P 0 N
L 1.60068002 5.1653 1.60068002 5.11758996 1 P 0 
L 1.60068002 5.11758996 1.605 5.11326998 1 P 0 
L 1.605 5.11326998 1.605 5.10216998 1 P 0 
L 1.605 5.10216998 1.60068002 5.09785 1 P 0 
L 1.60068002 5.09785 1.60068002 5.08675 1 P 0 
L 1.60068002 5.08675 1.605 5.08243002 1 P 0 
L 1.605 5.08243002 1.605 5.07133002 1 P 0 
L 1.605 5.07133002 1.60068002 5.06701004 1 P 0 
L 1.60068002 5.06701004 1.60068002 5.04316998 1 P 0 
L 1.60068002 5.04316998 1.60578002 5.01425 1 P 0 
L 1.60578002 5.01425 1.72641004 4.84198996 1 P 0 
L 1.72641004 4.84198996 1.731 4.81598002 1 P 0 
L 1.731 4.81598002 1.7286 4.80235 1 P 0 
L 1.7286 4.80235 1.73448002 4.76878002 1 P 0 
L 1.73448002 4.76878002 1.72023002 4.68793002 1 P 0 
L 1.72023002 4.68793002 1.64968002 4.58718996 1 P 0 
L 1.64968002 4.58718996 1.58445 4.52195 1 P 0 
A 1.58445 4.52195 1.54838976 4.50006713 1.52171289 4.58468002 1 P 0 Y
A 1.54838976 4.50006713 1.5063 4.49731004 1.52171201 4.58468002 1 P 0 Y
L 1.5063 4.49731004 1.45831998 4.50576998 1 P 0 
A 1.45831998 4.50576998 1.41329065 4.50281801 1.44183809 4.41226998 1 P 0 N
A 1.41329065 4.50281801 1.37471004 4.47941004 1.4418373 4.41226998 1 P 0 N
L 1.37471004 4.47941004 1.36345 4.46815 1 P 0 
A 1.36345 4.46815 1.32865118 4.41080384 1.46323996 4.36836398 1 P 0 N
A 1.32865118 4.41080384 1.32426004 4.34386998 1.46323996 4.36836329 1 P 0 N
L 1.32426004 4.34386998 1.43148996 3.73556998 1 P 0 
A 1.43148996 3.73556998 1.44757618 3.68037441 1.69146998 3.78139675 1 P 0 N
A 1.44757618 3.68037441 1.47523002 3.62996998 1.69146998 3.78139587 1 P 0 N
L 1.47523002 3.62996998 1.61826998 3.42571998 1 P 0 
L 1.61826998 3.42571998 1.69731004 3.37036998 1 P 0 
L 1.69731004 3.37036998 1.93408996 3.32863002 1 P 0 
L 1.93408996 3.32863002 2.02641998 3.3449 1 P 0 
L 2.02641998 3.3449 2.04236004 3.3449 1 P 0 
A 2.04236004 3.3449 2.04606004 3.3486 2.04236004 3.3486 1 P 0 N
L 2.04606004 3.3486 2.04606004 3.36615 1 P 0 
P 8.1 3.26615 5 P 0 0;2=3,4=1
P 7.58118996 4.707 5 P 0 0;2=3,4=1
L 7.58118996 4.707 7.59353996 4.707 1 P 0 
A 7.59353996 4.707 7.59743996 4.7031 7.59353996 4.7031 1 P 0 Y
L 7.59743996 4.7031 7.59743996 4.67005 1 P 0 
L 7.59743996 4.67005 7.59321998 4.64418002 1 P 0 
L 7.59321998 4.64418002 7.53686004 4.56368996 1 P 0 
A 7.53686004 4.56368996 7.52691457 4.55571033 7.51819154 4.57676998 1 P 0 Y
A 7.52691457 4.55571033 7.51423996 4.55431998 7.51819085 4.57676998 1 P 0 Y
L 7.51423996 4.55431998 7.42736004 4.5696 1 P 0 
L 7.42736004 4.5696 7.42731998 4.5696 1 P 0 
A 7.42731998 4.5696 7.3817624 4.560806 7.42732323 4.44718002 1 P 0 N
A 7.3817624 4.560806 7.34275 4.53568996 7.42732333 4.44718002 1 P 0 N
L 7.34275 4.53568996 7.34273996 4.53568002 1 P 0 
A 7.34273996 4.53568002 7.34051998 4.53348002 7.51009006 4.36458996 1 P 0 N
L 7.34051998 4.53348002 7.3405 4.53346004 1 P 0 
A 7.3405 4.53346004 7.28934951 4.45745709 7.50941004 4.3645686 1 P 0 N
A 7.28934951 4.45745709 7.27056998 4.36778996 7.50941004 4.36456841 1 P 0 N
L 7.27056998 4.36778996 7.27041998 4.35671004 1 P 0 
L 7.27041998 4.35671004 7.41288996 3.54851004 1 P 0 
L 7.41288996 3.54851004 7.57788002 3.31286004 1 P 0 
L 7.57788002 3.31286004 7.66808002 3.2497 1 P 0 
L 7.66808002 3.2497 7.9108 3.20666998 1 P 0 
A 7.9108 3.20666998 7.93466998 3.20453002 7.93461821 3.33815 1 P 0 N
L 7.93466998 3.20453002 7.93891998 3.20453002 1 P 0 
A 7.93891998 3.20453002 7.98528002 3.22373002 7.93892008 3.2701 1 P 0 N
L 7.98528002 3.22373002 7.99155 3.23 1 P 0 
L 7.99155 3.23 7.99153996 3.23 1 P 0 
A 7.99153996 3.23 7.99973927 3.23547736 8.00940669 3.21213002 1 P 0 Y
A 7.99973927 3.23547736 8.00941004 3.2374 8.00940748 3.21213002 1 P 0 Y
L 8.00941004 3.2374 8.06001998 3.2374 1 P 0 
A 8.06001998 3.2374 8.07875 3.25613002 8.06001998 3.25613002 1 P 0 N
L 8.07875 3.25613002 8.07875 3.27013996 1 P 0 
A 8.07875 3.27013996 8.0797935 3.27537421 8.09243002 3.27013386 1 P 0 Y
A 8.0797935 3.27537421 8.08276004 3.27981004 8.09243002 3.27013317 1 P 0 Y
L 8.08276004 3.27981004 8.08925 3.2863 1 P 0 
L 8.08925 3.2863 8.08925 3.28631004 1 P 0 
A 8.08925 3.28631004 8.09188002 3.2874 8.09188081 3.28368002 1 P 0 Y
L 8.09188002 3.2874 8.0963 3.2874 1 P 0 
L 8.0963 3.2874 8.09671998 3.28738002 1 P 0 
A 8.09671998 3.28738002 8.09906201 3.28616476 8.09629675 3.2837 1 P 0 Y
A 8.09906201 3.28616476 8.1 3.2837 8.0963 3.28370276 1 P 0 Y
L 8.1 3.2837 8.1 3.26615 1 P 0 
P 2.09606004 3.26615 5 P 0 0;2=3,4=1
P 1.57765 4.707 5 P 0 0;2=3,4=1
L 1.57765 4.707 1.59 4.707 1 P 0 
A 1.59 4.707 1.5939 4.7031 1.59 4.7031 1 P 0 Y
L 1.5939 4.7031 1.5939 4.67005 1 P 0 
L 1.5939 4.67005 1.58968002 4.64418002 1 P 0 
L 1.58968002 4.64418002 1.53331998 4.56368996 1 P 0 
A 1.53331998 4.56368996 1.52337451 4.55571033 1.51465148 4.57676998 1 P 0 Y
A 1.52337451 4.55571033 1.5107 4.55431998 1.51465079 4.57676998 1 P 0 Y
L 1.5107 4.55431998 1.42381998 4.5696 1 P 0 
L 1.42381998 4.5696 1.42378002 4.5696 1 P 0 
A 1.42378002 4.5696 1.37822244 4.560806 1.42378327 4.44718002 1 P 0 N
A 1.37822244 4.560806 1.33921004 4.53568996 1.42378337 4.44718002 1 P 0 N
L 1.33921004 4.53568996 1.3392 4.53568002 1 P 0 
A 1.3392 4.53568002 1.33698002 4.53348002 1.5065501 4.36458996 1 P 0 N
L 1.33698002 4.53348002 1.33696004 4.53346004 1 P 0 
A 1.33696004 4.53346004 1.28580945 4.45745709 1.50586998 4.36456841 1 P 0 N
A 1.28580945 4.45745709 1.26703002 4.36778996 1.50586998 4.3645686 1 P 0 N
L 1.26703002 4.36778996 1.26688002 4.35671004 1 P 0 
L 1.26688002 4.35671004 1.40935 3.54851004 1 P 0 
L 1.40935 3.54851004 1.57433996 3.31286004 1 P 0 
L 1.57433996 3.31286004 1.66453996 3.2497 1 P 0 
L 1.66453996 3.2497 1.90726004 3.20666998 1 P 0 
A 1.90726004 3.20666998 1.93113002 3.20453002 1.93107825 3.33815 1 P 0 N
L 1.93113002 3.20453002 1.93538002 3.20453002 1 P 0 
A 1.93538002 3.20453002 1.98173996 3.22373002 1.93538002 3.2701 1 P 0 N
L 1.98173996 3.22373002 1.98801004 3.23 1 P 0 
L 1.98801004 3.23 1.988 3.23 1 P 0 
A 1.988 3.23 1.99619921 3.23547726 2.00586663 3.21213002 1 P 0 Y
A 1.99619921 3.23547726 2.00586998 3.2374 2.00586762 3.21213002 1 P 0 Y
L 2.00586998 3.2374 2.05648002 3.2374 1 P 0 
A 2.05648002 3.2374 2.07481004 3.25573002 2.05648002 3.25573002 1 P 0 N
L 2.07481004 3.25573002 2.07481004 3.26918002 1 P 0 
A 2.07481004 3.26918002 2.0760312 3.27530108 2.09081998 3.26916831 1 P 0 Y
A 2.0760312 3.27530108 2.0795 3.28048996 2.09081998 3.2691686 1 P 0 Y
L 2.0795 3.28048996 2.08531004 3.2863 1 P 0 
L 2.08531004 3.2863 2.08531004 3.28631004 1 P 0 
A 2.08531004 3.28631004 2.08793996 3.2874 2.08794085 3.28368002 1 P 0 Y
L 2.08793996 3.2874 2.09236004 3.2874 1 P 0 
A 2.09236004 3.2874 2.09606004 3.2837 2.09236004 3.2837 1 P 0 Y
L 2.09606004 3.2837 2.09606004 3.26615 1 P 0 
P 8.1 3.31615 5 P 0 0;2=3,4=1
P 7.62118996 4.707 5 P 0 0;2=3,4=1
L 7.62118996 4.707 7.60863996 4.707 1 P 0 
A 7.60863996 4.707 7.60493996 4.7033 7.60863996 4.7033 1 P 0 N
L 7.60493996 4.7033 7.60493996 4.66943996 1 P 0 
L 7.60493996 4.66943996 7.60035 4.64126998 1 P 0 
L 7.60035 4.64126998 7.59066004 4.62743996 1 P 0 
L 7.59066004 4.62743996 7.59175 4.62141998 1 P 0 
L 7.59175 4.62141998 7.58536004 4.6123 1 P 0 
L 7.58536004 4.6123 7.57935 4.61126998 1 P 0 
L 7.57935 4.61126998 7.57296004 4.60215 1 P 0 
L 7.57296004 4.60215 7.57405 4.59613996 1 P 0 
L 7.57405 4.59613996 7.56766004 4.58701998 1 P 0 
L 7.56766004 4.58701998 7.56165 4.58598996 1 P 0 
L 7.56165 4.58598996 7.55231998 4.57266998 1 P 0 
L 7.55231998 4.57266998 7.54301004 4.55938002 1 P 0 
A 7.54301004 4.55938002 7.52978878 4.5487751 7.51819754 4.57676998 1 P 0 Y
A 7.52978878 4.5487751 7.51293996 4.54693002 7.51819764 4.57676998 1 P 0 Y
L 7.51293996 4.54693002 7.42671004 4.56208996 1 P 0 
A 7.42671004 4.56208996 7.38444252 4.55379016 7.42732549 4.44718002 1 P 0 N
A 7.38444252 4.55379016 7.3482 4.53051004 7.42732461 4.44718002 1 P 0 N
L 7.3482 4.53051004 7.34821004 4.5305 1 P 0 
A 7.34821004 4.5305 7.34793996 4.53025 7.42008632 4.45258002 1 P 0 N
L 7.34793996 4.53025 7.34793996 4.53026998 1 P 0 
L 7.34793996 4.53026998 7.34756998 4.52991004 1 P 0 
A 7.34756998 4.52991004 7.34583002 4.52818002 7.51015571 4.36465 1 P 0 N
L 7.34583002 4.52818002 7.34581004 4.52815 1 P 0 
A 7.34581004 4.52815 7.29626398 4.45453809 7.50941004 4.36455551 1 P 0 N
A 7.29626398 4.45453809 7.27806998 4.36768996 7.50941004 4.36455591 1 P 0 N
L 7.27806998 4.36768996 7.27793002 4.35731998 1 P 0 
L 7.27793002 4.35731998 7.41998996 3.55145 1 P 0 
L 7.41998996 3.55145 7.58326998 3.31825 1 P 0 
L 7.58326998 3.31825 7.67101998 3.2568 1 P 0 
L 7.67101998 3.2568 7.91211998 3.21406004 1 P 0 
L 7.91211998 3.21406004 7.91213996 3.21405 1 P 0 
A 7.91213996 3.21405 7.93466998 3.21203002 7.93462195 3.33815 1 P 0 N
L 7.93466998 3.21203002 7.93891998 3.21203002 1 P 0 
A 7.93891998 3.21203002 7.96113652 3.21645335 7.93890679 3.2701 1 P 0 N
A 7.96113652 3.21645335 7.97996998 3.22903996 7.9389065 3.2701 1 P 0 N
L 7.97996998 3.22903996 7.98623996 3.23531004 1 P 0 
L 7.98623996 3.23531004 7.98623996 3.23531998 1 P 0 
A 7.98623996 3.23531998 7.99687313 3.24241348 8.00939291 3.21213002 1 P 0 Y
A 7.99687313 3.24241348 8.00941004 3.2449 8.00939449 3.21213002 1 P 0 Y
L 8.00941004 3.2449 8.06001998 3.2449 1 P 0 
A 8.06001998 3.2449 8.07125 3.25613002 8.06001998 3.25613002 1 P 0 N
L 8.07125 3.25613002 8.07125 3.27015 1 P 0 
A 8.07125 3.27015 8.07286191 3.27825148 8.09243002 3.27014705 1 P 0 Y
A 8.07286191 3.27825148 8.07745 3.28511998 8.09243002 3.27014685 1 P 0 Y
L 8.07745 3.28511998 8.08366998 3.29133002 1 P 0 
A 8.08366998 3.29133002 8.08740374 3.29396929 8.09187717 3.28368002 1 P 0 Y
A 8.08740374 3.29396929 8.09188002 3.2949 8.09187795 3.28368002 1 P 0 Y
L 8.09188002 3.2949 8.09653996 3.2949 1 P 0 
L 8.09653996 3.2949 8.09671998 3.29491998 1 P 0 
A 8.09671998 3.29491998 8.09906201 3.29613524 8.09629675 3.2986 1 P 0 N
A 8.09906201 3.29613524 8.1 3.2986 8.0963 3.29859724 1 P 0 N
L 8.1 3.2986 8.1 3.31615 1 P 0 
P 2.09606004 3.31615 5 P 0 0;2=3,4=1
P 1.61765 4.707 5 P 0 0;2=3,4=1
L 1.61765 4.707 1.6051 4.707 1 P 0 
A 1.6051 4.707 1.6014 4.7033 1.6051 4.7033 1 P 0 N
L 1.6014 4.7033 1.6014 4.66943996 1 P 0 
L 1.6014 4.66943996 1.59681004 4.64126998 1 P 0 
L 1.59681004 4.64126998 1.58711998 4.62743996 1 P 0 
L 1.58711998 4.62743996 1.58821004 4.62141998 1 P 0 
L 1.58821004 4.62141998 1.58181998 4.6123 1 P 0 
L 1.58181998 4.6123 1.57581004 4.61126998 1 P 0 
L 1.57581004 4.61126998 1.56941998 4.60215 1 P 0 
L 1.56941998 4.60215 1.57051004 4.59613996 1 P 0 
L 1.57051004 4.59613996 1.56411998 4.58701998 1 P 0 
L 1.56411998 4.58701998 1.55811004 4.58598996 1 P 0 
L 1.55811004 4.58598996 1.54878002 4.57266998 1 P 0 
L 1.54878002 4.57266998 1.53946998 4.55938002 1 P 0 
A 1.53946998 4.55938002 1.52624882 4.5487751 1.51465738 4.57676998 1 P 0 Y
A 1.52624882 4.5487751 1.5094 4.54693002 1.51465768 4.57676998 1 P 0 Y
L 1.5094 4.54693002 1.42316998 4.56208996 1 P 0 
A 1.42316998 4.56208996 1.38090256 4.55379016 1.42378553 4.44718002 1 P 0 N
A 1.38090256 4.55379016 1.34466004 4.53051004 1.42378465 4.44718002 1 P 0 N
L 1.34466004 4.53051004 1.34466998 4.5305 1 P 0 
A 1.34466998 4.5305 1.3444 4.53025 1.41657264 4.45258002 1 P 0 N
L 1.3444 4.53025 1.3444 4.53026998 1 P 0 
L 1.3444 4.53026998 1.34403002 4.52991004 1 P 0 
A 1.34403002 4.52991004 1.34228996 4.52818002 1.5066065 4.36465 1 P 0 N
L 1.34228996 4.52818002 1.34226998 4.52815 1 P 0 
A 1.34226998 4.52815 1.29272392 4.45453809 1.50586998 4.36455551 1 P 0 N
A 1.29272392 4.45453809 1.27453002 4.36768996 1.50586998 4.3645561 1 P 0 N
L 1.27453002 4.36768996 1.27438996 4.35731998 1 P 0 
L 1.27438996 4.35731998 1.41645 3.55145 1 P 0 
L 1.41645 3.55145 1.57973002 3.31825 1 P 0 
L 1.57973002 3.31825 1.66748002 3.2568 1 P 0 
L 1.66748002 3.2568 1.90858002 3.21406004 1 P 0 
L 1.90858002 3.21406004 1.9086 3.21405 1 P 0 
A 1.9086 3.21405 1.93113002 3.21203002 1.93108199 3.33815 1 P 0 N
L 1.93113002 3.21203002 1.93538002 3.21203002 1 P 0 
A 1.93538002 3.21203002 1.95759656 3.21645335 1.93536683 3.2701 1 P 0 N
A 1.95759656 3.21645335 1.97643002 3.22903996 1.93536654 3.2701 1 P 0 N
L 1.97643002 3.22903996 1.9827 3.23531004 1 P 0 
L 1.9827 3.23531004 1.9827 3.23531998 1 P 0 
A 1.9827 3.23531998 1.99333307 3.24241348 2.00585305 3.21213002 1 P 0 Y
A 1.99333307 3.24241348 2.00586998 3.2449 2.00585443 3.21213002 1 P 0 Y
L 2.00586998 3.2449 2.05648002 3.2449 1 P 0 
A 2.05648002 3.2449 2.06731004 3.25573002 2.05648002 3.25573002 1 P 0 N
L 2.06731004 3.25573002 2.06731004 3.26918002 1 P 0 
A 2.06731004 3.26918002 2.06909961 3.27816841 2.09081998 3.26917156 1 P 0 Y
A 2.06909961 3.27816841 2.07418996 3.28578996 2.09081998 3.26917224 1 P 0 Y
L 2.07418996 3.28578996 2.07418996 3.2858 1 P 0 
L 2.07418996 3.2858 2.08 3.29161004 1 P 0 
A 2.08 3.29161004 2.08363809 3.2940435 2.08793711 3.28368002 1 P 0 Y
A 2.08363809 3.2940435 2.08793002 3.2949 2.0879377 3.28368002 1 P 0 Y
L 2.08793002 3.2949 2.09236004 3.2949 1 P 0 
A 2.09236004 3.2949 2.09606004 3.2986 2.09236004 3.2986 1 P 0 N
L 2.09606004 3.2986 2.09606004 3.31615 1 P 0 
P 0.58 5.591 6 P 0 0;2=2,4=1
P 5.67368996 2.85 6 P 0 0;2=1,4=1
P 5.855 3.07 6 P 0 0;2=1,4=1
P 5.8522 2.97 6 P 0 0;2=1,4=1
P 7.2926 5.15351004 6 P 0 0;2=1,4=1
P 7.2426 5.15351004 6 P 0 0;2=1,4=1
P 7.1926 4.95351004 6 P 0 0;2=1,4=1
P 7.42603996 5.15895 6 P 0 0;2=2,4=1
P 3.94 4.655 6 P 0 0;2=1,4=1
P 3.77 4.765 6 P 0 0;2=1,4=1
P 4.14 4.745 6 P 0 0;2=1,4=1
P 4.76 5.375 6 P 0 0;2=1,4=1
P 4.96 5.5 6 P 0 0;2=1,4=1
P 5.16 5.555 6 P 0 0;2=1,4=1
P 4.892 5.767 6 P 0 0;2=1,4=1
P 5.088 5.767 6 P 0 0;2=1,4=1
P 0.91 5.075 6 P 0 0;2=1,4=1
P 1.03 4.96 6 P 0 0;2=1,4=1
P 1.03 5.155 6 P 0 0;2=1,4=1
P 1.38906004 5.15351004 6 P 0 0;2=2,4=1
P 1.23906004 5.15351004 6 P 0 0;2=1,4=1
P 1.28906004 5.15351004 6 P 0 0;2=1,4=1
P 1.18906004 4.95351004 6 P 0 0;2=1,4=1
P 0.83 5.355 6 P 0 0;2=1,4=1
P 0.9 5.355 6 P 0 0;2=1,4=1
P 0.755 5.355 6 P 0 0;2=1,4=1
P 0.73 5.205 6 P 0 0;2=1,4=1
P 0.81016004 5.17 6 P 0 0;2=1,4=1
P 1.094 5.356 6 P 0 0;2=2,4=1
P 1.044 5.448 6 P 0 0;2=1,4=1
P 1.4 5.46 6 P 0 0;2=1,4=1
P 1.32 5.46 6 P 0 0;2=1,4=1
P 1.43798996 5.46016004 6 P 0 0;2=1,4=1
P 1.35925 5.46016004 6 P 0 0;2=1,4=1
P 0.89 5.885 6 P 0 0;2=1,4=1
P 0.81 5.885 6 P 0 0;2=1,4=1
P 0.73 5.885 6 P 0 0;2=1,4=1
P 0.97 5.885 6 P 0 0;2=1,4=1
P 1.04 5.885 6 P 0 0;2=1,4=1
P 1.12 5.885 6 P 0 0;2=1,4=1
S P 0
OB 5.6675 2.8375 I
OS 5.66 2.845
OS 5.66 3.59
OS 5.25 4
OS 5.25 5.2
OS 5.22 5.23
OS 4.29 5.23
OS 4.215 5.155
OS 4.215 4.68
OS 4.205 4.67
OS 4.15 4.67
OS 4.13 4.69
OS 4.13 4.875
OS 4.085 4.92
OS 3.98 4.92
OS 3.97 4.91
OS 3.97 4.89903996063
OC 3.97 4.88093996063 3.985 4.88998996063 N
OS 3.97 4.65
OS 3.945 4.625
OS 3.74 4.625
OS 3.68 4.685
OS 3.68 5.16
OS 3.55 5.29
OS 3.477130019685 5.29
OC 3.473934055118 5.291597047244 3.477131791339 5.294 Y
OC 3.47328996063 5.29511003937 3.477130019685 5.293998523622 Y
OC 3.439630019685 5.29511003937 3.45646003937 5.3 N
OC 3.438985925197 5.291597047244 3.43578996063 5.293998523622 Y
OC 3.43578996063 5.29 3.435788188976 5.294 Y
OS 2.084069980315 5.29
OS 2.08388996063 5.29178996063
OC 2.049030019685 5.29178996063 2.06646003937 5.29 N
OS 2.04885 5.29
OS 2.019069980315 5.29
OS 2.01888996063 5.29178996063
OC 1.984030019685 5.29178996063 2.00146003937 5.29 N
OS 1.98385 5.29
OS 1.543 5.29
OS 1.307980019685 5.054980019685
OC 1.30216003937 5.05515 1.305149901575 5.0578 Y
OC 1.277419980315 5.03041003937 1.28906003937 5.04351003937 N
OC 1.27758996063 5.02458996063 1.274769980315 5.02742007874 Y
OS 1.168 4.915
OS 0.59 4.915
OS 0.57 4.935
OS 0.57 5.89
OS 0.6 5.92
OS 6.68 5.92
OS 7.045 5.555
OS 7.365 5.555
OS 7.44 5.48
OS 7.44 5.104
OS 7.281 4.945
OS 7.05 4.945
OS 6.85 5.145
OS 6.145 5.145
OS 6.01 5.01
OS 5.655 5.01
OS 5.515 4.87
OS 5.515 4.4
OS 5.985 3.93
OS 5.985 2.945
OS 5.945 2.905
OS 5.84 2.905
OS 5.7725 2.8375
OS 5.6675 2.8375
OE
OB 0.80808996063 5.620080019685 H
OC 0.80808996063 5.620080019685 0.7687 5.620080019685 N
OE
OB 1.51675 5.620080019685 H
OC 1.51675 5.620080019685 1.47736003937 5.620080019685 N
OE
OB 6.00395 5.4441 H
OC 6.00395 5.4441 5.78346003937 5.4441 N
OE
OB 0.747519980315 4.96 H
OC 0.747519980315 4.96 0.73 4.96 N
OE
OB 0.717519980315 5.267 H
OC 0.717519980315 5.267 0.7 5.267 N
OE
OB 0.747519980315 5.175 H
OC 0.747519980315 5.175 0.73 5.175 N
OE
OB 0.722519980315 5.355 H
OC 0.722519980315 5.355 0.705 5.355 N
OE
OB 0.86705 5.17 H
OC 0.86705 5.17 0.849530019685 5.17 N
OE
OB 0.82558996063 5.46193996063 H
OC 0.82558996063 5.46193996063 0.808069980315 5.46193996063 N
OE
OB 0.74685 5.463 H
OC 0.74685 5.463 0.729330019685 5.463 N
OE
OB 0.827519980315 5.78 H
OC 0.827519980315 5.78 0.81 5.78 N
OE
OB 0.747519980315 5.78 H
OC 0.747519980315 5.78 0.73 5.78 N
OE
OB 0.904330019685 5.78181003937 H
OC 0.904330019685 5.78181003937 0.88681003937 5.78181003937 N
OE
OB 1.074519980315 5.027 H
OC 1.074519980315 5.027 1.057 5.027 N
OE
OB 1.047519980315 5.065 H
OC 1.047519980315 5.065 1.03 5.065 N
OE
OB 0.972519980315 5.325 H
OC 0.972519980315 5.325 0.955 5.325 N
OE
OB 1.14055 5.46016003937 H
OC 1.14055 5.46016003937 1.123030019685 5.46016003937 N
OE
OB 0.977030019685 5.4595 H
OC 0.977030019685 5.4595 0.95951003937 5.4595 N
OE
OB 1.139519980315 5.417 H
OC 1.139519980315 5.417 1.122 5.417 N
OE
OB 1.177519980315 5.85 H
OC 1.177519980315 5.85 1.16 5.85 N
OE
OB 0.983069980315 5.78055 H
OC 0.983069980315 5.78055 0.96555 5.78055 N
OE
OB 1.097519980315 5.85 H
OC 1.097519980315 5.85 1.08 5.85 N
OE
OB 1.256580019685 5.04351003937 H
OC 1.256580019685 5.04351003937 1.23906003937 5.04351003937 N
OE
OB 1.206580019685 5.15351003937 H
OC 1.206580019685 5.15351003937 1.18906003937 5.15351003937 N
OE
OB 1.356580019685 5.15351003937 H
OC 1.356580019685 5.15351003937 1.33906003937 5.15351003937 N
OE
OB 1.206580019685 5.04351003937 H
OC 1.206580019685 5.04351003937 1.18906003937 5.04351003937 N
OE
OB 1.377519980315 5.355 H
OC 1.377519980315 5.355 1.36 5.355 N
OE
OB 1.327519980315 5.355 H
OC 1.327519980315 5.355 1.31 5.355 N
OE
OB 1.298030019685 5.46016003937 H
OC 1.298030019685 5.46016003937 1.28051003937 5.46016003937 N
OE
OB 1.21928996063 5.46016003937 H
OC 1.21928996063 5.46016003937 1.201769980315 5.46016003937 N
OE
OB 1.422519980315 5.885 H
OC 1.422519980315 5.885 1.405 5.885 N
OE
OB 1.372519980315 5.885 H
OC 1.372519980315 5.885 1.355 5.885 N
OE
OB 1.322519980315 5.885 H
OC 1.322519980315 5.885 1.305 5.885 N
OE
OB 1.21928996063 5.78 H
OC 1.21928996063 5.78 1.201769980315 5.78 N
OE
OB 1.298030019685 5.78 H
OC 1.298030019685 5.78 1.28051003937 5.78 N
OE
OB 1.352519980315 5.78 H
OC 1.352519980315 5.78 1.335 5.78 N
OE
OB 1.396769980315 5.78 H
OC 1.396769980315 5.78 1.37925 5.78 N
OE
OB 1.477519980315 5.355 H
OC 1.477519980315 5.355 1.46 5.355 N
OE
OB 1.427519980315 5.355 H
OC 1.427519980315 5.355 1.41 5.355 N
OE
OB 1.53425 5.46016003937 H
OC 1.53425 5.46016003937 1.516730019685 5.46016003937 N
OE
OB 1.472519980315 5.885 H
OC 1.472519980315 5.885 1.455 5.885 N
OE
OB 1.53425 5.78 H
OC 1.53425 5.78 1.516730019685 5.78 N
OE
OB 2.160980019685 5.377 H
OC 2.160980019685 5.377 2.14346003937 5.377 N
OE
OB 1.940980019685 5.377 H
OC 1.940980019685 5.377 1.92346003937 5.377 N
OE
OB 3.08543996063 5.332 H
OC 3.08543996063 5.332 3.067919980315 5.332 N
OE
OB 3.277519980315 5.332 H
OC 3.277519980315 5.332 3.26 5.332 N
OE
OB 3.427519980315 5.332 H
OC 3.427519980315 5.332 3.41 5.332 N
OE
OB 3.857419980315 4.765 H
OC 3.857419980315 4.765 3.8399 4.765 N
OE
OB 3.907419980315 4.765 H
OC 3.907419980315 4.765 3.8899 4.765 N
OE
OB 3.787519980315 4.86 H
OC 3.787519980315 4.86 3.77 4.86 N
OE
OB 3.907519980315 4.655 H
OC 3.907519980315 4.655 3.89 4.655 N
OE
OB 3.750519980315 5.075 H
OC 3.750519980315 5.075 3.733 5.075 N
OE
OB 3.887519980315 5.125 H
OC 3.887519980315 5.125 3.87 5.125 N
OE
OB 3.792519980315 5.295 H
OC 3.792519980315 5.295 3.775 5.295 N
OE
OB 3.927419980315 5.395 H
OC 3.927419980315 5.395 3.9099 5.395 N
OE
OB 3.832519980315 5.815 H
OC 3.832519980315 5.815 3.815 5.815 N
OE
OB 3.699219980315 5.74 H
OC 3.699219980315 5.74 3.6817 5.74 N
OE
OB 3.957519980315 4.765 H
OC 3.957519980315 4.765 3.94 4.765 N
OE
OB 4.122519980315 4.985 H
OC 4.122519980315 4.985 4.105 4.985 N
OE
OB 4.017519980315 5.29 H
OC 4.017519980315 5.29 4 5.29 N
OE
OB 3.977419980315 5.395 H
OC 3.977419980315 5.395 3.9599 5.395 N
OE
OB 4.077419980315 5.395 H
OC 4.077419980315 5.395 4.0599 5.395 N
OE
OB 3.927519980315 5.51 H
OC 3.927519980315 5.51 3.91 5.51 N
OE
OB 4.877519980315 5.375 H
OC 4.877519980315 5.375 4.86 5.375 N
OE
OB 4.827519980315 5.375 H
OC 4.827519980315 5.375 4.81 5.375 N
OE
OB 4.717519980315 5.54928996063 H
OC 4.717519980315 5.54928996063 4.7 5.54928996063 N
OE
OB 4.977519980315 5.375 H
OC 4.977519980315 5.375 4.96 5.375 N
OE
OB 4.927519980315 5.375 H
OC 4.927519980315 5.375 4.91 5.375 N
OE
OB 5.061930019685 5.605 H
OC 5.061930019685 5.605 5.04441003937 5.605 N
OE
OB 5.142519980315 5.4 H
OC 5.142519980315 5.4 5.125 5.4 N
OE
OB 5.047519980315 5.4 H
OC 5.047519980315 5.4 5.03 5.4 N
OE
OB 4.937519980315 5.7 H
OC 4.937519980315 5.7 4.92 5.7 N
OE
OB 5.177519980315 5.645 H
OC 5.177519980315 5.645 5.16 5.645 N
OE
OB 5.77531003937 3.02558996063 H
OC 5.77531003937 3.02558996063 5.75778996063 3.02558996063 N
OE
OB 5.936719980315 2.943 H
OC 5.936719980315 2.943 5.9192 2.943 N
OE
OB 7.260119980315 5.04351003937 H
OC 7.260119980315 5.04351003937 7.2426 5.04351003937 N
OE
OB 7.360119980315 5.15351003937 H
OC 7.360119980315 5.15351003937 7.3426 5.15351003937 N
OE
OB 7.310119980315 5.04351003937 H
OC 7.310119980315 5.04351003937 7.2926 5.04351003937 N
OE
OB 7.210119980315 5.04351003937 H
OC 7.210119980315 5.04351003937 7.1926 5.04351003937 N
OE
OB 7.210119980315 5.15351003937 H
OC 7.210119980315 5.15351003937 7.1926 5.15351003937 N
OE
OB 1.43546003937 5.771769980315 H
OC 1.438992322835 5.773893700787 1.438994980315 5.76988996063 Y
OC 1.442530019685 5.771769980315 1.43899507874 5.76988996063 Y
OC 1.442530019685 5.788230019685 1.45798996063 5.78 N
OC 1.438992322835 5.786106299213 1.43899507874 5.79011003937 Y
OC 1.43546003937 5.788230019685 1.438994980315 5.79011003937 Y
OC 1.43546003937 5.771769980315 1.42 5.78 N
OE
SE
P 8.15 3.31615 5 P 0 0;2=3,4=1
P 7.65205 4.78291998 5 P 0 0;2=3,4=1
L 7.65205 4.78291998 7.66453996 4.78291998 1 P 0 
A 7.66453996 4.78291998 7.66843996 4.77901998 7.66453996 4.77901998 1 P 0 Y
L 7.66843996 4.77901998 7.66843996 4.73366998 1 P 0 
L 7.66843996 4.73366998 7.66076004 4.69011998 1 P 0 
L 7.66076004 4.69011998 7.65421004 4.65293002 1 P 0 
L 7.65421004 4.65293002 7.61083002 4.59098996 1 P 0 
L 7.61083002 4.59098996 7.61081998 4.59098996 1 P 0 
L 7.61081998 4.59098996 7.56048002 4.54063996 1 P 0 
A 7.56048002 4.54063996 7.51696998 4.52691998 7.52555049 4.57556004 1 P 0 Y
L 7.51696998 4.52691998 7.44745 4.53918002 1 P 0 
A 7.44745 4.53918002 7.4029751 4.53626772 7.43116378 4.44683996 1 P 0 N
A 7.4029751 4.53626772 7.36486998 4.51315 7.43116427 4.44683996 1 P 0 N
L 7.36486998 4.51315 7.3534 4.50168002 1 P 0 
A 7.3534 4.50168002 7.29326004 4.35648996 7.49861004 4.3564813 1 P 0 N
L 7.29326004 4.35648996 7.29326004 4.35581004 1 P 0 
L 7.29326004 4.35581004 7.43321998 3.56206004 1 P 0 
L 7.43321998 3.56206004 7.59578002 3.32988002 1 P 0 
L 7.59578002 3.32988002 7.67393002 3.27516998 1 P 0 
L 7.67393002 3.27516998 7.87576998 3.23958002 1 P 0 
L 7.87576998 3.23958002 7.93906004 3.25071998 1 P 0 
A 7.93906004 3.25071998 7.95278898 3.25537096 7.9308374 3.29758002 1 P 0 N
A 7.95278898 3.25537096 7.96448002 3.26393996 7.9308375 3.29758002 1 P 0 N
L 7.96448002 3.26393996 7.97453996 3.274 1 P 0 
A 7.97453996 3.274 8.00688996 3.2874 8.00689026 3.24165 1 P 0 Y
L 8.00688996 3.2874 8.05455 3.2874 1 P 0 
A 8.05455 3.2874 8.06214724 3.28891083 8.05454537 3.30728002 1 P 0 N
A 8.06214724 3.28891083 8.06858996 3.29321004 8.05454528 3.30728002 1 P 0 N
L 8.06858996 3.29321004 8.07246004 3.29706998 1 P 0 
A 8.07246004 3.29706998 8.07711811 3.30404892 8.05725 3.31226585 1 P 0 N
A 8.07711811 3.30404892 8.07875 3.31228002 8.05725 3.31226526 1 P 0 N
L 8.07875 3.31228002 8.07875 3.33338996 1 P 0 
A 8.07875 3.33338996 8.08276004 3.3374 8.08276004 3.33338996 1 P 0 Y
L 8.08276004 3.3374 8.14653996 3.3374 1 P 0 
L 8.14653996 3.3374 8.14671998 3.33738002 1 P 0 
A 8.14671998 3.33738002 8.14906201 3.33616476 8.14629675 3.3337 1 P 0 Y
A 8.14906201 3.33616476 8.15 3.3337 8.1463 3.33370276 1 P 0 Y
L 8.15 3.3337 8.15 3.31615 1 P 0 
P 2.19606004 3.26615 5 P 0 0;2=3,4=1
P 1.6485 5.0535 5 P 0 0;2=3,4=1
L 1.6485 5.0535 1.659 5.0535 1 P 0 
A 1.659 5.0535 1.66403002 5.04846998 1.659 5.04846998 1 P 0 Y
L 1.66403002 5.04846998 1.66403002 5.02541998 1 P 0 
L 1.66403002 5.02541998 1.7301 4.93108002 1 P 0 
L 1.7301 4.93108002 1.74838996 4.82736998 1 P 0 
L 1.74838996 4.82736998 1.74376998 4.80111004 1 P 0 
L 1.74376998 4.80111004 1.74981998 4.76666998 1 P 0 
L 1.74981998 4.76666998 1.73516998 4.68361004 1 P 0 
L 1.73516998 4.68361004 1.64641004 4.55686004 1 P 0 
L 1.64641004 4.55686004 1.6464 4.55686004 1 P 0 
L 1.6464 4.55686004 1.5875 4.49796004 1 P 0 
A 1.5875 4.49796004 1.55663789 4.47922205 1.53377648 4.55166004 1 P 0 Y
A 1.55663789 4.47922205 1.52061004 4.47685 1.53377657 4.55166004 1 P 0 Y
L 1.52061004 4.47685 1.44516998 4.49013002 1 P 0 
L 1.44516998 4.49013002 1.4445 4.49013002 1 P 0 
A 1.4445 4.49013002 1.41680266 4.48462549 1.44448701 4.41776004 1 P 0 N
A 1.41680266 4.48462549 1.39331998 4.46893996 1.44448622 4.41776004 1 P 0 N
L 1.39331998 4.46893996 1.38693002 4.46255 1 P 0 
A 1.38693002 4.46255 1.34333002 4.35728996 1.49218996 4.35729016 1 P 0 N
A 1.34333002 4.35728996 1.34796998 4.30416004 1.6498 4.35728711 1 P 0 N
L 1.34796998 4.30416004 1.44903996 3.731 1 P 0 
A 1.44903996 3.731 1.48498002 3.64421998 1.66273002 3.76866772 1 P 0 N
L 1.48498002 3.64421998 1.62943996 3.4379 1 P 0 
L 1.62943996 3.4379 1.70141004 3.38751004 1 P 0 
L 1.70141004 3.38751004 1.92583002 3.34795 1 P 0 
L 1.92583002 3.34795 2.00358996 3.36166004 1 P 0 
A 2.00358996 3.36166004 2.02011004 3.37026004 1.99821083 3.39216004 1 P 0 N
L 2.02011004 3.37026004 2.0346 3.38475 1 P 0 
A 2.0346 3.38475 2.041 3.3874 2.04099862 3.37835 1 P 0 Y
L 2.041 3.3874 2.15991004 3.3874 1 P 0 
A 2.15991004 3.3874 2.16731004 3.38 2.15991004 3.38 1 P 0 Y
L 2.16731004 3.38 2.16731004 3.30206998 1 P 0 
A 2.16731004 3.30206998 2.18198002 3.2874 2.18198002 3.30206998 1 P 0 N
L 2.18198002 3.2874 2.19236004 3.2874 1 P 0 
A 2.19236004 3.2874 2.19606004 3.2837 2.19236004 3.2837 1 P 0 Y
L 2.19606004 3.2837 2.19606004 3.26615 1 P 0 
P 8.15 3.36615 5 P 0 0;2=3,4=1
P 7.69205 4.78291998 5 P 0 0;2=3,4=1
L 7.69205 4.78291998 7.67963996 4.78291998 1 P 0 
A 7.67963996 4.78291998 7.67593996 4.77921998 7.67963996 4.77921998 1 P 0 N
L 7.67593996 4.77921998 7.67593996 4.73301004 1 P 0 
L 7.67593996 4.73301004 7.67333002 4.71818002 1 P 0 
L 7.67333002 4.71818002 7.67728996 4.71258002 1 P 0 
L 7.67728996 4.71258002 7.67536004 4.70163002 1 P 0 
L 7.67536004 4.70163002 7.66975 4.69771998 1 P 0 
L 7.66975 4.69771998 7.66781004 4.68676004 1 P 0 
L 7.66781004 4.68676004 7.67176998 4.68116004 1 P 0 
L 7.67176998 4.68116004 7.66983996 4.67021004 1 P 0 
L 7.66983996 4.67021004 7.66421998 4.66628996 1 P 0 
L 7.66421998 4.66628996 7.66131004 4.64998996 1 P 0 
L 7.66131004 4.64998996 7.6166 4.58615 1 P 0 
L 7.6166 4.58615 7.56578996 4.53533002 1 P 0 
A 7.56578996 4.53533002 7.54266368 4.52129685 7.52555728 4.57556004 1 P 0 Y
A 7.54266368 4.52129685 7.51566998 4.51953002 7.52555728 4.57556004 1 P 0 Y
L 7.51566998 4.51953002 7.44615 4.53178996 1 P 0 
A 7.44615 4.53178996 7.37018002 4.50783996 7.43117087 4.44683996 1 P 0 N
L 7.37018002 4.50783996 7.35871004 4.49636998 1 P 0 
A 7.35871004 4.49636998 7.31582234 4.43218819 7.4986 4.35647224 1 P 0 N
A 7.31582234 4.43218819 7.30076004 4.35648002 7.4986 4.35647175 1 P 0 N
L 7.30076004 4.35648002 7.30076004 4.35646998 1 P 0 
L 7.30076004 4.35646998 7.44031998 3.565 1 P 0 
L 7.44031998 3.565 7.60116998 3.33526998 1 P 0 
L 7.60116998 3.33526998 7.67686998 3.28226998 1 P 0 
L 7.67686998 3.28226998 7.87576998 3.2472 1 P 0 
L 7.87576998 3.2472 7.93776004 3.25811004 1 P 0 
A 7.93776004 3.25811004 7.94932372 3.26203002 7.93082638 3.29758002 1 P 0 N
A 7.94932372 3.26203002 7.95916998 3.26925 7.93082608 3.29758002 1 P 0 N
L 7.95916998 3.26925 7.96923002 3.27931004 1 P 0 
A 7.96923002 3.27931004 7.98650502 3.29084892 8.00687628 3.24165 1 P 0 Y
A 7.98650502 3.29084892 8.00688002 3.2949 8.00687726 3.24165 1 P 0 Y
L 8.00688002 3.2949 8.05453996 3.2949 1 P 0 
A 8.05453996 3.2949 8.05927569 3.29584508 8.0545315 3.30728002 1 P 0 N
A 8.05927569 3.29584508 8.06328996 3.29853002 8.05453248 3.30728002 1 P 0 N
L 8.06328996 3.29853002 8.06715 3.30238002 1 P 0 
A 8.06715 3.30238002 8.07125 3.31228002 8.05725 3.31227904 1 P 0 N
L 8.07125 3.31228002 8.07125 3.33338996 1 P 0 
A 8.07125 3.33338996 8.08276004 3.3449 8.08276004 3.33338996 1 P 0 Y
L 8.08276004 3.3449 8.1463 3.3449 1 P 0 
L 8.1463 3.3449 8.14671998 3.34491998 1 P 0 
A 8.14671998 3.34491998 8.14906201 3.34613524 8.14629675 3.3486 1 P 0 N
A 8.14906201 3.34613524 8.15 3.3486 8.1463 3.34859724 1 P 0 N
L 8.15 3.3486 8.15 3.36615 1 P 0 
P 2.19606004 3.31615 5 P 0 0;2=3,4=1
P 1.6885 5.0535 5 P 0 0;2=3,4=1
L 1.6885 5.0535 1.67523002 5.0535 1 P 0 
A 1.67523002 5.0535 1.67153002 5.0498 1.67523002 5.0498 1 P 0 N
L 1.67153002 5.0498 1.67153002 5.02778996 1 P 0 
L 1.67153002 5.02778996 1.6993 4.98815 1 P 0 
L 1.6993 4.98815 1.70508996 4.98713002 1 P 0 
L 1.70508996 4.98713002 1.71146998 4.97803002 1 P 0 
L 1.71146998 4.97803002 1.71043996 4.97225 1 P 0 
L 1.71043996 4.97225 1.71681998 4.96315 1 P 0 
L 1.71681998 4.96315 1.72261004 4.96213002 1 P 0 
L 1.72261004 4.96213002 1.72898996 4.95303002 1 P 0 
L 1.72898996 4.95303002 1.72796004 4.94725 1 P 0 
L 1.72796004 4.94725 1.7372 4.93401998 1 P 0 
L 1.7372 4.93401998 1.75601004 4.82736998 1 P 0 
L 1.75601004 4.82736998 1.75138996 4.80111004 1 P 0 
L 1.75138996 4.80111004 1.75743996 4.76666998 1 P 0 
L 1.75743996 4.76666998 1.75721004 4.76536004 1 P 0 
L 1.75721004 4.76536004 1.75721004 4.76536998 1 P 0 
L 1.75721004 4.76536998 1.74226998 4.68066998 1 P 0 
L 1.74226998 4.68066998 1.65218002 4.55201998 1 P 0 
L 1.65218002 4.55201998 1.59281004 4.49265 1 P 0 
A 1.59281004 4.49265 1.55889656 4.47206339 1.53378386 4.55166004 1 P 0 Y
A 1.55889656 4.47206339 1.51931004 4.46946004 1.53378317 4.55166004 1 P 0 Y
L 1.51931004 4.46946004 1.44451004 4.48263002 1 P 0 
L 1.44451004 4.48263002 1.4445 4.48263002 1 P 0 
A 1.4445 4.48263002 1.39863002 4.46363002 1.4445 4.41776004 1 P 0 N
L 1.39863002 4.46363002 1.39223996 4.45723996 1 P 0 
A 1.39223996 4.45723996 1.3616001 4.41138238 1.4922 4.35728652 1 P 0 N
A 1.3616001 4.41138238 1.35083996 4.35728996 1.4922 4.35728681 1 P 0 N
A 1.35083996 4.35728996 1.35536004 4.30546004 1.64981004 4.35725098 1 P 0 N
L 1.35536004 4.30546004 1.45643002 3.7323 1 P 0 
A 1.45643002 3.7323 1.46919341 3.68851506 1.66273002 3.76868406 1 P 0 N
A 1.46919341 3.68851506 1.49113002 3.64853002 1.66273002 3.76868327 1 P 0 N
L 1.49113002 3.64853002 1.63483002 3.44328996 1 P 0 
L 1.63483002 3.44328996 1.70435 3.39461004 1 P 0 
L 1.70435 3.39461004 1.92583002 3.35556998 1 P 0 
L 1.92583002 3.35556998 2.00228996 3.36905 1 P 0 
A 2.00228996 3.36905 2.00904646 3.37134734 1.99820433 3.39215 1 P 0 N
A 2.00904646 3.37134734 2.0148 3.37556998 1.99820522 3.39215 1 P 0 N
L 2.0148 3.37556998 2.02928996 3.39006004 1 P 0 
A 2.02928996 3.39006004 2.041 3.3949 2.04098927 3.37833996 1 P 0 Y
L 2.041 3.3949 2.15991004 3.3949 1 P 0 
A 2.15991004 3.3949 2.17481004 3.38 2.15991004 3.38 1 P 0 Y
L 2.17481004 3.38 2.17481004 3.30206998 1 P 0 
A 2.17481004 3.30206998 2.18198002 3.2949 2.18198002 3.30206998 1 P 0 N
L 2.18198002 3.2949 2.19236004 3.2949 1 P 0 
A 2.19236004 3.2949 2.19606004 3.2986 2.19236004 3.2986 1 P 0 N
L 2.19606004 3.2986 2.19606004 3.31615 1 P 0 
P 8.1 3.41615 5 P 0 0;2=3,4=1
P 7.79378996 4.78291998 5 P 0 0;2=3,4=1
L 7.79378996 4.78291998 7.80648002 4.78291998 1 P 0 
A 7.80648002 4.78291998 7.81018002 4.77921998 7.80648002 4.77921998 1 P 0 Y
L 7.81018002 4.77921998 7.81018002 4.74521998 1 P 0 
A 7.81018002 4.74521998 7.80994419 4.74374665 7.80523002 4.74525679 1 P 0 Y
A 7.80994419 4.74374665 7.80928002 4.74241004 7.80523002 4.74525581 1 P 0 Y
L 7.80928002 4.74241004 7.59471004 4.4359 1 P 0 
A 7.59471004 4.4359 7.5723815 4.42123976 7.54617382 4.48548996 1 P 0 Y
A 7.5723815 4.42123976 7.54616998 4.4161 7.54617313 4.48548996 1 P 0 Y
L 7.54616998 4.4161 7.54615 4.4161 1 P 0 
A 7.54615 4.4161 7.50246004 4.42793996 7.5461503 4.50263002 1 P 0 Y
L 7.50246004 4.42793996 7.49598002 4.43173002 1 P 0 
A 7.49598002 4.43173002 7.49511004 4.43241004 7.49817136 4.43543002 1 P 0 Y
L 7.49511004 4.43241004 7.49153002 4.43598002 1 P 0 
A 7.49153002 4.43598002 7.47100384 4.44969931 7.44677864 4.39123996 1 P 0 N
A 7.47100384 4.44969931 7.44678996 4.45451998 7.44677854 4.39123996 1 P 0 N
A 7.44678996 4.45451998 7.42986152 4.45114931 7.44680285 4.41026004 1 P 0 N
A 7.42986152 4.45114931 7.41551004 4.44156004 7.44680325 4.41026004 1 P 0 N
L 7.41551004 4.44156004 7.40241998 4.42846998 1 P 0 
A 7.40241998 4.42846998 7.3741 4.36015 7.47068996 4.36014114 1 P 0 N
L 7.3741 4.36015 7.3741 4.36011004 1 P 0 
A 7.3741 4.36011004 7.37618996 4.33463996 7.53038002 4.36011289 1 P 0 N
L 7.37618996 4.33463996 7.3768 4.33101004 1 P 0 
L 7.3768 4.33101004 7.3768 4.331 1 P 0 
A 7.3768 4.331 7.392 4.30155 7.43048002 4.34005827 1 P 0 N
L 7.392 4.30155 7.40353996 4.29 1 P 0 
A 7.40353996 4.29 7.43123376 4.27149675 7.46389695 4.35036004 1 P 0 N
A 7.43123376 4.27149675 7.4639 4.265 7.46389744 4.35036004 1 P 0 N
L 7.4639 4.265 7.52353996 4.265 1 P 0 
A 7.52353996 4.265 7.55326998 4.23526998 7.52353996 4.23526998 1 P 0 Y
L 7.55326998 4.23526998 7.55326998 4.23496998 1 P 0 
A 7.55326998 4.23496998 7.55158514 4.22027608 7.52025 4.2313126 1 P 0 Y
A 7.55158514 4.22027608 7.54368996 4.20776998 7.52025 4.23131289 1 P 0 Y
A 7.54368996 4.20776998 7.517925 4.19054833 7.48752707 4.26391004 1 P 0 Y
A 7.517925 4.19054833 7.48753002 4.1845 7.48752736 4.26391004 1 P 0 Y
L 7.48753002 4.1845 7.48628002 4.1845 1 P 0 
A 7.48628002 4.1845 7.43283996 4.16236998 7.48628032 4.10891004 1 P 0 N
L 7.43283996 4.16236998 7.43196004 4.16148996 1 P 0 
A 7.43196004 4.16148996 7.41880827 4.14262589 7.47833002 4.11514478 1 P 0 N
A 7.41880827 4.14262589 7.41298002 4.12038002 7.47833002 4.11514518 1 P 0 N
L 7.41298002 4.12038002 7.41276998 4.12016998 1 P 0 
L 7.41276998 4.12016998 7.41276998 4.09051998 1 P 0 
L 7.41276998 4.09051998 7.47421004 3.74218996 1 P 0 
A 7.47421004 3.74218996 7.48783937 3.69541545 7.69456004 3.78102343 1 P 0 N
A 7.48783937 3.69541545 7.51126998 3.6527 7.69456004 3.78102352 1 P 0 N
L 7.51126998 3.6527 7.65078996 3.45348002 1 P 0 
L 7.65078996 3.45348002 7.70258996 3.41721998 1 P 0 
L 7.70258996 3.41721998 7.93936998 3.37543996 1 P 0 
L 7.93936998 3.37543996 7.94066998 3.37566004 1 P 0 
L 7.94066998 3.37566004 7.94066998 3.37566998 1 P 0 
L 7.94066998 3.37566998 8.01418002 3.38865 1 P 0 
L 8.01418002 3.38865 8.02303002 3.3975 1 P 0 
A 8.02303002 3.3975 8.02875 3.41128002 8.00926998 3.41128888 1 P 0 N
L 8.02875 3.41128002 8.02875 3.41988996 1 P 0 
A 8.02875 3.41988996 8.02988386 3.42558386 8.04363002 3.41988661 1 P 0 Y
A 8.02988386 3.42558386 8.03311004 3.43041004 8.04363002 3.41988632 1 P 0 Y
L 8.03311004 3.43041004 8.03763002 3.43493002 1 P 0 
A 8.03763002 3.43493002 8.04356998 3.4374 8.04357933 3.429 1 P 0 Y
L 8.04356998 3.4374 8.0963 3.4374 1 P 0 
A 8.0963 3.4374 8.1 3.4337 8.0963 3.4337 1 P 0 Y
L 8.1 3.4337 8.1 3.41615 1 P 0 
P 2.14606004 3.31615 5 P 0 0;2=3,4=1
P 1.64851004 4.78291998 5 P 0 0;2=3,4=1
L 1.64851004 4.78291998 1.661 4.78291998 1 P 0 
A 1.661 4.78291998 1.6649 4.77901998 1.661 4.77901998 1 P 0 Y
L 1.6649 4.77901998 1.6649 4.73366998 1 P 0 
L 1.6649 4.73366998 1.65721998 4.69011998 1 P 0 
L 1.65721998 4.69011998 1.65066998 4.65293002 1 P 0 
L 1.65066998 4.65293002 1.60728996 4.59098996 1 P 0 
L 1.60728996 4.59098996 1.60728002 4.59098996 1 P 0 
L 1.60728002 4.59098996 1.55693996 4.54063996 1 P 0 
A 1.55693996 4.54063996 1.51343002 4.52691998 1.52201053 4.57556004 1 P 0 Y
L 1.51343002 4.52691998 1.44391004 4.53918002 1 P 0 
A 1.44391004 4.53918002 1.39943514 4.53626772 1.42762382 4.44683996 1 P 0 N
A 1.39943514 4.53626772 1.36133002 4.51315 1.42762431 4.44683996 1 P 0 N
L 1.36133002 4.51315 1.34986004 4.50168002 1 P 0 
A 1.34986004 4.50168002 1.28971998 4.35648996 1.49506998 4.3564812 1 P 0 N
L 1.28971998 4.35648996 1.28971998 4.35581004 1 P 0 
L 1.28971998 4.35581004 1.42968002 3.56206004 1 P 0 
L 1.42968002 3.56206004 1.59223996 3.32988002 1 P 0 
L 1.59223996 3.32988002 1.67038996 3.27516998 1 P 0 
L 1.67038996 3.27516998 1.87223002 3.23958002 1 P 0 
L 1.87223002 3.23958002 1.93551998 3.25071998 1 P 0 
A 1.93551998 3.25071998 1.94924892 3.25537096 1.92729734 3.29758002 1 P 0 N
A 1.94924892 3.25537096 1.96093996 3.26393996 1.92729744 3.29758002 1 P 0 N
L 1.96093996 3.26393996 1.971 3.274 1 P 0 
A 1.971 3.274 2.00335 3.2874 2.0033503 3.24165 1 P 0 Y
L 2.00335 3.2874 2.05101004 3.2874 1 P 0 
A 2.05101004 3.2874 2.05860728 3.28891083 2.05100541 3.30728002 1 P 0 N
A 2.05860728 3.28891083 2.06505 3.29321004 2.05100532 3.30728002 1 P 0 N
L 2.06505 3.29321004 2.06891998 3.29708002 1 P 0 
A 2.06891998 3.29708002 2.07327776 3.30360502 2.05468002 3.31130797 1 P 0 N
A 2.07327776 3.30360502 2.07481004 3.3113 2.05468002 3.31130837 1 P 0 N
L 2.07481004 3.3113 2.07481004 3.33298996 1 P 0 
A 2.07481004 3.33298996 2.07921998 3.3374 2.07921998 3.33299006 1 P 0 Y
L 2.07921998 3.3374 2.14236004 3.3374 1 P 0 
A 2.14236004 3.3374 2.14606004 3.3337 2.14236004 3.3337 1 P 0 Y
L 2.14606004 3.3337 2.14606004 3.31615 1 P 0 
P 8.1 3.46615 5 P 0 0;2=3,4=1
P 7.83378996 4.78291998 5 P 0 0;2=3,4=1
L 7.83378996 4.78291998 7.82138002 4.78291998 1 P 0 
A 7.82138002 4.78291998 7.81768002 4.77921998 7.82138002 4.77921998 1 P 0 N
L 7.81768002 4.77921998 7.81768002 4.74523996 1 P 0 
L 7.81768002 4.74523996 7.81768002 4.7452 1 P 0 
A 7.81768002 4.7452 7.8170935 4.74147687 7.80523002 4.74525354 1 P 0 Y
A 7.8170935 4.74147687 7.81541998 4.7381 7.80523002 4.74525305 1 P 0 Y
L 7.81541998 4.7381 7.60046998 4.43103996 1 P 0 
A 7.60046998 4.43103996 7.54616998 4.4086 7.5461813 4.48548996 1 P 0 Y
L 7.54616998 4.4086 7.54613996 4.4086 1 P 0 
A 7.54613996 4.4086 7.52154951 4.41187156 7.54613701 4.50263002 1 P 0 Y
A 7.52154951 4.41187156 7.49866998 4.42146004 7.54613612 4.50263002 1 P 0 Y
L 7.49866998 4.42146004 7.4922 4.42525 1 P 0 
L 7.4922 4.42525 7.49218002 4.42526004 1 P 0 
A 7.49218002 4.42526004 7.48978996 4.42711998 7.49816772 4.43541998 1 P 0 Y
L 7.48978996 4.42711998 7.48623002 4.43066998 1 P 0 
A 7.48623002 4.43066998 7.44678996 4.44701004 7.44678927 4.39123996 1 P 0 N
A 7.44678996 4.44701004 7.43273533 4.44421122 7.44680236 4.41026004 1 P 0 N
A 7.43273533 4.44421122 7.42081998 4.43625 7.44680246 4.41026004 1 P 0 N
L 7.42081998 4.43625 7.40771998 4.42316004 1 P 0 
A 7.40771998 4.42316004 7.38838839 4.39424921 7.47068002 4.36014242 1 P 0 N
A 7.38838839 4.39424921 7.3816 4.36013996 7.47068002 4.36014144 1 P 0 N
L 7.3816 4.36013996 7.3816 4.36011998 1 P 0 
A 7.3816 4.36011998 7.38358996 4.33586998 7.53038002 4.36012224 1 P 0 N
L 7.38358996 4.33586998 7.3842 4.33225 1 P 0 
A 7.3842 4.33225 7.38877589 4.31853327 7.43048002 4.34006732 1 P 0 N
A 7.38877589 4.31853327 7.39731004 4.30686004 7.43048002 4.34006644 1 P 0 N
L 7.39731004 4.30686004 7.40885 4.29531004 1 P 0 
A 7.40885 4.29531004 7.4639 4.2725 7.46391073 4.35036004 1 P 0 N
L 7.4639 4.2725 7.52353996 4.2725 1 P 0 
A 7.52353996 4.2725 7.56078002 4.23536998 7.52354016 4.23526004 1 P 0 Y
A 7.56078002 4.23536998 7.55859508 4.21758563 7.52025 4.23132303 1 P 0 Y
A 7.55859508 4.21758563 7.54898996 4.20246004 7.52025 4.23132313 1 P 0 Y
A 7.54898996 4.20246004 7.48753996 4.177 7.48753061 4.26391004 1 P 0 Y
L 7.48753996 4.177 7.48628996 4.177 1 P 0 
A 7.48628996 4.177 7.43815 4.15706004 7.48628967 4.10891998 1 P 0 N
L 7.43815 4.15706004 7.43726998 4.15618002 1 P 0 
A 7.43726998 4.15618002 7.42562776 4.13947628 7.47833002 4.11515276 1 P 0 N
A 7.42562776 4.13947628 7.42046998 4.11978002 7.47833002 4.11515187 1 P 0 N
A 7.42046998 4.11978002 7.42028002 4.11513002 7.47833002 4.1150875 1 P 0 N
L 7.42028002 4.11513002 7.42026998 4.11513996 1 P 0 
L 7.42026998 4.11513996 7.42026998 4.09118002 1 P 0 
L 7.42026998 4.09118002 7.4816 3.74348996 1 P 0 
A 7.4816 3.74348996 7.51741998 3.65701004 7.69456004 3.78103976 1 P 0 N
L 7.51741998 3.65701004 7.65618002 3.45886998 1 P 0 
L 7.65618002 3.45886998 7.70553002 3.42431998 1 P 0 
L 7.70553002 3.42431998 7.85738996 3.39753002 1 P 0 
L 7.85738996 3.39753002 7.86271004 3.40126004 1 P 0 
L 7.86271004 3.40126004 7.87366004 3.39931998 1 P 0 
L 7.87366004 3.39931998 7.87738002 3.39401004 1 P 0 
L 7.87738002 3.39401004 7.88833002 3.39206998 1 P 0 
L 7.88833002 3.39206998 7.89365 3.3958 1 P 0 
L 7.89365 3.3958 7.9046 3.39386004 1 P 0 
L 7.9046 3.39386004 7.90831998 3.38855 1 P 0 
L 7.90831998 3.38855 7.93936004 3.38306998 1 P 0 
L 7.93936004 3.38306998 8.01053996 3.39563002 1 P 0 
L 8.01053996 3.39563002 8.01773002 3.40281004 1 P 0 
A 8.01773002 3.40281004 8.02033455 3.40669931 8.00926998 3.41129213 1 P 0 N
A 8.02033455 3.40669931 8.02125 3.41128996 8.00926998 3.41129242 1 P 0 N
L 8.02125 3.41128996 8.02125 3.4199 1 P 0 
A 8.02125 3.4199 8.0278 3.43571998 8.04363002 3.4198999 1 P 0 Y
L 8.0278 3.43571998 8.03231998 3.44023996 1 P 0 
A 8.03231998 3.44023996 8.04356998 3.4449 8.04357018 3.42898996 1 P 0 Y
L 8.04356998 3.4449 8.0963 3.4449 1 P 0 
A 8.0963 3.4449 8.1 3.4486 8.0963 3.4486 1 P 0 N
L 8.1 3.4486 8.1 3.46615 1 P 0 
P 2.14606004 3.36615 5 P 0 0;2=3,4=1
P 1.68851004 4.78291998 5 P 0 0;2=3,4=1
L 1.68851004 4.78291998 1.6761 4.78291998 1 P 0 
A 1.6761 4.78291998 1.6724 4.77921998 1.6761 4.77921998 1 P 0 N
L 1.6724 4.77921998 1.6724 4.73301004 1 P 0 
L 1.6724 4.73301004 1.66978996 4.71818002 1 P 0 
L 1.66978996 4.71818002 1.67375 4.71258002 1 P 0 
L 1.67375 4.71258002 1.67181998 4.70163002 1 P 0 
L 1.67181998 4.70163002 1.66621004 4.69771998 1 P 0 
L 1.66621004 4.69771998 1.66426998 4.68676004 1 P 0 
L 1.66426998 4.68676004 1.66823002 4.68116004 1 P 0 
L 1.66823002 4.68116004 1.6663 4.67021004 1 P 0 
L 1.6663 4.67021004 1.66068002 4.66628996 1 P 0 
L 1.66068002 4.66628996 1.65776998 4.64998996 1 P 0 
L 1.65776998 4.64998996 1.61306004 4.58615 1 P 0 
L 1.61306004 4.58615 1.56225 4.53533002 1 P 0 
A 1.56225 4.53533002 1.53912372 4.52129685 1.52201732 4.57556004 1 P 0 Y
A 1.53912372 4.52129685 1.51213002 4.51953002 1.52201732 4.57556004 1 P 0 Y
L 1.51213002 4.51953002 1.44261004 4.53178996 1 P 0 
A 1.44261004 4.53178996 1.36663996 4.50783996 1.42763081 4.44683996 1 P 0 N
L 1.36663996 4.50783996 1.35516998 4.49636998 1 P 0 
A 1.35516998 4.49636998 1.31228228 4.43218819 1.49506004 4.35647215 1 P 0 N
A 1.31228228 4.43218819 1.29721998 4.35648002 1.49506004 4.35647175 1 P 0 N
L 1.29721998 4.35648002 1.29721998 4.35646998 1 P 0 
L 1.29721998 4.35646998 1.43678002 3.565 1 P 0 
L 1.43678002 3.565 1.59763002 3.33526998 1 P 0 
L 1.59763002 3.33526998 1.67333002 3.28226998 1 P 0 
L 1.67333002 3.28226998 1.87223002 3.2472 1 P 0 
L 1.87223002 3.2472 1.93421998 3.25811004 1 P 0 
A 1.93421998 3.25811004 1.94578366 3.26203002 1.92728632 3.29758002 1 P 0 N
A 1.94578366 3.26203002 1.95563002 3.26925 1.92728632 3.29758002 1 P 0 N
L 1.95563002 3.26925 1.96568996 3.27931004 1 P 0 
A 1.96568996 3.27931004 1.98296496 3.29084892 2.00333622 3.24165 1 P 0 Y
A 1.98296496 3.29084892 2.00333996 3.2949 2.0033372 3.24165 1 P 0 Y
L 2.00333996 3.2949 2.051 3.2949 1 P 0 
A 2.051 3.2949 2.05573573 3.29584508 2.05099154 3.30728002 1 P 0 N
A 2.05573573 3.29584508 2.05975 3.29853002 2.05099252 3.30728002 1 P 0 N
L 2.05975 3.29853002 2.06111004 3.29988002 1 P 0 
L 2.06111004 3.29988002 2.06361004 3.30238002 1 P 0 
A 2.06361004 3.30238002 2.06634813 3.30647697 2.05468002 3.31131161 1 P 0 N
A 2.06634813 3.30647697 2.06731004 3.31131004 2.05468002 3.31131152 1 P 0 N
L 2.06731004 3.31131004 2.06731004 3.33298996 1 P 0 
A 2.06731004 3.33298996 2.07921998 3.3449 2.07921998 3.33299006 1 P 0 Y
L 2.07921998 3.3449 2.14236004 3.3449 1 P 0 
A 2.14236004 3.3449 2.14606004 3.3486 2.14236004 3.3486 1 P 0 N
L 2.14606004 3.3486 2.14606004 3.36615 1 P 0 
P 8.15 3.46615 5 P 0 0;2=3,4=1
P 7.86465 4.657 5 P 0 0;2=3,4=1
L 7.86465 4.657 7.87733996 4.657 1 P 0 
A 7.87733996 4.657 7.88103996 4.6533 7.87733996 4.6533 1 P 0 Y
L 7.88103996 4.6533 7.88103996 4.61013996 1 P 0 
A 7.88103996 4.61013996 7.87493002 4.59538996 7.86018002 4.61014035 1 P 0 Y
L 7.87493002 4.59538996 7.87001998 4.59048002 1 P 0 
A 7.87001998 4.59048002 7.8526125 4.57939173 7.83631201 4.62418996 1 P 0 Y
A 7.8526125 4.57939173 7.83215 4.5767 7.83631122 4.62418996 1 P 0 Y
L 7.83215 4.5767 7.80593002 4.57898996 1 P 0 
L 7.80593002 4.57898996 7.7896 4.5761 1 P 0 
L 7.7896 4.5761 7.7701 4.56245 1 P 0 
L 7.7701 4.56245 7.6785 4.43168002 1 P 0 
A 7.6785 4.43168002 7.662519 4.40255925 7.80345 4.34416407 1 P 0 N
A 7.662519 4.40255925 7.65321998 4.37066998 7.80345 4.34416289 1 P 0 N
L 7.65321998 4.37066998 7.62281004 4.19833002 1 P 0 
A 7.62281004 4.19833002 7.61383415 4.17190935 7.53248002 4.21428278 1 P 0 Y
A 7.61383415 4.17190935 7.59733002 4.14941004 7.53248002 4.21428297 1 P 0 Y
L 7.59733002 4.14941004 7.54933996 4.10141998 1 P 0 
A 7.54933996 4.10141998 7.5445497 4.09338524 7.56281004 4.0879439 1 P 0 N
A 7.5445497 4.09338524 7.54416004 4.08403996 7.56281004 4.08794311 1 P 0 N
L 7.54416004 4.08403996 7.54416004 4.08393002 1 P 0 
L 7.54416004 4.08393002 7.54631998 4.07583002 1 P 0 
A 7.54631998 4.07583002 7.55405 4.06246998 7.57508996 4.08355984 1 P 0 N
L 7.55405 4.06246998 7.55406004 4.06245 1 P 0 
A 7.55406004 4.06245 7.56177431 4.05730344 7.57085532 4.07926998 1 P 0 N
A 7.56177431 4.05730344 7.57086998 4.0555 7.5708564 4.07926998 1 P 0 N
L 7.57086998 4.0555 7.58806004 4.0555 1 P 0 
A 7.58806004 4.0555 7.59723002 4.05168996 7.58803937 4.04251004 1 P 0 Y
L 7.59723002 4.05168996 7.60168002 4.04723996 1 P 0 
A 7.60168002 4.04723996 7.64453002 4.02948996 7.64453967 4.09011004 1 P 0 N
L 7.64453002 4.02948996 7.64458996 4.02948996 1 P 0 
A 7.64458996 4.02948996 7.68223996 4.0451 7.6445689 4.08275 1 P 0 N
L 7.68223996 4.0451 7.68775 4.0506 1 P 0 
L 7.68775 4.0506 7.68776004 4.0506 1 P 0 
A 7.68776004 4.0506 7.70647037 4.06310079 7.7285372 4.00981998 1 P 0 Y
A 7.70647037 4.06310079 7.72853996 4.06748996 7.72853809 4.00981998 1 P 0 Y
A 7.72853996 4.06748996 7.76578996 4.05206004 7.72853927 4.01481004 1 P 0 Y
L 7.76578996 4.05206004 7.77093996 4.04691004 1 P 0 
A 7.77093996 4.04691004 7.78706998 4.00796654 7.73198996 4.00796516 1 P 0 Y
A 7.78706998 4.00796654 7.77093996 3.96901998 7.73198996 4.00796486 1 P 0 Y
L 7.77093996 3.96901998 7.7652 3.96328002 1 P 0 
A 7.7652 3.96328002 7.74886998 3.95651004 7.74886998 3.97958996 1 P 0 Y
L 7.74886998 3.95651004 7.68053996 3.95651004 1 P 0 
A 7.68053996 3.95651004 7.65483878 3.95139734 7.68054291 3.88933996 1 P 0 N
A 7.65483878 3.95139734 7.63305 3.93683996 7.68054272 3.88933996 1 P 0 N
L 7.63305 3.93683996 7.62343996 3.92723002 1 P 0 
L 7.62343996 3.92723002 7.62343996 3.92676998 1 P 0 
A 7.62343996 3.92676998 7.61976831 3.90537992 7.65403996 3.91050728 1 P 0 N
A 7.61976831 3.90537992 7.62953996 3.886 7.65403996 3.91050669 1 P 0 N
A 7.62953996 3.886 7.64726378 3.87415797 7.66816831 3.92463002 1 P 0 N
A 7.64726378 3.87415797 7.66816998 3.87 7.6681686 3.92463002 1 P 0 N
L 7.66816998 3.87 7.69933002 3.87 1 P 0 
A 7.69933002 3.87 7.73453504 3.86299282 7.69931427 3.77798002 1 P 0 Y
A 7.73453504 3.86299282 7.76438002 3.84305 7.69931388 3.77798002 1 P 0 Y
L 7.76438002 3.84305 7.7644 3.84303002 1 P 0 
A 7.7644 3.84303002 7.7800436 3.81961693 7.71335 3.79198789 1 P 0 Y
A 7.7800436 3.81961693 7.78553996 3.792 7.71335 3.79198809 1 P 0 Y
A 7.78553996 3.792 7.76618002 3.74526004 7.71943996 3.79199951 1 P 0 Y
L 7.76618002 3.74526004 7.76381998 3.7429 1 P 0 
L 7.76381998 3.7429 7.68393996 3.68696998 1 P 0 
L 7.68393996 3.68696998 7.67453996 3.67756998 1 P 0 
A 7.67453996 3.67756998 7.66240974 3.64870423 7.70381998 3.64828406 1 P 0 N
A 7.66240974 3.64870423 7.67395 3.6196 7.70381998 3.64828396 1 P 0 N
A 7.67395 3.6196 7.67453996 3.619 7.70376998 3.64833091 1 P 0 N
L 7.67453996 3.619 7.67456998 3.61898002 1 P 0 
A 7.67456998 3.61898002 7.68805039 3.6087876 7.71795502 3.66235 1 P 0 N
A 7.68805039 3.6087876 7.7038 3.60266004 7.7179562 3.66235 1 P 0 N
L 7.7038 3.60266004 7.704 3.60246004 1 P 0 
L 7.704 3.60246004 7.70463996 3.60246004 1 P 0 
A 7.70463996 3.60246004 7.70553002 3.60245 7.70565886 3.65333002 1 P 0 N
A 7.70553002 3.60245 7.72499734 3.60632805 7.70551427 3.65333002 1 P 0 N
A 7.72499734 3.60632805 7.7415 3.61736004 7.70551535 3.65333002 1 P 0 N
L 7.7415 3.61736004 7.74958996 3.62541004 1 P 0 
A 7.74958996 3.62541004 7.7555377 3.62937618 7.76255502 3.61241004 1 P 0 Y
A 7.7555377 3.62937618 7.76255 3.63076998 7.76255463 3.61241004 1 P 0 Y
A 7.76255 3.63076998 7.77384498 3.62851959 7.76253819 3.60123996 1 P 0 Y
A 7.77384498 3.62851959 7.78341998 3.62211998 7.76253829 3.60123996 1 P 0 Y
L 7.78341998 3.62211998 7.79006998 3.61548002 1 P 0 
A 7.79006998 3.61548002 7.79076004 3.61451004 7.78743996 3.61287854 1 P 0 Y
L 7.79076004 3.61451004 7.79076004 3.6145 1 P 0 
L 7.79076004 3.6145 7.79298002 3.61001998 1 P 0 
A 7.79298002 3.61001998 7.79623996 3.59928002 7.76238996 3.59487008 1 P 0 Y
A 7.79623996 3.59928002 7.79653002 3.59486998 7.7624 3.59483976 1 P 0 Y
L 7.79653002 3.59486998 7.79653996 3.59488002 1 P 0 
L 7.79653996 3.59488002 7.79653996 3.58871998 1 P 0 
A 7.79653996 3.58871998 7.80319252 3.57043888 7.82498002 3.58871841 1 P 0 N
A 7.80319252 3.57043888 7.82003996 3.56071004 7.82498199 3.58871998 1 P 0 N
L 7.82003996 3.56071004 7.95228002 3.5374 1 P 0 
L 7.95228002 3.5374 8.11496004 3.5374 1 P 0 
A 8.11496004 3.5374 8.12125 3.53111004 8.11496004 3.53111004 1 P 0 Y
L 8.12125 3.53111004 8.12125 3.5079 1 P 0 
A 8.12125 3.5079 8.1221 3.50360394 8.13246998 3.5078878 1 P 0 N
A 8.1221 3.50360394 8.12453002 3.49996004 8.13246998 3.5078872 1 P 0 N
L 8.12453002 3.49996004 8.13226004 3.49223002 1 P 0 
A 8.13226004 3.49223002 8.14393002 3.4874 8.14392874 3.50391004 1 P 0 N
L 8.14393002 3.4874 8.1463 3.4874 1 P 0 
A 8.1463 3.4874 8.15 3.4837 8.1463 3.4837 1 P 0 Y
L 8.15 3.4837 8.15 3.46615 1 P 0 
P 2.09606004 3.41615 5 P 0 0;2=3,4=1
P 1.79025 4.78291998 5 P 0 0;2=3,4=1
L 1.79025 4.78291998 1.80293996 4.78291998 1 P 0 
A 1.80293996 4.78291998 1.80663996 4.77921998 1.80293996 4.77921998 1 P 0 Y
L 1.80663996 4.77921998 1.80663996 4.74521998 1 P 0 
A 1.80663996 4.74521998 1.80640413 4.74374665 1.80168996 4.74525679 1 P 0 Y
A 1.80640413 4.74374665 1.80573996 4.74241004 1.80168996 4.74525581 1 P 0 Y
L 1.80573996 4.74241004 1.59116998 4.4359 1 P 0 
A 1.59116998 4.4359 1.56884144 4.42123986 1.54263396 4.48548996 1 P 0 Y
A 1.56884144 4.42123986 1.54263002 4.4161 1.54263278 4.48548996 1 P 0 Y
L 1.54263002 4.4161 1.54261004 4.4161 1 P 0 
A 1.54261004 4.4161 1.49891998 4.42793996 1.54261024 4.50263002 1 P 0 Y
L 1.49891998 4.42793996 1.49243996 4.43173002 1 P 0 
A 1.49243996 4.43173002 1.49156998 4.43241004 1.4946313 4.43543002 1 P 0 Y
L 1.49156998 4.43241004 1.48798996 4.43598002 1 P 0 
A 1.48798996 4.43598002 1.46746378 4.44969931 1.44323858 4.39123996 1 P 0 N
A 1.46746378 4.44969931 1.44325 4.45451998 1.44323848 4.39123996 1 P 0 N
A 1.44325 4.45451998 1.42632156 4.45114931 1.44326289 4.41026004 1 P 0 N
A 1.42632156 4.45114931 1.41196998 4.44156004 1.44326309 4.41026004 1 P 0 N
L 1.41196998 4.44156004 1.39888002 4.42846998 1 P 0 
A 1.39888002 4.42846998 1.37056004 4.36015 1.46715 4.36014114 1 P 0 N
L 1.37056004 4.36015 1.37056004 4.36011004 1 P 0 
A 1.37056004 4.36011004 1.37265 4.33463996 1.52683996 4.36011289 1 P 0 N
L 1.37265 4.33463996 1.37326004 4.33101004 1 P 0 
L 1.37326004 4.33101004 1.37326004 4.331 1 P 0 
A 1.37326004 4.331 1.37856457 4.31509035 1.42693996 4.34005856 1 P 0 N
A 1.37856457 4.31509035 1.38846004 4.30155 1.42693996 4.34005768 1 P 0 N
L 1.38846004 4.30155 1.4 4.29 1 P 0 
A 1.4 4.29 1.4276938 4.27149675 1.46035699 4.35036004 1 P 0 N
A 1.4276938 4.27149675 1.46036004 4.265 1.46035748 4.35036004 1 P 0 N
L 1.46036004 4.265 1.52 4.265 1 P 0 
A 1.52 4.265 1.54973002 4.23526998 1.52 4.23526998 1 P 0 Y
L 1.54973002 4.23526998 1.54973002 4.23496998 1 P 0 
A 1.54973002 4.23496998 1.54804518 4.22027608 1.51671004 4.2313126 1 P 0 Y
A 1.54804518 4.22027608 1.54015 4.20776998 1.51671004 4.23131289 1 P 0 Y
A 1.54015 4.20776998 1.51438494 4.19054833 1.4839872 4.26391004 1 P 0 Y
A 1.51438494 4.19054833 1.48398996 4.1845 1.4839873 4.26391004 1 P 0 Y
L 1.48398996 4.1845 1.48273996 4.1845 1 P 0 
A 1.48273996 4.1845 1.4293 4.16236998 1.48274035 4.10891004 1 P 0 N
L 1.4293 4.16236998 1.42841998 4.16148996 1 P 0 
A 1.42841998 4.16148996 1.41526821 4.14262589 1.47478996 4.11514478 1 P 0 N
A 1.41526821 4.14262589 1.40943996 4.12038002 1.47478996 4.11514518 1 P 0 N
L 1.40943996 4.12038002 1.40923002 4.12016998 1 P 0 
L 1.40923002 4.12016998 1.40923002 4.09051998 1 P 0 
L 1.40923002 4.09051998 1.47066998 3.74218996 1 P 0 
A 1.47066998 3.74218996 1.48429941 3.69541545 1.69101998 3.78102382 1 P 0 N
A 1.48429941 3.69541545 1.50773002 3.6527 1.69101998 3.78102352 1 P 0 N
L 1.50773002 3.6527 1.64725 3.45348002 1 P 0 
L 1.64725 3.45348002 1.69905 3.41721998 1 P 0 
L 1.69905 3.41721998 1.93583002 3.37543996 1 P 0 
L 1.93583002 3.37543996 2.01065 3.38865 1 P 0 
L 2.01065 3.38865 2.01915 3.39715 1 P 0 
A 2.01915 3.39715 2.02481004 3.41081998 2.00546998 3.41082096 1 P 0 N
L 2.02481004 3.41081998 2.02481004 3.41893002 1 P 0 
A 2.02481004 3.41893002 2.02956998 3.43041004 2.04106004 3.41891909 1 P 0 Y
L 2.02956998 3.43041004 2.03408996 3.43493002 1 P 0 
A 2.03408996 3.43493002 2.04003002 3.4374 2.04003927 3.429 1 P 0 Y
L 2.04003002 3.4374 2.09236004 3.4374 1 P 0 
A 2.09236004 3.4374 2.09606004 3.4337 2.09236004 3.4337 1 P 0 Y
L 2.09606004 3.4337 2.09606004 3.41615 1 P 0 
P 8.15 3.51615 5 P 0 0;2=3,4=1
P 7.90465 4.657 5 P 0 0;2=3,4=1
L 7.90465 4.657 7.89223996 4.657 1 P 0 
A 7.89223996 4.657 7.88853996 4.6533 7.89223996 4.6533 1 P 0 N
L 7.88853996 4.6533 7.88853996 4.61015 1 P 0 
A 7.88853996 4.61015 7.88023996 4.59008002 7.86016998 4.6101312 1 P 0 Y
L 7.88023996 4.59008002 7.87533002 4.58516998 1 P 0 
A 7.87533002 4.58516998 7.85518278 4.57233642 7.83631368 4.62418996 1 P 0 Y
A 7.85518278 4.57233642 7.8315 4.56921998 7.83631289 4.62418996 1 P 0 Y
L 7.8315 4.56921998 7.80626004 4.57143002 1 P 0 
L 7.80626004 4.57143002 7.79253996 4.569 1 P 0 
L 7.79253996 4.569 7.77548996 4.55706004 1 P 0 
L 7.77548996 4.55706004 7.76498996 4.54206998 1 P 0 
L 7.76498996 4.54206998 7.76616998 4.53546004 1 P 0 
L 7.76616998 4.53546004 7.75978996 4.52633996 1 P 0 
L 7.75978996 4.52633996 7.75316998 4.52518002 1 P 0 
L 7.75316998 4.52518002 7.74678996 4.51606998 1 P 0 
L 7.74678996 4.51606998 7.74796998 4.50946004 1 P 0 
L 7.74796998 4.50946004 7.74158996 4.50033996 1 P 0 
L 7.74158996 4.50033996 7.73496998 4.49918002 1 P 0 
L 7.73496998 4.49918002 7.73495 4.49918002 1 P 0 
L 7.73495 4.49918002 7.68465 4.42736998 1 P 0 
A 7.68465 4.42736998 7.66061004 4.36936998 7.80343996 4.34415157 1 P 0 N
L 7.66061004 4.36936998 7.6302 4.19703002 1 P 0 
A 7.6302 4.19703002 7.60263996 4.1441 7.53248002 4.21427156 1 P 0 Y
L 7.60263996 4.1441 7.55465 4.09611004 1 P 0 
A 7.55465 4.09611004 7.55151004 4.08558002 7.56281998 4.08794065 1 P 0 N
A 7.55151004 4.08558002 7.55166004 4.08493002 7.56341004 4.08798386 1 P 0 N
L 7.55166004 4.08493002 7.55166004 4.08491998 1 P 0 
L 7.55166004 4.08491998 7.55356998 4.07776998 1 P 0 
A 7.55356998 4.07776998 7.55580207 4.07239419 7.57508996 4.08355404 1 P 0 N
A 7.55580207 4.07239419 7.55935 4.06778002 7.57508996 4.08355394 1 P 0 N
L 7.55935 4.06778002 7.55936998 4.06776004 1 P 0 
A 7.55936998 4.06776004 7.57086998 4.063 7.57086929 4.07926998 1 P 0 N
L 7.57086998 4.063 7.58805 4.063 1 P 0 
A 7.58805 4.063 7.59589154 4.06144114 7.58805236 4.04251004 1 P 0 Y
A 7.59589154 4.06144114 7.60253996 4.057 7.58805315 4.04251004 1 P 0 Y
L 7.60253996 4.057 7.60698996 4.05255 1 P 0 
A 7.60698996 4.05255 7.64453996 4.03698996 7.64454892 4.0901 1 P 0 N
L 7.64453996 4.03698996 7.64456004 4.03698996 1 P 0 
A 7.64456004 4.03698996 7.66202274 4.04045217 7.64456801 4.08271998 1 P 0 N
A 7.66202274 4.04045217 7.67683996 4.05031998 7.64456811 4.08271998 1 P 0 N
L 7.67683996 4.05031998 7.68245 4.05591004 1 P 0 
A 7.68245 4.05591004 7.70359656 4.07003898 7.72853809 4.00981998 1 P 0 Y
A 7.70359656 4.07003898 7.72853996 4.075 7.72853868 4.00981998 1 P 0 Y
A 7.72853996 4.075 7.75157343 4.07041782 7.72853848 4.01481004 1 P 0 Y
A 7.75157343 4.07041782 7.7711 4.05736998 7.72853839 4.01481004 1 P 0 Y
L 7.7711 4.05736998 7.77625 4.05221998 1 P 0 
A 7.77625 4.05221998 7.79457943 4.00796654 7.73198996 4.00796516 1 P 0 Y
A 7.79457943 4.00796654 7.77625 3.96371004 7.73198996 4.00796486 1 P 0 Y
L 7.77625 3.96371004 7.77051004 3.95796998 1 P 0 
A 7.77051004 3.95796998 7.7605815 3.95133612 7.74888386 3.97958996 1 P 0 Y
A 7.7605815 3.95133612 7.74886998 3.94901004 7.74888307 3.97958996 1 P 0 Y
L 7.74886998 3.94901004 7.6851 3.94901004 1 P 0 
L 7.6851 3.94901004 7.6851 3.949 1 P 0 
L 7.6851 3.949 7.68508996 3.94898996 1 P 0 
L 7.68508996 3.94898996 7.68053996 3.949 1 P 0 
A 7.68053996 3.949 7.6577127 3.94445925 7.68054213 3.88933996 1 P 0 N
A 7.6577127 3.94445925 7.63836004 3.93153002 7.68054183 3.88933996 1 P 0 N
L 7.63836004 3.93153002 7.63008002 3.92325 1 P 0 
A 7.63008002 3.92325 7.62719951 3.90649301 7.65405 3.91050354 1 P 0 N
A 7.62719951 3.90649301 7.63485 3.89131004 7.65405 3.91050364 1 P 0 N
A 7.63485 3.89131004 7.65013652 3.88109154 7.66818189 3.92463002 1 P 0 N
A 7.65013652 3.88109154 7.66816998 3.8775 7.66818199 3.92463002 1 P 0 N
L 7.66816998 3.8775 7.69933996 3.8775 1 P 0 
A 7.69933996 3.8775 7.7374123 3.86992441 7.69932746 3.77798002 1 P 0 Y
A 7.7374123 3.86992441 7.76968996 3.84836004 7.69932746 3.77798002 1 P 0 Y
L 7.76968996 3.84836004 7.76971004 3.84833996 1 P 0 
A 7.76971004 3.84833996 7.79305 3.792 7.71336004 3.79199134 1 P 0 Y
A 7.79305 3.792 7.77148996 3.73995 7.71943996 3.7920003 1 P 0 Y
L 7.77148996 3.73995 7.76828996 3.73675 1 P 0 
L 7.76828996 3.73675 7.76811998 3.73675 1 P 0 
L 7.76811998 3.73675 7.68878002 3.6812 1 P 0 
L 7.68878002 3.6812 7.67985 3.67226004 1 P 0 
A 7.67985 3.67226004 7.67936004 3.6248 7.70383002 3.64827992 1 P 0 N
L 7.67936004 3.6248 7.67988002 3.62428996 1 P 0 
A 7.67988002 3.62428996 7.70553002 3.60996004 7.71797096 3.66235 1 P 0 N
A 7.70553002 3.60996004 7.72212884 3.61326496 7.70552126 3.65333996 1 P 0 N
A 7.72212884 3.61326496 7.7362 3.62266998 7.70552175 3.65333996 1 P 0 N
L 7.7362 3.62266998 7.74428996 3.63073002 1 P 0 
A 7.74428996 3.63073002 7.7526623 3.63630856 7.76254134 3.61241004 1 P 0 Y
A 7.7526623 3.63630856 7.76253002 3.63826998 7.76254144 3.61241004 1 P 0 Y
L 7.76253002 3.63826998 7.76253996 3.63826998 1 P 0 
A 7.76253996 3.63826998 7.77671309 3.63545502 7.76255148 3.60123996 1 P 0 Y
A 7.77671309 3.63545502 7.78873002 3.62743002 7.76255207 3.60123996 1 P 0 Y
L 7.78873002 3.62743002 7.79538002 3.62078002 1 P 0 
A 7.79538002 3.62078002 7.79748996 3.61783002 7.78743996 3.61287146 1 P 0 Y
L 7.79748996 3.61783002 7.79971004 3.61336004 1 P 0 
A 7.79971004 3.61336004 7.8037 3.60025 7.7624 3.59484282 1 P 0 Y
L 7.8037 3.60025 7.80403996 3.5999 1 P 0 
L 7.80403996 3.5999 7.80403996 3.58871998 1 P 0 
A 7.80403996 3.58871998 7.80893819 3.57526201 7.82498002 3.58872106 1 P 0 N
A 7.80893819 3.57526201 7.82133996 3.5681 7.82497904 3.58871998 1 P 0 N
L 7.82133996 3.5681 7.95293996 3.5449 1 P 0 
L 7.95293996 3.5449 8.11496004 3.5449 1 P 0 
A 8.11496004 3.5449 8.12875 3.53111004 8.11496004 3.53111004 1 P 0 Y
L 8.12875 3.53111004 8.12875 3.5079 1 P 0 
A 8.12875 3.5079 8.12983996 3.50526998 8.13246998 3.50790079 1 P 0 N
L 8.12983996 3.50526998 8.13756998 3.49753996 1 P 0 
A 8.13756998 3.49753996 8.14049232 3.49558652 8.14394213 3.50391004 1 P 0 N
A 8.14049232 3.49558652 8.14393996 3.4949 8.14394193 3.50391004 1 P 0 N
L 8.14393996 3.4949 8.1463 3.4949 1 P 0 
L 8.1463 3.4949 8.14671998 3.49491998 1 P 0 
A 8.14671998 3.49491998 8.14906201 3.49613524 8.14629675 3.4986 1 P 0 N
A 8.14906201 3.49613524 8.15 3.4986 8.1463 3.49859724 1 P 0 N
L 8.15 3.4986 8.15 3.51615 1 P 0 
P 2.09606004 3.46615 5 P 0 0;2=3,4=1
P 1.83025 4.78291998 5 P 0 0;2=3,4=1
L 1.83025 4.78291998 1.81783996 4.78291998 1 P 0 
A 1.81783996 4.78291998 1.81413996 4.77921998 1.81783996 4.77921998 1 P 0 N
L 1.81413996 4.77921998 1.81413996 4.74523996 1 P 0 
L 1.81413996 4.74523996 1.81413996 4.7452 1 P 0 
A 1.81413996 4.7452 1.81355354 4.74147687 1.80168996 4.74525325 1 P 0 Y
A 1.81355354 4.74147687 1.81188002 4.7381 1.80168996 4.74525315 1 P 0 Y
L 1.81188002 4.7381 1.59693002 4.43103996 1 P 0 
A 1.59693002 4.43103996 1.54263002 4.4086 1.54264134 4.48548996 1 P 0 Y
L 1.54263002 4.4086 1.5426 4.4086 1 P 0 
A 1.5426 4.4086 1.51800955 4.41187156 1.54259705 4.50263002 1 P 0 Y
A 1.51800955 4.41187156 1.49513002 4.42146004 1.54259616 4.50263002 1 P 0 Y
L 1.49513002 4.42146004 1.48866004 4.42525 1 P 0 
L 1.48866004 4.42525 1.48863996 4.42526004 1 P 0 
A 1.48863996 4.42526004 1.48625 4.42711998 1.49462795 4.43541998 1 P 0 Y
L 1.48625 4.42711998 1.48268996 4.43066998 1 P 0 
A 1.48268996 4.43066998 1.44325 4.44701004 1.44324921 4.39123996 1 P 0 N
A 1.44325 4.44701004 1.42919537 4.44421122 1.4432624 4.41026004 1 P 0 N
A 1.42919537 4.44421122 1.41728002 4.43625 1.4432625 4.41026004 1 P 0 N
L 1.41728002 4.43625 1.40418002 4.42316004 1 P 0 
A 1.40418002 4.42316004 1.38484843 4.39424921 1.46713996 4.36014252 1 P 0 N
A 1.38484843 4.39424921 1.37806004 4.36013996 1.46713996 4.36014154 1 P 0 N
L 1.37806004 4.36013996 1.37806004 4.36011998 1 P 0 
A 1.37806004 4.36011998 1.38005 4.33586998 1.52683996 4.36012224 1 P 0 N
L 1.38005 4.33586998 1.38066004 4.33225 1 P 0 
A 1.38066004 4.33225 1.38523593 4.31853327 1.42693996 4.34006732 1 P 0 N
A 1.38523593 4.31853327 1.39376998 4.30686004 1.42693996 4.34006604 1 P 0 N
L 1.39376998 4.30686004 1.40531004 4.29531004 1 P 0 
A 1.40531004 4.29531004 1.46036004 4.2725 1.46037077 4.35036004 1 P 0 N
L 1.46036004 4.2725 1.52 4.2725 1 P 0 
A 1.52 4.2725 1.55723996 4.23536998 1.5200001 4.23526004 1 P 0 Y
A 1.55723996 4.23536998 1.55505512 4.21758563 1.51671004 4.23132274 1 P 0 Y
A 1.55505512 4.21758563 1.54545 4.20246004 1.51671004 4.23132313 1 P 0 Y
A 1.54545 4.20246004 1.484 4.177 1.48399065 4.26391004 1 P 0 Y
L 1.484 4.177 1.48275 4.177 1 P 0 
A 1.48275 4.177 1.43461004 4.15706004 1.4827497 4.10891998 1 P 0 N
L 1.43461004 4.15706004 1.43373002 4.15618002 1 P 0 
A 1.43373002 4.15618002 1.4220878 4.13947628 1.47478996 4.11515285 1 P 0 N
A 1.4220878 4.13947628 1.41693002 4.11978002 1.47478996 4.11515197 1 P 0 N
A 1.41693002 4.11978002 1.41673996 4.11513002 1.47478996 4.11508622 1 P 0 N
L 1.41673996 4.11513002 1.41673002 4.11513996 1 P 0 
L 1.41673002 4.11513996 1.41673002 4.09118002 1 P 0 
L 1.41673002 4.09118002 1.47806004 3.74348996 1 P 0 
A 1.47806004 3.74348996 1.51388002 3.65701004 1.69101998 3.78103967 1 P 0 N
L 1.51388002 3.65701004 1.65263996 3.45886998 1 P 0 
L 1.65263996 3.45886998 1.70198996 3.42431998 1 P 0 
L 1.70198996 3.42431998 1.85385 3.39753002 1 P 0 
L 1.85385 3.39753002 1.85916998 3.40126004 1 P 0 
L 1.85916998 3.40126004 1.87011998 3.39931998 1 P 0 
L 1.87011998 3.39931998 1.87383996 3.39401004 1 P 0 
L 1.87383996 3.39401004 1.88478996 3.39206998 1 P 0 
L 1.88478996 3.39206998 1.89011004 3.3958 1 P 0 
L 1.89011004 3.3958 1.90106004 3.39386004 1 P 0 
L 1.90106004 3.39386004 1.90478002 3.38855 1 P 0 
L 1.90478002 3.38855 1.93583002 3.38306004 1 P 0 
L 1.93583002 3.38306004 2.00701004 3.39563002 1 P 0 
L 2.00701004 3.39563002 2.01383996 3.40246004 1 P 0 
A 2.01383996 3.40246004 2.01731004 3.41081998 2.00548002 3.41083032 1 P 0 N
L 2.01731004 3.41081998 2.01731004 3.41893996 1 P 0 
A 2.01731004 3.41893996 2.01911772 3.42802037 2.04106004 3.41893209 1 P 0 Y
A 2.01911772 3.42802037 2.02426004 3.43571998 2.04106004 3.41893278 1 P 0 Y
L 2.02426004 3.43571998 2.02878002 3.44023996 1 P 0 
A 2.02878002 3.44023996 2.04003002 3.4449 2.04003022 3.42898996 1 P 0 Y
L 2.04003002 3.4449 2.09236004 3.4449 1 P 0 
A 2.09236004 3.4449 2.09606004 3.4486 2.09236004 3.4486 1 P 0 N
L 2.09606004 3.4486 2.09606004 3.46615 1 P 0 
P 2.19606004 3.41615 5 P 0 0;2=3,4=1
P 1.86111004 5.169 5 P 0 0;2=3,4=1
L 1.86111004 5.169 1.87293996 5.169 1 P 0 
A 1.87293996 5.169 1.87663996 5.1653 1.87293996 5.1653 1 P 0 Y
L 1.87663996 5.1653 1.87663996 5.12566004 1 P 0 
L 1.87663996 5.12566004 1.86925 5.08375 1 P 0 
L 1.86925 5.08375 1.88613002 4.98811004 1 P 0 
L 1.88613002 4.98811004 1.87383996 4.91841998 1 P 0 
L 1.87383996 4.91841998 1.88541004 4.85283002 1 P 0 
L 1.88541004 4.85283002 1.86538996 4.7394 1 P 0 
L 1.86538996 4.7394 1.85821998 4.72913002 1 P 0 
L 1.85821998 4.72913002 1.85056004 4.72376998 1 P 0 
L 1.85056004 4.72376998 1.83703002 4.72138002 1 P 0 
L 1.83703002 4.72138002 1.80216998 4.69696998 1 P 0 
L 1.80216998 4.69696998 1.623 4.44113002 1 P 0 
A 1.623 4.44113002 1.6045 4.39646998 1.71456004 4.37704035 1 P 0 N
L 1.6045 4.39646998 1.60448996 4.39646004 1 P 0 
L 1.60448996 4.39646004 1.6045 4.39646004 1 P 0 
L 1.6045 4.39646004 1.5733 4.21951004 1 P 0 
A 1.5733 4.21951004 1.5476249 4.17505453 1.49938996 4.23255443 1 P 0 Y
A 1.5476249 4.17505453 1.49938002 4.1575 1.49938465 4.23256004 1 P 0 Y
L 1.49938002 4.1575 1.49118996 4.1575 1 P 0 
A 1.49118996 4.1575 1.4497 4.14031004 1.4912001 4.09881004 1 P 0 N
L 1.4497 4.14031004 1.44968996 4.14031004 1 P 0 
A 1.44968996 4.14031004 1.4408437 4.12786663 1.48213996 4.10787451 1 P 0 N
A 1.4408437 4.12786663 1.43656998 4.11321004 1.48213996 4.10787362 1 P 0 N
L 1.43656998 4.11321004 1.43626004 4.1129 1 P 0 
L 1.43626004 4.1129 1.43626004 4.09286998 1 P 0 
L 1.43626004 4.09286998 1.4984 3.74056004 1 P 0 
A 1.4984 3.74056004 1.55566998 3.63053002 1.70153002 3.7763687 1 P 0 N
L 1.55566998 3.63053002 1.55615 3.63006004 1 P 0 
L 1.55615 3.63006004 1.79261004 3.4645 1 P 0 
L 1.79261004 3.4645 1.94628996 3.4374 1 P 0 
L 1.94628996 3.4374 2.00075 3.4374 1 P 0 
A 2.00075 3.4374 2.00780689 3.43880305 2.00075167 3.45583996 1 P 0 N
A 2.00780689 3.43880305 2.01378996 3.4428 2.00075207 3.45583996 1 P 0 N
L 2.01378996 3.4428 2.0202 3.44921004 1 P 0 
A 2.0202 3.44921004 2.02361073 3.45431201 2.00908002 3.46033494 1 P 0 N
A 2.02361073 3.45431201 2.02481004 3.46033002 2.00908002 3.46033632 1 P 0 N
L 2.02481004 3.46033002 2.02481004 3.48005 1 P 0 
A 2.02481004 3.48005 2.03216004 3.4874 2.03216004 3.48005 1 P 0 Y
L 2.03216004 3.4874 2.10021998 3.4874 1 P 0 
A 2.10021998 3.4874 2.10554075 3.4863373 2.10020827 3.47348996 1 P 0 Y
A 2.10554075 3.4863373 2.11005 3.48331998 2.10020817 3.47348996 1 P 0 Y
L 2.11005 3.48331998 2.113 3.48036998 1 P 0 
A 2.113 3.48036998 2.11731004 3.46998996 2.10263002 3.46997923 1 P 0 Y
L 2.11731004 3.46998996 2.11731004 3.45551998 1 P 0 
A 2.11731004 3.45551998 2.13543002 3.4374 2.13543002 3.45551998 1 P 0 N
L 2.13543002 3.4374 2.19236004 3.4374 1 P 0 
A 2.19236004 3.4374 2.19606004 3.4337 2.19236004 3.4337 1 P 0 Y
L 2.19606004 3.4337 2.19606004 3.41615 1 P 0 
P 2.19606004 3.46615 5 P 0 0;2=3,4=1
P 1.90111004 5.169 5 P 0 0;2=3,4=1
L 1.90111004 5.169 1.88783996 5.169 1 P 0 
A 1.88783996 5.169 1.88413996 5.1653 1.88783996 5.1653 1 P 0 N
L 1.88413996 5.1653 1.88413996 5.125 1 P 0 
L 1.88413996 5.125 1.87686998 5.08375 1 P 0 
L 1.87686998 5.08375 1.89375 4.98811004 1 P 0 
L 1.89375 4.98811004 1.88911998 4.96185 1 P 0 
L 1.88911998 4.96185 1.89245 4.95713002 1 P 0 
L 1.89245 4.95713002 1.89051004 4.94618002 1 P 0 
L 1.89051004 4.94618002 1.88578002 4.94288996 1 P 0 
L 1.88578002 4.94288996 1.88146004 4.91841998 1 P 0 
L 1.88146004 4.91841998 1.88613002 4.89196998 1 P 0 
L 1.88613002 4.89196998 1.89203002 4.88785 1 P 0 
L 1.89203002 4.88785 1.89396998 4.8769 1 P 0 
L 1.89396998 4.8769 1.88983002 4.87098996 1 P 0 
L 1.88983002 4.87098996 1.89303002 4.85283002 1 P 0 
L 1.89303002 4.85283002 1.8725 4.73646004 1 P 0 
L 1.8725 4.73646004 1.86361998 4.72373996 1 P 0 
L 1.86361998 4.72373996 1.86251998 4.72296998 1 P 0 
L 1.86251998 4.72296998 1.86251998 4.72298002 1 P 0 
L 1.86251998 4.72298002 1.8535 4.71666998 1 P 0 
L 1.8535 4.71666998 1.83996998 4.71428002 1 P 0 
L 1.83996998 4.71428002 1.80756004 4.69158002 1 P 0 
L 1.80756004 4.69158002 1.62915 4.43681998 1 P 0 
A 1.62915 4.43681998 1.61181004 4.39471998 1.71456004 4.37702067 1 P 0 N
L 1.61181004 4.39471998 1.58068996 4.21821004 1 P 0 
A 1.58068996 4.21821004 1.55245187 4.16931211 1.49938996 4.23255738 1 P 0 Y
A 1.55245187 4.16931211 1.49938996 4.15 1.4993872 4.23256004 1 P 0 Y
L 1.49938996 4.15 1.4912 4.15 1 P 0 
A 1.4912 4.15 1.47160768 4.14610079 1.49120354 4.09881004 1 P 0 N
A 1.47160768 4.14610079 1.455 4.135 1.49120364 4.09881004 1 P 0 N
A 1.455 4.135 1.44403002 4.11233996 1.48215 4.10787096 1 P 0 N
A 1.44403002 4.11233996 1.44376998 4.10786004 1.48215 4.10787972 1 P 0 N
L 1.44376998 4.10786004 1.44376004 4.10786998 1 P 0 
L 1.44376004 4.10786998 1.44376004 4.09353002 1 P 0 
L 1.44376004 4.09353002 1.50578996 3.74186004 1 P 0 
A 1.50578996 3.74186004 1.56098002 3.63583996 1.70153002 3.77637992 1 P 0 N
L 1.56098002 3.63583996 1.56098996 3.63583002 1 P 0 
L 1.56098996 3.63583002 1.79555 3.4716 1 P 0 
L 1.79555 3.4716 1.94695 3.4449 1 P 0 
L 1.94695 3.4449 2.00076004 3.4449 1 P 0 
A 2.00076004 3.4449 2.00493888 3.4457377 2.00074232 3.45583002 1 P 0 N
A 2.00493888 3.4457377 2.00848002 3.44811004 2.00074291 3.45583002 1 P 0 N
L 2.00848002 3.44811004 2.01488996 3.45451998 1 P 0 
A 2.01488996 3.45451998 2.01731004 3.46033996 2.00908002 3.46034902 1 P 0 N
L 2.01731004 3.46033996 2.01731004 3.48005 1 P 0 
A 2.01731004 3.48005 2.03216004 3.4949 2.03216004 3.48005 1 P 0 Y
L 2.03216004 3.4949 2.10023002 3.4949 1 P 0 
A 2.10023002 3.4949 2.10841919 3.49326417 2.10021122 3.47348996 1 P 0 Y
A 2.10841919 3.49326417 2.11536004 3.48861998 2.1002122 3.47348996 1 P 0 Y
L 2.11536004 3.48861998 2.1183 3.48568002 1 P 0 
A 2.1183 3.48568002 2.12311467 3.4784873 2.10263002 3.46998307 1 P 0 Y
A 2.12311467 3.4784873 2.12481004 3.47 2.10263002 3.46998238 1 P 0 Y
L 2.12481004 3.47 2.12481004 3.45551998 1 P 0 
A 2.12481004 3.45551998 2.13543002 3.4449 2.13543002 3.45551998 1 P 0 N
L 2.13543002 3.4449 2.19236004 3.4449 1 P 0 
A 2.19236004 3.4449 2.19606004 3.4486 2.19236004 3.4486 1 P 0 N
L 2.19606004 3.4486 2.19606004 3.46615 1 P 0 
P 10.99998996 4.9531 6 P 0 0;2=1,4=1
P 11.03998996 4.9531 6 P 0 0;2=1,4=1
P 10.99998996 4.9131 6 P 0 0;2=1,4=1
P 11.03998996 4.9131 6 P 0 0;2=1,4=1
P 11.21998996 4.9531 6 P 0 0;2=1,4=1
P 11.17998996 4.9531 6 P 0 0;2=1,4=1
P 11.13498996 4.9531 6 P 0 0;2=1,4=1
P 11.08498996 4.9531 6 P 0 0;2=1,4=1
P 11.21998996 4.9131 6 P 0 0;2=1,4=1
P 11.17998996 4.9131 6 P 0 0;2=1,4=1
P 11.08498996 4.9131 6 P 0 0;2=1,4=1
P 11.13498996 4.9131 6 P 0 0;2=1,4=1
P 10.99998996 5.1631 6 P 0 0;2=1,4=1
P 11.03998996 5.1631 6 P 0 0;2=1,4=1
P 10.99998996 5.1231 6 P 0 0;2=1,4=1
P 10.99998996 5.0381 6 P 0 0;2=1,4=1
P 10.99998996 5.0831 6 P 0 0;2=1,4=1
P 10.99998996 4.9931 6 P 0 0;2=1,4=1
P 11.03998996 4.9931 6 P 0 0;2=1,4=1
P 11.03998996 5.0831 6 P 0 0;2=1,4=1
P 11.03998996 5.0381 6 P 0 0;2=1,4=1
P 11.03998996 5.1231 6 P 0 0;2=1,4=1
P 11.21998996 5.1631 6 P 0 0;2=1,4=1
P 11.17998996 5.1631 6 P 0 0;2=1,4=1
P 11.08498996 5.1631 6 P 0 0;2=1,4=1
P 11.13498996 5.1631 6 P 0 0;2=1,4=1
P 11.21998996 5.1231 6 P 0 0;2=1,4=1
P 11.21998996 5.0381 6 P 0 0;2=1,4=1
P 11.21998996 5.0831 6 P 0 0;2=1,4=1
P 11.21998996 4.9931 6 P 0 0;2=1,4=1
P 11.17998996 4.9931 6 P 0 0;2=1,4=1
P 11.17998996 5.1231 6 P 0 0;2=1,4=1
P 11.17998996 5.0831 6 P 0 0;2=1,4=1
P 11.17998996 5.0381 6 P 0 0;2=1,4=1
P 11.13498996 5.1231 6 P 0 0;2=1,4=1
P 11.08498996 5.1231 6 P 0 0;2=1,4=1
P 11.6269 4.90498996 6 P 0 0;2=1,4=1
P 11.6269 4.85498996 6 P 0 0;2=1,4=1
P 11.4269 4.80998996 6 P 0 0;2=1,4=1
P 11.4269 4.85498996 6 P 0 0;2=1,4=1
P 11.4269 4.90498996 6 P 0 0;2=1,4=1
P 11.4269 4.94998996 6 P 0 0;2=1,4=1
P 11.4769 4.94998996 6 P 0 0;2=1,4=1
P 11.4769 4.80998996 6 P 0 0;2=1,4=1
P 11.5269 4.94998996 6 P 0 0;2=1,4=1
P 11.5269 4.80998996 6 P 0 0;2=1,4=1
P 11.5769 4.94998996 6 P 0 0;2=1,4=1
P 11.6269 4.94998996 6 P 0 0;2=1,4=1
P 11.6269 4.80998996 6 P 0 0;2=1,4=1
P 11.5769 4.80998996 6 P 0 0;2=1,4=1
P 10.82676998 5.71338996 8 P 0 0;2=5,4=0
P 10.99213002 5.71338996 8 P 0 0;2=5,4=0
P 11.15748002 5.71338996 8 P 0 0;2=5,4=0
P 11.32283996 5.71338996 8 P 0 0;2=5,4=0
P 11.48818996 5.71338996 8 P 0 0;2=5,4=0
P 11.65353996 5.71338996 8 P 0 0;2=5,4=0
P 11.8189 5.71338996 8 P 0 0;2=5,4=0
P 11.98425 5.71338996 8 P 0 0;2=5,4=0
P 12.14961004 5.71338996 8 P 0 0;2=5,4=0
P 10.80498996 5.7831 6 P 0 0;2=1,4=1
P 10.84498996 5.7831 6 P 0 0;2=1,4=1
P 10.80498996 5.6431 6 P 0 0;2=1,4=1
P 10.84498996 5.6431 6 P 0 0;2=1,4=1
P 11.01035 5.6431 6 P 0 0;2=1,4=1
P 10.97035 5.6431 6 P 0 0;2=1,4=1
P 11.01035 5.7831 6 P 0 0;2=1,4=1
P 10.97035 5.7831 6 P 0 0;2=1,4=1
P 11.17571004 5.6431 6 P 0 0;2=1,4=1
P 11.13571004 5.6431 6 P 0 0;2=1,4=1
P 11.17571004 5.7831 6 P 0 0;2=1,4=1
P 11.13571004 5.7831 6 P 0 0;2=1,4=1
P 11.34106998 5.6431 6 P 0 0;2=1,4=1
P 11.30106998 5.6431 6 P 0 0;2=1,4=1
P 11.34106998 5.7831 6 P 0 0;2=1,4=1
P 11.30106998 5.7831 6 P 0 0;2=1,4=1
P 11.50643002 5.6431 6 P 0 0;2=1,4=1
P 11.46643002 5.6431 6 P 0 0;2=1,4=1
P 11.50643002 5.7831 6 P 0 0;2=1,4=1
P 11.46643002 5.7831 6 P 0 0;2=1,4=1
P 11.67178996 5.6431 6 P 0 0;2=1,4=1
P 11.63178996 5.6431 6 P 0 0;2=1,4=1
P 11.67178996 5.7831 6 P 0 0;2=1,4=1
P 11.63178996 5.7831 6 P 0 0;2=1,4=1
P 11.83715 5.6431 6 P 0 0;2=1,4=1
P 11.79715 5.6431 6 P 0 0;2=1,4=1
P 11.83715 5.7831 6 P 0 0;2=1,4=1
P 11.79715 5.7831 6 P 0 0;2=1,4=1
P 12.00251004 5.6431 6 P 0 0;2=1,4=1
P 11.96251004 5.6431 6 P 0 0;2=1,4=1
P 12.00251004 5.7831 6 P 0 0;2=1,4=1
P 11.96251004 5.7831 6 P 0 0;2=1,4=1
P 12.16786998 5.6431 6 P 0 0;2=1,4=1
P 12.12786998 5.6431 6 P 0 0;2=1,4=1
P 12.16786998 5.7831 6 P 0 0;2=1,4=1
P 12.12786998 5.7831 6 P 0 0;2=1,4=1
S P 0
OB 11.31405 4.78405 I
OS 11.195 4.9031
OS 10.99498996063 4.9031
OS 10.98998996063 4.9081
OS 10.98998996063 5.12
OS 10.95498996063 5.155
OS 10.577 5.155
OS 10.567 5.165
OS 10.567 5.836
OS 10.616 5.885
OS 12.49 5.885
OS 12.52 5.855
OS 12.52 5.285
OS 12.255 5.02
OS 11.730969980315 5.02
OS 11.7 4.989030019685
OS 11.7 4.825
OS 11.65905 4.78405
OS 11.31405 4.78405
OE
OB 10.79585 5.394980019685 H
OS 12.19415 5.394980019685
OS 12.215019980315 5.41585
OS 12.215019980315 5.57415
OS 12.19415 5.595019980315
OS 10.79585 5.595019980315
OS 10.769980019685 5.56915
OS 10.769980019685 5.42085
OS 10.79585 5.394980019685
OE
OB 12.415380019685 5.695280019685 H
OC 12.415380019685 5.695280019685 12.33465 5.695280019685 N
OE
SE
P 2.14606004 3.46615 5 P 0 0;2=3,4=1
P 1.86111004 4.657 5 P 0 0;2=3,4=1
L 1.86111004 4.657 1.8738 4.657 1 P 0 
A 1.8738 4.657 1.8775 4.6533 1.8738 4.6533 1 P 0 Y
L 1.8775 4.6533 1.8775 4.61013996 1 P 0 
A 1.8775 4.61013996 1.87138996 4.59538996 1.85663996 4.61014055 1 P 0 Y
L 1.87138996 4.59538996 1.86648002 4.59048002 1 P 0 
A 1.86648002 4.59048002 1.84907254 4.57939173 1.83277205 4.62418996 1 P 0 Y
A 1.84907254 4.57939173 1.82861004 4.5767 1.83277126 4.62418996 1 P 0 Y
L 1.82861004 4.5767 1.80238996 4.57898996 1 P 0 
L 1.80238996 4.57898996 1.78606004 4.5761 1 P 0 
L 1.78606004 4.5761 1.76656004 4.56245 1 P 0 
L 1.76656004 4.56245 1.67496004 4.43168002 1 P 0 
A 1.67496004 4.43168002 1.65897904 4.40255925 1.79991004 4.34416407 1 P 0 N
A 1.65897904 4.40255925 1.64968002 4.37066998 1.79991004 4.34416289 1 P 0 N
L 1.64968002 4.37066998 1.61926998 4.19833002 1 P 0 
A 1.61926998 4.19833002 1.61029409 4.17190935 1.52893996 4.21428278 1 P 0 Y
A 1.61029409 4.17190935 1.59378996 4.14941004 1.52893996 4.21428297 1 P 0 Y
L 1.59378996 4.14941004 1.5458 4.10141998 1 P 0 
A 1.5458 4.10141998 1.54100974 4.09338533 1.55926998 4.0879439 1 P 0 N
A 1.54100974 4.09338533 1.54061998 4.08403996 1.55926998 4.08794291 1 P 0 N
L 1.54061998 4.08403996 1.54061998 4.08393002 1 P 0 
L 1.54061998 4.08393002 1.54278002 4.07583002 1 P 0 
A 1.54278002 4.07583002 1.55051004 4.06246998 1.57155 4.08355984 1 P 0 N
L 1.55051004 4.06246998 1.55051998 4.06245 1 P 0 
A 1.55051998 4.06245 1.55823425 4.05730344 1.56731526 4.07926998 1 P 0 N
A 1.55823425 4.05730344 1.56733002 4.0555 1.56731634 4.07926998 1 P 0 N
L 1.56733002 4.0555 1.58451998 4.0555 1 P 0 
A 1.58451998 4.0555 1.59368996 4.05168996 1.58449931 4.04251004 1 P 0 Y
L 1.59368996 4.05168996 1.59813996 4.04723996 1 P 0 
A 1.59813996 4.04723996 1.64098996 4.02948996 1.64099961 4.09011004 1 P 0 N
L 1.64098996 4.02948996 1.64105 4.02948996 1 P 0 
A 1.64105 4.02948996 1.6787 4.0451 1.64102894 4.08275 1 P 0 N
L 1.6787 4.0451 1.68421004 4.0506 1 P 0 
L 1.68421004 4.0506 1.68421998 4.0506 1 P 0 
A 1.68421998 4.0506 1.70293041 4.06310079 1.72499705 4.00981998 1 P 0 Y
A 1.70293041 4.06310079 1.725 4.06748996 1.72499813 4.00981998 1 P 0 Y
A 1.725 4.06748996 1.76225 4.05206004 1.72499931 4.01481004 1 P 0 Y
L 1.76225 4.05206004 1.7674 4.04691004 1 P 0 
A 1.7674 4.04691004 1.78353002 4.00796654 1.72845 4.00796516 1 P 0 Y
A 1.78353002 4.00796654 1.7674 3.96901998 1.72845 4.00796486 1 P 0 Y
L 1.7674 3.96901998 1.76166004 3.96328002 1 P 0 
A 1.76166004 3.96328002 1.74533002 3.95651004 1.74533002 3.97958996 1 P 0 Y
L 1.74533002 3.95651004 1.677 3.95651004 1 P 0 
A 1.677 3.95651004 1.65129882 3.95139734 1.67700295 3.88933996 1 P 0 N
A 1.65129882 3.95139734 1.62951004 3.93683996 1.67700276 3.88933996 1 P 0 N
L 1.62951004 3.93683996 1.6199 3.92723002 1 P 0 
L 1.6199 3.92723002 1.6199 3.92676998 1 P 0 
A 1.6199 3.92676998 1.61622835 3.90537992 1.6505 3.91050728 1 P 0 N
A 1.61622835 3.90537992 1.626 3.886 1.6505 3.91050669 1 P 0 N
A 1.626 3.886 1.64372382 3.87415797 1.66462835 3.92463002 1 P 0 N
A 1.64372382 3.87415797 1.66463002 3.87 1.66462864 3.92463002 1 P 0 N
L 1.66463002 3.87 1.69578996 3.87 1 P 0 
A 1.69578996 3.87 1.73099498 3.86299282 1.69577421 3.77798002 1 P 0 Y
A 1.73099498 3.86299282 1.76083996 3.84305 1.69577382 3.77798002 1 P 0 Y
L 1.76083996 3.84305 1.76086004 3.84303002 1 P 0 
A 1.76086004 3.84303002 1.77650364 3.81961693 1.70981004 3.79198789 1 P 0 Y
A 1.77650364 3.81961693 1.782 3.792 1.70981004 3.79198809 1 P 0 Y
A 1.782 3.792 1.76263996 3.74526004 1.7159 3.79199961 1 P 0 Y
L 1.76263996 3.74526004 1.76028002 3.7429 1 P 0 
L 1.76028002 3.7429 1.6804 3.68696998 1 P 0 
L 1.6804 3.68696998 1.671 3.67756998 1 P 0 
A 1.671 3.67756998 1.65886978 3.64870423 1.70028002 3.64828406 1 P 0 N
A 1.65886978 3.64870423 1.67041004 3.6196 1.70028002 3.64828396 1 P 0 N
A 1.67041004 3.6196 1.671 3.619 1.70023002 3.64833091 1 P 0 N
L 1.671 3.619 1.67103002 3.61898002 1 P 0 
A 1.67103002 3.61898002 1.68451043 3.6087876 1.71441506 3.66235 1 P 0 N
A 1.68451043 3.6087876 1.70026004 3.60266004 1.71441624 3.66235 1 P 0 N
L 1.70026004 3.60266004 1.70046004 3.60246004 1 P 0 
L 1.70046004 3.60246004 1.7011 3.60246004 1 P 0 
A 1.7011 3.60246004 1.70198996 3.60245 1.7021189 3.65333002 1 P 0 N
A 1.70198996 3.60245 1.72145728 3.60632805 1.70197421 3.65333002 1 P 0 N
A 1.72145728 3.60632805 1.73796004 3.61736004 1.70197549 3.65333002 1 P 0 N
L 1.73796004 3.61736004 1.74605 3.62541004 1 P 0 
A 1.74605 3.62541004 1.75199774 3.62937618 1.75901506 3.61241004 1 P 0 Y
A 1.75199774 3.62937618 1.75901004 3.63076998 1.75901467 3.61241004 1 P 0 Y
A 1.75901004 3.63076998 1.77030502 3.62851959 1.75899823 3.60123996 1 P 0 Y
A 1.77030502 3.62851959 1.77988002 3.62211998 1.75899833 3.60123996 1 P 0 Y
L 1.77988002 3.62211998 1.78653002 3.61548002 1 P 0 
A 1.78653002 3.61548002 1.78721998 3.61451004 1.7839 3.61287884 1 P 0 Y
L 1.78721998 3.61451004 1.78721998 3.6145 1 P 0 
L 1.78721998 3.6145 1.78943996 3.61001998 1 P 0 
A 1.78943996 3.61001998 1.7927 3.59928002 1.75885 3.59486988 1 P 0 Y
A 1.7927 3.59928002 1.79298996 3.59486998 1.75886004 3.59484045 1 P 0 Y
L 1.79298996 3.59486998 1.793 3.59488002 1 P 0 
L 1.793 3.59488002 1.793 3.58871998 1 P 0 
A 1.793 3.58871998 1.79916417 3.57176909 1.81938002 3.58871683 1 P 0 N
A 1.79916417 3.57176909 1.81478002 3.56273996 1.81938346 3.58871998 1 P 0 N
L 1.81478002 3.56273996 1.95851998 3.5374 1 P 0 
L 1.95851998 3.5374 2.11101998 3.5374 1 P 0 
A 2.11101998 3.5374 2.11731004 3.53111004 2.11102008 3.53111004 1 P 0 Y
L 2.11731004 3.53111004 2.11731004 3.5079 1 P 0 
A 2.11731004 3.5079 2.11816004 3.50360394 2.12853002 3.5078878 1 P 0 N
A 2.11816004 3.50360394 2.12058996 3.49996004 2.12853002 3.50788701 1 P 0 N
L 2.12058996 3.49996004 2.12831998 3.49223002 1 P 0 
A 2.12831998 3.49223002 2.13998996 3.4874 2.13998868 3.50391004 1 P 0 N
L 2.13998996 3.4874 2.14236004 3.4874 1 P 0 
A 2.14236004 3.4874 2.14606004 3.4837 2.14236004 3.4837 1 P 0 Y
L 2.14606004 3.4837 2.14606004 3.46615 1 P 0 
P 2.14606004 3.51615 5 P 0 0;2=3,4=1
P 1.90111004 4.657 5 P 0 0;2=3,4=1
L 1.90111004 4.657 1.8887 4.657 1 P 0 
A 1.8887 4.657 1.885 4.6533 1.8887 4.6533 1 P 0 N
L 1.885 4.6533 1.885 4.61015 1 P 0 
A 1.885 4.61015 1.8767 4.59008002 1.85663002 4.6101312 1 P 0 Y
L 1.8767 4.59008002 1.87178996 4.58516998 1 P 0 
A 1.87178996 4.58516998 1.85164272 4.57233642 1.83277362 4.62418996 1 P 0 Y
A 1.85164272 4.57233642 1.82796004 4.56921998 1.83277283 4.62418996 1 P 0 Y
L 1.82796004 4.56921998 1.80271998 4.57143002 1 P 0 
L 1.80271998 4.57143002 1.789 4.569 1 P 0 
L 1.789 4.569 1.77195 4.55706004 1 P 0 
L 1.77195 4.55706004 1.76145 4.54206998 1 P 0 
L 1.76145 4.54206998 1.76263002 4.53546004 1 P 0 
L 1.76263002 4.53546004 1.75625 4.52633996 1 P 0 
L 1.75625 4.52633996 1.74963002 4.52518002 1 P 0 
L 1.74963002 4.52518002 1.74325 4.51606998 1 P 0 
L 1.74325 4.51606998 1.74443002 4.50946004 1 P 0 
L 1.74443002 4.50946004 1.73805 4.50033996 1 P 0 
L 1.73805 4.50033996 1.73143002 4.49918002 1 P 0 
L 1.73143002 4.49918002 1.73141004 4.49918002 1 P 0 
L 1.73141004 4.49918002 1.68111004 4.42736998 1 P 0 
A 1.68111004 4.42736998 1.65706998 4.36936998 1.7999 4.34415138 1 P 0 N
L 1.65706998 4.36936998 1.62666004 4.19703002 1 P 0 
A 1.62666004 4.19703002 1.5991 4.1441 1.52893996 4.21427156 1 P 0 Y
L 1.5991 4.1441 1.55111004 4.09611004 1 P 0 
A 1.55111004 4.09611004 1.54796998 4.08558002 1.55928002 4.08794055 1 P 0 N
A 1.54796998 4.08558002 1.54811998 4.08493002 1.55986998 4.08798386 1 P 0 N
L 1.54811998 4.08493002 1.54811998 4.08491998 1 P 0 
L 1.54811998 4.08491998 1.55003002 4.07776998 1 P 0 
A 1.55003002 4.07776998 1.55226211 4.07239419 1.57155 4.08355404 1 P 0 N
A 1.55226211 4.07239419 1.55581004 4.06778002 1.57155 4.08355394 1 P 0 N
L 1.55581004 4.06778002 1.55583002 4.06776004 1 P 0 
A 1.55583002 4.06776004 1.56733002 4.063 1.56732933 4.07926998 1 P 0 N
L 1.56733002 4.063 1.58451004 4.063 1 P 0 
A 1.58451004 4.063 1.59235157 4.06144114 1.5845124 4.04251004 1 P 0 Y
A 1.59235157 4.06144114 1.599 4.057 1.58451319 4.04251004 1 P 0 Y
L 1.599 4.057 1.60345 4.05255 1 P 0 
A 1.60345 4.05255 1.641 4.03698996 1.64100896 4.0901 1 P 0 N
L 1.641 4.03698996 1.64101998 4.03698996 1 P 0 
A 1.64101998 4.03698996 1.65848268 4.04045217 1.64102795 4.08271998 1 P 0 N
A 1.65848268 4.04045217 1.6733 4.05031998 1.64102825 4.08271998 1 P 0 N
L 1.6733 4.05031998 1.67891004 4.05591004 1 P 0 
A 1.67891004 4.05591004 1.70005659 4.07003898 1.72499813 4.00981998 1 P 0 Y
A 1.70005659 4.07003898 1.725 4.075 1.72499872 4.00981998 1 P 0 Y
A 1.725 4.075 1.74803346 4.07041782 1.72499852 4.01481004 1 P 0 Y
A 1.74803346 4.07041782 1.76756004 4.05736998 1.72499843 4.01481004 1 P 0 Y
L 1.76756004 4.05736998 1.77271004 4.05221998 1 P 0 
A 1.77271004 4.05221998 1.79103947 4.00796654 1.72845 4.00796516 1 P 0 Y
A 1.79103947 4.00796654 1.77271004 3.96371004 1.72845 4.00796486 1 P 0 Y
L 1.77271004 3.96371004 1.76696998 3.95796998 1 P 0 
A 1.76696998 3.95796998 1.75704154 3.95133612 1.7453437 3.97958996 1 P 0 Y
A 1.75704154 3.95133612 1.74533002 3.94901004 1.74534311 3.97958996 1 P 0 Y
L 1.74533002 3.94901004 1.68156004 3.94901004 1 P 0 
L 1.68156004 3.94901004 1.68156004 3.949 1 P 0 
L 1.68156004 3.949 1.68155 3.94898996 1 P 0 
L 1.68155 3.94898996 1.677 3.949 1 P 0 
A 1.677 3.949 1.65417264 3.94445935 1.67700187 3.88933996 1 P 0 N
A 1.65417264 3.94445935 1.63481998 3.93153002 1.67700207 3.88933996 1 P 0 N
L 1.63481998 3.93153002 1.62653996 3.92325 1 P 0 
A 1.62653996 3.92325 1.62365955 3.90649301 1.65051004 3.91050364 1 P 0 N
A 1.62365955 3.90649301 1.63131004 3.89131004 1.65051004 3.91050364 1 P 0 N
A 1.63131004 3.89131004 1.64659656 3.88109154 1.66464193 3.92463002 1 P 0 N
A 1.64659656 3.88109154 1.66463002 3.8775 1.66464203 3.92463002 1 P 0 N
L 1.66463002 3.8775 1.6958 3.8775 1 P 0 
A 1.6958 3.8775 1.73387234 3.86992441 1.6957875 3.77798002 1 P 0 Y
A 1.73387234 3.86992441 1.76615 3.84836004 1.6957875 3.77798002 1 P 0 Y
L 1.76615 3.84836004 1.76616998 3.84833996 1 P 0 
A 1.76616998 3.84833996 1.78951004 3.792 1.70981998 3.79199114 1 P 0 Y
A 1.78951004 3.792 1.76795 3.73995 1.7159 3.7920003 1 P 0 Y
L 1.76795 3.73995 1.76475 3.73675 1 P 0 
L 1.76475 3.73675 1.76458002 3.73675 1 P 0 
L 1.76458002 3.73675 1.68523996 3.6812 1 P 0 
L 1.68523996 3.6812 1.67631004 3.67226004 1 P 0 
A 1.67631004 3.67226004 1.67581998 3.6248 1.70028996 3.64827992 1 P 0 N
L 1.67581998 3.6248 1.67633996 3.62428996 1 P 0 
A 1.67633996 3.62428996 1.70198996 3.60996004 1.71443091 3.66235 1 P 0 N
A 1.70198996 3.60996004 1.71858878 3.61326496 1.7019812 3.65333996 1 P 0 N
A 1.71858878 3.61326496 1.73266004 3.62266998 1.70198199 3.65333996 1 P 0 N
L 1.73266004 3.62266998 1.74075 3.63073002 1 P 0 
A 1.74075 3.63073002 1.74912234 3.63630856 1.75900138 3.61241004 1 P 0 Y
A 1.74912234 3.63630856 1.75898996 3.63826998 1.75900148 3.61241004 1 P 0 Y
L 1.75898996 3.63826998 1.759 3.63826998 1 P 0 
A 1.759 3.63826998 1.77317303 3.63545502 1.75901142 3.60123996 1 P 0 Y
A 1.77317303 3.63545502 1.78518996 3.62743002 1.75901201 3.60123996 1 P 0 Y
L 1.78518996 3.62743002 1.79183996 3.62078002 1 P 0 
A 1.79183996 3.62078002 1.79395 3.61783002 1.7839 3.61287116 1 P 0 Y
L 1.79395 3.61783002 1.79616998 3.61336004 1 P 0 
A 1.79616998 3.61336004 1.80016004 3.60025 1.75886004 3.59484252 1 P 0 Y
L 1.80016004 3.60025 1.8005 3.5999 1 P 0 
L 1.8005 3.5999 1.8005 3.58871998 1 P 0 
A 1.8005 3.58871998 1.80491378 3.57658917 1.81938002 3.58872106 1 P 0 N
A 1.80491378 3.57658917 1.81608996 3.57013002 1.81937923 3.58871998 1 P 0 N
L 1.81608996 3.57013002 1.95918002 3.5449 1 P 0 
L 1.95918002 3.5449 2.11101998 3.5449 1 P 0 
A 2.11101998 3.5449 2.12481004 3.53111004 2.11102008 3.53111004 1 P 0 Y
L 2.12481004 3.53111004 2.12481004 3.5079 1 P 0 
A 2.12481004 3.5079 2.1259 3.50526998 2.12853002 3.50790079 1 P 0 N
L 2.1259 3.50526998 2.13363002 3.49753996 1 P 0 
A 2.13363002 3.49753996 2.13655236 3.49558652 2.14000217 3.50391004 1 P 0 N
A 2.13655236 3.49558652 2.14 3.4949 2.14000197 3.50391004 1 P 0 N
L 2.14 3.4949 2.14236004 3.4949 1 P 0 
A 2.14236004 3.4949 2.14606004 3.4986 2.14236004 3.4986 1 P 0 N
L 2.14606004 3.4986 2.14606004 3.51615 1 P 0 
P 1.93196998 5.0535 5 P 0 0;2=3,4=1
P 1.99606004 3.46615 5 P 0 0;2=3,4=1
L 1.99606004 3.46615 1.99606004 3.4837 1 P 0 
A 1.99606004 3.4837 1.99236004 3.4874 1.99236004 3.4837 1 P 0 N
L 1.99236004 3.4874 1.93006998 3.4874 1 P 0 
L 1.93006998 3.4874 1.87508002 3.47768996 1 P 0 
L 1.87508002 3.47768996 1.7994 3.49103996 1 P 0 
L 1.7994 3.49103996 1.62191004 3.6153 1 P 0 
A 1.62191004 3.6153 1.61131152 3.62738573 1.64131004 3.64300276 1 P 0 Y
A 1.61131152 3.62738573 1.60748996 3.643 1.64131004 3.64300256 1 P 0 Y
A 1.60748996 3.643 1.61008415 3.6560377 1.64156004 3.64299783 1 P 0 Y
A 1.61008415 3.6560377 1.61746998 3.66708996 1.64156004 3.64299744 1 P 0 Y
L 1.61746998 3.66708996 1.62568996 3.67531004 1 P 0 
A 1.62568996 3.67531004 1.63168563 3.68808976 1.611 3.68999823 1 P 0 N
A 1.63168563 3.68808976 1.62813002 3.70175 1.611 3.68999843 1 P 0 N
A 1.62813002 3.70175 1.60886998 3.7095 1.60886083 3.68166998 1 P 0 N
L 1.60886998 3.7095 1.57113002 3.7095 1 P 0 
A 1.57113002 3.7095 1.55519813 3.71266762 1.57112815 3.75113996 1 P 0 Y
A 1.55519813 3.71266762 1.54168996 3.72168996 1.57112726 3.75113996 1 P 0 Y
A 1.54168996 3.72168996 1.53227608 3.73578543 1.57243002 3.75241152 1 P 0 Y
A 1.53227608 3.73578543 1.52896998 3.75241004 1.57243002 3.75241181 1 P 0 Y
L 1.52896998 3.75241004 1.52896998 3.75248996 1 P 0 
A 1.52896998 3.75248996 1.53751998 3.77313996 1.55818002 3.75249075 1 P 0 Y
L 1.53751998 3.77313996 1.53753002 3.77315 1 P 0 
A 1.53753002 3.77315 1.55175276 3.7826562 1.56855138 3.74213002 1 P 0 Y
A 1.55175276 3.7826562 1.56853002 3.786 1.56855167 3.74213002 1 P 0 Y
L 1.56853002 3.786 1.56855 3.786 1 P 0 
A 1.56855 3.786 1.59261161 3.79070167 1.56855787 3.84988002 1 P 0 N
A 1.59261161 3.79070167 1.61313002 3.80411998 1.56855778 3.84988002 1 P 0 N
L 1.61313002 3.80411998 1.61408002 3.80505 1 P 0 
A 1.61408002 3.80505 1.61950502 3.81893868 1.59968996 3.8186747 1 P 0 N
A 1.61950502 3.81893868 1.61371004 3.83268002 1.59968996 3.8186749 1 P 0 N
L 1.61371004 3.83268002 1.6127 3.83368996 1 P 0 
L 1.6127 3.83368996 1.61268996 3.83368996 1 P 0 
A 1.61268996 3.83368996 1.59845463 3.8432065 1.58165394 3.80266998 1 P 0 N
A 1.59845463 3.8432065 1.58166004 3.84655 1.58165443 3.80266998 1 P 0 N
L 1.58166004 3.84655 1.58111998 3.84655 1 P 0 
A 1.58111998 3.84655 1.51753002 3.87408996 1.58414085 3.94071004 1 P 0 Y
L 1.51753002 3.87408996 1.51388002 3.87773996 1 P 0 
L 1.51388002 3.87773996 1.51388002 3.87775 1 P 0 
L 1.51388002 3.87775 1.5135 3.87806998 1 P 0 
A 1.5135 3.87806998 1.49655 3.91426004 1.54366004 3.91426014 1 P 0 Y
L 1.49655 3.91426004 1.49655 3.91953996 1 P 0 
A 1.49655 3.91953996 1.51 3.952 1.54246998 3.91952933 1 P 0 Y
L 1.51 3.952 1.51556998 3.95756004 1 P 0 
A 1.51556998 3.95756004 1.548 3.971 1.54800994 3.92513002 1 P 0 Y
L 1.548 3.971 1.55003996 3.971 1 P 0 
A 1.55003996 3.971 1.56207106 3.97339419 1.5500372 4.00243996 1 P 0 N
A 1.56207106 3.97339419 1.57226998 3.98021004 1.55003691 4.00243996 1 P 0 N
A 1.57226998 3.98021004 1.57948996 4.001 1.54595 4.00099911 1 P 0 N
A 1.57948996 4.001 1.57155 4.02018002 1.55233002 4.00099006 1 P 0 N
L 1.57155 4.02018002 1.57153002 4.0202 1 P 0 
A 1.57153002 4.0202 1.5503 4.029 1.55029941 3.99898996 1 P 0 N
L 1.5503 4.029 1.54028996 4.029 1 P 0 
A 1.54028996 4.029 1.50895994 4.03523179 1.5402878 4.11086004 1 P 0 Y
A 1.50895994 4.03523179 1.4824 4.05298002 1.5402873 4.11086004 1 P 0 Y
L 1.4824 4.05298002 1.48238002 4.053 1 P 0 
A 1.48238002 4.053 1.47136762 4.06948002 1.5183 4.08892215 1 P 0 Y
A 1.47136762 4.06948002 1.4675 4.08891998 1.5183 4.08892205 1 P 0 Y
A 1.4675 4.08891998 1.47082343 4.10563652 1.51118996 4.08892254 1 P 0 Y
A 1.47082343 4.10563652 1.48028996 4.11981004 1.51118996 4.08892372 1 P 0 Y
L 1.48028996 4.11981004 1.48058996 4.12008996 1 P 0 
L 1.48058996 4.12008996 1.48061004 4.12011004 1 P 0 
L 1.48061004 4.12011004 1.48361004 4.12258002 1 P 0 
A 1.48361004 4.12258002 1.51545 4.134 1.51545128 4.0839 1 P 0 Y
L 1.51545 4.134 1.53653996 4.134 1 P 0 
A 1.53653996 4.134 1.5405688 4.13479724 1.53654163 4.14456998 1 P 0 N
A 1.5405688 4.13479724 1.54398996 4.13706998 1.53654203 4.14456998 1 P 0 N
L 1.54398996 4.13706998 1.58646998 4.17946004 1 P 0 
A 1.58646998 4.17946004 1.5913 4.18866004 1.57451998 4.19160167 1 P 0 N
L 1.5913 4.18866004 1.6276 4.39458996 1 P 0 
A 1.6276 4.39458996 1.63088652 4.40588445 1.6808 4.38523504 1 P 0 Y
A 1.63088652 4.40588445 1.63653996 4.4162 1.6808 4.38523632 1 P 0 Y
L 1.63653996 4.4162 1.8243 4.68441998 1 P 0 
L 1.8243 4.68441998 1.84565 4.69935 1 P 0 
L 1.84565 4.69935 1.86045 4.70195 1 P 0 
L 1.86045 4.70195 1.90098996 4.73035 1 P 0 
L 1.90098996 4.73035 1.94781998 4.79693002 1 P 0 
L 1.94781998 4.79693002 1.95918002 4.86138996 1 P 0 
L 1.95918002 4.86138996 1.93973996 4.97166998 1 P 0 
L 1.93973996 4.97166998 1.9475 5.01566004 1 P 0 
L 1.9475 5.01566004 1.9475 5.049 1 P 0 
A 1.9475 5.049 1.943 5.0535 1.943 5.049 1 P 0 N
L 1.943 5.0535 1.93196998 5.0535 1 P 0 
P 1.97196998 5.0535 5 P 0 0;2=3,4=1
P 1.99606004 3.51615 5 P 0 0;2=3,4=1
L 1.99606004 3.51615 1.99606004 3.4986 1 P 0 
A 1.99606004 3.4986 1.99236004 3.4949 1.99236004 3.4986 1 P 0 Y
L 1.99236004 3.4949 1.92941004 3.4949 1 P 0 
L 1.92941004 3.4949 1.87508002 3.48531004 1 P 0 
L 1.87508002 3.48531004 1.80233996 3.49813996 1 P 0 
L 1.80233996 3.49813996 1.62621998 3.62145 1 P 0 
A 1.62621998 3.62145 1.61797362 3.63085207 1.64131004 3.64300256 1 P 0 Y
A 1.61797362 3.63085207 1.615 3.643 1.64131004 3.64300236 1 P 0 Y
A 1.615 3.643 1.61702234 3.65316388 1.64156004 3.64299843 1 P 0 Y
A 1.61702234 3.65316388 1.62278002 3.66178002 1.64156004 3.64299852 1 P 0 Y
L 1.62278002 3.66178002 1.631 3.67 1 P 0 
A 1.631 3.67 1.63916299 3.68740089 1.611 3.68999734 1 P 0 N
A 1.63916299 3.68740089 1.63431998 3.706 1.611 3.68999764 1 P 0 N
A 1.63431998 3.706 1.63386998 3.70663996 1.61096004 3.69005217 1 P 0 N
L 1.63386998 3.70663996 1.63386004 3.70665 1 P 0 
A 1.63386004 3.70665 1.62239961 3.71430925 1.60887569 3.68166998 1 P 0 N
A 1.62239961 3.71430925 1.60888002 3.717 1.60887598 3.68166998 1 P 0 N
L 1.60888002 3.717 1.57113996 3.717 1 P 0 
A 1.57113996 3.717 1.547 3.727 1.57114124 3.75113996 1 P 0 Y
A 1.547 3.727 1.53646998 3.75241998 1.57241998 3.75242096 1 P 0 Y
L 1.53646998 3.75241998 1.53646998 3.75248002 1 P 0 
A 1.53646998 3.75248002 1.53812343 3.7607877 1.55818002 3.75247756 1 P 0 Y
A 1.53812343 3.7607877 1.54283002 3.76783002 1.55818002 3.75247717 1 P 0 Y
L 1.54283002 3.76783002 1.54283996 3.76783996 1 P 0 
A 1.54283996 3.76783996 1.56853996 3.7785 1.56856083 3.74213996 1 P 0 Y
L 1.56853996 3.7785 1.5686 3.7785 1 P 0 
L 1.5686 3.7785 1.56863996 3.7785 1 P 0 
A 1.56863996 3.7785 1.619 3.79936004 1.56863967 3.84971998 1 P 0 N
L 1.619 3.79936004 1.61901004 3.79936004 1 P 0 
A 1.61901004 3.79936004 1.61901004 3.838 1.5997 3.81868002 1 P 0 N
L 1.61901004 3.838 1.618 3.839 1 P 0 
A 1.618 3.839 1.60133189 3.85013809 1.58166782 3.80266998 1 P 0 N
A 1.60133189 3.85013809 1.58166998 3.85405 1.58166762 3.80266998 1 P 0 N
L 1.58166998 3.85405 1.58125 3.85405 1 P 0 
A 1.58125 3.85405 1.54963356 3.86116939 1.58415433 3.94071004 1 P 0 Y
A 1.54963356 3.86116939 1.52283996 3.8794 1.58415482 3.94071004 1 P 0 Y
L 1.52283996 3.8794 1.51876004 3.88348002 1 P 0 
L 1.51876004 3.88348002 1.51871998 3.88348002 1 P 0 
L 1.51871998 3.88348002 1.51831004 3.88383996 1 P 0 
A 1.51831004 3.88383996 1.50405 3.91426004 1.54365 3.91427096 1 P 0 Y
L 1.50405 3.91426004 1.50405 3.91953002 1 P 0 
A 1.50405 3.91953002 1.50697461 3.93422884 1.54246998 3.91952598 1 P 0 Y
A 1.50697461 3.93422884 1.5153 3.94668996 1.54246998 3.91952569 1 P 0 Y
L 1.5153 3.94668996 1.52086998 3.95225 1 P 0 
L 1.52086998 3.95225 1.52088002 3.95225 1 P 0 
A 1.52088002 3.95225 1.54801004 3.9635 1.54801929 3.92513996 1 P 0 Y
L 1.54801004 3.9635 1.55005 3.9635 1 P 0 
A 1.55005 3.9635 1.57756998 3.9749 1.55004055 4.00243996 1 P 0 N
L 1.57756998 3.9749 1.57816004 3.97548996 1 P 0 
L 1.57816004 3.97548996 1.57816004 3.97555 1 P 0 
A 1.57816004 3.97555 1.58472736 3.98752923 1.54595 4.00099813 1 P 0 N
A 1.58472736 3.98752923 1.587 4.001 1.54595 4.00099843 1 P 0 N
A 1.587 4.001 1.57686004 4.02548996 1.55233002 4.00098917 1 P 0 N
L 1.57686004 4.02548996 1.57683996 4.02551004 1 P 0 
A 1.57683996 4.02551004 1.56466339 4.03364616 1.55031329 3.99898996 1 P 0 N
A 1.56466339 4.03364616 1.5503 4.0365 1.5503124 3.99898996 1 P 0 N
L 1.5503 4.0365 1.54028002 4.0365 1 P 0 
A 1.54028002 4.0365 1.51182805 4.04216644 1.54029715 4.11085 1 P 0 Y
A 1.51182805 4.04216644 1.48771004 4.05828996 1.54029626 4.11085 1 P 0 Y
L 1.48771004 4.05828996 1.48768996 4.05831004 1 P 0 
A 1.48768996 4.05831004 1.475 4.08891998 1.51828996 4.0889313 1 P 0 Y
L 1.475 4.08891998 1.47501004 4.08891998 1 P 0 
A 1.47501004 4.08891998 1.48546998 4.11438002 1.5112 4.08893051 1 P 0 Y
L 1.48546998 4.11438002 1.48556998 4.11446998 1 P 0 
L 1.48556998 4.11446998 1.48838002 4.11678996 1 P 0 
A 1.48838002 4.11678996 1.50107067 4.12399833 1.51545423 4.0839 1 P 0 Y
A 1.50107067 4.12399833 1.51545 4.1265 1.51545413 4.0839 1 P 0 Y
L 1.51545 4.1265 1.53653002 4.1265 1 P 0 
A 1.53653002 4.1265 1.54343041 4.12785925 1.53655463 4.14456998 1 P 0 N
A 1.54343041 4.12785925 1.54928996 4.13175 1.53655591 4.14456998 1 P 0 N
L 1.54928996 4.13175 1.59173002 4.17411004 1 P 0 
A 1.59173002 4.17411004 1.59624518 4.18019134 1.57453002 4.19159724 1 P 0 N
A 1.59624518 4.18019134 1.59868996 4.18736004 1.57453002 4.19159823 1 P 0 N
L 1.59868996 4.18736004 1.63498996 4.39328996 1 P 0 
A 1.63498996 4.39328996 1.64268996 4.41188996 1.6808 4.38521939 1 P 0 Y
L 1.64268996 4.41188996 1.82968996 4.67903002 1 P 0 
L 1.82968996 4.67903002 1.84858996 4.69225 1 P 0 
L 1.84858996 4.69225 1.86338996 4.69485 1 P 0 
L 1.86338996 4.69485 1.90636998 4.72496004 1 P 0 
L 1.90636998 4.72496004 1.95491998 4.79398002 1 P 0 
L 1.95491998 4.79398002 1.9668 4.86138996 1 P 0 
L 1.9668 4.86138996 1.9651 4.87101004 1 P 0 
L 1.9651 4.87101004 1.96881998 4.87628002 1 P 0 
L 1.96881998 4.87628002 1.96688002 4.88723002 1 P 0 
L 1.96688002 4.88723002 1.9616 4.89091998 1 P 0 
L 1.9616 4.89091998 1.95411004 4.93336998 1 P 0 
L 1.95411004 4.93336998 1.95783002 4.93863002 1 P 0 
L 1.95783002 4.93863002 1.95588996 4.94958002 1 P 0 
L 1.95588996 4.94958002 1.95061004 4.95328002 1 P 0 
L 1.95061004 4.95328002 1.94736004 4.97166998 1 P 0 
L 1.94736004 4.97166998 1.955 5.015 1 P 0 
L 1.955 5.015 1.955 5.0498 1 P 0 
A 1.955 5.0498 1.9587 5.0535 1.9587 5.0498 1 P 0 Y
L 1.9587 5.0535 1.97196998 5.0535 1 P 0 
P 4.30605 4.6631 6 P 0 0;2=1,4=1
P 4.34105 4.6431 6 P 0 0;2=1,4=1
P 4.38605 4.6431 6 P 0 0;2=1,4=1
P 4.42605 4.6631 6 P 0 0;2=1,4=1
P 4.46605 4.6631 6 P 0 0;2=1,4=1
P 4.30605 4.7031 6 P 0 0;2=1,4=1
P 4.42605 4.7031 6 P 0 0;2=1,4=1
P 4.46605 4.7031 6 P 0 0;2=1,4=1
P 4.26605 4.6631 6 P 0 0;2=1,4=1
P 4.26605 4.7031 6 P 0 0;2=1,4=1
P 4.65605 4.6631 6 P 0 0;2=1,4=1
P 4.69605 4.6631 6 P 0 0;2=1,4=1
P 4.65605 4.7031 6 P 0 0;2=1,4=1
P 4.69605 4.7031 6 P 0 0;2=1,4=1
P 4.73105 4.6431 6 P 0 0;2=1,4=1
P 4.81605 4.6631 6 P 0 0;2=1,4=1
P 4.85605 4.6631 6 P 0 0;2=1,4=1
P 4.81605 4.7031 6 P 0 0;2=1,4=1
P 4.85605 4.7031 6 P 0 0;2=1,4=1
P 4.77605 4.6431 6 P 0 0;2=1,4=1
P 5.17605 4.7131 6 P 0 0;2=1,4=1
P 5.17605 4.6731 6 P 0 0;2=1,4=1
P 5.08105 4.6731 6 P 0 0;2=1,4=1
P 5.13105 4.6731 6 P 0 0;2=1,4=1
P 5.03605 4.6731 6 P 0 0;2=1,4=1
P 5.03605 4.7131 6 P 0 0;2=1,4=1
P 4.30605 4.7481 6 P 0 0;2=1,4=1
P 4.30605 4.7931 6 P 0 0;2=1,4=1
P 4.30605 4.8381 6 P 0 0;2=1,4=1
P 4.38605 4.8381 6 P 0 0;2=1,4=1
P 4.34605 4.8381 6 P 0 0;2=1,4=1
P 4.46605 4.8381 6 P 0 0;2=1,4=1
P 4.42605 4.8381 6 P 0 0;2=1,4=1
P 4.42605 4.7931 6 P 0 0;2=1,4=1
P 4.42605 4.7481 6 P 0 0;2=1,4=1
P 4.46605 4.7931 6 P 0 0;2=1,4=1
P 4.46605 4.7481 6 P 0 0;2=1,4=1
P 4.26605 4.7481 6 P 0 0;2=1,4=1
P 4.26605 4.7931 6 P 0 0;2=1,4=1
P 4.26605 4.8381 6 P 0 0;2=1,4=1
P 4.65605 4.8381 6 P 0 0;2=1,4=1
P 4.65605 4.7931 6 P 0 0;2=1,4=1
P 4.65605 4.7481 6 P 0 0;2=1,4=1
P 4.69605 4.8381 6 P 0 0;2=1,4=1
P 4.69605 4.7931 6 P 0 0;2=1,4=1
P 4.69605 4.7481 6 P 0 0;2=1,4=1
P 4.73605 4.8381 6 P 0 0;2=1,4=1
P 4.81605 4.8381 6 P 0 0;2=1,4=1
P 4.81605 4.7931 6 P 0 0;2=1,4=1
P 4.81605 4.7481 6 P 0 0;2=1,4=1
P 4.85605 4.8381 6 P 0 0;2=1,4=1
P 4.85605 4.7931 6 P 0 0;2=1,4=1
P 4.85605 4.7481 6 P 0 0;2=1,4=1
P 4.77605 4.8381 6 P 0 0;2=1,4=1
P 5.08105 4.8431 6 P 0 0;2=1,4=1
P 5.13105 4.8431 6 P 0 0;2=1,4=1
P 5.17605 4.8431 6 P 0 0;2=1,4=1
P 5.17605 4.8031 6 P 0 0;2=1,4=1
P 5.17605 4.7581 6 P 0 0;2=1,4=1
P 5.03605 4.8431 6 P 0 0;2=1,4=1
P 5.03605 4.8031 6 P 0 0;2=1,4=1
P 5.03605 4.7581 6 P 0 0;2=1,4=1
P 4.58268002 2.96615 5 P 0 0;2=3,4=1
P 4.63268002 2.96615 5 P 0 0;2=3,4=1
P 4.63268002 3.11615 5 P 0 0;2=3,4=1
P 4.58268002 3.01615 5 P 0 0;2=3,4=1
P 4.58268002 3.11615 5 P 0 0;2=3,4=1
P 4.63268002 3.01615 5 P 0 0;2=3,4=1
P 4.63268002 3.31615 5 P 0 0;2=3,4=1
P 4.58268002 3.26615 5 P 0 0;2=3,4=1
P 4.58268002 3.31615 5 P 0 0;2=3,4=1
P 4.63268002 3.26615 5 P 0 0;2=3,4=1
P 4.63268002 3.16615 5 P 0 0;2=3,4=1
P 4.58268002 3.16615 5 P 0 0;2=3,4=1
P 4.58268002 3.46615 5 P 0 0;2=3,4=1
P 4.63268002 3.41615 5 P 0 0;2=3,4=1
P 4.63268002 3.46615 5 P 0 0;2=3,4=1
P 4.58268002 3.41615 5 P 0 0;2=3,4=1
P 4.58268002 3.61615 5 P 0 0;2=3,4=1
P 4.58268002 3.56615 5 P 0 0;2=3,4=1
P 4.63268002 3.61615 5 P 0 0;2=3,4=1
P 4.63268002 3.56615 5 P 0 0;2=3,4=1
P 4.58268002 3.71615 5 P 0 0;2=3,4=1
P 4.63268002 3.71615 5 P 0 0;2=3,4=1
P 4.58268002 3.76615 5 P 0 0;2=3,4=1
P 4.58268002 3.86615 5 P 0 0;2=3,4=1
P 4.63268002 3.76615 5 P 0 0;2=3,4=1
P 4.63268002 3.86615 5 P 0 0;2=3,4=1
P 4.68268002 2.96615 5 P 0 0;2=3,4=1
P 4.73268002 2.96615 5 P 0 0;2=3,4=1
P 4.78268002 2.96615 5 P 0 0;2=3,4=1
P 4.68268002 3.11615 5 P 0 0;2=3,4=1
P 4.68268002 3.01615 5 P 0 0;2=3,4=1
P 4.73268002 3.11615 5 P 0 0;2=3,4=1
P 4.73268002 3.01615 5 P 0 0;2=3,4=1
P 4.78268002 3.11615 5 P 0 0;2=3,4=1
P 4.78268002 3.01615 5 P 0 0;2=3,4=1
P 4.73268002 3.31615 5 P 0 0;2=3,4=1
P 4.73268002 3.26615 5 P 0 0;2=3,4=1
P 4.68268002 3.26615 5 P 0 0;2=3,4=1
P 4.68268002 3.31615 5 P 0 0;2=3,4=1
P 4.78268002 3.26615 5 P 0 0;2=3,4=1
P 4.78268002 3.31615 5 P 0 0;2=3,4=1
P 4.73268002 3.16615 5 P 0 0;2=3,4=1
P 4.68268002 3.16615 5 P 0 0;2=3,4=1
P 4.78268002 3.16615 5 P 0 0;2=3,4=1
P 4.73268002 3.41615 5 P 0 0;2=3,4=1
P 4.68268002 3.41615 5 P 0 0;2=3,4=1
P 4.68268002 3.46615 5 P 0 0;2=3,4=1
P 4.73268002 3.46615 5 P 0 0;2=3,4=1
P 4.78268002 3.46615 5 P 0 0;2=3,4=1
P 4.78268002 3.41615 5 P 0 0;2=3,4=1
P 4.73268002 3.56615 5 P 0 0;2=3,4=1
P 4.73268002 3.61615 5 P 0 0;2=3,4=1
P 4.68268002 3.56615 5 P 0 0;2=3,4=1
P 4.68268002 3.61615 5 P 0 0;2=3,4=1
P 4.78268002 3.61615 5 P 0 0;2=3,4=1
P 4.78268002 3.56615 5 P 0 0;2=3,4=1
P 4.73268002 3.71615 5 P 0 0;2=3,4=1
P 4.68268002 3.71615 5 P 0 0;2=3,4=1
P 4.78268002 3.71615 5 P 0 0;2=3,4=1
P 4.73268002 3.76615 5 P 0 0;2=3,4=1
P 4.73268002 3.86615 5 P 0 0;2=3,4=1
P 4.68268002 3.76615 5 P 0 0;2=3,4=1
P 4.68268002 3.86615 5 P 0 0;2=3,4=1
P 4.78268002 3.76615 5 P 0 0;2=3,4=1
P 4.78268002 3.86615 5 P 0 0;2=3,4=1
P 4.88268002 3.86615 5 P 0 0;2=3,4=1
P 4.83268002 3.86615 5 P 0 0;2=3,4=1
P 5.03268002 3.86615 5 P 0 0;2=3,4=1
P 4.93268002 3.86615 5 P 0 0;2=3,4=1
P 4.98268002 3.86615 5 P 0 0;2=3,4=1
P 4.88268002 3.76615 5 P 0 0;2=3,4=1
P 4.83268002 3.76615 5 P 0 0;2=3,4=1
P 5.03268002 3.76615 5 P 0 0;2=3,4=1
P 4.93268002 3.76615 5 P 0 0;2=3,4=1
P 4.98268002 3.76615 5 P 0 0;2=3,4=1
P 4.88268002 3.71615 5 P 0 0;2=3,4=1
P 4.83268002 3.71615 5 P 0 0;2=3,4=1
P 5.03268002 3.71615 5 P 0 0;2=3,4=1
P 4.93268002 3.71615 5 P 0 0;2=3,4=1
P 4.98268002 3.71615 5 P 0 0;2=3,4=1
P 4.88268002 3.61615 5 P 0 0;2=3,4=1
P 4.83268002 3.61615 5 P 0 0;2=3,4=1
P 5.03268002 3.61615 5 P 0 0;2=3,4=1
P 4.93268002 3.61615 5 P 0 0;2=3,4=1
P 4.98268002 3.61615 5 P 0 0;2=3,4=1
P 4.88268002 3.56615 5 P 0 0;2=3,4=1
P 4.83268002 3.56615 5 P 0 0;2=3,4=1
P 5.03268002 3.56615 5 P 0 0;2=3,4=1
P 4.93268002 3.56615 5 P 0 0;2=3,4=1
P 4.98268002 3.56615 5 P 0 0;2=3,4=1
P 4.88268002 3.46615 5 P 0 0;2=3,4=1
P 4.83268002 3.46615 5 P 0 0;2=3,4=1
P 5.03268002 3.46615 5 P 0 0;2=3,4=1
P 4.93268002 3.46615 5 P 0 0;2=3,4=1
P 4.98268002 3.46615 5 P 0 0;2=3,4=1
P 4.88268002 3.41615 5 P 0 0;2=3,4=1
P 4.83268002 3.41615 5 P 0 0;2=3,4=1
P 5.03268002 3.41615 5 P 0 0;2=3,4=1
P 4.93268002 3.41615 5 P 0 0;2=3,4=1
P 4.98268002 3.41615 5 P 0 0;2=3,4=1
P 4.88268002 3.31615 5 P 0 0;2=3,4=1
P 4.83268002 3.31615 5 P 0 0;2=3,4=1
P 5.03268002 3.31615 5 P 0 0;2=3,4=1
P 4.93268002 3.31615 5 P 0 0;2=3,4=1
P 4.98268002 3.31615 5 P 0 0;2=3,4=1
P 4.83268002 3.26615 5 P 0 0;2=3,4=1
P 4.88268002 3.26615 5 P 0 0;2=3,4=1
P 4.98268002 3.26615 5 P 0 0;2=3,4=1
P 4.93268002 3.26615 5 P 0 0;2=3,4=1
P 5.03268002 3.26615 5 P 0 0;2=3,4=1
P 4.83268002 3.16615 5 P 0 0;2=3,4=1
P 4.88268002 3.16615 5 P 0 0;2=3,4=1
P 4.98268002 3.16615 5 P 0 0;2=3,4=1
P 4.93268002 3.16615 5 P 0 0;2=3,4=1
P 5.03268002 3.16615 5 P 0 0;2=3,4=1
P 4.83268002 3.11615 5 P 0 0;2=3,4=1
P 4.88268002 3.11615 5 P 0 0;2=3,4=1
P 4.98268002 3.11615 5 P 0 0;2=3,4=1
P 4.93268002 3.11615 5 P 0 0;2=3,4=1
P 5.03268002 3.11615 5 P 0 0;2=3,4=1
P 4.83268002 3.01615 5 P 0 0;2=3,4=1
P 4.88268002 3.01615 5 P 0 0;2=3,4=1
P 4.98268002 3.01615 5 P 0 0;2=3,4=1
P 4.93268002 3.01615 5 P 0 0;2=3,4=1
P 5.03268002 3.01615 5 P 0 0;2=3,4=1
P 4.83268002 2.96615 5 P 0 0;2=3,4=1
P 4.88268002 2.96615 5 P 0 0;2=3,4=1
P 4.98268002 2.96615 5 P 0 0;2=3,4=1
P 4.93268002 2.96615 5 P 0 0;2=3,4=1
P 5.03268002 2.96615 5 P 0 0;2=3,4=1
S P 0
OB 4.29998996063 2.958 I
OS 4.25605 3.00193996063
OS 4.25605 4.8381
OS 4.26605 4.8481
OS 5.18105 4.8481
OS 5.22106003937 4.80808996063
OS 5.22106003937 3.033
OS 5.14606003937 2.958
OS 4.29998996063 2.958
OE
OB 4.5987 3.06615 H
OC 4.5987 3.06615 4.582680019685 3.06615 N
OE
OB 4.6487 3.06615 H
OC 4.6487 3.06615 4.632680019685 3.06615 N
OE
OB 4.5987 3.21615 H
OC 4.5987 3.21615 4.582680019685 3.21615 N
OE
OB 4.6487 3.21615 H
OC 4.6487 3.21615 4.632680019685 3.21615 N
OE
OB 4.5987 3.36615 H
OC 4.5987 3.36615 4.582680019685 3.36615 N
OE
OB 4.6487 3.36615 H
OC 4.6487 3.36615 4.632680019685 3.36615 N
OE
OB 4.5987 3.51615 H
OC 4.5987 3.51615 4.582680019685 3.51615 N
OE
OB 4.6487 3.51615 H
OC 4.6487 3.51615 4.632680019685 3.51615 N
OE
OB 4.5987 3.66615 H
OC 4.5987 3.66615 4.582680019685 3.66615 N
OE
OB 4.5987 3.81615 H
OC 4.5987 3.81615 4.582680019685 3.81615 N
OE
OB 4.6487 3.66615 H
OC 4.6487 3.66615 4.632680019685 3.66615 N
OE
OB 4.6487 3.81615 H
OC 4.6487 3.81615 4.632680019685 3.81615 N
OE
OB 4.8987 3.06615 H
OC 4.8987 3.06615 4.882680019685 3.06615 N
OE
OB 4.8487 3.06615 H
OC 4.8487 3.06615 4.832680019685 3.06615 N
OE
OB 4.6987 3.06615 H
OC 4.6987 3.06615 4.682680019685 3.06615 N
OE
OB 4.7487 3.06615 H
OC 4.7487 3.06615 4.732680019685 3.06615 N
OE
OB 4.7987 3.06615 H
OC 4.7987 3.06615 4.782680019685 3.06615 N
OE
OB 4.8987 3.21615 H
OC 4.8987 3.21615 4.882680019685 3.21615 N
OE
OB 4.8487 3.21615 H
OC 4.8487 3.21615 4.832680019685 3.21615 N
OE
OB 4.8487 3.36615 H
OC 4.8487 3.36615 4.832680019685 3.36615 N
OE
OB 4.8987 3.36615 H
OC 4.8987 3.36615 4.882680019685 3.36615 N
OE
OB 4.6987 3.21615 H
OC 4.6987 3.21615 4.682680019685 3.21615 N
OE
OB 4.6987 3.36615 H
OC 4.6987 3.36615 4.682680019685 3.36615 N
OE
OB 4.7487 3.21615 H
OC 4.7487 3.21615 4.732680019685 3.21615 N
OE
OB 4.7987 3.21615 H
OC 4.7987 3.21615 4.782680019685 3.21615 N
OE
OB 4.7487 3.36615 H
OC 4.7487 3.36615 4.732680019685 3.36615 N
OE
OB 4.7987 3.36615 H
OC 4.7987 3.36615 4.782680019685 3.36615 N
OE
OB 4.8487 3.51615 H
OC 4.8487 3.51615 4.832680019685 3.51615 N
OE
OB 4.8987 3.51615 H
OC 4.8987 3.51615 4.882680019685 3.51615 N
OE
OB 4.6987 3.51615 H
OC 4.6987 3.51615 4.682680019685 3.51615 N
OE
OB 4.7487 3.51615 H
OC 4.7487 3.51615 4.732680019685 3.51615 N
OE
OB 4.7987 3.51615 H
OC 4.7987 3.51615 4.782680019685 3.51615 N
OE
OB 4.8487 3.81615 H
OC 4.8487 3.81615 4.832680019685 3.81615 N
OE
OB 4.8987 3.81615 H
OC 4.8987 3.81615 4.882680019685 3.81615 N
OE
OB 4.8487 3.66615 H
OC 4.8487 3.66615 4.832680019685 3.66615 N
OE
OB 4.8987 3.66615 H
OC 4.8987 3.66615 4.882680019685 3.66615 N
OE
OB 4.6987 3.66615 H
OC 4.6987 3.66615 4.682680019685 3.66615 N
OE
OB 4.6987 3.81615 H
OC 4.6987 3.81615 4.682680019685 3.81615 N
OE
OB 4.7487 3.66615 H
OC 4.7487 3.66615 4.732680019685 3.66615 N
OE
OB 4.7487 3.81615 H
OC 4.7487 3.81615 4.732680019685 3.81615 N
OE
OB 4.7987 3.66615 H
OC 4.7987 3.66615 4.782680019685 3.66615 N
OE
OB 4.7987 3.81615 H
OC 4.7987 3.81615 4.782680019685 3.81615 N
OE
OB 5.0487 3.06615 H
OC 5.0487 3.06615 5.032680019685 3.06615 N
OE
OB 4.9487 3.06615 H
OC 4.9487 3.06615 4.932680019685 3.06615 N
OE
OB 4.9987 3.06615 H
OC 4.9987 3.06615 4.982680019685 3.06615 N
OE
OB 5.0487 3.21615 H
OC 5.0487 3.21615 5.032680019685 3.21615 N
OE
OB 4.9487 3.21615 H
OC 4.9487 3.21615 4.932680019685 3.21615 N
OE
OB 4.9987 3.21615 H
OC 4.9987 3.21615 4.982680019685 3.21615 N
OE
OB 4.9987 3.36615 H
OC 4.9987 3.36615 4.982680019685 3.36615 N
OE
OB 4.9487 3.36615 H
OC 4.9487 3.36615 4.932680019685 3.36615 N
OE
OB 5.0487 3.36615 H
OC 5.0487 3.36615 5.032680019685 3.36615 N
OE
OB 4.9987 3.51615 H
OC 4.9987 3.51615 4.982680019685 3.51615 N
OE
OB 4.9487 3.51615 H
OC 4.9487 3.51615 4.932680019685 3.51615 N
OE
OB 5.0487 3.51615 H
OC 5.0487 3.51615 5.032680019685 3.51615 N
OE
OB 4.9987 3.81615 H
OC 4.9987 3.81615 4.982680019685 3.81615 N
OE
OB 4.9487 3.81615 H
OC 4.9487 3.81615 4.932680019685 3.81615 N
OE
OB 4.9987 3.66615 H
OC 4.9987 3.66615 4.982680019685 3.66615 N
OE
OB 4.9487 3.66615 H
OC 4.9487 3.66615 4.932680019685 3.66615 N
OE
OB 5.0487 3.66615 H
OC 5.0487 3.66615 5.032680019685 3.66615 N
OE
OB 5.0487 3.81615 H
OC 5.0487 3.81615 5.032680019685 3.81615 N
OE
OB 5.043980019685 4.22441003937 H
OC 5.043980019685 4.22441003937 4.832680019685 4.22441003937 N
OE
SE
P 10.395 1.28555 5 P 0 0;2=3,4=1
P 12.81495 1.96456998 7 P 0 0;2=4,4=0
L 12.81495 1.96456998 12.80603002 1.97348996 1 P 0 
L 12.80603002 1.97348996 12.7744 1.97348996 1 P 0 
L 12.7744 1.97348996 12.7618 1.9609 1 P 0 
L 12.7618 1.9609 12.64351004 1.9609 1 P 0 
L 12.64351004 1.9609 12.62253002 1.9646 1 P 0 
L 12.62253002 1.9646 12.57481998 1.99801998 1 P 0 
L 12.57481998 1.99801998 12.56473996 1.9998 1 P 0 
L 12.56473996 1.9998 12.53586004 1.9998 1 P 0 
L 12.53586004 1.9998 12.52213002 1.99738002 1 P 0 
L 12.52213002 1.99738002 12.47016998 1.96096998 1 P 0 
L 12.47016998 1.96096998 12.44411998 1.92376998 1 P 0 
L 12.44411998 1.92376998 12.35146004 1.3984 1 P 0 
L 12.35146004 1.3984 12.30081004 1.32603996 1 P 0 
L 12.30081004 1.32603996 12.16601998 1.23168002 1 P 0 
L 12.16601998 1.23168002 11.82466998 1.17148996 1 P 0 
L 11.82466998 1.17148996 11.48211998 1.23188996 1 P 0 
L 11.48211998 1.23188996 10.8491 1.12028002 1 P 0 
L 10.8491 1.12028002 10.67855 1.15035 1 P 0 
L 10.67855 1.15035 10.47211004 1.29491998 1 P 0 
L 10.47211004 1.29491998 10.43133996 1.3021 1 P 0 
L 10.43133996 1.3021 10.41155 1.3021 1 P 0 
L 10.41155 1.3021 10.395 1.28555 1 P 0 
P 9.42358002 5.22001998 5 P 0 0;2=3,4=1
L 8.98115 2.825 8.9974 2.84125 1 P 0 
L 8.9974 2.84125 9.00341004 2.84125 1 P 0 
L 9.00341004 2.84125 9.03355 2.84656998 1 P 0 
L 9.03355 2.84656998 9.08566998 2.88306004 1 P 0 
L 9.08566998 2.88306004 9.14846004 2.97271004 1 P 0 
L 9.14846004 2.97271004 9.28366998 3.73956004 1 P 0 
L 9.28366998 3.73956004 9.24731998 3.94573996 1 P 0 
L 9.24731998 3.94573996 9.35865 4.57718996 1 P 0 
L 9.35865 4.57718996 9.32756998 4.75353002 1 P 0 
L 9.32756998 4.75353002 9.34191998 4.83488996 1 P 0 
L 9.34191998 4.83488996 9.33505 4.87353996 1 P 0 
L 9.33505 4.87353996 9.34635 4.93758996 1 P 0 
L 9.34635 4.93758996 9.40121004 5.01595 1 P 0 
L 9.40121004 5.01595 9.4191 5.11361998 1 P 0 
L 9.4191 5.11361998 9.40703996 5.182 1 P 0 
L 9.40703996 5.182 9.40703996 5.20348002 1 P 0 
L 9.40703996 5.20348002 9.42358002 5.22001998 1 P 0 
P 8.98115 2.825 5 P 0 0;2=3,4=1
P 9.38358002 5.22001998 5 P 0 0;2=3,4=1
L 8.98115 2.865 8.9974 2.84875 1 P 0 
L 8.9974 2.84875 9.00275 2.84875 1 P 0 
L 9.00275 2.84875 9.03061004 2.85366998 1 P 0 
L 9.03061004 2.85366998 9.03933996 2.85978002 1 P 0 
L 9.03933996 2.85978002 9.04031998 2.86536004 1 P 0 
L 9.04031998 2.86536004 9.04893002 2.87138002 1 P 0 
L 9.04893002 2.87138002 9.0545 2.8704 1 P 0 
L 9.0545 2.8704 9.08028002 2.88845 1 P 0 
L 9.08028002 2.88845 9.0863 2.89705 1 P 0 
L 9.0863 2.89705 9.08531998 2.90261998 1 P 0 
L 9.08531998 2.90261998 9.09133996 2.91123002 1 P 0 
L 9.09133996 2.91123002 9.09691998 2.91221004 1 P 0 
L 9.09691998 2.91221004 9.10293996 2.92081004 1 P 0 
L 9.10293996 2.92081004 9.10196004 2.92638002 1 P 0 
L 9.10196004 2.92638002 9.10798002 2.93498996 1 P 0 
L 9.10798002 2.93498996 9.11356004 2.93596998 1 P 0 
L 9.11356004 2.93596998 9.11355 2.93596998 1 P 0 
L 9.11355 2.93596998 9.14136004 2.97565 1 P 0 
L 9.14136004 2.97565 9.27605 3.73956004 1 P 0 
L 9.27605 3.73956004 9.2397 3.94573996 1 P 0 
L 9.2397 3.94573996 9.35103002 4.57718996 1 P 0 
L 9.35103002 4.57718996 9.31995 4.75353002 1 P 0 
L 9.31995 4.75353002 9.3343 4.83488002 1 P 0 
L 9.3343 4.83488002 9.32743002 4.87353996 1 P 0 
L 9.32743002 4.87353996 9.33925 4.94053002 1 P 0 
L 9.33925 4.94053002 9.35288002 4.96 1 P 0 
L 9.35288002 4.96 9.3516 4.96721004 1 P 0 
L 9.3516 4.96721004 9.35798002 4.97631004 1 P 0 
L 9.35798002 4.97631004 9.36518002 4.97756998 1 P 0 
L 9.36518002 4.97756998 9.39411998 5.01891998 1 P 0 
L 9.39411998 5.01891998 9.39821004 5.04123002 1 P 0 
L 9.39821004 5.04123002 9.39441998 5.04668002 1 P 0 
L 9.39441998 5.04668002 9.39643002 5.05761004 1 P 0 
L 9.39643002 5.05761004 9.4019 5.06138002 1 P 0 
L 9.4019 5.06138002 9.40391004 5.07233002 1 P 0 
L 9.40391004 5.07233002 9.40011998 5.07778002 1 P 0 
L 9.40011998 5.07778002 9.40213002 5.08871004 1 P 0 
L 9.40213002 5.08871004 9.4076 5.09248002 1 P 0 
L 9.4076 5.09248002 9.41146998 5.11365 1 P 0 
L 9.41146998 5.11365 9.40938996 5.12541004 1 P 0 
L 9.40938996 5.12541004 9.40431004 5.12895 1 P 0 
L 9.40431004 5.12895 9.40236998 5.1399 1 P 0 
L 9.40236998 5.1399 9.40593996 5.14496004 1 P 0 
L 9.40593996 5.14496004 9.39953996 5.18133996 1 P 0 
L 9.39953996 5.18133996 9.39953996 5.20406004 1 P 0 
L 9.39953996 5.20406004 9.38358002 5.22001998 1 P 0 
P 8.98115 2.865 5 P 0 0;2=3,4=1
P 4.83268002 2.16615 5 P 0 0;2=3,4=1
L 4.83268002 2.16615 4.85023002 2.16615 1 P 0 
L 4.85023002 2.16615 4.85393002 2.16245 1 P 0 
L 4.85393002 2.16245 4.85393002 2.11671998 1 P 0 
L 4.85393002 2.11671998 4.80721004 1.85173996 1 P 0 
L 4.80721004 1.85173996 4.76296998 1.78853996 1 P 0 
L 4.76296998 1.78853996 4.62276004 1.69036998 1 P 0 
L 4.62276004 1.69036998 4.19983002 1.61578996 1 P 0 
L 4.19983002 1.61578996 3.32481998 1.00311004 1 P 0 
L 3.32481998 1.00311004 2.22553002 0.80928002 1 P 0 
L 2.22553002 0.80928002 1.94818996 0.85818002 1 P 0 
L 1.94818996 0.85818002 1.45731004 1.20191998 1 P 0 
L 1.45731004 1.20191998 1.11483002 1.69105 1 P 0 
L 1.11483002 1.69105 0.87143996 1.86148002 1 P 0 
L 0.87143996 1.86148002 0.86203002 1.86806998 1 P 0 
L 0.86203002 1.86806998 0.84301004 1.87143002 1 P 0 
L 0.84301004 1.87143002 0.83876004 1.87748996 1 P 0 
L 0.83876004 1.87748996 0.8278 1.87943002 1 P 0 
L 0.8278 1.87943002 0.82175 1.87516998 1 P 0 
L 0.82175 1.87516998 0.81081004 1.87711004 1 P 0 
L 0.81081004 1.87711004 0.80656004 1.88316998 1 P 0 
L 0.80656004 1.88316998 0.7956 1.88511004 1 P 0 
L 0.7956 1.88511004 0.78955 1.88085 1 P 0 
L 0.78955 1.88085 0.73836998 1.88986998 1 P 0 
L 0.73836998 1.88986998 0.70973996 1.88986998 1 P 0 
L 0.70973996 1.88986998 0.69348996 1.90611998 1 P 0 
P 0.69348996 1.90611998 5 P 0 0;2=3,4=1
P 4.88268002 2.16615 5 P 0 0;2=3,4=1
L 4.88268002 2.16615 4.86513002 2.16615 1 P 0 
L 4.86513002 2.16615 4.86143002 2.16245 1 P 0 
L 4.86143002 2.16245 4.86143002 2.11606004 1 P 0 
L 4.86143002 2.11606004 4.81431004 1.8488 1 P 0 
L 4.81431004 1.8488 4.76836004 1.78315 1 P 0 
L 4.76836004 1.78315 4.6257 1.68326998 1 P 0 
L 4.6257 1.68326998 4.20276998 1.60868996 1 P 0 
L 4.20276998 1.60868996 3.32776004 0.99601004 1 P 0 
L 3.32776004 0.99601004 2.22553002 0.80166004 1 P 0 
L 2.22553002 0.80166004 1.94525 0.85108002 1 P 0 
L 1.94525 0.85108002 1.45191998 1.19653002 1 P 0 
L 1.45191998 1.19653002 1.10943996 1.68566004 1 P 0 
L 1.10943996 1.68566004 0.8685 1.85438002 1 P 0 
L 0.8685 1.85438002 0.85908996 1.86096998 1 P 0 
L 0.85908996 1.86096998 0.73771004 1.88236998 1 P 0 
L 0.73771004 1.88236998 0.70973996 1.88236998 1 P 0 
L 0.70973996 1.88236998 0.69348996 1.86611998 1 P 0 
P 0.69348996 1.86611998 5 P 0 0;2=3,4=1
P 12.81495 3.53936998 7 P 0 0;2=4,4=0
P 9.975 2.3758 5 P 0 0;2=3,4=1
L 9.975 2.3758 9.99115 2.35965 1 P 0 
L 9.99115 2.35965 10.01086004 2.35965 1 P 0 
L 10.01086004 2.35965 10.02966998 2.35633996 1 P 0 
L 10.02966998 2.35633996 10.04636004 2.34466004 1 P 0 
L 10.04636004 2.34466004 10.05778002 2.32833996 1 P 0 
L 10.05778002 2.32833996 10.06973996 2.26048996 1 P 0 
L 10.06973996 2.26048996 10.07898996 2.24728996 1 P 0 
L 10.07898996 2.24728996 10.0855 2.24271998 1 P 0 
L 10.0855 2.24271998 10.18845 2.22456004 1 P 0 
L 10.18845 2.22456004 10.26618002 2.17016998 1 P 0 
L 10.26618002 2.17016998 10.46841998 1.88131998 1 P 0 
L 10.46841998 1.88131998 10.59126998 1.79528996 1 P 0 
L 10.59126998 1.79528996 10.69148996 1.77761998 1 P 0 
L 10.69148996 1.77761998 10.83831998 1.80348996 1 P 0 
L 10.83831998 1.80348996 10.98741004 1.77721004 1 P 0 
L 10.98741004 1.77721004 11.09736004 1.7966 1 P 0 
L 11.09736004 1.7966 11.29215 1.933 1 P 0 
L 11.29215 1.933 11.49403996 2.22133002 1 P 0 
L 11.49403996 2.22133002 11.55153996 2.26158002 1 P 0 
L 11.55153996 2.26158002 11.61511998 2.35238996 1 P 0 
L 11.61511998 2.35238996 11.63926004 2.48931004 1 P 0 
L 11.63926004 2.48931004 11.66811004 2.53053996 1 P 0 
L 11.66811004 2.53053996 11.6974 2.55105 1 P 0 
L 11.6974 2.55105 11.74306004 2.5591 1 P 0 
L 11.74306004 2.5591 11.79408996 2.59483996 1 P 0 
L 11.79408996 2.59483996 11.82131998 2.63371998 1 P 0 
L 11.82131998 2.63371998 12.43858996 3.51526998 1 P 0 
L 12.43858996 3.51526998 12.53203002 3.58068002 1 P 0 
L 12.53203002 3.58068002 12.54761998 3.58341998 1 P 0 
L 12.54761998 3.58341998 12.57218996 3.58341998 1 P 0 
L 12.57218996 3.58341998 12.62253002 3.61866004 1 P 0 
L 12.62253002 3.61866004 12.64153996 3.62201998 1 P 0 
L 12.64153996 3.62201998 12.75731004 3.62201998 1 P 0 
L 12.75731004 3.62201998 12.7849 3.59443002 1 P 0 
L 12.7849 3.59443002 12.7849 3.56941998 1 P 0 
L 12.7849 3.56941998 12.81495 3.53936998 1 P 0 
P 12.81495 3.38188996 7 P 0 0;2=4,4=0
P 9.975 2.23955 5 P 0 0;2=3,4=1
L 9.975 2.23955 9.99115 2.2234 1 P 0 
L 9.99115 2.2234 10.04786004 2.2234 1 P 0 
L 10.04786004 2.2234 10.17456998 2.20103996 1 P 0 
L 10.17456998 2.20103996 10.25733002 2.14306004 1 P 0 
L 10.25733002 2.14306004 10.45196004 1.86511004 1 P 0 
L 10.45196004 1.86511004 10.5822 1.77388996 1 P 0 
L 10.5822 1.77388996 10.69293002 1.75436998 1 P 0 
L 10.69293002 1.75436998 10.83843996 1.78003996 1 P 0 
L 10.83843996 1.78003996 10.98676998 1.75388996 1 P 0 
L 10.98676998 1.75388996 11.11226998 1.77601998 1 P 0 
L 11.11226998 1.77601998 11.31866004 1.92051998 1 P 0 
L 11.31866004 1.92051998 11.50891998 2.19225 1 P 0 
L 11.50891998 2.19225 11.56371998 2.23061998 1 P 0 
L 11.56371998 2.23061998 11.65238002 2.35723002 1 P 0 
L 11.65238002 2.35723002 11.69166998 2.38473002 1 P 0 
L 11.69166998 2.38473002 11.72061004 2.38983002 1 P 0 
L 11.72061004 2.38983002 11.78105 2.43215 1 P 0 
L 11.78105 2.43215 12.44333996 3.37801004 1 P 0 
L 12.44333996 3.37801004 12.50498996 3.42116998 1 P 0 
L 12.50498996 3.42116998 12.53203996 3.42593996 1 P 0 
L 12.53203996 3.42593996 12.57218996 3.42593996 1 P 0 
L 12.57218996 3.42593996 12.62253002 3.46118002 1 P 0 
L 12.62253002 3.46118002 12.64153996 3.46453996 1 P 0 
L 12.64153996 3.46453996 12.75731004 3.46453996 1 P 0 
L 12.75731004 3.46453996 12.7849 3.43695 1 P 0 
L 12.7849 3.43695 12.7849 3.41193996 1 P 0 
L 12.7849 3.41193996 12.81495 3.38188996 1 P 0 
P 12.81495 2.20078996 7 P 0 0;2=4,4=0
P 10.42445 1.395 5 P 0 0;2=3,4=1
L 10.42445 1.395 10.4407 1.37875 1 P 0 
L 10.4407 1.37875 10.4407 1.36723996 1 P 0 
L 10.4407 1.36723996 10.44228996 1.35818002 1 P 0 
L 10.44228996 1.35818002 10.45006004 1.34708996 1 P 0 
L 10.45006004 1.34708996 10.68711998 1.18108996 1 P 0 
L 10.68711998 1.18108996 10.8528 1.15188002 1 P 0 
L 10.8528 1.15188002 11.48006004 1.26248996 1 P 0 
L 11.48006004 1.26248996 11.83525 1.19986004 1 P 0 
L 11.83525 1.19986004 12.1632 1.25768002 1 P 0 
L 12.1632 1.25768002 12.28366998 1.34203002 1 P 0 
L 12.28366998 1.34203002 12.33006004 1.40828002 1 P 0 
L 12.33006004 1.40828002 12.45193002 2.09948002 1 P 0 
L 12.45193002 2.09948002 12.47496004 2.13238996 1 P 0 
L 12.47496004 2.13238996 12.50016998 2.15005 1 P 0 
L 12.50016998 2.15005 12.53833996 2.15678002 1 P 0 
L 12.53833996 2.15678002 12.56278002 2.15678002 1 P 0 
L 12.56278002 2.15678002 12.57658996 2.15433996 1 P 0 
L 12.57658996 2.15433996 12.62366004 2.12138002 1 P 0 
L 12.62366004 2.12138002 12.63841004 2.11878002 1 P 0 
L 12.63841004 2.11878002 12.75831004 2.11878002 1 P 0 
L 12.75831004 2.11878002 12.7863 2.14676998 1 P 0 
L 12.7863 2.14676998 12.7863 2.17213996 1 P 0 
L 12.7863 2.17213996 12.81495 2.20078996 1 P 0 
P 12.81495 2.75196998 7 P 0 0;2=4,4=0
P 10.26025 1.82845 5 P 0 0;2=3,4=1
L 10.26025 1.82845 10.277 1.8452 1 P 0 
L 10.277 1.8452 10.30183996 1.8452 1 P 0 
L 10.30183996 1.8452 10.31591004 1.84271998 1 P 0 
L 10.31591004 1.84271998 10.33746004 1.82761998 1 P 0 
L 10.33746004 1.82761998 10.54933002 1.52501004 1 P 0 
L 10.54933002 1.52501004 10.5618 1.45426004 1 P 0 
L 10.5618 1.45426004 10.65011998 1.32811998 1 P 0 
L 10.65011998 1.32811998 10.7288 1.27303002 1 P 0 
L 10.7288 1.27303002 10.8599 1.24991004 1 P 0 
L 10.8599 1.24991004 11.08716998 1.28998002 1 P 0 
L 11.08716998 1.28998002 11.34696998 1.47188996 1 P 0 
L 11.34696998 1.47188996 11.34696998 1.47188002 1 P 0 
L 11.34696998 1.47188002 11.57035 1.51128996 1 P 0 
L 11.57035 1.51128996 11.65528002 1.57076004 1 P 0 
L 11.65528002 1.57076004 11.78918996 1.59436998 1 P 0 
L 11.78918996 1.59436998 11.82443002 1.61903996 1 P 0 
L 11.82443002 1.61903996 12.05393002 1.9468 1 P 0 
L 12.05393002 1.9468 12.0797 2.09291004 1 P 0 
L 12.0797 2.09291004 12.49623002 2.68773996 1 P 0 
L 12.49623002 2.68773996 12.52043002 2.70468996 1 P 0 
L 12.52043002 2.70468996 12.539 2.70796004 1 P 0 
L 12.539 2.70796004 12.56278002 2.70796004 1 P 0 
L 12.56278002 2.70796004 12.57658996 2.70551998 1 P 0 
L 12.57658996 2.70551998 12.62366004 2.67256004 1 P 0 
L 12.62366004 2.67256004 12.63841004 2.66996004 1 P 0 
L 12.63841004 2.66996004 12.75831004 2.66996004 1 P 0 
L 12.75831004 2.66996004 12.7863 2.69795 1 P 0 
L 12.7863 2.69795 12.7863 2.72331998 1 P 0 
L 12.7863 2.72331998 12.81495 2.75196998 1 P 0 
P 12.73621004 3.73621998 7 P 0 0;2=4,4=0
P 10.09 2.26825 5 P 0 0;2=3,4=1
L 10.09 2.26825 10.10635 2.2846 1 P 0 
L 10.10635 2.2846 10.141 2.2846 1 P 0 
L 10.141 2.2846 10.16546998 2.28028996 1 P 0 
L 10.16546998 2.28028996 10.24971998 2.22128996 1 P 0 
L 10.24971998 2.22128996 10.48048002 1.89171998 1 P 0 
L 10.48048002 1.89171998 10.59711998 1.81001998 1 P 0 
L 10.59711998 1.81001998 10.69353996 1.79303002 1 P 0 
L 10.69353996 1.79303002 10.83975 1.8188 1 P 0 
L 10.83975 1.8188 10.98741004 1.79276998 1 P 0 
L 10.98741004 1.79276998 11.09135 1.8111 1 P 0 
L 11.09135 1.8111 11.26626998 1.93356004 1 P 0 
L 11.26626998 1.93356004 11.48163996 2.24116004 1 P 0 
L 11.48163996 2.24116004 11.53826004 2.28078996 1 P 0 
L 11.53826004 2.28078996 11.59261998 2.35843996 1 P 0 
L 11.59261998 2.35843996 11.64208996 2.63891998 1 P 0 
L 11.64208996 2.63891998 11.67888996 2.69146998 1 P 0 
L 11.67888996 2.69146998 11.89076004 2.83983996 1 P 0 
L 11.89076004 2.83983996 12.50115 3.71236004 1 P 0 
L 12.50115 3.71236004 12.5252 3.7292 1 P 0 
L 12.5252 3.7292 12.549 3.7334 1 P 0 
L 12.549 3.7334 12.57456004 3.7334 1 P 0 
L 12.57456004 3.7334 12.62546998 3.76903996 1 P 0 
L 12.62546998 3.76903996 12.6422 3.772 1 P 0 
L 12.6422 3.772 12.7542 3.772 1 P 0 
L 12.7542 3.772 12.7774 3.7488 1 P 0 
L 12.7774 3.7488 12.7774 3.72271004 1 P 0 
L 12.7774 3.72271004 12.77278996 3.7181 1 P 0 
L 12.77278996 3.7181 12.75433002 3.7181 1 P 0 
L 12.75433002 3.7181 12.73621004 3.73621998 1 P 0 
P 10.09 2.69655 5 P 0 0;2=3,4=1
P 12.73621004 4.52361998 7 P 0 0;2=4,4=0
L 12.73621004 4.52361998 12.75653002 4.5033 1 P 0 
L 12.75653002 4.5033 12.76988996 4.5033 1 P 0 
L 12.76988996 4.5033 12.77623002 4.50963996 1 P 0 
L 12.77623002 4.50963996 12.77623002 4.54146998 1 P 0 
L 12.77623002 4.54146998 12.7582 4.5595 1 P 0 
L 12.7582 4.5595 12.6429 4.5595 1 P 0 
L 12.6429 4.5595 12.62506004 4.55636004 1 P 0 
L 12.62506004 4.55636004 12.62506004 4.55635 1 P 0 
L 12.62506004 4.55635 12.57663002 4.52241998 1 P 0 
L 12.57663002 4.52241998 12.56913002 4.5211 1 P 0 
L 12.56913002 4.5211 12.47996004 4.5211 1 P 0 
L 12.47996004 4.5211 11.94498002 4.42678996 1 P 0 
L 11.94498002 4.42678996 11.50796998 4.12083002 1 P 0 
L 11.50796998 4.12083002 10.83538996 4.00223002 1 P 0 
L 10.83538996 4.00223002 10.68866004 4.0281 1 P 0 
L 10.68866004 4.0281 10.52805 3.99978002 1 P 0 
L 10.52805 3.99978002 10.44958996 3.94483002 1 P 0 
L 10.44958996 3.94483002 10.42301004 3.90686998 1 P 0 
L 10.42301004 3.90686998 10.42301004 3.90686004 1 P 0 
L 10.42301004 3.90686004 10.39645 3.86893996 1 P 0 
L 10.39645 3.86893996 10.20166004 2.7646 1 P 0 
L 10.20166004 2.7646 10.18151004 2.73581998 1 P 0 
L 10.18151004 2.73581998 10.15541998 2.71756004 1 P 0 
L 10.15541998 2.71756004 10.13236004 2.7135 1 P 0 
L 10.13236004 2.7135 10.10695 2.7135 1 P 0 
L 10.10695 2.7135 10.09 2.69655 1 P 0 
P 12.73621004 3.57873996 7 P 0 0;2=4,4=0
P 9.975 2.3358 5 P 0 0;2=3,4=1
L 9.975 2.3358 9.99135 2.35215 1 P 0 
L 9.99135 2.35215 10.0102 2.35215 1 P 0 
L 10.0102 2.35215 10.02673002 2.34923996 1 P 0 
L 10.02673002 2.34923996 10.04096998 2.33926998 1 P 0 
L 10.04096998 2.33926998 10.05068002 2.3254 1 P 0 
L 10.05068002 2.3254 10.06263996 2.25755 1 P 0 
L 10.06263996 2.25755 10.0736 2.24191004 1 P 0 
L 10.0736 2.24191004 10.08255 2.23561998 1 P 0 
L 10.08255 2.23561998 10.18551004 2.21746004 1 P 0 
L 10.18551004 2.21746004 10.26078996 2.16478002 1 P 0 
L 10.26078996 2.16478002 10.46303002 1.87593002 1 P 0 
L 10.46303002 1.87593002 10.58833002 1.78818996 1 P 0 
L 10.58833002 1.78818996 10.69148996 1.77 1 P 0 
L 10.69148996 1.77 10.83831998 1.79586998 1 P 0 
L 10.83831998 1.79586998 10.98741004 1.76958996 1 P 0 
L 10.98741004 1.76958996 10.98871004 1.76981004 1 P 0 
L 10.98871004 1.76981004 10.98871004 1.76981998 1 P 0 
L 10.98871004 1.76981998 11.1003 1.7895 1 P 0 
L 11.1003 1.7895 11.29753996 1.92761004 1 P 0 
L 11.29753996 1.92761004 11.49943002 2.21593996 1 P 0 
L 11.49943002 2.21593996 11.55693002 2.25618996 1 P 0 
L 11.55693002 2.25618996 11.62221998 2.34945 1 P 0 
L 11.62221998 2.34945 11.64636004 2.48636998 1 P 0 
L 11.64636004 2.48636998 11.6735 2.52515 1 P 0 
L 11.6735 2.52515 11.70033996 2.54395 1 P 0 
L 11.70033996 2.54395 11.746 2.552 1 P 0 
L 11.746 2.552 11.79948002 2.58945 1 P 0 
L 11.79948002 2.58945 11.82938002 2.63215 1 P 0 
L 11.82938002 2.63215 12.44398002 3.50988002 1 P 0 
L 12.44398002 3.50988002 12.53496998 3.57358002 1 P 0 
L 12.53496998 3.57358002 12.54828002 3.57591998 1 P 0 
L 12.54828002 3.57591998 12.57456004 3.57591998 1 P 0 
L 12.57456004 3.57591998 12.62546998 3.61156004 1 P 0 
L 12.62546998 3.61156004 12.6422 3.61451998 1 P 0 
L 12.6422 3.61451998 12.7542 3.61451998 1 P 0 
L 12.7542 3.61451998 12.7774 3.59131998 1 P 0 
L 12.7774 3.59131998 12.7774 3.56523002 1 P 0 
L 12.7774 3.56523002 12.77278996 3.56061998 1 P 0 
L 12.77278996 3.56061998 12.75433002 3.56061998 1 P 0 
L 12.75433002 3.56061998 12.73621004 3.57873996 1 P 0 
P 12.73621004 3.42126004 7 P 0 0;2=4,4=0
P 9.975 2.19955 5 P 0 0;2=3,4=1
L 9.975 2.19955 9.99135 2.2159 1 P 0 
L 9.99135 2.2159 10.0472 2.2159 1 P 0 
L 10.0472 2.2159 10.17163002 2.19393996 1 P 0 
L 10.17163002 2.19393996 10.25193996 2.13766998 1 P 0 
L 10.25193996 2.13766998 10.44656998 1.85971998 1 P 0 
L 10.44656998 1.85971998 10.57926004 1.76678996 1 P 0 
L 10.57926004 1.76678996 10.69293002 1.74675 1 P 0 
L 10.69293002 1.74675 10.83843996 1.77241998 1 P 0 
L 10.83843996 1.77241998 10.98676998 1.74626998 1 P 0 
L 10.98676998 1.74626998 10.98806998 1.74648996 1 P 0 
L 10.98806998 1.74648996 10.98806998 1.7465 1 P 0 
L 10.98806998 1.7465 11.11521004 1.76891998 1 P 0 
L 11.11521004 1.76891998 11.32405 1.91513002 1 P 0 
L 11.32405 1.91513002 11.51431004 2.18686004 1 P 0 
L 11.51431004 2.18686004 11.56911004 2.22523002 1 P 0 
L 11.56911004 2.22523002 11.65776998 2.35183996 1 P 0 
L 11.65776998 2.35183996 11.69461004 2.37763002 1 P 0 
L 11.69461004 2.37763002 11.72355 2.38273002 1 P 0 
L 11.72355 2.38273002 11.78643996 2.42676004 1 P 0 
L 11.78643996 2.42676004 12.44873002 3.37261998 1 P 0 
L 12.44873002 3.37261998 12.50793002 3.41406998 1 P 0 
L 12.50793002 3.41406998 12.5327 3.41843996 1 P 0 
L 12.5327 3.41843996 12.57456004 3.41843996 1 P 0 
L 12.57456004 3.41843996 12.62546998 3.45408002 1 P 0 
L 12.62546998 3.45408002 12.6422 3.45703996 1 P 0 
L 12.6422 3.45703996 12.7542 3.45703996 1 P 0 
L 12.7542 3.45703996 12.7774 3.43383996 1 P 0 
L 12.7774 3.43383996 12.7774 3.40775 1 P 0 
L 12.7774 3.40775 12.77278996 3.40313996 1 P 0 
L 12.77278996 3.40313996 12.75433002 3.40313996 1 P 0 
L 12.75433002 3.40313996 12.73621004 3.42126004 1 P 0 
P 10.395 1.32555 5 P 0 0;2=3,4=1
P 12.73621004 2.00393996 7 P 0 0;2=4,4=0
L 12.73621004 2.00393996 12.75866004 2.00393996 1 P 0 
L 12.75866004 2.00393996 12.7673 1.9953 1 P 0 
L 12.7673 1.9953 12.7673 1.97701004 1 P 0 
L 12.7673 1.97701004 12.75868996 1.9684 1 P 0 
L 12.75868996 1.9684 12.64416998 1.9684 1 P 0 
L 12.64416998 1.9684 12.62546998 1.9717 1 P 0 
L 12.62546998 1.9717 12.57776004 2.00511998 1 P 0 
L 12.57776004 2.00511998 12.5654 2.0073 1 P 0 
L 12.5654 2.0073 12.5352 2.0073 1 P 0 
L 12.5352 2.0073 12.51918996 2.00448002 1 P 0 
L 12.51918996 2.00448002 12.46478002 1.96636004 1 P 0 
L 12.46478002 1.96636004 12.43701998 1.92671004 1 P 0 
L 12.43701998 1.92671004 12.34436004 1.40133996 1 P 0 
L 12.34436004 1.40133996 12.29541998 1.33143002 1 P 0 
L 12.29541998 1.33143002 12.16308002 1.23878002 1 P 0 
L 12.16308002 1.23878002 11.82466998 1.17911004 1 P 0 
L 11.82466998 1.17911004 11.48211998 1.23951004 1 P 0 
L 11.48211998 1.23951004 10.8491 1.1279 1 P 0 
L 10.8491 1.1279 10.76528002 1.14268002 1 P 0 
L 10.76528002 1.14268002 10.76528002 1.14268996 1 P 0 
L 10.76528002 1.14268996 10.68148996 1.15745 1 P 0 
L 10.68148996 1.15745 10.47505 1.30201998 1 P 0 
L 10.47505 1.30201998 10.432 1.3096 1 P 0 
L 10.432 1.3096 10.41095 1.3096 1 P 0 
L 10.41095 1.3096 10.395 1.32555 1 P 0 
P 3.38003996 5.22001998 5 P 0 0;2=3,4=1
P 2.97721004 2.865 5 P 0 0;2=3,4=1
L 2.97721004 2.865 2.99346004 2.84875 1 P 0 
L 2.99346004 2.84875 2.99881004 2.84875 1 P 0 
L 2.99881004 2.84875 3.0272 2.85376004 1 P 0 
L 3.0272 2.85376004 3.0358 2.85978002 1 P 0 
L 3.0358 2.85978002 3.03678002 2.86536004 1 P 0 
L 3.03678002 2.86536004 3.04538996 2.87138002 1 P 0 
L 3.04538996 2.87138002 3.05096004 2.8704 1 P 0 
L 3.05096004 2.8704 3.07673996 2.88845 1 P 0 
L 3.07673996 2.88845 3.08276004 2.89705 1 P 0 
L 3.08276004 2.89705 3.08178002 2.90261998 1 P 0 
L 3.08178002 2.90261998 3.0878 2.91123002 1 P 0 
L 3.0878 2.91123002 3.09338002 2.91221004 1 P 0 
L 3.09338002 2.91221004 3.0994 2.92081004 1 P 0 
L 3.0994 2.92081004 3.09841998 2.92638002 1 P 0 
L 3.09841998 2.92638002 3.10443996 2.93498996 1 P 0 
L 3.10443996 2.93498996 3.11001998 2.93596998 1 P 0 
L 3.11001998 2.93596998 3.11001004 2.93596998 1 P 0 
L 3.11001004 2.93596998 3.13781998 2.97565 1 P 0 
L 3.13781998 2.97565 3.27251004 3.73956004 1 P 0 
L 3.27251004 3.73956004 3.23616004 3.94573996 1 P 0 
L 3.23616004 3.94573996 3.34738996 4.57663996 1 P 0 
L 3.34738996 4.57663996 3.31631004 4.75298002 1 P 0 
L 3.31631004 4.75298002 3.33076004 4.83488002 1 P 0 
L 3.33076004 4.83488002 3.32388996 4.87353996 1 P 0 
L 3.32388996 4.87353996 3.33571004 4.94053002 1 P 0 
L 3.33571004 4.94053002 3.34933996 4.96 1 P 0 
L 3.34933996 4.96 3.34806004 4.96721004 1 P 0 
L 3.34806004 4.96721004 3.35443996 4.97631004 1 P 0 
L 3.35443996 4.97631004 3.36163996 4.97756998 1 P 0 
L 3.36163996 4.97756998 3.39058002 5.01891998 1 P 0 
L 3.39058002 5.01891998 3.39466998 5.04123002 1 P 0 
L 3.39466998 5.04123002 3.39088002 5.04668002 1 P 0 
L 3.39088002 5.04668002 3.39288996 5.05761004 1 P 0 
L 3.39288996 5.05761004 3.39836004 5.06138002 1 P 0 
L 3.39836004 5.06138002 3.40036998 5.07233002 1 P 0 
L 3.40036998 5.07233002 3.39658002 5.07778002 1 P 0 
L 3.39658002 5.07778002 3.39858996 5.08871004 1 P 0 
L 3.39858996 5.08871004 3.40406004 5.09248002 1 P 0 
L 3.40406004 5.09248002 3.40793002 5.11365 1 P 0 
L 3.40793002 5.11365 3.40585 5.12541004 1 P 0 
L 3.40585 5.12541004 3.40076998 5.12895 1 P 0 
L 3.40076998 5.12895 3.39883002 5.1399 1 P 0 
L 3.39883002 5.1399 3.4024 5.14496004 1 P 0 
L 3.4024 5.14496004 3.396 5.18133996 1 P 0 
L 3.396 5.18133996 3.396 5.20406004 1 P 0 
L 3.396 5.20406004 3.38003996 5.22001998 1 P 0 
P 3.42003996 5.22001998 5 P 0 0;2=3,4=1
P 2.97721004 2.825 5 P 0 0;2=3,4=1
L 2.97721004 2.825 2.99346004 2.84125 1 P 0 
L 2.99346004 2.84125 2.99946998 2.84125 1 P 0 
L 2.99946998 2.84125 3.03013996 2.84666004 1 P 0 
L 3.03013996 2.84666004 3.08213002 2.88306004 1 P 0 
L 3.08213002 2.88306004 3.14491998 2.97271004 1 P 0 
L 3.14491998 2.97271004 3.28013002 3.73956004 1 P 0 
L 3.28013002 3.73956004 3.24378002 3.94573996 1 P 0 
L 3.24378002 3.94573996 3.35501004 4.57663996 1 P 0 
L 3.35501004 4.57663996 3.32393002 4.75298002 1 P 0 
L 3.32393002 4.75298002 3.33838002 4.83488996 1 P 0 
L 3.33838002 4.83488996 3.33151004 4.87353996 1 P 0 
L 3.33151004 4.87353996 3.34281004 4.93758996 1 P 0 
L 3.34281004 4.93758996 3.39766998 5.01595 1 P 0 
L 3.39766998 5.01595 3.41556004 5.11361998 1 P 0 
L 3.41556004 5.11361998 3.4035 5.182 1 P 0 
L 3.4035 5.182 3.4035 5.20348002 1 P 0 
L 3.4035 5.20348002 3.42003996 5.22001998 1 P 0 
P 12.81495 3.22441004 7 P 0 0;2=4,4=0
P 10.09 2.13095 5 P 0 0;2=3,4=1
L 10.09 2.13095 10.10635 2.1473 1 P 0 
L 10.10635 2.1473 10.141 2.1473 1 P 0 
L 10.141 2.1473 10.18903996 2.13883002 1 P 0 
L 10.18903996 2.13883002 10.24351004 2.10068996 1 P 0 
L 10.24351004 2.10068996 10.41761998 1.85203996 1 P 0 
L 10.41761998 1.85203996 10.57078996 1.7448 1 P 0 
L 10.57078996 1.7448 10.69081998 1.72363996 1 P 0 
L 10.69081998 1.72363996 10.69211998 1.72386004 1 P 0 
L 10.69211998 1.72386004 10.69211998 1.72386998 1 P 0 
L 10.69211998 1.72386998 10.83656998 1.74933996 1 P 0 
L 10.83656998 1.74933996 10.98711998 1.72278002 1 P 0 
L 10.98711998 1.72278002 11.12883002 1.74778002 1 P 0 
L 11.12883002 1.74778002 11.25261004 1.83446004 1 P 0 
L 11.25261004 1.83446004 11.44901004 1.97198002 1 P 0 
L 11.44901004 1.97198002 11.592 1.9972 1 P 0 
L 11.592 1.9972 11.67153002 2.05288996 1 P 0 
L 11.67153002 2.05288996 11.84141998 2.08283996 1 P 0 
L 11.84141998 2.08283996 11.9369 2.1497 1 P 0 
L 11.9369 2.1497 12.2283 2.56586004 1 P 0 
L 12.2283 2.56586004 12.29085 2.92056004 1 P 0 
L 12.29085 2.92056004 12.43786004 3.13051998 1 P 0 
L 12.43786004 3.13051998 12.49901998 3.17335 1 P 0 
L 12.49901998 3.17335 12.539 3.1804 1 P 0 
L 12.539 3.1804 12.56278002 3.1804 1 P 0 
L 12.56278002 3.1804 12.57658996 3.17796004 1 P 0 
L 12.57658996 3.17796004 12.62366004 3.145 1 P 0 
L 12.62366004 3.145 12.63841004 3.1424 1 P 0 
L 12.63841004 3.1424 12.75831004 3.1424 1 P 0 
L 12.75831004 3.1424 12.7863 3.17038996 1 P 0 
L 12.7863 3.17038996 12.7863 3.19576004 1 P 0 
L 12.7863 3.19576004 12.81495 3.22441004 1 P 0 
P 10.09 2.40335 5 P 0 0;2=3,4=1
P 12.81495 3.85433002 7 P 0 0;2=4,4=0
L 12.81495 3.85433002 12.80428002 3.865 1 P 0 
L 12.80428002 3.865 12.77613996 3.865 1 P 0 
L 12.77613996 3.865 12.7624 3.85126004 1 P 0 
L 12.7624 3.85126004 12.64126004 3.85126004 1 P 0 
L 12.64126004 3.85126004 12.62048002 3.8476 1 P 0 
L 12.62048002 3.8476 12.57155 3.81333996 1 P 0 
L 12.57155 3.81333996 12.55581004 3.81056004 1 P 0 
L 12.55581004 3.81056004 12.53476004 3.81056004 1 P 0 
L 12.53476004 3.81056004 12.40451998 3.78758996 1 P 0 
L 12.40451998 3.78758996 11.26923002 3.98776004 1 P 0 
L 11.26923002 3.98776004 10.83741998 3.91163002 1 P 0 
L 10.83741998 3.91163002 10.69395 3.93693002 1 P 0 
L 10.69395 3.93693002 10.56068996 3.91343996 1 P 0 
L 10.56068996 3.91343996 10.52706998 3.8899 1 P 0 
L 10.52706998 3.8899 10.48763002 3.83356998 1 P 0 
L 10.48763002 3.83356998 10.2609 2.55598996 1 P 0 
L 10.2609 2.55598996 10.18151004 2.44261998 1 P 0 
L 10.18151004 2.44261998 10.15541998 2.42436004 1 P 0 
L 10.15541998 2.42436004 10.13236004 2.4203 1 P 0 
L 10.13236004 2.4203 10.10695 2.4203 1 P 0 
L 10.10695 2.4203 10.09 2.40335 1 P 0 
P 12.81495 3.69685 7 P 0 0;2=4,4=0
P 10.09 2.30825 5 P 0 0;2=3,4=1
L 10.09 2.30825 10.10615 2.2921 1 P 0 
L 10.10615 2.2921 10.14166004 2.2921 1 P 0 
L 10.14166004 2.2921 10.16841004 2.28738996 1 P 0 
L 10.16841004 2.28738996 10.25511004 2.22668002 1 P 0 
L 10.25511004 2.22668002 10.48586998 1.89711004 1 P 0 
L 10.48586998 1.89711004 10.60006004 1.81711998 1 P 0 
L 10.60006004 1.81711998 10.69353996 1.80065 1 P 0 
L 10.69353996 1.80065 10.83975 1.82641998 1 P 0 
L 10.83975 1.82641998 10.98741004 1.80038996 1 P 0 
L 10.98741004 1.80038996 11.08841004 1.8182 1 P 0 
L 11.08841004 1.8182 11.26088002 1.93895 1 P 0 
L 11.26088002 1.93895 11.47625 2.24655 1 P 0 
L 11.47625 2.24655 11.53286998 2.28618002 1 P 0 
L 11.53286998 2.28618002 11.58551998 2.36138002 1 P 0 
L 11.58551998 2.36138002 11.63498996 2.64186004 1 P 0 
L 11.63498996 2.64186004 11.6735 2.69686004 1 P 0 
L 11.6735 2.69686004 11.88536998 2.84523002 1 P 0 
L 11.88536998 2.84523002 12.49576004 3.71775 1 P 0 
L 12.49576004 3.71775 12.52226004 3.7363 1 P 0 
L 12.52226004 3.7363 12.54833996 3.7409 1 P 0 
L 12.54833996 3.7409 12.57218996 3.7409 1 P 0 
L 12.57218996 3.7409 12.62253002 3.77613996 1 P 0 
L 12.62253002 3.77613996 12.64153996 3.7795 1 P 0 
L 12.64153996 3.7795 12.75731004 3.7795 1 P 0 
L 12.75731004 3.7795 12.7849 3.75191004 1 P 0 
L 12.7849 3.75191004 12.7849 3.7269 1 P 0 
L 12.7849 3.7269 12.81495 3.69685 1 P 0 
P 12.81495 4.32676998 7 P 0 0;2=4,4=0
P 9.975 2.62445 5 P 0 0;2=3,4=1
L 9.975 2.62445 9.99195 2.6414 1 P 0 
L 9.99195 2.6414 10.04486998 2.6414 1 P 0 
L 10.04486998 2.6414 10.13373996 2.65706998 1 P 0 
L 10.13373996 2.65706998 10.17686998 2.68726004 1 P 0 
L 10.17686998 2.68726004 10.22453002 2.75531998 1 P 0 
L 10.22453002 2.75531998 10.41886004 3.85706998 1 P 0 
L 10.41886004 3.85706998 10.47256998 3.93378996 1 P 0 
L 10.47256998 3.93378996 10.53596998 3.97816998 1 P 0 
L 10.53596998 3.97816998 10.68988996 4.00531998 1 P 0 
L 10.68988996 4.00531998 10.83533996 3.97966998 1 P 0 
L 10.83533996 3.97966998 11.52655 4.10151004 1 P 0 
L 11.52655 4.10151004 11.95921998 4.40448002 1 P 0 
L 11.95921998 4.40448002 12.11096998 4.43123996 1 P 0 
L 12.11096998 4.43123996 12.31001004 4.39613996 1 P 0 
L 12.31001004 4.39613996 12.44846998 4.29921004 1 P 0 
L 12.44846998 4.29921004 12.54048002 4.283 1 P 0 
L 12.54048002 4.283 12.5558 4.283 1 P 0 
L 12.5558 4.283 12.57155 4.28578002 1 P 0 
L 12.57155 4.28578002 12.62048002 4.32003996 1 P 0 
L 12.62048002 4.32003996 12.64126004 4.3237 1 P 0 
L 12.64126004 4.3237 12.7624 4.3237 1 P 0 
L 12.7624 4.3237 12.7765 4.3378 1 P 0 
L 12.7765 4.3378 12.80391998 4.3378 1 P 0 
L 12.80391998 4.3378 12.81495 4.32676998 1 P 0 
P 10.09 2.73655 5 P 0 0;2=3,4=1
P 12.81495 4.48425 7 P 0 0;2=4,4=0
L 12.81495 4.48425 12.78373002 4.51546998 1 P 0 
L 12.78373002 4.51546998 12.78373002 4.54458002 1 P 0 
L 12.78373002 4.54458002 12.76131004 4.567 1 P 0 
L 12.76131004 4.567 12.64223996 4.567 1 P 0 
L 12.64223996 4.567 12.62211998 4.56346004 1 P 0 
L 12.62211998 4.56346004 12.57368996 4.52951998 1 P 0 
L 12.57368996 4.52951998 12.56846998 4.5286 1 P 0 
L 12.56846998 4.5286 12.4793 4.5286 1 P 0 
L 12.4793 4.5286 11.94203996 4.43388996 1 P 0 
L 11.94203996 4.43388996 11.50503002 4.12793002 1 P 0 
L 11.50503002 4.12793002 10.83538996 4.00985 1 P 0 
L 10.83538996 4.00985 10.68866004 4.03571998 1 P 0 
L 10.68866004 4.03571998 10.52511004 4.00688002 1 P 0 
L 10.52511004 4.00688002 10.4442 3.95021998 1 P 0 
L 10.4442 3.95021998 10.38935 3.87188002 1 P 0 
L 10.38935 3.87188002 10.19456004 2.76753996 1 P 0 
L 10.19456004 2.76753996 10.17611998 2.74121004 1 P 0 
L 10.17611998 2.74121004 10.15248002 2.72466004 1 P 0 
L 10.15248002 2.72466004 10.1317 2.721 1 P 0 
L 10.1317 2.721 10.10555 2.721 1 P 0 
L 10.10555 2.721 10.09 2.73655 1 P 0 
P 10.09 2.44335 5 P 0 0;2=3,4=1
P 12.73621004 3.8937 7 P 0 0;2=4,4=0
L 12.73621004 3.8937 12.76036004 3.8937 1 P 0 
L 12.76036004 3.8937 12.7686 3.88546004 1 P 0 
L 12.7686 3.88546004 12.7686 3.86806998 1 P 0 
L 12.7686 3.86806998 12.75928996 3.85876004 1 P 0 
L 12.75928996 3.85876004 12.6406 3.85876004 1 P 0 
L 12.6406 3.85876004 12.61753996 3.8547 1 P 0 
L 12.61753996 3.8547 12.56861004 3.82043996 1 P 0 
L 12.56861004 3.82043996 12.55515 3.81806004 1 P 0 
L 12.55515 3.81806004 12.5341 3.81806004 1 P 0 
L 12.5341 3.81806004 12.40451998 3.79521004 1 P 0 
L 12.40451998 3.79521004 11.26923002 3.99538002 1 P 0 
L 11.26923002 3.99538002 10.83741998 3.91925 1 P 0 
L 10.83741998 3.91925 10.69395 3.94455 1 P 0 
L 10.69395 3.94455 10.55775 3.92053996 1 P 0 
L 10.55775 3.92053996 10.52168002 3.89528996 1 P 0 
L 10.52168002 3.89528996 10.48053002 3.83651004 1 P 0 
L 10.48053002 3.83651004 10.2538 2.55893996 1 P 0 
L 10.2538 2.55893996 10.17611998 2.44801004 1 P 0 
L 10.17611998 2.44801004 10.15248002 2.43146004 1 P 0 
L 10.15248002 2.43146004 10.1317 2.4278 1 P 0 
L 10.1317 2.4278 10.10555 2.4278 1 P 0 
L 10.10555 2.4278 10.09 2.44335 1 P 0 
P 9.975 2.5109 5 P 0 0;2=3,4=1
P 12.81495 4.16928996 7 P 0 0;2=4,4=0
L 12.81495 4.16928996 12.78373002 4.20051004 1 P 0 
L 12.78373002 4.20051004 12.78373002 4.22961998 1 P 0 
L 12.78373002 4.22961998 12.76131004 4.25203996 1 P 0 
L 12.76131004 4.25203996 12.64223996 4.25203996 1 P 0 
L 12.64223996 4.25203996 12.62211998 4.2485 1 P 0 
L 12.62211998 4.2485 12.57368996 4.21456004 1 P 0 
L 12.57368996 4.21456004 12.56846998 4.21363996 1 P 0 
L 12.56846998 4.21363996 12.54226004 4.21363996 1 P 0 
L 12.54226004 4.21363996 12.49621998 4.18141004 1 P 0 
L 12.49621998 4.18141004 12.43793996 4.09816998 1 P 0 
L 12.43793996 4.09816998 12.28298002 3.98966004 1 P 0 
L 12.28298002 3.98966004 11.96718996 3.93398996 1 P 0 
L 11.96718996 3.93398996 11.31428996 4.04911998 1 P 0 
L 11.31428996 4.04911998 10.83553996 3.9647 1 P 0 
L 10.83553996 3.9647 10.6912 3.99015 1 P 0 
L 10.6912 3.99015 10.54216998 3.96388002 1 P 0 
L 10.54216998 3.96388002 10.48871004 3.92643996 1 P 0 
L 10.48871004 3.92643996 10.43438996 3.8489 1 P 0 
L 10.43438996 3.8489 10.23861004 2.74613996 1 P 0 
L 10.23861004 2.74613996 10.18753996 2.67321998 1 P 0 
L 10.18753996 2.67321998 10.12758996 2.63123002 1 P 0 
L 10.12758996 2.63123002 10.07366004 2.62173002 1 P 0 
L 10.07366004 2.62173002 10.05871004 2.61125 1 P 0 
L 10.05871004 2.61125 10.0505 2.59951998 1 P 0 
L 10.0505 2.59951998 10.03578996 2.51613002 1 P 0 
L 10.03578996 2.51613002 10.0281 2.50516004 1 P 0 
L 10.0281 2.50516004 10.01766004 2.49785 1 P 0 
L 10.01766004 2.49785 10.0035 2.49535 1 P 0 
L 10.0035 2.49535 9.99055 2.49535 1 P 0 
L 9.99055 2.49535 9.975 2.5109 1 P 0 
P 12.73621004 4.05118002 7 P 0 0;2=4,4=0
P 10.09 2.53845 5 P 0 0;2=3,4=1
L 10.09 2.53845 10.10695 2.5554 1 P 0 
L 10.10695 2.5554 10.13236004 2.5554 1 P 0 
L 10.13236004 2.5554 10.15541998 2.55946004 1 P 0 
L 10.15541998 2.55946004 10.18151004 2.57771998 1 P 0 
L 10.18151004 2.57771998 10.2609 2.6911 1 P 0 
L 10.2609 2.6911 10.46305 3.83773002 1 P 0 
L 10.46305 3.83773002 10.51046004 3.90538996 1 P 0 
L 10.51046004 3.90538996 10.55226004 3.93466998 1 P 0 
L 10.55226004 3.93466998 10.69351004 3.95956998 1 P 0 
L 10.69351004 3.95956998 10.83638996 3.93436998 1 P 0 
L 10.83638996 3.93436998 11.29081004 4.01448996 1 P 0 
L 11.29081004 4.01448996 11.96256004 3.89606004 1 P 0 
L 11.96256004 3.89606004 12.4165 3.97611004 1 P 0 
L 12.4165 3.97611004 12.51418002 4.04451004 1 P 0 
L 12.51418002 4.04451004 12.5377 4.04866004 1 P 0 
L 12.5377 4.04866004 12.56913002 4.04866004 1 P 0 
L 12.56913002 4.04866004 12.57663002 4.04998002 1 P 0 
L 12.57663002 4.04998002 12.62506004 4.08391998 1 P 0 
L 12.62506004 4.08391998 12.6429 4.08706004 1 P 0 
L 12.6429 4.08706004 12.7582 4.08706004 1 P 0 
L 12.7582 4.08706004 12.77623002 4.06903002 1 P 0 
L 12.77623002 4.06903002 12.77623002 4.0372 1 P 0 
L 12.77623002 4.0372 12.76988996 4.03086004 1 P 0 
L 12.76988996 4.03086004 12.75653002 4.03086004 1 P 0 
L 12.75653002 4.03086004 12.73621004 4.05118002 1 P 0 
P 12.81495 2.35826998 7 P 0 0;2=4,4=0
P 10.35543002 1.52156998 5 P 0 0;2=3,4=1
L 10.35543002 1.52156998 10.37816004 1.52156998 1 P 0 
L 10.37816004 1.52156998 10.38996004 1.53336998 1 P 0 
L 10.38996004 1.53336998 10.41488996 1.55081004 1 P 0 
L 10.41488996 1.55081004 10.43293996 1.554 1 P 0 
L 10.43293996 1.554 10.46363002 1.5486 1 P 0 
L 10.46363002 1.5486 10.48183996 1.53581998 1 P 0 
L 10.48183996 1.53581998 10.50193002 1.50711998 1 P 0 
L 10.50193002 1.50711998 10.5173 1.41995 1 P 0 
L 10.5173 1.41995 10.61031004 1.28711004 1 P 0 
L 10.61031004 1.28711004 10.70913996 1.2179 1 P 0 
L 10.70913996 1.2179 10.85491998 1.1922 1 P 0 
L 10.85491998 1.1922 11.61913002 1.32695 1 P 0 
L 11.61913002 1.32695 11.79176998 1.44785 1 P 0 
L 11.79176998 1.44785 12.09265 1.87753002 1 P 0 
L 12.09265 1.87753002 12.1295 2.08653002 1 P 0 
L 12.1295 2.08653002 12.36718002 2.42595 1 P 0 
L 12.36718002 2.42595 12.4071 2.4539 1 P 0 
L 12.4071 2.4539 12.43196004 2.45828002 1 P 0 
L 12.43196004 2.45828002 12.46298996 2.45281004 1 P 0 
L 12.46298996 2.45281004 12.48556998 2.437 1 P 0 
L 12.48556998 2.437 12.49755 2.41988996 1 P 0 
L 12.49755 2.41988996 12.5076 2.36286004 1 P 0 
L 12.5076 2.36286004 12.52763002 2.33423002 1 P 0 
L 12.52763002 2.33423002 12.54348996 2.32315 1 P 0 
L 12.54348996 2.32315 12.55898996 2.32041998 1 P 0 
L 12.55898996 2.32041998 12.56706998 2.32185 1 P 0 
L 12.56706998 2.32185 12.61981004 2.35876004 1 P 0 
L 12.61981004 2.35876004 12.63868002 2.3621 1 P 0 
L 12.63868002 2.3621 12.76108002 2.3621 1 P 0 
L 12.76108002 2.3621 12.77458002 2.3486 1 P 0 
L 12.77458002 2.3486 12.80528002 2.3486 1 P 0 
L 12.80528002 2.3486 12.81495 2.35826998 1 P 0 
P 12.73621004 2.16141998 7 P 0 0;2=4,4=0
P 10.46445 1.395 5 P 0 0;2=3,4=1
L 10.46445 1.395 10.4482 1.37875 1 P 0 
L 10.4482 1.37875 10.4482 1.3679 1 P 0 
L 10.4482 1.3679 10.44938996 1.36111998 1 P 0 
L 10.44938996 1.36111998 10.45545 1.35248002 1 P 0 
L 10.45545 1.35248002 10.47145 1.34126998 1 P 0 
L 10.47145 1.34126998 10.48013002 1.34281004 1 P 0 
L 10.48013002 1.34281004 10.48923996 1.33643002 1 P 0 
L 10.48923996 1.33643002 10.49076004 1.32775 1 P 0 
L 10.49076004 1.32775 10.49986998 1.32136998 1 P 0 
L 10.49986998 1.32136998 10.50855 1.32291004 1 P 0 
L 10.50855 1.32291004 10.51766004 1.31653002 1 P 0 
L 10.51766004 1.31653002 10.51918002 1.30786004 1 P 0 
L 10.51918002 1.30786004 10.69006004 1.18818996 1 P 0 
L 10.69006004 1.18818996 10.8528 1.1595 1 P 0 
L 10.8528 1.1595 11.48006004 1.27011004 1 P 0 
L 11.48006004 1.27011004 11.83525 1.20748002 1 P 0 
L 11.83525 1.20748002 12.16026004 1.26478002 1 P 0 
L 12.16026004 1.26478002 12.27828002 1.34741998 1 P 0 
L 12.27828002 1.34741998 12.32296004 1.41121998 1 P 0 
L 12.32296004 1.41121998 12.44483002 2.10241998 1 P 0 
L 12.44483002 2.10241998 12.46956998 2.13778002 1 P 0 
L 12.46956998 2.13778002 12.49723002 2.15715 1 P 0 
L 12.49723002 2.15715 12.53768002 2.16428002 1 P 0 
L 12.53768002 2.16428002 12.56343996 2.16428002 1 P 0 
L 12.56343996 2.16428002 12.57953002 2.16143996 1 P 0 
L 12.57953002 2.16143996 12.6266 2.12848002 1 P 0 
L 12.6266 2.12848002 12.63906998 2.12628002 1 P 0 
L 12.63906998 2.12628002 12.7552 2.12628002 1 P 0 
L 12.7552 2.12628002 12.7788 2.14988002 1 P 0 
L 12.7788 2.14988002 12.7788 2.1741 1 P 0 
L 12.7788 2.1741 12.7751 2.1778 1 P 0 
L 12.7751 2.1778 12.75258996 2.1778 1 P 0 
L 12.75258996 2.1778 12.73621004 2.16141998 1 P 0 
L 1.88908002 -1.91246004 1.89293002 -1.91246004 0 P 0 ;0
L 1.89126998 -1.91146004 1.89656998 -1.91146004 0 P 0 ;0
L 1.89393996 -1.91046004 1.9155 -1.91046004 0 P 0 ;0
L 1.91593996 -1.91246004 1.92048996 -1.91246004 0 P 0 ;0
L 1.9126 -1.91146004 1.9184 -1.91146004 0 P 0 ;0
L 1.89763002 -1.90946004 1.91016998 -1.90946004 0 P 0 ;0
L 1.89053002 -1.96001004 1.8974 -1.96001004 0 P 0 ;0
L 1.89053002 -1.95901004 1.8974 -1.95901004 0 P 0 ;0
L 1.89053002 -1.95801004 1.8974 -1.95801004 0 P 0 ;0
L 1.89053002 -1.95701004 1.8974 -1.95701004 0 P 0 ;0
L 1.89053002 -1.95601004 1.8974 -1.95601004 0 P 0 ;0
L 1.89053002 -1.95501004 1.8974 -1.95501004 0 P 0 ;0
L 1.89053002 -1.95401004 1.8974 -1.95401004 0 P 0 ;0
L 1.89053002 -1.95301004 1.89741004 -1.95301004 0 P 0 ;0
L 1.89053002 -1.95201004 1.89741998 -1.95201004 0 P 0 ;0
L 1.89053002 -1.95101004 1.89743996 -1.95101004 0 P 0 ;0
L 1.89053002 -1.95001004 1.89745 -1.95001004 0 P 0 ;0
L 1.89053002 -1.94901004 1.89746004 -1.94901004 0 P 0 ;0
L 1.89053002 -1.94801004 1.89753002 -1.94801004 0 P 0 ;0
L 1.89053002 -1.94701004 1.8977 -1.94701004 0 P 0 ;0
L 1.89053002 -1.94601004 1.89798002 -1.94601004 0 P 0 ;0
L 1.89053002 -1.94501004 1.89861004 -1.94501004 0 P 0 ;0
L 1.89053002 -1.94401004 1.90005 -1.94401004 0 P 0 ;0
L 1.89053002 -1.94301004 1.9113 -1.94301004 0 P 0 ;0
L 1.89053002 -1.94201004 1.91168002 -1.94201004 0 P 0 ;0
L 1.89053002 -1.94101004 1.91246998 -1.94101004 0 P 0 ;0
L 1.89053002 -1.94001004 1.90093996 -1.94001004 0 P 0 ;0
L 1.89053002 -1.93901004 1.89856004 -1.93901004 0 P 0 ;0
L 1.89053002 -1.93801004 1.89786998 -1.93801004 0 P 0 ;0
L 1.89053002 -1.93701004 1.89753996 -1.93701004 0 P 0 ;0
L 1.89053002 -1.93601004 1.89746998 -1.93601004 0 P 0 ;0
L 1.89053002 -1.93501004 1.89743996 -1.93501004 0 P 0 ;0
L 1.89053002 -1.93401004 1.89741998 -1.93401004 0 P 0 ;0
L 1.89053002 -1.93301004 1.8974 -1.93301004 0 P 0 ;0
L 1.89053002 -1.93201004 1.8974 -1.93201004 0 P 0 ;0
L 1.89053002 -1.93101004 1.8974 -1.93101004 0 P 0 ;0
L 1.89053002 -1.93001004 1.8974 -1.93001004 0 P 0 ;0
L 1.89053002 -1.92901004 1.8974 -1.92901004 0 P 0 ;0
L 1.89053002 -1.92801004 1.89753002 -1.92801004 0 P 0 ;0
L 1.89053002 -1.92701004 1.89793996 -1.92701004 0 P 0 ;0
L 1.89053002 -1.92601004 1.91713002 -1.92601004 0 P 0 ;0
L 1.89053002 -1.92501004 1.91628996 -1.92501004 0 P 0 ;0
L 1.89053002 -1.92401004 1.91513996 -1.92401004 0 P 0 ;0
L 1.89053002 -1.92301004 1.91321998 -1.92301004 0 P 0 ;0
L 1.89053002 -1.92201004 1.90551004 -1.92201004 0 P 0 ;0
L 1.89438996 -1.97246004 1.91331004 -1.97246004 0 P 0 ;0
L 1.89106998 -1.97146004 1.89973002 -1.97146004 0 P 0 ;0
L 1.88878002 -1.97046004 1.8949 -1.97046004 0 P 0 ;0
L 1.88698002 -1.96946004 1.89206998 -1.96946004 0 P 0 ;0
L 1.88546004 -1.96846004 1.88986998 -1.96846004 0 P 0 ;0
L 1.88416998 -1.96746004 1.88808996 -1.96746004 0 P 0 ;0
L 1.88288002 -1.96646004 1.88655 -1.96646004 0 P 0 ;0
L 1.88176998 -1.96546004 1.88518002 -1.96546004 0 P 0 ;0
L 1.88068996 -1.96446004 1.88393996 -1.96446004 0 P 0 ;0
L 1.87968996 -1.96346004 1.88286004 -1.96346004 0 P 0 ;0
L 1.87878002 -1.96246004 1.88186004 -1.96246004 0 P 0 ;0
L 1.8786 -1.92046004 1.88126998 -1.92046004 0 P 0 ;0
L 1.87946998 -1.91946004 1.88223002 -1.91946004 0 P 0 ;0
L 1.88048002 -1.91846004 1.88321004 -1.91846004 0 P 0 ;0
L 1.88153996 -1.91746004 1.88436998 -1.91746004 0 P 0 ;0
L 1.88273002 -1.91646004 1.88558996 -1.91646004 0 P 0 ;0
L 1.88406004 -1.91546004 1.88696998 -1.91546004 0 P 0 ;0
L 1.88548996 -1.91446004 1.88853002 -1.91446004 0 P 0 ;0
L 1.88718002 -1.91346004 1.89041998 -1.91346004 0 P 0 ;0
L 1.90896004 -1.92963996 1.90921998 -1.92991998 0 P 0 ;0
L 1.90921998 -1.92991998 1.90945 -1.93021998 0 P 0 ;0
L 1.90945 -1.93021998 1.90966004 -1.93053002 0 P 0 ;0
L 1.90966004 -1.93053002 1.90983002 -1.93086004 0 P 0 ;0
L 1.90983002 -1.93086004 1.90998002 -1.93121004 0 P 0 ;0
L 1.90998002 -1.93121004 1.9101 -1.93156998 0 P 0 ;0
L 1.9101 -1.93156998 1.91018996 -1.93193996 0 P 0 ;0
L 1.91018996 -1.93193996 1.91023996 -1.93231004 0 P 0 ;0
L 1.91023996 -1.93231004 1.91026998 -1.93265 0 P 0 ;0
L 1.91026998 -1.93265 1.91026004 -1.93298002 0 P 0 ;0
L 1.91026004 -1.93298002 1.91023002 -1.93331004 0 P 0 ;0
L 1.91023002 -1.93331004 1.91016998 -1.93363996 0 P 0 ;0
L 1.91016998 -1.93363996 1.91008996 -1.93396004 0 P 0 ;0
L 1.91008996 -1.93396004 1.90998002 -1.93428002 0 P 0 ;0
L 1.90998002 -1.93428002 1.90983996 -1.93458002 0 P 0 ;0
L 1.90983996 -1.93458002 1.90968996 -1.93486998 0 P 0 ;0
L 1.90968996 -1.93486998 1.90951004 -1.93516004 0 P 0 ;0
L 1.90951004 -1.93516004 1.90921004 -1.93556004 0 P 0 ;0
L 1.90921004 -1.93556004 1.90888002 -1.93593002 0 P 0 ;0
L 1.90888002 -1.93593002 1.90853002 -1.93626998 0 P 0 ;0
L 1.90853002 -1.93626998 1.90815 -1.93658996 0 P 0 ;0
L 1.90815 -1.93658996 1.90773996 -1.93686998 0 P 0 ;0
L 1.90773996 -1.93686998 1.90731998 -1.93711998 0 P 0 ;0
L 1.90731998 -1.93711998 1.90686998 -1.93733996 0 P 0 ;0
L 1.90686998 -1.93733996 1.90615 -1.93761004 0 P 0 ;0
L 1.90615 -1.93761004 1.90541998 -1.93783002 0 P 0 ;0
L 1.90541998 -1.93783002 1.90466004 -1.93798002 0 P 0 ;0
L 1.90466004 -1.93798002 1.9039 -1.93808002 0 P 0 ;0
L 1.9039 -1.93808002 1.90311998 -1.9381 0 P 0 ;0
L 1.90311998 -1.9381 1.90196004 -1.93808002 0 P 0 ;0
L 1.90196004 -1.93808002 1.90078996 -1.93798996 0 P 0 ;0
L 1.90078996 -1.93798996 1.90068002 -1.93798002 0 P 0 ;0
L 1.90068002 -1.93798002 1.90058002 -1.93795 0 P 0 ;0
L 1.90058002 -1.93795 1.90046998 -1.93791998 0 P 0 ;0
L 1.90046998 -1.93791998 1.90038002 -1.93788002 0 P 0 ;0
L 1.90038002 -1.93788002 1.90028002 -1.93783002 0 P 0 ;0
L 1.90028002 -1.93783002 1.90018996 -1.93778002 0 P 0 ;0
L 1.90018996 -1.93778002 1.9001 -1.93771004 0 P 0 ;0
L 1.9001 -1.93771004 1.90001998 -1.93763996 0 P 0 ;0
L 1.90001998 -1.93763996 1.89988002 -1.93748002 0 P 0 ;0
L 1.89988002 -1.93748002 1.89978002 -1.93733996 0 P 0 ;0
L 1.89978002 -1.93733996 1.89961998 -1.93703996 0 P 0 ;0
L 1.89961998 -1.93703996 1.89956998 -1.93688002 0 P 0 ;0
L 1.89956998 -1.93688002 1.89951998 -1.93671004 0 P 0 ;0
L 1.89951998 -1.93671004 1.89948996 -1.93655 0 P 0 ;0
L 1.89948996 -1.93655 1.89946998 -1.93636998 0 P 0 ;0
L 1.89946998 -1.93636998 1.8994 -1.93323002 0 P 0 ;0
L 1.8994 -1.93323002 1.8994 -1.92833002 0 P 0 ;0
L 1.8994 -1.92833002 1.90353996 -1.92833002 0 P 0 ;0
L 1.90353996 -1.92833002 1.90436998 -1.92835 0 P 0 ;0
L 1.90436998 -1.92835 1.9052 -1.92843002 0 P 0 ;0
L 1.9052 -1.92843002 1.90603002 -1.92853996 0 P 0 ;0
L 1.90603002 -1.92853996 1.90683996 -1.92871004 0 P 0 ;0
L 1.90683996 -1.92871004 1.90751004 -1.9289 0 P 0 ;0
L 1.90751004 -1.9289 1.90818002 -1.92913002 0 P 0 ;0
L 1.90818002 -1.92913002 1.90851998 -1.92928996 0 P 0 ;0
L 1.90851998 -1.92928996 1.90868002 -1.92938996 0 P 0 ;0
L 1.90868002 -1.92938996 1.90883002 -1.92951004 0 P 0 ;0
L 1.90883002 -1.92951004 1.90896004 -1.92963996 0 P 0 ;0
L 1.91188996 -1.96001004 1.91638996 -1.96001004 0 P 0 ;0
L 1.91156998 -1.95901004 1.91926998 -1.95901004 0 P 0 ;0
L 1.91125 -1.95801004 1.91891998 -1.95801004 0 P 0 ;0
L 1.91091998 -1.95701004 1.91853002 -1.95701004 0 P 0 ;0
L 1.9106 -1.95601004 1.91811004 -1.95601004 0 P 0 ;0
L 1.91025 -1.95501004 1.91765 -1.95501004 0 P 0 ;0
L 1.90988996 -1.95401004 1.91718996 -1.95401004 0 P 0 ;0
L 1.90953002 -1.95301004 1.91673002 -1.95301004 0 P 0 ;0
L 1.90918002 -1.95201004 1.91626998 -1.95201004 0 P 0 ;0
L 1.90881998 -1.95101004 1.91576004 -1.95101004 0 P 0 ;0
L 1.90841004 -1.95001004 1.91523996 -1.95001004 0 P 0 ;0
L 1.90793996 -1.94901004 1.91471004 -1.94901004 0 P 0 ;0
L 1.90738996 -1.94801004 1.91418002 -1.94801004 0 P 0 ;0
L 1.90676998 -1.94701004 1.9136 -1.94701004 0 P 0 ;0
L 1.90598996 -1.94601004 1.91261004 -1.94601004 0 P 0 ;0
L 1.90495 -1.94501004 1.91175 -1.94501004 0 P 0 ;0
L 1.90325 -1.94401004 1.91133002 -1.94401004 0 P 0 ;0
L 1.90456004 -1.94001004 1.91383002 -1.94001004 0 P 0 ;0
L 1.90801004 -1.93901004 1.91523002 -1.93901004 0 P 0 ;0
L 1.90956998 -1.93801004 1.91635 -1.93801004 0 P 0 ;0
L 1.9106 -1.93701004 1.91718002 -1.93701004 0 P 0 ;0
L 1.91133996 -1.93601004 1.91781004 -1.93601004 0 P 0 ;0
L 1.91183996 -1.93501004 1.91826004 -1.93501004 0 P 0 ;0
L 1.91213002 -1.93401004 1.9186 -1.93401004 0 P 0 ;0
L 1.91226004 -1.93301004 1.9188 -1.93301004 0 P 0 ;0
L 1.91221998 -1.93201004 1.9189 -1.93201004 0 P 0 ;0
L 1.91201998 -1.93101004 1.9189 -1.93101004 0 P 0 ;0
L 1.91163996 -1.93001004 1.91878996 -1.93001004 0 P 0 ;0
L 1.91105 -1.92901004 1.91856998 -1.92901004 0 P 0 ;0
L 1.91013996 -1.92801004 1.91823002 -1.92801004 0 P 0 ;0
L 1.90816998 -1.92701004 1.91776004 -1.92701004 0 P 0 ;0
L 1.90313996 -1.94011004 1.90316998 -1.9401 0 P 0 ;0
L 1.90316998 -1.9401 1.9032 -1.9401 0 P 0 ;0
L 1.9032 -1.9401 1.90398002 -1.94006998 0 P 0 ;0
L 1.90398002 -1.94006998 1.90406004 -1.94006998 0 P 0 ;0
L 1.90406004 -1.94006998 1.90413996 -1.94006004 0 P 0 ;0
L 1.90413996 -1.94006004 1.9049 -1.93996998 0 P 0 ;0
L 1.9049 -1.93996998 1.90493996 -1.93996004 0 P 0 ;0
L 1.90493996 -1.93996004 1.90498996 -1.93996004 0 P 0 ;0
L 1.90498996 -1.93996004 1.90506998 -1.93993996 0 P 0 ;0
L 1.90506998 -1.93993996 1.90581998 -1.93978002 0 P 0 ;0
L 1.90581998 -1.93978002 1.90586004 -1.93978002 0 P 0 ;0
L 1.90586004 -1.93978002 1.90593996 -1.93976004 0 P 0 ;0
L 1.90593996 -1.93976004 1.90596998 -1.93973996 0 P 0 ;0
L 1.90596998 -1.93973996 1.90671004 -1.93953002 0 P 0 ;0
L 1.90671004 -1.93953002 1.90678996 -1.93951004 0 P 0 ;0
L 1.90678996 -1.93951004 1.90758996 -1.93921004 0 P 0 ;0
L 1.90758996 -1.93921004 1.90766004 -1.93916998 0 P 0 ;0
L 1.90766004 -1.93916998 1.9077 -1.93915 0 P 0 ;0
L 1.9077 -1.93915 1.90773996 -1.93913996 0 P 0 ;0
L 1.90773996 -1.93913996 1.90818996 -1.93891998 0 P 0 ;0
L 1.90818996 -1.93891998 1.90821998 -1.9389 0 P 0 ;0
L 1.90821998 -1.9389 1.90826004 -1.93888996 0 P 0 ;0
L 1.90826004 -1.93888996 1.90828996 -1.93886998 0 P 0 ;0
L 1.90828996 -1.93886998 1.90833002 -1.93885 0 P 0 ;0
L 1.90833002 -1.93885 1.90875 -1.9386 0 P 0 ;0
L 1.90875 -1.9386 1.90883002 -1.93856004 0 P 0 ;0
L 1.90883002 -1.93856004 1.90888996 -1.93851004 0 P 0 ;0
L 1.90888996 -1.93851004 1.90928996 -1.93823002 0 P 0 ;0
L 1.90928996 -1.93823002 1.90933002 -1.9382 0 P 0 ;0
L 1.90933002 -1.9382 1.90936004 -1.93818002 0 P 0 ;0
L 1.90936004 -1.93818002 1.90938996 -1.93815 0 P 0 ;0
L 1.90938996 -1.93815 1.90941998 -1.93813002 0 P 0 ;0
L 1.90941998 -1.93813002 1.9098 -1.93781998 0 P 0 ;0
L 1.9098 -1.93781998 1.90986004 -1.93776004 0 P 0 ;0
L 1.90986004 -1.93776004 1.90988996 -1.93773996 0 P 0 ;0
L 1.90988996 -1.93773996 1.90991998 -1.93771004 0 P 0 ;0
L 1.90991998 -1.93771004 1.91028002 -1.93736004 0 P 0 ;0
L 1.91028002 -1.93736004 1.91038996 -1.93725 0 P 0 ;0
L 1.91038996 -1.93725 1.91071004 -1.93688002 0 P 0 ;0
L 1.91071004 -1.93688002 1.91073996 -1.93685 0 P 0 ;0
L 1.91073996 -1.93685 1.91116004 -1.9363 0 P 0 ;0
L 1.91116004 -1.9363 1.9112 -1.93623002 0 P 0 ;0
L 1.9112 -1.93623002 1.91138002 -1.93595 0 P 0 ;0
L 1.91138002 -1.93595 1.9114 -1.93591004 0 P 0 ;0
L 1.9114 -1.93591004 1.91143996 -1.93585 0 P 0 ;0
L 1.91143996 -1.93585 1.91146004 -1.93581004 0 P 0 ;0
L 1.91146004 -1.93581004 1.91161004 -1.93551998 0 P 0 ;0
L 1.91161004 -1.93551998 1.91163002 -1.93548996 0 P 0 ;0
L 1.91163002 -1.93548996 1.91165 -1.93545 0 P 0 ;0
L 1.91165 -1.93545 1.91166004 -1.93541004 0 P 0 ;0
L 1.91166004 -1.93541004 1.91168002 -1.93538002 0 P 0 ;0
L 1.91168002 -1.93538002 1.91181004 -1.93506998 0 P 0 ;0
L 1.91181004 -1.93506998 1.91183996 -1.935 0 P 0 ;0
L 1.91183996 -1.935 1.91186004 -1.93496004 0 P 0 ;0
L 1.91186004 -1.93496004 1.91186998 -1.93493002 0 P 0 ;0
L 1.91186998 -1.93493002 1.91198002 -1.93461004 0 P 0 ;0
L 1.91198002 -1.93461004 1.91198996 -1.93456998 0 P 0 ;0
L 1.91198996 -1.93456998 1.912 -1.93453996 0 P 0 ;0
L 1.912 -1.93453996 1.9121 -1.93413996 0 P 0 ;0
L 1.9121 -1.93413996 1.91211998 -1.9341 0 P 0 ;0
L 1.91211998 -1.9341 1.91211998 -1.93406004 0 P 0 ;0
L 1.91211998 -1.93406004 1.91213002 -1.93401998 0 P 0 ;0
L 1.91213002 -1.93401998 1.91213996 -1.93398996 0 P 0 ;0
L 1.91213996 -1.93398996 1.9122 -1.93366004 0 P 0 ;0
L 1.9122 -1.93366004 1.91221004 -1.93358002 0 P 0 ;0
L 1.91221004 -1.93358002 1.91221004 -1.93353996 0 P 0 ;0
L 1.91221004 -1.93353996 1.91221998 -1.9335 0 P 0 ;0
L 1.91221998 -1.9335 1.91225 -1.93316998 0 P 0 ;0
L 1.91225 -1.93316998 1.91226004 -1.93308996 0 P 0 ;0
L 1.91226004 -1.93308996 1.91226004 -1.93268002 0 P 0 ;0
L 1.91226004 -1.93268002 1.91226998 -1.93263996 0 P 0 ;0
L 1.91226998 -1.93263996 1.91226998 -1.9326 0 P 0 ;0
L 1.91226998 -1.9326 1.91226004 -1.93251998 0 P 0 ;0
L 1.91226004 -1.93251998 1.91223996 -1.93218996 0 P 0 ;0
L 1.91223996 -1.93218996 1.91223996 -1.93215 0 P 0 ;0
L 1.91223996 -1.93215 1.91223002 -1.9321 0 P 0 ;0
L 1.91223002 -1.9321 1.91223002 -1.93206004 0 P 0 ;0
L 1.91223002 -1.93206004 1.91221998 -1.93201998 0 P 0 ;0
L 1.91221998 -1.93201998 1.91216998 -1.93163996 0 P 0 ;0
L 1.91216998 -1.93163996 1.91216004 -1.9316 0 P 0 ;0
L 1.91216004 -1.9316 1.91213996 -1.93151004 0 P 0 ;0
L 1.91213996 -1.93151004 1.91213002 -1.93146998 0 P 0 ;0
L 1.91213002 -1.93146998 1.91205 -1.93111004 0 P 0 ;0
L 1.91205 -1.93111004 1.91203996 -1.93106004 0 P 0 ;0
L 1.91203996 -1.93106004 1.91203002 -1.93101998 0 P 0 ;0
L 1.91203002 -1.93101998 1.91201004 -1.93098002 0 P 0 ;0
L 1.91201004 -1.93098002 1.912 -1.93093996 0 P 0 ;0
L 1.912 -1.93093996 1.91188002 -1.93058002 0 P 0 ;0
L 1.91188002 -1.93058002 1.91186998 -1.93053996 0 P 0 ;0
L 1.91186998 -1.93053996 1.91185 -1.9305 0 P 0 ;0
L 1.91185 -1.9305 1.91183996 -1.93046004 0 P 0 ;0
L 1.91183996 -1.93046004 1.91181998 -1.93043002 0 P 0 ;0
L 1.91181998 -1.93043002 1.91166998 -1.93008002 0 P 0 ;0
L 1.91166998 -1.93008002 1.91166004 -1.93003996 0 P 0 ;0
L 1.91166004 -1.93003996 1.9116 -1.92991998 0 P 0 ;0
L 1.9116 -1.92991998 1.91141998 -1.92958996 0 P 0 ;0
L 1.91141998 -1.92958996 1.9114 -1.92955 0 P 0 ;0
L 1.9114 -1.92955 1.91138002 -1.92951998 0 P 0 ;0
L 1.91138002 -1.92951998 1.91133002 -1.92945 0 P 0 ;0
L 1.91133002 -1.92945 1.91113002 -1.92913002 0 P 0 ;0
L 1.91113002 -1.92913002 1.91111004 -1.92908996 0 P 0 ;0
L 1.91111004 -1.92908996 1.91108996 -1.92906004 0 P 0 ;0
L 1.91108996 -1.92906004 1.91106004 -1.92901998 0 P 0 ;0
L 1.91106004 -1.92901998 1.91103002 -1.92898996 0 P 0 ;0
L 1.91103002 -1.92898996 1.9108 -1.92868996 0 P 0 ;0
L 1.9108 -1.92868996 1.91076998 -1.92866004 0 P 0 ;0
L 1.91076998 -1.92866004 1.91075 -1.92861998 0 P 0 ;0
L 1.91075 -1.92861998 1.91068996 -1.92856004 0 P 0 ;0
L 1.91068996 -1.92856004 1.91043002 -1.92828002 0 P 0 ;0
L 1.91043002 -1.92828002 1.91035 -1.9282 0 P 0 ;0
L 1.91035 -1.9282 1.91033002 -1.92816998 0 P 0 ;0
L 1.91033002 -1.92816998 1.91018996 -1.92803996 0 P 0 ;0
L 1.91018996 -1.92803996 1.91018002 -1.92803996 0 P 0 ;0
L 1.91018002 -1.92803996 1.91016004 -1.92801998 0 P 0 ;0
L 1.91016004 -1.92801998 1.91011998 -1.92798996 0 P 0 ;0
L 1.91011998 -1.92798996 1.91006004 -1.92793002 0 P 0 ;0
L 1.91006004 -1.92793002 1.90991004 -1.92781998 0 P 0 ;0
L 1.90991004 -1.92781998 1.90988002 -1.9278 0 P 0 ;0
L 1.90988002 -1.9278 1.90983996 -1.92776998 0 P 0 ;0
L 1.90983996 -1.92776998 1.90976998 -1.92771998 0 P 0 ;0
L 1.90976998 -1.92771998 1.90961004 -1.92761998 0 P 0 ;0
L 1.90961004 -1.92761998 1.90953996 -1.92756998 0 P 0 ;0
L 1.90953996 -1.92756998 1.9095 -1.92755 0 P 0 ;0
L 1.9095 -1.92755 1.90946998 -1.92753002 0 P 0 ;0
L 1.90946998 -1.92753002 1.9093 -1.92743996 0 P 0 ;0
L 1.9093 -1.92743996 1.90926004 -1.92741998 0 P 0 ;0
L 1.90926004 -1.92741998 1.90923002 -1.9274 0 P 0 ;0
L 1.90923002 -1.9274 1.90915 -1.92736998 0 P 0 ;0
L 1.90915 -1.92736998 1.90896998 -1.92728996 0 P 0 ;0
L 1.90896998 -1.92728996 1.90893996 -1.92728002 0 P 0 ;0
L 1.90893996 -1.92728002 1.9089 -1.92726004 0 P 0 ;0
L 1.9089 -1.92726004 1.90886998 -1.92725 0 P 0 ;0
L 1.90886998 -1.92725 1.90883002 -1.92723996 0 P 0 ;0
L 1.90883002 -1.92723996 1.90816004 -1.92701004 0 P 0 ;0
L 1.90816004 -1.92701004 1.90813996 -1.927 0 P 0 ;0
L 1.90813996 -1.927 1.9081 -1.92698996 0 P 0 ;0
L 1.9081 -1.92698996 1.90803996 -1.92696998 0 P 0 ;0
L 1.90803996 -1.92696998 1.90736998 -1.92678002 0 P 0 ;0
L 1.90736998 -1.92678002 1.90723996 -1.92675 0 P 0 ;0
L 1.90723996 -1.92675 1.90643002 -1.92658996 0 P 0 ;0
L 1.90643002 -1.92658996 1.90636998 -1.92656998 0 P 0 ;0
L 1.90636998 -1.92656998 1.90633996 -1.92656998 0 P 0 ;0
L 1.90633996 -1.92656998 1.90631004 -1.92656004 0 P 0 ;0
L 1.90631004 -1.92656004 1.90548996 -1.92645 0 P 0 ;0
L 1.90548996 -1.92645 1.90543996 -1.92643996 0 P 0 ;0
L 1.90543996 -1.92643996 1.9054 -1.92643002 0 P 0 ;0
L 1.9054 -1.92643002 1.90538002 -1.92643002 0 P 0 ;0
L 1.90538002 -1.92643002 1.90455 -1.92636004 0 P 0 ;0
L 1.90455 -1.92636004 1.90443002 -1.92636004 0 P 0 ;0
L 1.90443002 -1.92636004 1.9036 -1.92633002 0 P 0 ;0
L 1.9036 -1.92633002 1.8994 -1.92633002 0 P 0 ;0
L 1.8994 -1.92633002 1.89798002 -1.92691004 0 P 0 ;0
L 1.89798002 -1.92691004 1.8974 -1.92833002 0 P 0 ;0
L 1.8974 -1.92833002 1.8974 -1.93328002 0 P 0 ;0
L 1.8974 -1.93328002 1.89748002 -1.93643002 0 P 0 ;0
L 1.89748002 -1.93643002 1.89748002 -1.93656004 0 P 0 ;0
L 1.89748002 -1.93656004 1.8975 -1.93673002 0 P 0 ;0
L 1.8975 -1.93673002 1.89751004 -1.93681004 0 P 0 ;0
L 1.89751004 -1.93681004 1.89751998 -1.9369 0 P 0 ;0
L 1.89751998 -1.9369 1.89755 -1.93706004 0 P 0 ;0
L 1.89755 -1.93706004 1.89758002 -1.93718996 0 P 0 ;0
L 1.89758002 -1.93718996 1.89758996 -1.93723002 0 P 0 ;0
L 1.89758996 -1.93723002 1.89763002 -1.9374 0 P 0 ;0
L 1.89763002 -1.9374 1.89763996 -1.93743996 0 P 0 ;0
L 1.89763996 -1.93743996 1.89766004 -1.93748002 0 P 0 ;0
L 1.89766004 -1.93748002 1.89768002 -1.93756004 0 P 0 ;0
L 1.89768002 -1.93756004 1.89773996 -1.93771998 0 P 0 ;0
L 1.89773996 -1.93771998 1.89776004 -1.93776004 0 P 0 ;0
L 1.89776004 -1.93776004 1.89776998 -1.9378 0 P 0 ;0
L 1.89776998 -1.9378 1.89781004 -1.93788002 0 P 0 ;0
L 1.89781004 -1.93788002 1.89788002 -1.93803996 0 P 0 ;0
L 1.89788002 -1.93803996 1.8979 -1.93808002 0 P 0 ;0
L 1.8979 -1.93808002 1.89791998 -1.93811004 0 P 0 ;0
L 1.89791998 -1.93811004 1.89796004 -1.93818996 0 P 0 ;0
L 1.89796004 -1.93818996 1.89803996 -1.93833996 0 P 0 ;0
L 1.89803996 -1.93833996 1.89813996 -1.93848002 0 P 0 ;0
L 1.89813996 -1.93848002 1.89823002 -1.93861998 0 P 0 ;0
L 1.89823002 -1.93861998 1.89828002 -1.93868996 0 P 0 ;0
L 1.89828002 -1.93868996 1.89831004 -1.93873002 0 P 0 ;0
L 1.89831004 -1.93873002 1.89833996 -1.93876004 0 P 0 ;0
L 1.89833996 -1.93876004 1.8984 -1.93883996 0 P 0 ;0
L 1.8984 -1.93883996 1.89848996 -1.93893002 0 P 0 ;0
L 1.89848996 -1.93893002 1.89851004 -1.93896004 0 P 0 ;0
L 1.89851004 -1.93896004 1.89868002 -1.93913002 0 P 0 ;0
L 1.89868002 -1.93913002 1.89871004 -1.93915 0 P 0 ;0
L 1.89871004 -1.93915 1.89878996 -1.93921998 0 P 0 ;0
L 1.89878996 -1.93921998 1.89885 -1.93928002 0 P 0 ;0
L 1.89885 -1.93928002 1.89888002 -1.9393 0 P 0 ;0
L 1.89888002 -1.9393 1.89891998 -1.93931998 0 P 0 ;0
L 1.89891998 -1.93931998 1.89901004 -1.93938996 0 P 0 ;0
L 1.89901004 -1.93938996 1.89903996 -1.93941004 0 P 0 ;0
L 1.89903996 -1.93941004 1.89906998 -1.93943996 0 P 0 ;0
L 1.89906998 -1.93943996 1.8991 -1.93946004 0 P 0 ;0
L 1.8991 -1.93946004 1.89913996 -1.93948002 0 P 0 ;0
L 1.89913996 -1.93948002 1.89923002 -1.93953996 0 P 0 ;0
L 1.89923002 -1.93953996 1.89926998 -1.93956004 0 P 0 ;0
L 1.89926998 -1.93956004 1.8993 -1.93958002 0 P 0 ;0
L 1.8993 -1.93958002 1.89933996 -1.9396 0 P 0 ;0
L 1.89933996 -1.9396 1.89936998 -1.93961004 0 P 0 ;0
L 1.89936998 -1.93961004 1.89938002 -1.93961004 0 P 0 ;0
L 1.89938002 -1.93961004 1.89946998 -1.93966004 0 P 0 ;0
L 1.89946998 -1.93966004 1.89953996 -1.9397 0 P 0 ;0
L 1.89953996 -1.9397 1.89971998 -1.93976998 0 P 0 ;0
L 1.89971998 -1.93976998 1.89975 -1.93978996 0 P 0 ;0
L 1.89975 -1.93978996 1.89978996 -1.9398 0 P 0 ;0
L 1.89978996 -1.9398 1.89986998 -1.93983002 0 P 0 ;0
L 1.89986998 -1.93983002 1.89996998 -1.93986004 0 P 0 ;0
L 1.89996998 -1.93986004 1.90001004 -1.93986998 0 P 0 ;0
L 1.90001004 -1.93986998 1.90005 -1.93988996 0 P 0 ;0
L 1.90005 -1.93988996 1.90013002 -1.9399 0 P 0 ;0
L 1.90013002 -1.9399 1.90023002 -1.93993002 0 P 0 ;0
L 1.90023002 -1.93993002 1.90023996 -1.93993002 0 P 0 ;0
L 1.90023996 -1.93993002 1.90028002 -1.93993996 0 P 0 ;0
L 1.90028002 -1.93993996 1.90031004 -1.93995 0 P 0 ;0
L 1.90031004 -1.93995 1.90036004 -1.93995 0 P 0 ;0
L 1.90036004 -1.93995 1.9004 -1.93996004 0 P 0 ;0
L 1.9004 -1.93996004 1.9005 -1.93996998 0 P 0 ;0
L 1.9005 -1.93996998 1.90061004 -1.93998996 0 P 0 ;0
L 1.90061004 -1.93998996 1.90063996 -1.93998996 0 P 0 ;0
L 1.90063996 -1.93998996 1.90181004 -1.94006998 0 P 0 ;0
L 1.90181004 -1.94006998 1.90183996 -1.94008002 0 P 0 ;0
L 1.90183996 -1.94008002 1.90191004 -1.94008002 0 P 0 ;0
L 1.90191004 -1.94008002 1.90308002 -1.9401 0 P 0 ;0
L 1.90308002 -1.9401 1.90311004 -1.9401 0 P 0 ;0
L 1.90311004 -1.9401 1.90313996 -1.94011004 0 P 0 ;0
L 1.90841004 -1.97146004 1.91683996 -1.97146004 0 P 0 ;0
L 1.9135 -1.97046004 1.91931004 -1.97046004 0 P 0 ;0
L 1.91655 -1.96946004 1.92131004 -1.96946004 0 P 0 ;0
L 1.91891998 -1.96846004 1.92301004 -1.96846004 0 P 0 ;0
L 1.92088996 -1.96746004 1.9245 -1.96746004 0 P 0 ;0
L 1.92251004 -1.96646004 1.9258 -1.96646004 0 P 0 ;0
L 1.92391004 -1.96546004 1.92696004 -1.96546004 0 P 0 ;0
L 1.92513002 -1.96446004 1.92803002 -1.96446004 0 P 0 ;0
L 1.9262 -1.96346004 1.92898996 -1.96346004 0 P 0 ;0
L 1.92713996 -1.96246004 1.92986004 -1.96246004 0 P 0 ;0
L 1.928 -1.96146004 1.93068996 -1.96146004 0 P 0 ;0
L 1.92878002 -1.96046004 1.93143002 -1.96046004 0 P 0 ;0
L 1.92951004 -1.95946004 1.93216004 -1.95946004 0 P 0 ;0
L 1.93016998 -1.95846004 1.93278996 -1.95846004 0 P 0 ;0
L 1.93078002 -1.95746004 1.93341004 -1.95746004 0 P 0 ;0
L 1.93133002 -1.95646004 1.93396004 -1.95646004 0 P 0 ;0
L 1.93185 -1.95546004 1.93448996 -1.95546004 0 P 0 ;0
L 1.93231004 -1.95446004 1.93495 -1.95446004 0 P 0 ;0
L 1.93275 -1.95346004 1.93541004 -1.95346004 0 P 0 ;0
L 1.93311998 -1.95246004 1.93586004 -1.95246004 0 P 0 ;0
L 1.93348002 -1.95146004 1.93628996 -1.95146004 0 P 0 ;0
L 1.93376998 -1.95046004 1.93666004 -1.95046004 0 P 0 ;0
L 1.93405 -1.94946004 1.93693002 -1.94946004 0 P 0 ;0
L 1.93428002 -1.94846004 1.93715 -1.94846004 0 P 0 ;0
L 1.93446998 -1.94746004 1.93733002 -1.94746004 0 P 0 ;0
L 1.93466004 -1.94646004 1.93743002 -1.94646004 0 P 0 ;0
L 1.93478996 -1.94546004 1.93748996 -1.94546004 0 P 0 ;0
L 1.9349 -1.94446998 1.93751998 -1.94446998 0 P 0 ;0
L 1.93496998 -1.94346004 1.93755 -1.94346004 0 P 0 ;0
L 1.93501998 -1.94246004 1.93758002 -1.94246004 0 P 0 ;0
L 1.93505 -1.94146998 1.93758996 -1.94146998 0 P 0 ;0
L 1.93503002 -1.94046004 1.93755 -1.94046004 0 P 0 ;0
L 1.935 -1.93946004 1.93751998 -1.93946004 0 P 0 ;0
L 1.93491998 -1.93846004 1.93748002 -1.93846004 0 P 0 ;0
L 1.93481004 -1.93746004 1.93738996 -1.93746004 0 P 0 ;0
L 1.93468996 -1.93646004 1.93726998 -1.93646004 0 P 0 ;0
L 1.93451004 -1.93546004 1.93716004 -1.93546004 0 P 0 ;0
L 1.93433002 -1.93446004 1.93703996 -1.93446004 0 P 0 ;0
L 1.93408996 -1.93346004 1.93685 -1.93346004 0 P 0 ;0
L 1.93383002 -1.93246004 1.93666004 -1.93246004 0 P 0 ;0
L 1.93353002 -1.93146004 1.93638996 -1.93146004 0 P 0 ;0
L 1.9332 -1.93046004 1.93611998 -1.93046004 0 P 0 ;0
L 1.93283996 -1.92946004 1.93576998 -1.92946004 0 P 0 ;0
L 1.93241004 -1.92846004 1.93541004 -1.92846004 0 P 0 ;0
L 1.93198996 -1.92746004 1.93498002 -1.92746004 0 P 0 ;0
L 1.93146998 -1.92646004 1.93451004 -1.92646004 0 P 0 ;0
L 1.93096004 -1.92546004 1.93398002 -1.92546004 0 P 0 ;0
L 1.93035 -1.92446998 1.93338002 -1.92446998 0 P 0 ;0
L 1.92973002 -1.92346004 1.93275 -1.92346004 0 P 0 ;0
L 1.92903002 -1.92246004 1.93201004 -1.92246004 0 P 0 ;0
L 1.92831004 -1.92146004 1.93125 -1.92146004 0 P 0 ;0
L 1.92746998 -1.92046004 1.93041004 -1.92046004 0 P 0 ;0
L 1.92661004 -1.91946004 1.92948996 -1.91946004 0 P 0 ;0
L 1.92558996 -1.91846004 1.92851004 -1.91846004 0 P 0 ;0
L 1.9245 -1.91746004 1.92741998 -1.91746004 0 P 0 ;0
L 1.92328996 -1.91646004 1.92621998 -1.91646004 0 P 0 ;0
L 1.92188002 -1.91546004 1.92491998 -1.91546004 0 P 0 ;0
L 1.92026004 -1.91446004 1.92358996 -1.91446004 0 P 0 ;0
L 1.91835 -1.91346004 1.92208002 -1.91346004 0 P 0 ;0
L 1.82446998 -2.08323996 1.87608002 -2.08323996 0 P 0 ;0
L 1.82403002 -2.08223996 1.87601004 -2.08223996 0 P 0 ;0
L 1.8234 -2.08123996 1.87591004 -2.08123996 0 P 0 ;0
L 1.82256004 -2.08023996 1.87578002 -2.08023996 0 P 0 ;0
L 1.82166004 -2.07923996 1.87558996 -2.07923996 0 P 0 ;0
L 1.82061998 -2.07823996 1.87533002 -2.07823996 0 P 0 ;0
L 1.81946004 -2.07723996 1.87498996 -2.07723996 0 P 0 ;0
L 1.81818002 -2.07623996 1.8746 -2.07623996 0 P 0 ;0
L 1.8168 -2.07523996 1.87416998 -2.07523996 0 P 0 ;0
L 1.81541998 -2.07423996 1.87371004 -2.07423996 0 P 0 ;0
L 1.81403002 -2.07323996 1.87316998 -2.07323996 0 P 0 ;0
L 1.81265 -2.07223996 1.87261004 -2.07223996 0 P 0 ;0
L 1.81126998 -2.07123996 1.87196004 -2.07123996 0 P 0 ;0
L 1.80986004 -2.07023996 1.87128002 -2.07023996 0 P 0 ;0
L 1.80843996 -2.06923996 1.87051998 -2.06923996 0 P 0 ;0
L 1.80703002 -2.06823996 1.8697 -2.06823996 0 P 0 ;0
L 1.80561004 -2.06723996 1.86883002 -2.06723996 0 P 0 ;0
L 1.8042 -2.06623996 1.86796004 -2.06623996 0 P 0 ;0
L 1.80278002 -2.06523996 1.86705 -2.06523996 0 P 0 ;0
L 1.80136004 -2.06423996 1.86608002 -2.06423996 0 P 0 ;0
L 1.79995 -2.06323996 1.8651 -2.06323996 0 P 0 ;0
L 1.79865 -2.06223996 1.86411004 -2.06223996 0 P 0 ;0
L 1.79735 -2.06123996 1.86301998 -2.06123996 0 P 0 ;0
L 1.79605 -2.06023996 1.86193002 -2.06023996 0 P 0 ;0
L 1.79475 -2.05923996 1.86083996 -2.05923996 0 P 0 ;0
L 1.79345 -2.05823996 1.85966998 -2.05823996 0 P 0 ;0
L 1.79215 -2.05723996 1.85846004 -2.05723996 0 P 0 ;0
L 1.79088002 -2.05623996 1.85726004 -2.05623996 0 P 0 ;0
L 1.78971998 -2.05523996 1.85598996 -2.05523996 0 P 0 ;0
L 1.78856004 -2.05423996 1.85461998 -2.05423996 0 P 0 ;0
L 1.7874 -2.05323996 1.85326004 -2.05323996 0 P 0 ;0
L 1.78623002 -2.05223996 1.8519 -2.05223996 0 P 0 ;0
L 1.78506998 -2.05123996 1.85053996 -2.05123996 0 P 0 ;0
L 1.78398002 -2.05023996 1.84918002 -2.05023996 0 P 0 ;0
L 1.783 -2.04923996 1.84781004 -2.04923996 0 P 0 ;0
L 1.87086004 -2.03023996 1.87535 -2.03023996 0 P 0 ;0
L 1.91633002 -1.91473002 1.9183 -1.91565 0 P 0 ;0
L 1.9183 -1.91565 1.92018996 -1.91673002 0 P 0 ;0
L 1.92018996 -1.91673002 1.92196998 -1.91796998 0 P 0 ;0
L 1.92196998 -1.91796998 1.92365 -1.91936004 0 P 0 ;0
L 1.92365 -1.91936004 1.9252 -1.92088002 0 P 0 ;0
L 1.9252 -1.92088002 1.92661004 -1.92253996 0 P 0 ;0
L 1.92661004 -1.92253996 1.92795 -1.92436998 0 P 0 ;0
L 1.92795 -1.92436998 1.92913996 -1.9263 0 P 0 ;0
L 1.92913996 -1.9263 1.93018002 -1.92831998 0 P 0 ;0
L 1.93018002 -1.92831998 1.93106998 -1.93041004 0 P 0 ;0
L 1.93106998 -1.93041004 1.93178996 -1.93256004 0 P 0 ;0
L 1.93178996 -1.93256004 1.93236004 -1.93476004 0 P 0 ;0
L 1.93236004 -1.93476004 1.93276004 -1.93703996 0 P 0 ;0
L 1.93276004 -1.93703996 1.93298996 -1.93933996 0 P 0 ;0
L 1.93298996 -1.93933996 1.93306004 -1.94165 0 P 0 ;0
L 1.93306004 -1.94165 1.93295 -1.94396998 0 P 0 ;0
L 1.93295 -1.94396998 1.93268002 -1.94626004 0 P 0 ;0
L 1.93268002 -1.94626004 1.93223002 -1.94853996 0 P 0 ;0
L 1.93223002 -1.94853996 1.93161998 -1.95071998 0 P 0 ;0
L 1.93161998 -1.95071998 1.93085 -1.95285 0 P 0 ;0
L 1.93085 -1.95285 1.92991004 -1.95491004 0 P 0 ;0
L 1.92991004 -1.95491004 1.92881004 -1.95688996 0 P 0 ;0
L 1.92881004 -1.95688996 1.92756004 -1.95878002 0 P 0 ;0
L 1.92756004 -1.95878002 1.92616004 -1.96056998 0 P 0 ;0
L 1.92616004 -1.96056998 1.92493996 -1.9619 0 P 0 ;0
L 1.92493996 -1.9619 1.92361998 -1.96313996 0 P 0 ;0
L 1.92361998 -1.96313996 1.9222 -1.96426004 0 P 0 ;0
L 1.9222 -1.96426004 1.9207 -1.96526998 0 P 0 ;0
L 1.9207 -1.96526998 1.91911004 -1.96616998 0 P 0 ;0
L 1.91911004 -1.96616998 1.91686998 -1.96721004 0 P 0 ;0
L 1.91686998 -1.96721004 1.91456004 -1.96806998 0 P 0 ;0
L 1.91456004 -1.96806998 1.91218996 -1.96876004 0 P 0 ;0
L 1.91218996 -1.96876004 1.90975 -1.96926998 0 P 0 ;0
L 1.90975 -1.96926998 1.90725 -1.9696 0 P 0 ;0
L 1.90725 -1.9696 1.90473002 -1.96973996 0 P 0 ;0
L 1.90473002 -1.96973996 1.9022 -1.96968996 0 P 0 ;0
L 1.9022 -1.96968996 1.89966998 -1.96945 0 P 0 ;0
L 1.89966998 -1.96945 1.89778002 -1.96913002 0 P 0 ;0
L 1.89778002 -1.96913002 1.89591998 -1.96868996 0 P 0 ;0
L 1.89591998 -1.96868996 1.8941 -1.96811004 0 P 0 ;0
L 1.8941 -1.96811004 1.89231004 -1.96741004 0 P 0 ;0
L 1.89231004 -1.96741004 1.89058002 -1.96658002 0 P 0 ;0
L 1.89058002 -1.96658002 1.88875 -1.96553996 0 P 0 ;0
L 1.88875 -1.96553996 1.88698996 -1.96435 0 P 0 ;0
L 1.88698996 -1.96435 1.88533996 -1.96303002 0 P 0 ;0
L 1.88533996 -1.96303002 1.88378996 -1.9616 0 P 0 ;0
L 1.88378996 -1.9616 1.88235 -1.96003996 0 P 0 ;0
L 1.88235 -1.96003996 1.88103002 -1.95838996 0 P 0 ;0
L 1.88103002 -1.95838996 1.87983996 -1.95663002 0 P 0 ;0
L 1.87983996 -1.95663002 1.87861998 -1.95446998 0 P 0 ;0
L 1.87861998 -1.95446998 1.87758002 -1.9522 0 P 0 ;0
L 1.87758002 -1.9522 1.87673996 -1.94986004 0 P 0 ;0
L 1.87673996 -1.94986004 1.8761 -1.94745 0 P 0 ;0
L 1.8761 -1.94745 1.87568002 -1.945 0 P 0 ;0
L 1.87568002 -1.945 1.87546004 -1.94248996 0 P 0 ;0
L 1.87546004 -1.94248996 1.87546004 -1.93998996 0 P 0 ;0
L 1.87546004 -1.93998996 1.87566998 -1.93748996 0 P 0 ;0
L 1.87566998 -1.93748996 1.87608996 -1.93501998 0 P 0 ;0
L 1.87608996 -1.93501998 1.87671998 -1.9326 0 P 0 ;0
L 1.87671998 -1.9326 1.87755 -1.93023002 0 P 0 ;0
L 1.87755 -1.93023002 1.8786 -1.92793002 0 P 0 ;0
L 1.8786 -1.92793002 1.87981998 -1.92575 0 P 0 ;0
L 1.87981998 -1.92575 1.88123002 -1.92368002 0 P 0 ;0
L 1.88123002 -1.92368002 1.88281004 -1.92175 0 P 0 ;0
L 1.88281004 -1.92175 1.88455 -1.91996004 0 P 0 ;0
L 1.88455 -1.91996004 1.88643002 -1.91831998 0 P 0 ;0
L 1.88643002 -1.91831998 1.88845 -1.91686004 0 P 0 ;0
L 1.88845 -1.91686004 1.88986998 -1.91598996 0 P 0 ;0
L 1.88986998 -1.91598996 1.89135 -1.91523002 0 P 0 ;0
L 1.89135 -1.91523002 1.89288002 -1.91458996 0 P 0 ;0
L 1.89288002 -1.91458996 1.89446998 -1.91406004 0 P 0 ;0
L 1.89446998 -1.91406004 1.89688996 -1.91343996 0 P 0 ;0
L 1.89688996 -1.91343996 1.89935 -1.91298996 0 P 0 ;0
L 1.89935 -1.91298996 1.90183996 -1.91271004 0 P 0 ;0
L 1.90183996 -1.91271004 1.9044 -1.91261004 0 P 0 ;0
L 1.9044 -1.91261004 1.90695 -1.91268002 0 P 0 ;0
L 1.90695 -1.91268002 1.90948996 -1.91291998 0 P 0 ;0
L 1.90948996 -1.91291998 1.91181998 -1.91331998 0 P 0 ;0
L 1.91181998 -1.91331998 1.91408996 -1.91393002 0 P 0 ;0
L 1.91408996 -1.91393002 1.91633002 -1.91473002 0 P 0 ;0
L 1.89498002 -1.90801998 1.8922 -1.90893002 0 P 0 ;0
L 1.8922 -1.90893002 1.88948002 -1.91003002 0 P 0 ;0
L 1.88948002 -1.91003002 1.88686004 -1.91133002 0 P 0 ;0
L 1.88686004 -1.91133002 1.88431004 -1.91283996 0 P 0 ;0
L 1.88431004 -1.91283996 1.88201004 -1.91446004 0 P 0 ;0
L 1.88201004 -1.91446004 1.87985 -1.91626998 0 P 0 ;0
L 1.87985 -1.91626998 1.87785 -1.91826004 0 P 0 ;0
L 1.87785 -1.91826004 1.87601998 -1.92041004 0 P 0 ;0
L 1.87601998 -1.92041004 1.87441004 -1.92266998 0 P 0 ;0
L 1.87441004 -1.92266998 1.87298996 -1.92505 0 P 0 ;0
L 1.87298996 -1.92505 1.87178002 -1.92756004 0 P 0 ;0
L 1.87178002 -1.92756004 1.87078996 -1.93015 0 P 0 ;0
L 1.87078996 -1.93015 1.87 -1.93286998 0 P 0 ;0
L 1.87 -1.93286998 1.86943996 -1.93563996 0 P 0 ;0
L 1.86943996 -1.93563996 1.86908996 -1.93845 0 P 0 ;0
L 1.86908996 -1.93845 1.86898002 -1.94128996 0 P 0 ;0
L 1.86898002 -1.94128996 1.86911998 -1.94485 0 P 0 ;0
L 1.86911998 -1.94485 1.86953996 -1.94841004 0 P 0 ;0
L 1.86953996 -1.94841004 1.86996004 -1.95048996 0 P 0 ;0
L 1.86996004 -1.95048996 1.87053002 -1.95251998 0 P 0 ;0
L 1.87053002 -1.95251998 1.87125 -1.95451998 0 P 0 ;0
L 1.87125 -1.95451998 1.87211004 -1.95643002 0 P 0 ;0
L 1.87211004 -1.95643002 1.8731 -1.95826004 0 P 0 ;0
L 1.8731 -1.95826004 1.87423996 -1.96001998 0 P 0 ;0
L 1.87423996 -1.96001998 1.87636998 -1.96278996 0 P 0 ;0
L 1.87636998 -1.96278996 1.87871998 -1.96536998 0 P 0 ;0
L 1.87871998 -1.96536998 1.88145 -1.96788002 0 P 0 ;0
L 1.88145 -1.96788002 1.88436998 -1.97015 0 P 0 ;0
L 1.88436998 -1.97015 1.88621004 -1.97135 0 P 0 ;0
L 1.88621004 -1.97135 1.88813002 -1.97238002 0 P 0 ;0
L 1.88813002 -1.97238002 1.89013002 -1.97326004 0 P 0 ;0
L 1.89013002 -1.97326004 1.89228002 -1.97398996 0 P 0 ;0
L 1.89228002 -1.97398996 1.89446998 -1.97455 0 P 0 ;0
L 1.89446998 -1.97455 1.89671004 -1.97493996 0 P 0 ;0
L 1.89671004 -1.97493996 1.90076998 -1.97533996 0 P 0 ;0
L 1.90076998 -1.97533996 1.90485 -1.97546998 0 P 0 ;0
L 1.90485 -1.97546998 1.90821004 -1.97531998 0 P 0 ;0
L 1.90821004 -1.97531998 1.91153996 -1.97488996 0 P 0 ;0
L 1.91153996 -1.97488996 1.91481998 -1.97418996 0 P 0 ;0
L 1.91481998 -1.97418996 1.9171 -1.9735 0 P 0 ;0
L 1.9171 -1.9735 1.91933002 -1.97266004 0 P 0 ;0
L 1.91933002 -1.97266004 1.92148002 -1.97166004 0 P 0 ;0
L 1.92148002 -1.97166004 1.92356998 -1.97048996 0 P 0 ;0
L 1.92356998 -1.97048996 1.92553996 -1.96918996 0 P 0 ;0
L 1.92553996 -1.96918996 1.92741004 -1.96773996 0 P 0 ;0
L 1.92741004 -1.96773996 1.92916004 -1.96616998 0 P 0 ;0
L 1.92916004 -1.96616998 1.93081004 -1.96446004 0 P 0 ;0
L 1.93081004 -1.96446004 1.93236998 -1.96256998 0 P 0 ;0
L 1.93236998 -1.96256998 1.93381004 -1.96058996 0 P 0 ;0
L 1.93381004 -1.96058996 1.93511998 -1.95851004 0 P 0 ;0
L 1.93511998 -1.95851004 1.93628996 -1.95633996 0 P 0 ;0
L 1.93628996 -1.95633996 1.93803996 -1.95251998 0 P 0 ;0
L 1.93803996 -1.95251998 1.93858002 -1.95101998 0 P 0 ;0
L 1.93858002 -1.95101998 1.93898996 -1.94948002 0 P 0 ;0
L 1.93898996 -1.94948002 1.93928996 -1.94786998 0 P 0 ;0
L 1.93928996 -1.94786998 1.93946004 -1.94625 0 P 0 ;0
L 1.93946004 -1.94625 1.9396 -1.94178002 0 P 0 ;0
L 1.9396 -1.94178002 1.93946004 -1.93803996 0 P 0 ;0
L 1.93946004 -1.93803996 1.93905 -1.9343 0 P 0 ;0
L 1.93905 -1.9343 1.93863996 -1.93213996 0 P 0 ;0
L 1.93863996 -1.93213996 1.93808002 -1.93001998 0 P 0 ;0
L 1.93808002 -1.93001998 1.93736004 -1.92795 0 P 0 ;0
L 1.93736004 -1.92795 1.93653002 -1.92601004 0 P 0 ;0
L 1.93653002 -1.92601004 1.93555 -1.92415 0 P 0 ;0
L 1.93555 -1.92415 1.93441998 -1.92236004 0 P 0 ;0
L 1.93441998 -1.92236004 1.9331 -1.92056004 0 P 0 ;0
L 1.9331 -1.92056004 1.93166998 -1.91885 0 P 0 ;0
L 1.93166998 -1.91885 1.93011998 -1.91723002 0 P 0 ;0
L 1.93011998 -1.91723002 1.92896004 -1.91615 0 P 0 ;0
L 1.92896004 -1.91615 1.92775 -1.91511004 0 P 0 ;0
L 1.92775 -1.91511004 1.92493002 -1.91295 0 P 0 ;0
L 1.92493002 -1.91295 1.9221 -1.91108002 0 P 0 ;0
L 1.9221 -1.91108002 1.92095 -1.91043002 0 P 0 ;0
L 1.92095 -1.91043002 1.91975 -1.90985 0 P 0 ;0
L 1.91975 -1.90985 1.91796004 -1.90913996 0 P 0 ;0
L 1.91796004 -1.90913996 1.91613002 -1.90856004 0 P 0 ;0
L 1.91613002 -1.90856004 1.91423996 -1.9081 0 P 0 ;0
L 1.91423996 -1.9081 1.91086004 -1.90751998 0 P 0 ;0
L 1.91086004 -1.90751998 1.90743002 -1.90716004 0 P 0 ;0
L 1.90743002 -1.90716004 1.90401004 -1.90701004 0 P 0 ;0
L 1.90401004 -1.90701004 1.90058002 -1.90708002 0 P 0 ;0
L 1.90058002 -1.90708002 1.8987 -1.90726004 0 P 0 ;0
L 1.8987 -1.90726004 1.89683002 -1.90756998 0 P 0 ;0
L 1.89683002 -1.90756998 1.89498002 -1.90801998 0 P 0 ;0
L 1.86643002 -2.02923996 1.87525 -2.02923996 0 P 0 ;0
L 1.86176998 -2.02823996 1.87515 -2.02823996 0 P 0 ;0
L 1.85588996 -2.02723996 1.87505 -2.02723996 0 P 0 ;0
L 1.78365 -2.00523996 1.87281004 -2.00523996 0 P 0 ;0
L 1.78451004 -2.00423996 1.87271004 -2.00423996 0 P 0 ;0
L 1.78546998 -2.00323996 1.87261004 -2.00323996 0 P 0 ;0
L 1.78655 -2.00223996 1.8725 -2.00223996 0 P 0 ;0
L 1.78776004 -2.00123996 1.8724 -2.00123996 0 P 0 ;0
L 1.78915 -2.00023996 1.8723 -2.00023996 0 P 0 ;0
L 1.79078996 -1.99923996 1.8722 -1.99923996 0 P 0 ;0
L 1.79263996 -1.99823996 1.87208996 -1.99823996 0 P 0 ;0
L 1.79458996 -1.99723996 1.87198996 -1.99723996 0 P 0 ;0
L 1.79686998 -1.99623996 1.87188002 -1.99623996 0 P 0 ;0
L 1.79946004 -1.99523996 1.87178002 -1.99523996 0 P 0 ;0
L 1.80231004 -1.99423996 1.86961998 -1.99423996 0 P 0 ;0
L 1.80596004 -1.99323996 1.86218002 -1.99323996 0 P 0 ;0
L 1.81051004 -1.99223996 1.85398002 -1.99223996 0 P 0 ;0
L 1.81676004 -1.99123996 1.84395 -1.99123996 0 P 0 ;0
L 1.87786998 -1.96146004 1.88093996 -1.96146004 0 P 0 ;0
L 1.8771 -1.96046004 1.88013002 -1.96046004 0 P 0 ;0
L 1.87633996 -1.95946004 1.87933996 -1.95946004 0 P 0 ;0
L 1.87561998 -1.95846004 1.87866998 -1.95846004 0 P 0 ;0
L 1.87496998 -1.95746004 1.87801998 -1.95746004 0 P 0 ;0
L 1.8744 -1.95646004 1.87745 -1.95646004 0 P 0 ;0
L 1.87386998 -1.95546004 1.87688002 -1.95546004 0 P 0 ;0
L 1.87341998 -1.95446004 1.87641998 -1.95446004 0 P 0 ;0
L 1.87298996 -1.95346004 1.87596004 -1.95346004 0 P 0 ;0
L 1.87263002 -1.95246004 1.87555 -1.95246004 0 P 0 ;0
L 1.87231004 -1.95146004 1.87518996 -1.95146004 0 P 0 ;0
L 1.87203002 -1.95046004 1.87483002 -1.95046004 0 P 0 ;0
L 1.87178996 -1.94946004 1.87456998 -1.94946004 0 P 0 ;0
L 1.87158996 -1.94846004 1.87431004 -1.94846004 0 P 0 ;0
L 1.87143996 -1.94746004 1.87408002 -1.94746004 0 P 0 ;0
L 1.87133002 -1.94646004 1.8739 -1.94646004 0 P 0 ;0
L 1.87121004 -1.94546004 1.87373002 -1.94546004 0 P 0 ;0
L 1.8711 -1.94446998 1.87361998 -1.94446998 0 P 0 ;0
L 1.87106998 -1.94346004 1.87353996 -1.94346004 0 P 0 ;0
L 1.87103002 -1.94246004 1.87346004 -1.94246004 0 P 0 ;0
L 1.87098996 -1.94146998 1.87346004 -1.94146998 0 P 0 ;0
L 1.87101004 -1.94046004 1.87346004 -1.94046004 0 P 0 ;0
L 1.87106004 -1.93946004 1.87348996 -1.93946004 0 P 0 ;0
L 1.87111004 -1.93846004 1.87358002 -1.93846004 0 P 0 ;0
L 1.87123002 -1.93746004 1.87366004 -1.93746004 0 P 0 ;0
L 1.87135 -1.93646004 1.87381998 -1.93646004 0 P 0 ;0
L 1.87151004 -1.93546004 1.87398996 -1.93546004 0 P 0 ;0
L 1.87171998 -1.93446004 1.87416998 -1.93446004 0 P 0 ;0
L 1.87191998 -1.93346004 1.87443002 -1.93346004 0 P 0 ;0
L 1.8722 -1.93246004 1.87468996 -1.93246004 0 P 0 ;0
L 1.87248996 -1.93146004 1.875 -1.93146004 0 P 0 ;0
L 1.87281004 -1.93046004 1.87535 -1.93046004 0 P 0 ;0
L 1.87318996 -1.92946004 1.87571004 -1.92946004 0 P 0 ;0
L 1.87356998 -1.92846004 1.87616004 -1.92846004 0 P 0 ;0
L 1.87405 -1.92746004 1.87661004 -1.92746004 0 P 0 ;0
L 1.87453002 -1.92646004 1.87711998 -1.92646004 0 P 0 ;0
L 1.87506998 -1.92546004 1.87768996 -1.92546004 0 P 0 ;0
L 1.87566004 -1.92446998 1.87826998 -1.92446998 0 P 0 ;0
L 1.87628996 -1.92346004 1.87896004 -1.92346004 0 P 0 ;0
L 1.87701004 -1.92246004 1.87963996 -1.92246004 0 P 0 ;0
L 1.87775 -1.92146004 1.88046004 -1.92146004 0 P 0 ;0
L 1.90483996 -1.97346004 1.9009 -1.97333996 0 P 0 ;0
L 1.9009 -1.97333996 1.89698002 -1.97295 0 P 0 ;0
L 1.89698002 -1.97295 1.89488996 -1.97258996 0 P 0 ;0
L 1.89488996 -1.97258996 1.89285 -1.97206998 0 P 0 ;0
L 1.89285 -1.97206998 1.89086004 -1.97138996 0 P 0 ;0
L 1.89086004 -1.97138996 1.889 -1.97058002 0 P 0 ;0
L 1.889 -1.97058002 1.88723002 -1.96961998 0 P 0 ;0
L 1.88723002 -1.96961998 1.88553002 -1.96851998 0 P 0 ;0
L 1.88553002 -1.96851998 1.88273996 -1.96636004 0 P 0 ;0
L 1.88273996 -1.96636004 1.88013996 -1.96396004 0 P 0 ;0
L 1.88013996 -1.96396004 1.8779 -1.9615 0 P 0 ;0
L 1.8779 -1.9615 1.87588002 -1.95886998 0 P 0 ;0
L 1.87588002 -1.95886998 1.87483002 -1.95723996 0 P 0 ;0
L 1.87483002 -1.95723996 1.8739 -1.95553996 0 P 0 ;0
L 1.8739 -1.95553996 1.87311004 -1.95376998 0 P 0 ;0
L 1.87311004 -1.95376998 1.87243002 -1.95191004 0 P 0 ;0
L 1.87243002 -1.95191004 1.8719 -1.95001998 0 P 0 ;0
L 1.8719 -1.95001998 1.87151998 -1.9481 0 P 0 ;0
L 1.87151998 -1.9481 1.87111004 -1.94468996 0 P 0 ;0
L 1.87111004 -1.94468996 1.87098002 -1.94128996 0 P 0 ;0
L 1.87098002 -1.94128996 1.87108996 -1.93861004 0 P 0 ;0
L 1.87108996 -1.93861004 1.87141004 -1.93596998 0 P 0 ;0
L 1.87141004 -1.93596998 1.87195 -1.93335 0 P 0 ;0
L 1.87195 -1.93335 1.87268996 -1.93078996 0 P 0 ;0
L 1.87268996 -1.93078996 1.87361998 -1.92835 0 P 0 ;0
L 1.87361998 -1.92835 1.87475 -1.926 0 P 0 ;0
L 1.87475 -1.926 1.87608996 -1.92376004 0 P 0 ;0
L 1.87608996 -1.92376004 1.8776 -1.92163996 0 P 0 ;0
L 1.8776 -1.92163996 1.87931998 -1.91961998 0 P 0 ;0
L 1.87931998 -1.91961998 1.8812 -1.91775 0 P 0 ;0
L 1.8812 -1.91775 1.88323002 -1.91605 0 P 0 ;0
L 1.88323002 -1.91605 1.8854 -1.91451998 0 P 0 ;0
L 1.8854 -1.91451998 1.88781004 -1.91308996 0 P 0 ;0
L 1.88781004 -1.91308996 1.89031004 -1.91186004 0 P 0 ;0
L 1.89031004 -1.91186004 1.89288002 -1.9108 0 P 0 ;0
L 1.89288002 -1.9108 1.89553002 -1.90995 0 P 0 ;0
L 1.89553002 -1.90995 1.89723002 -1.90953002 0 P 0 ;0
L 1.89723002 -1.90953002 1.89896004 -1.90923996 0 P 0 ;0
L 1.89896004 -1.90923996 1.90068996 -1.90908002 0 P 0 ;0
L 1.90068996 -1.90908002 1.90398996 -1.90901004 0 P 0 ;0
L 1.90398996 -1.90901004 1.90728002 -1.90915 0 P 0 ;0
L 1.90728002 -1.90915 1.91058996 -1.90951004 0 P 0 ;0
L 1.91058996 -1.90951004 1.91383996 -1.91006004 0 P 0 ;0
L 1.91383996 -1.91006004 1.91558996 -1.91048996 0 P 0 ;0
L 1.91558996 -1.91048996 1.91728996 -1.91101998 0 P 0 ;0
L 1.91728996 -1.91101998 1.91895 -1.91168002 0 P 0 ;0
L 1.91895 -1.91168002 1.92001998 -1.9122 0 P 0 ;0
L 1.92001998 -1.9122 1.92105 -1.91278996 0 P 0 ;0
L 1.92105 -1.91278996 1.92376998 -1.91458002 0 P 0 ;0
L 1.92376998 -1.91458002 1.92648996 -1.91666998 0 P 0 ;0
L 1.92648996 -1.91666998 1.92763002 -1.91763996 0 P 0 ;0
L 1.92763002 -1.91763996 1.92871004 -1.91865 0 P 0 ;0
L 1.92871004 -1.91865 1.93018002 -1.92018996 0 P 0 ;0
L 1.93018002 -1.92018996 1.93153002 -1.9218 0 P 0 ;0
L 1.93153002 -1.9218 1.93276998 -1.92348996 0 P 0 ;0
L 1.93276998 -1.92348996 1.93381004 -1.92515 0 P 0 ;0
L 1.93381004 -1.92515 1.93471998 -1.92686998 0 P 0 ;0
L 1.93471998 -1.92686998 1.9355 -1.92866998 0 P 0 ;0
L 1.9355 -1.92866998 1.93616998 -1.93061004 0 P 0 ;0
L 1.93616998 -1.93061004 1.93668996 -1.93258002 0 P 0 ;0
L 1.93668996 -1.93258002 1.93706998 -1.93458996 0 P 0 ;0
L 1.93706998 -1.93458996 1.93746998 -1.93818996 0 P 0 ;0
L 1.93746998 -1.93818996 1.9376 -1.94178996 0 P 0 ;0
L 1.9376 -1.94178996 1.93746004 -1.94611004 0 P 0 ;0
L 1.93746004 -1.94611004 1.93731004 -1.94758996 0 P 0 ;0
L 1.93731004 -1.94758996 1.93705 -1.94903996 0 P 0 ;0
L 1.93705 -1.94903996 1.93666998 -1.95041998 0 P 0 ;0
L 1.93666998 -1.95041998 1.93618002 -1.95176004 0 P 0 ;0
L 1.93618002 -1.95176004 1.9345 -1.95545 0 P 0 ;0
L 1.9345 -1.95545 1.93338996 -1.9575 0 P 0 ;0
L 1.93338996 -1.9575 1.93216004 -1.95946998 0 P 0 ;0
L 1.93216004 -1.95946998 1.93078996 -1.96133996 0 P 0 ;0
L 1.93078996 -1.96133996 1.92931004 -1.96311998 0 P 0 ;0
L 1.92931004 -1.96311998 1.92776998 -1.96473002 0 P 0 ;0
L 1.92776998 -1.96473002 1.92613002 -1.96621004 0 P 0 ;0
L 1.92613002 -1.96621004 1.92438002 -1.96756004 0 P 0 ;0
L 1.92438002 -1.96756004 1.92253002 -1.96878002 0 P 0 ;0
L 1.92253002 -1.96878002 1.92056998 -1.96986998 0 P 0 ;0
L 1.92056998 -1.96986998 1.91855 -1.97081998 0 P 0 ;0
L 1.91855 -1.97081998 1.91646004 -1.97161004 0 P 0 ;0
L 1.91646004 -1.97161004 1.91433002 -1.97223996 0 P 0 ;0
L 1.91433002 -1.97223996 1.9112 -1.97291004 0 P 0 ;0
L 1.9112 -1.97291004 1.90803996 -1.97331998 0 P 0 ;0
L 1.90803996 -1.97331998 1.90483996 -1.97346004 0 P 0 ;0
L 1.90476004 -1.97173996 1.9048 -1.97173996 0 P 0 ;0
L 1.9048 -1.97173996 1.90483996 -1.97173002 0 P 0 ;0
L 1.90483996 -1.97173002 1.90736004 -1.9716 0 P 0 ;0
L 1.90736004 -1.9716 1.9074 -1.97158996 0 P 0 ;0
L 1.9074 -1.97158996 1.90746998 -1.97158996 0 P 0 ;0
L 1.90746998 -1.97158996 1.90751004 -1.97158002 0 P 0 ;0
L 1.90751004 -1.97158002 1.91001004 -1.97126004 0 P 0 ;0
L 1.91001004 -1.97126004 1.91005 -1.97125 0 P 0 ;0
L 1.91005 -1.97125 1.91008002 -1.97123996 0 P 0 ;0
L 1.91008002 -1.97123996 1.91011998 -1.97123996 0 P 0 ;0
L 1.91011998 -1.97123996 1.91016004 -1.97123002 0 P 0 ;0
L 1.91016004 -1.97123002 1.9126 -1.97071998 0 P 0 ;0
L 1.9126 -1.97071998 1.9126 -1.97071004 0 P 0 ;0
L 1.9126 -1.97071004 1.91266998 -1.97071004 0 P 0 ;0
L 1.91266998 -1.97071004 1.91271004 -1.97068996 0 P 0 ;0
L 1.91271004 -1.97068996 1.91275 -1.97068002 0 P 0 ;0
L 1.91275 -1.97068002 1.91511998 -1.96998996 0 P 0 ;0
L 1.91511998 -1.96998996 1.91515 -1.96998996 0 P 0 ;0
L 1.91515 -1.96998996 1.91518996 -1.96996998 0 P 0 ;0
L 1.91518996 -1.96996998 1.91523002 -1.96996004 0 P 0 ;0
L 1.91523002 -1.96996004 1.91526004 -1.96995 0 P 0 ;0
L 1.91526004 -1.96995 1.91756998 -1.96908002 0 P 0 ;0
L 1.91756998 -1.96908002 1.91761004 -1.96906998 0 P 0 ;0
L 1.91761004 -1.96906998 1.91768002 -1.96903996 0 P 0 ;0
L 1.91768002 -1.96903996 1.91771004 -1.96901998 0 P 0 ;0
L 1.91771004 -1.96901998 1.91995 -1.96798002 0 P 0 ;0
L 1.91995 -1.96798002 1.92001998 -1.96795 0 P 0 ;0
L 1.92001998 -1.96795 1.92005 -1.96793002 0 P 0 ;0
L 1.92005 -1.96793002 1.92008996 -1.96791004 0 P 0 ;0
L 1.92008996 -1.96791004 1.92168002 -1.96701998 0 P 0 ;0
L 1.92168002 -1.96701998 1.92171998 -1.967 0 P 0 ;0
L 1.92171998 -1.967 1.92175 -1.96698002 0 P 0 ;0
L 1.92175 -1.96698002 1.92178996 -1.96695 0 P 0 ;0
L 1.92178996 -1.96695 1.92181998 -1.96693002 0 P 0 ;0
L 1.92181998 -1.96693002 1.92331998 -1.96591998 0 P 0 ;0
L 1.92331998 -1.96591998 1.92336004 -1.9659 0 P 0 ;0
L 1.92336004 -1.9659 1.92341998 -1.96586004 0 P 0 ;0
L 1.92341998 -1.96586004 1.92345 -1.96583002 0 P 0 ;0
L 1.92345 -1.96583002 1.92486004 -1.9647 0 P 0 ;0
L 1.92486004 -1.9647 1.92493002 -1.96465 0 P 0 ;0
L 1.92493002 -1.96465 1.92496004 -1.96463002 0 P 0 ;0
L 1.92496004 -1.96463002 1.92498996 -1.9646 0 P 0 ;0
L 1.92498996 -1.9646 1.92631004 -1.96336998 0 P 0 ;0
L 1.92631004 -1.96336998 1.9264 -1.96328002 0 P 0 ;0
L 1.9264 -1.96328002 1.92641998 -1.96325 0 P 0 ;0
L 1.92641998 -1.96325 1.92763996 -1.96191998 0 P 0 ;0
L 1.92763996 -1.96191998 1.92766998 -1.96188996 0 P 0 ;0
L 1.92766998 -1.96188996 1.92768996 -1.96186004 0 P 0 ;0
L 1.92768996 -1.96186004 1.92771998 -1.96183002 0 P 0 ;0
L 1.92771998 -1.96183002 1.92773996 -1.9618 0 P 0 ;0
L 1.92773996 -1.9618 1.92913996 -1.96001004 0 P 0 ;0
L 1.92913996 -1.96001004 1.92918996 -1.95995 0 P 0 ;0
L 1.92918996 -1.95995 1.92921004 -1.95991004 0 P 0 ;0
L 1.92921004 -1.95991004 1.92923002 -1.95988002 0 P 0 ;0
L 1.92923002 -1.95988002 1.93048002 -1.95798996 0 P 0 ;0
L 1.93048002 -1.95798996 1.93051998 -1.95793002 0 P 0 ;0
L 1.93051998 -1.95793002 1.93053996 -1.95788996 0 P 0 ;0
L 1.93053996 -1.95788996 1.93056004 -1.95786004 0 P 0 ;0
L 1.93056004 -1.95786004 1.93166004 -1.95588002 0 P 0 ;0
L 1.93166004 -1.95588002 1.93171004 -1.95576998 0 P 0 ;0
L 1.93171004 -1.95576998 1.93173002 -1.95573996 0 P 0 ;0
L 1.93173002 -1.95573996 1.93266998 -1.95366998 0 P 0 ;0
L 1.93266998 -1.95366998 1.93271004 -1.95356998 0 P 0 ;0
L 1.93271004 -1.95356998 1.93273002 -1.95353002 0 P 0 ;0
L 1.93273002 -1.95353002 1.9335 -1.9514 0 P 0 ;0
L 1.9335 -1.9514 1.93351004 -1.95136998 0 P 0 ;0
L 1.93351004 -1.95136998 1.93353002 -1.95133002 0 P 0 ;0
L 1.93353002 -1.95133002 1.93355 -1.95125 0 P 0 ;0
L 1.93355 -1.95125 1.93416004 -1.94906998 0 P 0 ;0
L 1.93416004 -1.94906998 1.93416998 -1.94903002 0 P 0 ;0
L 1.93416998 -1.94903002 1.93418002 -1.949 0 P 0 ;0
L 1.93418002 -1.949 1.93418002 -1.94896004 0 P 0 ;0
L 1.93418002 -1.94896004 1.93418996 -1.94891998 0 P 0 ;0
L 1.93418996 -1.94891998 1.93463996 -1.94665 0 P 0 ;0
L 1.93463996 -1.94665 1.93463996 -1.94661004 0 P 0 ;0
L 1.93463996 -1.94661004 1.93465 -1.94656998 0 P 0 ;0
L 1.93465 -1.94656998 1.93466004 -1.9465 0 P 0 ;0
L 1.93466004 -1.9465 1.93493996 -1.9442 0 P 0 ;0
L 1.93493996 -1.9442 1.93493996 -1.94413002 0 P 0 ;0
L 1.93493996 -1.94413002 1.93495 -1.94408996 0 P 0 ;0
L 1.93495 -1.94408996 1.93495 -1.94406004 0 P 0 ;0
L 1.93495 -1.94406004 1.93505 -1.94173996 0 P 0 ;0
L 1.93505 -1.94173996 1.93506004 -1.94171004 0 P 0 ;0
L 1.93506004 -1.94171004 1.93506004 -1.9416 0 P 0 ;0
L 1.93506004 -1.9416 1.93498996 -1.93928996 0 P 0 ;0
L 1.93498996 -1.93928996 1.93498996 -1.93921004 0 P 0 ;0
L 1.93498996 -1.93921004 1.93498002 -1.93913996 0 P 0 ;0
L 1.93498002 -1.93913996 1.93475 -1.93683996 0 P 0 ;0
L 1.93475 -1.93683996 1.93473996 -1.93676998 0 P 0 ;0
L 1.93473996 -1.93676998 1.93473002 -1.93673002 0 P 0 ;0
L 1.93473002 -1.93673002 1.93473002 -1.93668996 0 P 0 ;0
L 1.93473002 -1.93668996 1.93433002 -1.93441004 0 P 0 ;0
L 1.93433002 -1.93441004 1.93431998 -1.93436998 0 P 0 ;0
L 1.93431998 -1.93436998 1.93431004 -1.93433996 0 P 0 ;0
L 1.93431004 -1.93433996 1.93428996 -1.93426004 0 P 0 ;0
L 1.93428996 -1.93426004 1.93373002 -1.93206004 0 P 0 ;0
L 1.93373002 -1.93206004 1.93368996 -1.93191998 0 P 0 ;0
L 1.93368996 -1.93191998 1.93296004 -1.92976998 0 P 0 ;0
L 1.93296004 -1.92976998 1.93293996 -1.9297 0 P 0 ;0
L 1.93293996 -1.9297 1.93291004 -1.92963002 0 P 0 ;0
L 1.93291004 -1.92963002 1.93201998 -1.92753996 0 P 0 ;0
L 1.93201998 -1.92753996 1.93196998 -1.92743002 0 P 0 ;0
L 1.93196998 -1.92743002 1.93196004 -1.9274 0 P 0 ;0
L 1.93196004 -1.9274 1.93091998 -1.92538996 0 P 0 ;0
L 1.93091998 -1.92538996 1.9309 -1.92536004 0 P 0 ;0
L 1.9309 -1.92536004 1.93088002 -1.92531998 0 P 0 ;0
L 1.93088002 -1.92531998 1.93086004 -1.92528996 0 P 0 ;0
L 1.93086004 -1.92528996 1.93083996 -1.92525 0 P 0 ;0
L 1.93083996 -1.92525 1.92965 -1.92331998 0 P 0 ;0
L 1.92965 -1.92331998 1.92956998 -1.9232 0 P 0 ;0
L 1.92956998 -1.9232 1.92823002 -1.92136004 0 P 0 ;0
L 1.92823002 -1.92136004 1.92818002 -1.9213 0 P 0 ;0
L 1.92818002 -1.9213 1.92816004 -1.92126998 0 P 0 ;0
L 1.92816004 -1.92126998 1.92813002 -1.92123996 0 P 0 ;0
L 1.92813002 -1.92123996 1.92671998 -1.91958002 0 P 0 ;0
L 1.92671998 -1.91958002 1.9266 -1.91946004 0 P 0 ;0
L 1.9266 -1.91946004 1.92505 -1.91793002 0 P 0 ;0
L 1.92505 -1.91793002 1.92498996 -1.91786998 0 P 0 ;0
L 1.92498996 -1.91786998 1.92493002 -1.91781998 0 P 0 ;0
L 1.92493002 -1.91781998 1.92325 -1.91643002 0 P 0 ;0
L 1.92325 -1.91643002 1.92318996 -1.91636998 0 P 0 ;0
L 1.92318996 -1.91636998 1.92311998 -1.91631998 0 P 0 ;0
L 1.92311998 -1.91631998 1.92133002 -1.91508002 0 P 0 ;0
L 1.92133002 -1.91508002 1.92126004 -1.91503996 0 P 0 ;0
L 1.92126004 -1.91503996 1.92121998 -1.91501004 0 P 0 ;0
L 1.92121998 -1.91501004 1.92118002 -1.91498996 0 P 0 ;0
L 1.92118002 -1.91498996 1.91928996 -1.91391004 0 P 0 ;0
L 1.91928996 -1.91391004 1.91926004 -1.91388996 0 P 0 ;0
L 1.91926004 -1.91388996 1.91913996 -1.91383002 0 P 0 ;0
L 1.91913996 -1.91383002 1.91716998 -1.91291004 0 P 0 ;0
L 1.91716998 -1.91291004 1.91711998 -1.91288996 0 P 0 ;0
L 1.91711998 -1.91288996 1.91705 -1.91286004 0 P 0 ;0
L 1.91705 -1.91286004 1.917 -1.91285 0 P 0 ;0
L 1.917 -1.91285 1.91476998 -1.91203996 0 P 0 ;0
L 1.91476998 -1.91203996 1.91468996 -1.91201998 0 P 0 ;0
L 1.91468996 -1.91201998 1.91465 -1.912 0 P 0 ;0
L 1.91465 -1.912 1.9146 -1.91198996 0 P 0 ;0
L 1.9146 -1.91198996 1.91233002 -1.91138996 0 P 0 ;0
L 1.91233002 -1.91138996 1.91228002 -1.91138002 0 P 0 ;0
L 1.91228002 -1.91138002 1.91223996 -1.91136998 0 P 0 ;0
L 1.91223996 -1.91136998 1.91216004 -1.91136004 0 P 0 ;0
L 1.91216004 -1.91136004 1.90983002 -1.91095 0 P 0 ;0
L 1.90983002 -1.91095 1.9098 -1.91093996 0 P 0 ;0
L 1.9098 -1.91093996 1.90976004 -1.91093996 0 P 0 ;0
L 1.90976004 -1.91093996 1.90971998 -1.91093002 0 P 0 ;0
L 1.90971998 -1.91093002 1.90968002 -1.91093002 0 P 0 ;0
L 1.90968002 -1.91093002 1.90713996 -1.91068996 0 P 0 ;0
L 1.90713996 -1.91068996 1.9071 -1.91068002 0 P 0 ;0
L 1.9071 -1.91068002 1.907 -1.91068002 0 P 0 ;0
L 1.907 -1.91068002 1.90445 -1.91061004 0 P 0 ;0
L 1.90445 -1.91061004 1.90431004 -1.91061004 0 P 0 ;0
L 1.90431004 -1.91061004 1.90176004 -1.91071004 0 P 0 ;0
L 1.90176004 -1.91071004 1.90173002 -1.91071998 0 P 0 ;0
L 1.90173002 -1.91071998 1.90166004 -1.91071998 0 P 0 ;0
L 1.90166004 -1.91071998 1.90161998 -1.91073002 0 P 0 ;0
L 1.90161998 -1.91073002 1.89913002 -1.911 0 P 0 ;0
L 1.89913002 -1.911 1.89906004 -1.91101004 0 P 0 ;0
L 1.89906004 -1.91101004 1.89901998 -1.91101998 0 P 0 ;0
L 1.89901998 -1.91101998 1.89898996 -1.91101998 0 P 0 ;0
L 1.89898996 -1.91101998 1.89653002 -1.91146998 0 P 0 ;0
L 1.89653002 -1.91146998 1.8965 -1.91148002 0 P 0 ;0
L 1.8965 -1.91148002 1.89646004 -1.91148002 0 P 0 ;0
L 1.89646004 -1.91148002 1.8964 -1.9115 0 P 0 ;0
L 1.8964 -1.9115 1.89396998 -1.91211998 0 P 0 ;0
L 1.89396998 -1.91211998 1.89393996 -1.91213002 0 P 0 ;0
L 1.89393996 -1.91213002 1.89383002 -1.91216004 0 P 0 ;0
L 1.89383002 -1.91216004 1.89225 -1.91268996 0 P 0 ;0
L 1.89225 -1.91268996 1.89218002 -1.91271998 0 P 0 ;0
L 1.89218002 -1.91271998 1.89211004 -1.91273996 0 P 0 ;0
L 1.89211004 -1.91273996 1.8921 -1.91273996 0 P 0 ;0
L 1.8921 -1.91273996 1.89058002 -1.91338996 0 P 0 ;0
L 1.89058002 -1.91338996 1.89043996 -1.91345 0 P 0 ;0
L 1.89043996 -1.91345 1.88896004 -1.91421004 0 P 0 ;0
L 1.88896004 -1.91421004 1.88893002 -1.91423002 0 P 0 ;0
L 1.88893002 -1.91423002 1.8889 -1.91423996 0 P 0 ;0
L 1.8889 -1.91423996 1.88886004 -1.91426004 0 P 0 ;0
L 1.88886004 -1.91426004 1.88883002 -1.91428002 0 P 0 ;0
L 1.88883002 -1.91428002 1.88741004 -1.91515 0 P 0 ;0
L 1.88741004 -1.91515 1.88733996 -1.91518996 0 P 0 ;0
L 1.88733996 -1.91518996 1.88728002 -1.91523996 0 P 0 ;0
L 1.88728002 -1.91523996 1.88526004 -1.9167 0 P 0 ;0
L 1.88526004 -1.9167 1.88521998 -1.91673002 0 P 0 ;0
L 1.88521998 -1.91673002 1.88518996 -1.91675 0 P 0 ;0
L 1.88518996 -1.91675 1.88516004 -1.91678002 0 P 0 ;0
L 1.88516004 -1.91678002 1.88511998 -1.91681004 0 P 0 ;0
L 1.88511998 -1.91681004 1.88323002 -1.91845 0 P 0 ;0
L 1.88323002 -1.91845 1.8832 -1.91846998 0 P 0 ;0
L 1.8832 -1.91846998 1.88311004 -1.91856004 0 P 0 ;0
L 1.88311004 -1.91856004 1.88136998 -1.92036004 0 P 0 ;0
L 1.88136998 -1.92036004 1.88128002 -1.92045 0 P 0 ;0
L 1.88128002 -1.92045 1.88125 -1.92048996 0 P 0 ;0
L 1.88125 -1.92048996 1.87968002 -1.92241998 0 P 0 ;0
L 1.87968002 -1.92241998 1.87965 -1.92245 0 P 0 ;0
L 1.87965 -1.92245 1.87961998 -1.92248996 0 P 0 ;0
L 1.87961998 -1.92248996 1.87956998 -1.92256004 0 P 0 ;0
L 1.87956998 -1.92256004 1.87816998 -1.92461998 0 P 0 ;0
L 1.87816998 -1.92461998 1.8781 -1.92473002 0 P 0 ;0
L 1.8781 -1.92473002 1.87808002 -1.92476998 0 P 0 ;0
L 1.87808002 -1.92476998 1.87685 -1.92695 0 P 0 ;0
L 1.87685 -1.92695 1.87683002 -1.92698996 0 P 0 ;0
L 1.87683002 -1.92698996 1.87681004 -1.92701998 0 P 0 ;0
L 1.87681004 -1.92701998 1.87678996 -1.92706998 0 P 0 ;0
L 1.87678996 -1.92706998 1.87676998 -1.92711004 0 P 0 ;0
L 1.87676998 -1.92711004 1.87573002 -1.92941004 0 P 0 ;0
L 1.87573002 -1.92941004 1.87571004 -1.92945 0 P 0 ;0
L 1.87571004 -1.92945 1.8757 -1.92948996 0 P 0 ;0
L 1.8757 -1.92948996 1.87568002 -1.92951998 0 P 0 ;0
L 1.87568002 -1.92951998 1.87566998 -1.92956998 0 P 0 ;0
L 1.87566998 -1.92956998 1.87483996 -1.93193002 0 P 0 ;0
L 1.87483996 -1.93193002 1.87481004 -1.93201004 0 P 0 ;0
L 1.87481004 -1.93201004 1.87478996 -1.93208996 0 P 0 ;0
L 1.87478996 -1.93208996 1.87416004 -1.93451998 0 P 0 ;0
L 1.87416004 -1.93451998 1.87413996 -1.93456004 0 P 0 ;0
L 1.87413996 -1.93456004 1.87413002 -1.9346 0 P 0 ;0
L 1.87413002 -1.9346 1.87413002 -1.93463996 0 P 0 ;0
L 1.87413002 -1.93463996 1.87411998 -1.93468002 0 P 0 ;0
L 1.87411998 -1.93468002 1.8737 -1.93715 0 P 0 ;0
L 1.8737 -1.93715 1.87368996 -1.93718996 0 P 0 ;0
L 1.87368996 -1.93718996 1.87368002 -1.93723996 0 P 0 ;0
L 1.87368002 -1.93723996 1.87368002 -1.93731998 0 P 0 ;0
L 1.87368002 -1.93731998 1.87346998 -1.93981998 0 P 0 ;0
L 1.87346998 -1.93981998 1.87346004 -1.93986004 0 P 0 ;0
L 1.87346004 -1.93986004 1.87346004 -1.94258002 0 P 0 ;0
L 1.87346004 -1.94258002 1.87346998 -1.94266004 0 P 0 ;0
L 1.87346998 -1.94266004 1.87368002 -1.94516998 0 P 0 ;0
L 1.87368002 -1.94516998 1.87368996 -1.94521004 0 P 0 ;0
L 1.87368996 -1.94521004 1.87368996 -1.94525 0 P 0 ;0
L 1.87368996 -1.94525 1.87371004 -1.94533996 0 P 0 ;0
L 1.87371004 -1.94533996 1.87413996 -1.94778996 0 P 0 ;0
L 1.87413996 -1.94778996 1.87413996 -1.94783996 0 P 0 ;0
L 1.87413996 -1.94783996 1.87416998 -1.94796004 0 P 0 ;0
L 1.87416998 -1.94796004 1.87481004 -1.95036998 0 P 0 ;0
L 1.87481004 -1.95036998 1.87483996 -1.95048996 0 P 0 ;0
L 1.87483996 -1.95048996 1.87486004 -1.95053002 0 P 0 ;0
L 1.87486004 -1.95053002 1.8757 -1.95288002 0 P 0 ;0
L 1.8757 -1.95288002 1.87571004 -1.95291998 0 P 0 ;0
L 1.87571004 -1.95291998 1.87575 -1.953 0 P 0 ;0
L 1.87575 -1.953 1.87576004 -1.95303996 0 P 0 ;0
L 1.87576004 -1.95303996 1.8768 -1.9553 0 P 0 ;0
L 1.8768 -1.9553 1.87686004 -1.95541998 0 P 0 ;0
L 1.87686004 -1.95541998 1.87688002 -1.95545 0 P 0 ;0
L 1.87688002 -1.95545 1.8781 -1.95761004 0 P 0 ;0
L 1.8781 -1.95761004 1.87811998 -1.95761004 0 P 0 ;0
L 1.87811998 -1.95761004 1.8781 -1.95761998 0 P 0 ;0
L 1.8781 -1.95761998 1.87813996 -1.95768996 0 P 0 ;0
L 1.87813996 -1.95768996 1.87816998 -1.95771998 0 P 0 ;0
L 1.87816998 -1.95771998 1.87818996 -1.95775 0 P 0 ;0
L 1.87818996 -1.95775 1.87938002 -1.95951004 0 P 0 ;0
L 1.87938002 -1.95951004 1.87943996 -1.9596 0 P 0 ;0
L 1.87943996 -1.9596 1.87946998 -1.95963002 0 P 0 ;0
L 1.87946998 -1.95963002 1.88078002 -1.96128996 0 P 0 ;0
L 1.88078002 -1.96128996 1.88081004 -1.96131998 0 P 0 ;0
L 1.88081004 -1.96131998 1.88083002 -1.96135 0 P 0 ;0
L 1.88083002 -1.96135 1.88086004 -1.96136998 0 P 0 ;0
L 1.88086004 -1.96136998 1.88088002 -1.9614 0 P 0 ;0
L 1.88088002 -1.9614 1.88231998 -1.96295 0 P 0 ;0
L 1.88231998 -1.96295 1.88233996 -1.96298002 0 P 0 ;0
L 1.88233996 -1.96298002 1.8824 -1.96303996 0 P 0 ;0
L 1.8824 -1.96303996 1.88243002 -1.96306004 0 P 0 ;0
L 1.88243002 -1.96306004 1.88398002 -1.9645 0 P 0 ;0
L 1.88398002 -1.9645 1.88401004 -1.96451998 0 P 0 ;0
L 1.88401004 -1.96451998 1.88403002 -1.96455 0 P 0 ;0
L 1.88403002 -1.96455 1.88406998 -1.96458002 0 P 0 ;0
L 1.88406998 -1.96458002 1.88408996 -1.9646 0 P 0 ;0
L 1.88408996 -1.9646 1.88575 -1.96591004 0 P 0 ;0
L 1.88575 -1.96591004 1.88578002 -1.96593996 0 P 0 ;0
L 1.88578002 -1.96593996 1.88586998 -1.966 0 P 0 ;0
L 1.88586998 -1.966 1.88761998 -1.96718996 0 P 0 ;0
L 1.88761998 -1.96718996 1.88766004 -1.96721004 0 P 0 ;0
L 1.88766004 -1.96721004 1.88775 -1.96726998 0 P 0 ;0
L 1.88775 -1.96726998 1.88958996 -1.96831998 0 P 0 ;0
L 1.88958996 -1.96831998 1.88965 -1.96836004 0 P 0 ;0
L 1.88965 -1.96836004 1.88968002 -1.96836998 0 P 0 ;0
L 1.88968002 -1.96836998 1.88971998 -1.96838996 0 P 0 ;0
L 1.88971998 -1.96838996 1.89145 -1.96921998 0 P 0 ;0
L 1.89145 -1.96921998 1.89151004 -1.96925 0 P 0 ;0
L 1.89151004 -1.96925 1.89155 -1.96926004 0 P 0 ;0
L 1.89155 -1.96926004 1.89158002 -1.96926998 0 P 0 ;0
L 1.89158002 -1.96926998 1.89336004 -1.96996998 0 P 0 ;0
L 1.89336004 -1.96996998 1.89336004 -1.96998002 0 P 0 ;0
L 1.89336004 -1.96998002 1.89346004 -1.97001004 0 P 0 ;0
L 1.89346004 -1.97001004 1.89348996 -1.97001998 0 P 0 ;0
L 1.89348996 -1.97001998 1.89531998 -1.9706 0 P 0 ;0
L 1.89531998 -1.9706 1.89536004 -1.97061004 0 P 0 ;0
L 1.89536004 -1.97061004 1.89541998 -1.97063002 0 P 0 ;0
L 1.89541998 -1.97063002 1.89546004 -1.97063002 0 P 0 ;0
L 1.89546004 -1.97063002 1.89731998 -1.97108002 0 P 0 ;0
L 1.89731998 -1.97108002 1.89741998 -1.9711 0 P 0 ;0
L 1.89741998 -1.9711 1.89746004 -1.9711 0 P 0 ;0
L 1.89746004 -1.9711 1.89746004 -1.97111004 0 P 0 ;0
L 1.89746004 -1.97111004 1.89933996 -1.97141998 0 P 0 ;0
L 1.89933996 -1.97141998 1.89936998 -1.97143002 0 P 0 ;0
L 1.89936998 -1.97143002 1.89941004 -1.97143002 0 P 0 ;0
L 1.89941004 -1.97143002 1.89945 -1.97143996 0 P 0 ;0
L 1.89945 -1.97143996 1.89948002 -1.97143996 0 P 0 ;0
L 1.89948002 -1.97143996 1.90201004 -1.97168002 0 P 0 ;0
L 1.90201004 -1.97168002 1.90205 -1.97168002 0 P 0 ;0
L 1.90205 -1.97168002 1.90208996 -1.97168996 0 P 0 ;0
L 1.90208996 -1.97168996 1.90216004 -1.97168996 0 P 0 ;0
L 1.90216004 -1.97168996 1.90468996 -1.97173996 0 P 0 ;0
L 1.90468996 -1.97173996 1.90476004 -1.97173996 0 P 0 ;0
L 1.80616004 -2.12823996 1.83348996 -2.12823996 0 P 0 ;0
L 1.79591998 -2.12723996 1.8396 -2.12723996 0 P 0 ;0
L 1.78818002 -2.12623996 1.84465 -2.12623996 0 P 0 ;0
L 1.82003996 -2.09123996 1.87618996 -2.09123996 0 P 0 ;0
L 1.82198996 -2.09023996 1.8762 -2.09023996 0 P 0 ;0
L 1.82325 -2.08923996 1.8762 -2.08923996 0 P 0 ;0
L 1.82411998 -2.08823996 1.87618996 -2.08823996 0 P 0 ;0
L 1.82463002 -2.08723996 1.87616998 -2.08723996 0 P 0 ;0
L 1.82488002 -2.08623996 1.87615 -2.08623996 0 P 0 ;0
L 1.82493002 -2.08523996 1.87613002 -2.08523996 0 P 0 ;0
L 1.82476998 -2.08423996 1.87611004 -2.08423996 0 P 0 ;0
L 1.64846004 -2.08295 1.73316998 -2.08295 0 P 0 ;0
L 1.64811998 -2.08195 1.73356998 -2.08195 0 P 0 ;0
L 1.64776998 -2.08095 1.73398002 -2.08095 0 P 0 ;0
L 1.64743002 -2.07995 1.73438002 -2.07995 0 P 0 ;0
L 1.64708996 -2.07895 1.73478996 -2.07895 0 P 0 ;0
L 1.64673996 -2.07795 1.7352 -2.07795 0 P 0 ;0
L 1.6464 -2.07695 1.7356 -2.07695 0 P 0 ;0
L 1.64605 -2.07595 1.73601004 -2.07595 0 P 0 ;0
L 1.64571004 -2.07495 1.73641004 -2.07495 0 P 0 ;0
L 1.64536004 -2.07395 1.73681004 -2.07395 0 P 0 ;0
L 1.64501998 -2.07295 1.73721998 -2.07295 0 P 0 ;0
L 1.64466998 -2.07195 1.73761998 -2.07195 0 P 0 ;0
L 1.64433002 -2.07095 1.73803002 -2.07095 0 P 0 ;0
L 1.64398002 -2.06995 1.69251004 -2.06995 0 P 0 ;0
L 1.69583002 -2.06995 1.73843996 -2.06995 0 P 0 ;0
L 1.64363002 -2.06895 1.69168002 -2.06895 0 P 0 ;0
L 1.69671998 -2.06895 1.73883996 -2.06895 0 P 0 ;0
L 1.64328996 -2.06795 1.69136004 -2.06795 0 P 0 ;0
L 1.69708996 -2.06795 1.73925 -2.06795 0 P 0 ;0
L 1.64293996 -2.06695 1.69108002 -2.06695 0 P 0 ;0
L 1.69738002 -2.06695 1.73965 -2.06695 0 P 0 ;0
L 1.64258996 -2.06595 1.6908 -2.06595 0 P 0 ;0
L 1.69768002 -2.06595 1.74006004 -2.06595 0 P 0 ;0
L 1.64223996 -2.06495 1.69051998 -2.06495 0 P 0 ;0
L 1.69796998 -2.06495 1.74046004 -2.06495 0 P 0 ;0
L 1.6419 -2.06395 1.69023002 -2.06395 0 P 0 ;0
L 1.69826998 -2.06395 1.74086004 -2.06395 0 P 0 ;0
L 1.64155 -2.06295 1.68996004 -2.06295 0 P 0 ;0
L 1.69856004 -2.06295 1.74126998 -2.06295 0 P 0 ;0
L 1.6412 -2.06195 1.68966998 -2.06195 0 P 0 ;0
L 1.69886004 -2.06195 1.74168002 -2.06195 0 P 0 ;0
L 1.64085 -2.06095 1.68938996 -2.06095 0 P 0 ;0
L 1.69915 -2.06095 1.74208002 -2.06095 0 P 0 ;0
L 1.6405 -2.05995 1.68911004 -2.05995 0 P 0 ;0
L 1.69945 -2.05995 1.74248002 -2.05995 0 P 0 ;0
L 1.64016004 -2.05895 1.68883002 -2.05895 0 P 0 ;0
L 1.69973996 -2.05895 1.74288996 -2.05895 0 P 0 ;0
L 1.63981004 -2.05795 1.68855 -2.05795 0 P 0 ;0
L 1.70003996 -2.05795 1.74328996 -2.05795 0 P 0 ;0
L 1.63946004 -2.05695 1.68826998 -2.05695 0 P 0 ;0
L 1.70033002 -2.05695 1.7437 -2.05695 0 P 0 ;0
L 1.63911004 -2.05595 1.68798996 -2.05595 0 P 0 ;0
L 1.70063002 -2.05595 1.7441 -2.05595 0 P 0 ;0
L 1.63876998 -2.05495 1.68771004 -2.05495 0 P 0 ;0
L 1.70091998 -2.05495 1.74451004 -2.05495 0 P 0 ;0
L 1.63841998 -2.05395 1.68741998 -2.05395 0 P 0 ;0
L 1.70121998 -2.05395 1.74491004 -2.05395 0 P 0 ;0
L 1.63806998 -2.05295 1.68713996 -2.05295 0 P 0 ;0
L 1.70151004 -2.05295 1.74531004 -2.05295 0 P 0 ;0
L 1.63771998 -2.05195 1.68686004 -2.05195 0 P 0 ;0
L 1.70181004 -2.05195 1.74571998 -2.05195 0 P 0 ;0
L 1.63738002 -2.05095 1.68658002 -2.05095 0 P 0 ;0
L 1.7021 -2.05095 1.74611998 -2.05095 0 P 0 ;0
L 1.63703002 -2.04995 1.6863 -2.04995 0 P 0 ;0
L 1.7024 -2.04995 1.74653002 -2.04995 0 P 0 ;0
L 1.63668002 -2.04895 1.68601998 -2.04895 0 P 0 ;0
L 1.70268996 -2.04895 1.74693002 -2.04895 0 P 0 ;0
L 1.63633002 -2.04795 1.68573996 -2.04795 0 P 0 ;0
L 1.70298996 -2.04795 1.74733002 -2.04795 0 P 0 ;0
L 1.63598002 -2.04695 1.68546004 -2.04695 0 P 0 ;0
L 1.70328002 -2.04695 1.74773996 -2.04695 0 P 0 ;0
L 1.63563996 -2.04595 1.68518002 -2.04595 0 P 0 ;0
L 1.70358002 -2.04595 1.74813996 -2.04595 0 P 0 ;0
L 1.63528996 -2.04495 1.6849 -2.04495 0 P 0 ;0
L 1.70386998 -2.04495 1.74855 -2.04495 0 P 0 ;0
L 1.63493996 -2.04395 1.68461004 -2.04395 0 P 0 ;0
L 1.70416998 -2.04395 1.74895 -2.04395 0 P 0 ;0
L 1.63458996 -2.04295 1.68433002 -2.04295 0 P 0 ;0
L 1.70446004 -2.04295 1.74936004 -2.04295 0 P 0 ;0
L 1.63425 -2.04195 1.68405 -2.04195 0 P 0 ;0
L 1.70475 -2.04195 1.74976004 -2.04195 0 P 0 ;0
L 1.6339 -2.04095 1.68376998 -2.04095 0 P 0 ;0
L 1.70503002 -2.04095 1.75016004 -2.04095 0 P 0 ;0
L 1.63355 -2.03995 1.68348996 -2.03995 0 P 0 ;0
L 1.70531998 -2.03995 1.75056998 -2.03995 0 P 0 ;0
L 1.6332 -2.03895 1.68321004 -2.03895 0 P 0 ;0
L 1.7056 -2.03895 1.75096998 -2.03895 0 P 0 ;0
L 1.63286004 -2.03795 1.68293002 -2.03795 0 P 0 ;0
L 1.70588996 -2.03795 1.75138002 -2.03795 0 P 0 ;0
L 1.63251004 -2.03695 1.68266004 -2.03695 0 P 0 ;0
L 1.70618002 -2.03695 1.75178002 -2.03695 0 P 0 ;0
L 1.63216004 -2.03595 1.68238002 -2.03595 0 P 0 ;0
L 1.70646998 -2.03595 1.75218996 -2.03595 0 P 0 ;0
L 1.63181004 -2.03495 1.6821 -2.03495 0 P 0 ;0
L 1.70675 -2.03495 1.75258996 -2.03495 0 P 0 ;0
L 1.63146998 -2.03395 1.68183002 -2.03395 0 P 0 ;0
L 1.70703996 -2.03395 1.75298996 -2.03395 0 P 0 ;0
L 1.63111998 -2.03295 1.68155 -2.03295 0 P 0 ;0
L 1.70733002 -2.03295 1.7534 -2.03295 0 P 0 ;0
L 1.63076998 -2.03195 1.68126998 -2.03195 0 P 0 ;0
L 1.70761004 -2.03195 1.75381004 -2.03195 0 P 0 ;0
L 1.63041998 -2.03095 1.68098996 -2.03095 0 P 0 ;0
L 1.7079 -2.03095 1.75421004 -2.03095 0 P 0 ;0
L 1.63006998 -2.02995 1.68071004 -2.02995 0 P 0 ;0
L 1.70818996 -2.02995 1.75461004 -2.02995 0 P 0 ;0
L 1.62973002 -2.02895 1.68043996 -2.02895 0 P 0 ;0
L 1.70846998 -2.02895 1.75501998 -2.02895 0 P 0 ;0
L 1.62938002 -2.02795 1.68016004 -2.02795 0 P 0 ;0
L 1.70876004 -2.02795 1.75541998 -2.02795 0 P 0 ;0
L 1.62903002 -2.02695 1.67988002 -2.02695 0 P 0 ;0
L 1.70905 -2.02695 1.75583002 -2.02695 0 P 0 ;0
L 1.62868002 -2.02595 1.6796 -2.02595 0 P 0 ;0
L 1.70933996 -2.02595 1.75623002 -2.02595 0 P 0 ;0
L 1.62831004 -2.02495 1.67933002 -2.02495 0 P 0 ;0
L 1.70961998 -2.02495 1.75663996 -2.02495 0 P 0 ;0
L 1.62793996 -2.02395 1.67905 -2.02395 0 P 0 ;0
L 1.70991004 -2.02395 1.75703996 -2.02395 0 P 0 ;0
L 1.62756998 -2.02295 1.67876998 -2.02295 0 P 0 ;0
L 1.7102 -2.02295 1.75743996 -2.02295 0 P 0 ;0
L 1.6272 -2.02195 1.6785 -2.02195 0 P 0 ;0
L 1.71048002 -2.02195 1.75785 -2.02195 0 P 0 ;0
L 1.62683002 -2.02095 1.67821998 -2.02095 0 P 0 ;0
L 1.71076004 -2.02095 1.75825 -2.02095 0 P 0 ;0
L 1.62646998 -2.01995 1.67793996 -2.01995 0 P 0 ;0
L 1.71101004 -2.01995 1.75866004 -2.01995 0 P 0 ;0
L 1.6261 -2.01895 1.67766004 -2.01895 0 P 0 ;0
L 1.71126998 -2.01895 1.75906004 -2.01895 0 P 0 ;0
L 1.62573002 -2.01795 1.67738996 -2.01795 0 P 0 ;0
L 1.71151998 -2.01795 1.75946998 -2.01795 0 P 0 ;0
L 1.62536004 -2.01695 1.67711004 -2.01695 0 P 0 ;0
L 1.71176998 -2.01695 1.75986998 -2.01695 0 P 0 ;0
L 1.62498996 -2.01595 1.67683002 -2.01595 0 P 0 ;0
L 1.71203002 -2.01595 1.76026998 -2.01595 0 P 0 ;0
L 1.62461998 -2.01495 1.67656004 -2.01495 0 P 0 ;0
L 1.71228002 -2.01495 1.76068002 -2.01495 0 P 0 ;0
L 1.62425 -2.01395 1.67628002 -2.01395 0 P 0 ;0
L 1.71253996 -2.01395 1.76108002 -2.01395 0 P 0 ;0
L 1.62388002 -2.01295 1.67601998 -2.01295 0 P 0 ;0
L 1.71278996 -2.01295 1.76148996 -2.01295 0 P 0 ;0
L 1.62351004 -2.01195 1.67576998 -2.01195 0 P 0 ;0
L 1.71305 -2.01195 1.76188996 -2.01195 0 P 0 ;0
L 1.62313996 -2.01095 1.67551998 -2.01095 0 P 0 ;0
L 1.7133 -2.01095 1.76228996 -2.01095 0 P 0 ;0
L 1.62276998 -2.00995 1.67528002 -2.00995 0 P 0 ;0
L 1.71355 -2.00995 1.7627 -2.00995 0 P 0 ;0
L 1.6224 -2.00895 1.67503002 -2.00895 0 P 0 ;0
L 1.71381004 -2.00895 1.7631 -2.00895 0 P 0 ;0
L 1.62203002 -2.00795 1.67478996 -2.00795 0 P 0 ;0
L 1.71406004 -2.00795 1.76351004 -2.00795 0 P 0 ;0
L 1.62166004 -2.00695 1.67453996 -2.00695 0 P 0 ;0
L 1.71431004 -2.00695 1.76391004 -2.00695 0 P 0 ;0
L 1.62128996 -2.00595 1.67428996 -2.00595 0 P 0 ;0
L 1.71453996 -2.00595 1.76431998 -2.00595 0 P 0 ;0
L 1.62091004 -2.00495 1.67405 -2.00495 0 P 0 ;0
L 1.71476998 -2.00495 1.76471998 -2.00495 0 P 0 ;0
L 1.62051998 -2.00395 1.6738 -2.00395 0 P 0 ;0
L 1.715 -2.00395 1.76511998 -2.00395 0 P 0 ;0
L 1.62013002 -2.00295 1.67355 -2.00295 0 P 0 ;0
L 1.71523002 -2.00295 1.76553002 -2.00295 0 P 0 ;0
L 1.61973996 -2.00195 1.67331004 -2.00195 0 P 0 ;0
L 1.71546004 -2.00195 1.76593996 -2.00195 0 P 0 ;0
L 1.61935 -2.00095 1.67306004 -2.00095 0 P 0 ;0
L 1.71568996 -2.00095 1.76633996 -2.00095 0 P 0 ;0
L 1.61896004 -1.99995 1.67283996 -1.99995 0 P 0 ;0
L 1.71591998 -1.99995 1.76673996 -1.99995 0 P 0 ;0
L 1.61856998 -1.99895 1.67261998 -1.99895 0 P 0 ;0
L 1.71613996 -1.99895 1.76715 -1.99895 0 P 0 ;0
L 1.71638002 -1.99795 1.76755 -1.99795 0 P 0 ;0
L 1.7166 -1.99695 1.76796004 -1.99695 0 P 0 ;0
L 1.71683002 -1.99595 1.76836004 -1.99595 0 P 0 ;0
L 1.71866998 -1.99495 1.76876998 -1.99495 0 P 0 ;0
L 1.78213996 -2.04823996 1.84641998 -2.04823996 0 P 0 ;0
L 1.78138002 -2.04723996 1.84498996 -2.04723996 0 P 0 ;0
L 1.78071004 -2.04623996 1.84356004 -2.04623996 0 P 0 ;0
L 1.7801 -2.04523996 1.84213996 -2.04523996 0 P 0 ;0
L 1.77956004 -2.04423996 1.84071004 -2.04423996 0 P 0 ;0
L 1.77908996 -2.04323996 1.83928002 -2.04323996 0 P 0 ;0
L 1.77866004 -2.04223996 1.83786004 -2.04223996 0 P 0 ;0
L 1.77831004 -2.04123996 1.83658996 -2.04123996 0 P 0 ;0
L 1.77796004 -2.04023996 1.83536004 -2.04023996 0 P 0 ;0
L 1.77761004 -2.03923996 1.83428002 -2.03923996 0 P 0 ;0
L 1.77733996 -2.03823996 1.83321998 -2.03823996 0 P 0 ;0
L 1.77706998 -2.03723996 1.83236998 -2.03723996 0 P 0 ;0
L 1.7768 -2.03623996 1.83171004 -2.03623996 0 P 0 ;0
L 1.7766 -2.03523996 1.83121004 -2.03523996 0 P 0 ;0
L 1.77641004 -2.03423996 1.83085 -2.03423996 0 P 0 ;0
L 1.77621004 -2.03323996 1.83071004 -2.03323996 0 P 0 ;0
L 1.77608002 -2.03223996 1.83076998 -2.03223996 0 P 0 ;0
L 1.77596004 -2.03123996 1.83106004 -2.03123996 0 P 0 ;0
L 1.77583996 -2.03023996 1.83158996 -2.03023996 0 P 0 ;0
L 1.77576004 -2.02923996 1.83238002 -2.02923996 0 P 0 ;0
L 1.7757 -2.02823996 1.83356998 -2.02823996 0 P 0 ;0
L 1.7757 -2.02723996 1.83591998 -2.02723996 0 P 0 ;0
L 1.77571998 -2.02623996 1.87495 -2.02623996 0 P 0 ;0
L 1.7758 -2.02523996 1.87485 -2.02523996 0 P 0 ;0
L 1.77588996 -2.02423996 1.87475 -2.02423996 0 P 0 ;0
L 1.77605 -2.02323996 1.87465 -2.02323996 0 P 0 ;0
L 1.77621004 -2.02223996 1.87455 -2.02223996 0 P 0 ;0
L 1.7764 -2.02123996 1.87445 -2.02123996 0 P 0 ;0
L 1.77665 -2.02023996 1.87433996 -2.02023996 0 P 0 ;0
L 1.7769 -2.01923996 1.87425 -2.01923996 0 P 0 ;0
L 1.7772 -2.01823996 1.87413996 -2.01823996 0 P 0 ;0
L 1.77753002 -2.01723996 1.87405 -2.01723996 0 P 0 ;0
L 1.77786004 -2.01623996 1.87393996 -2.01623996 0 P 0 ;0
L 1.77823002 -2.01523996 1.87383996 -2.01523996 0 P 0 ;0
L 1.77863996 -2.01423996 1.87373996 -2.01423996 0 P 0 ;0
L 1.77903996 -2.01323996 1.87363996 -2.01323996 0 P 0 ;0
L 1.7795 -2.01223996 1.87353996 -2.01223996 0 P 0 ;0
L 1.77998996 -2.01123996 1.87343996 -2.01123996 0 P 0 ;0
L 1.78046998 -2.01023996 1.87333002 -2.01023996 0 P 0 ;0
L 1.78103996 -2.00923996 1.87323002 -2.00923996 0 P 0 ;0
L 1.78161004 -2.00823996 1.87311998 -2.00823996 0 P 0 ;0
L 1.78221004 -2.00723996 1.87301998 -2.00723996 0 P 0 ;0
L 1.78288002 -2.00623996 1.87291998 -2.00623996 0 P 0 ;0
L 1.64213996 -2.14795 1.70566004 -2.14795 0 P 0 ;0
L 1.64518996 -2.14695 1.7062 -2.14695 0 P 0 ;0
L 1.64728996 -2.14595 1.70673996 -2.14595 0 P 0 ;0
L 1.64906998 -2.14495 1.70728002 -2.14495 0 P 0 ;0
L 1.65058002 -2.14395 1.70783002 -2.14395 0 P 0 ;0
L 1.6519 -2.14295 1.70836998 -2.14295 0 P 0 ;0
L 1.65311998 -2.14195 1.70881998 -2.14195 0 P 0 ;0
L 1.65416998 -2.14095 1.70926998 -2.14095 0 P 0 ;0
L 1.65508996 -2.13995 1.70973002 -2.13995 0 P 0 ;0
L 1.65588002 -2.13895 1.71018002 -2.13895 0 P 0 ;0
L 1.65658002 -2.13795 1.71063002 -2.13795 0 P 0 ;0
L 1.65726998 -2.13695 1.71108996 -2.13695 0 P 0 ;0
L 1.65791998 -2.13595 1.71153996 -2.13595 0 P 0 ;0
L 1.65853002 -2.13495 1.71198996 -2.13495 0 P 0 ;0
L 1.65913002 -2.13395 1.71245 -2.13395 0 P 0 ;0
L 1.65968002 -2.13295 1.7129 -2.13295 0 P 0 ;0
L 1.66021998 -2.13195 1.71331004 -2.13195 0 P 0 ;0
L 1.66071998 -2.13095 1.71371998 -2.13095 0 P 0 ;0
L 1.66121004 -2.12995 1.71411998 -2.12995 0 P 0 ;0
L 1.66166998 -2.12895 1.71453002 -2.12895 0 P 0 ;0
L 1.66201004 -2.12795 1.71493996 -2.12795 0 P 0 ;0
L 1.66223996 -2.12695 1.71533996 -2.12695 0 P 0 ;0
L 1.66235 -2.12595 1.71575 -2.12595 0 P 0 ;0
L 1.66236004 -2.12495 1.71615 -2.12495 0 P 0 ;0
L 1.66228002 -2.12395 1.71656004 -2.12395 0 P 0 ;0
L 1.66211998 -2.12295 1.71696004 -2.12295 0 P 0 ;0
L 1.66188002 -2.12195 1.71736004 -2.12195 0 P 0 ;0
L 1.66156004 -2.12095 1.71776998 -2.12095 0 P 0 ;0
L 1.66121004 -2.11995 1.71818002 -2.11995 0 P 0 ;0
L 1.66086998 -2.11895 1.71858002 -2.11895 0 P 0 ;0
L 1.66053002 -2.11795 1.71898996 -2.11795 0 P 0 ;0
L 1.66018002 -2.11695 1.71938996 -2.11695 0 P 0 ;0
L 1.65983996 -2.11595 1.7198 -2.11595 0 P 0 ;0
L 1.65948996 -2.11495 1.7202 -2.11495 0 P 0 ;0
L 1.65913996 -2.11395 1.72061004 -2.11395 0 P 0 ;0
L 1.6588 -2.11295 1.72101004 -2.11295 0 P 0 ;0
L 1.65846004 -2.11195 1.72141998 -2.11195 0 P 0 ;0
L 1.65811004 -2.11095 1.72181998 -2.11095 0 P 0 ;0
L 1.65776998 -2.10995 1.72223002 -2.10995 0 P 0 ;0
L 1.65741998 -2.10895 1.72263002 -2.10895 0 P 0 ;0
L 1.65708002 -2.10795 1.72303996 -2.10795 0 P 0 ;0
L 1.65673002 -2.10695 1.72343996 -2.10695 0 P 0 ;0
L 1.65638996 -2.10595 1.72385 -2.10595 0 P 0 ;0
L 1.65605 -2.10495 1.72425 -2.10495 0 P 0 ;0
L 1.6557 -2.10395 1.72466004 -2.10395 0 P 0 ;0
L 1.65536004 -2.10295 1.72506998 -2.10295 0 P 0 ;0
L 1.65501004 -2.10195 1.72546998 -2.10195 0 P 0 ;0
L 1.65466998 -2.10095 1.72588002 -2.10095 0 P 0 ;0
L 1.65431998 -2.09995 1.72628002 -2.09995 0 P 0 ;0
L 1.65398002 -2.09895 1.72668996 -2.09895 0 P 0 ;0
L 1.65363002 -2.09795 1.72708996 -2.09795 0 P 0 ;0
L 1.65328996 -2.09695 1.72748996 -2.09695 0 P 0 ;0
L 1.65293996 -2.09595 1.7279 -2.09595 0 P 0 ;0
L 1.6526 -2.09495 1.72831004 -2.09495 0 P 0 ;0
L 1.65225 -2.09395 1.72871004 -2.09395 0 P 0 ;0
L 1.65191004 -2.09295 1.72911998 -2.09295 0 P 0 ;0
L 1.65156998 -2.09195 1.72951998 -2.09195 0 P 0 ;0
L 1.65121998 -2.09095 1.72993002 -2.09095 0 P 0 ;0
L 1.65088002 -2.08995 1.73033002 -2.08995 0 P 0 ;0
L 1.65053002 -2.08895 1.73073996 -2.08895 0 P 0 ;0
L 1.65018996 -2.08795 1.73113996 -2.08795 0 P 0 ;0
L 1.64983996 -2.08695 1.73155 -2.08695 0 P 0 ;0
L 1.6495 -2.08595 1.73195 -2.08595 0 P 0 ;0
L 1.64915 -2.08495 1.73236004 -2.08495 0 P 0 ;0
L 1.64881004 -2.08395 1.73276004 -2.08395 0 P 0 ;0
L 1.81726998 -1.98915 1.81196004 -1.9899 0 P 0 ;0
L 1.81196004 -1.9899 1.80668996 -1.99096998 0 P 0 ;0
L 1.80668996 -1.99096998 1.8019 -1.99226004 0 P 0 ;0
L 1.8019 -1.99226004 1.79718996 -1.99391004 0 P 0 ;0
L 1.79718996 -1.99391004 1.79316004 -1.99568002 0 P 0 ;0
L 1.79316004 -1.99568002 1.78926998 -1.99778002 0 P 0 ;0
L 1.78926998 -1.99778002 1.78771004 -1.99878002 0 P 0 ;0
L 1.78771004 -1.99878002 1.78623002 -1.99988002 0 P 0 ;0
L 1.78623002 -1.99988002 1.78481004 -2.00108002 0 P 0 ;0
L 1.78481004 -2.00108002 1.78346998 -2.00238996 0 P 0 ;0
L 1.78346998 -2.00238996 1.78228996 -2.00371998 0 P 0 ;0
L 1.78228996 -2.00371998 1.78121004 -2.00513002 0 P 0 ;0
L 1.78121004 -2.00513002 1.78023002 -2.00661004 0 P 0 ;0
L 1.78023002 -2.00661004 1.77868002 -2.00933996 0 P 0 ;0
L 1.77868002 -2.00933996 1.77731998 -2.01216998 0 P 0 ;0
L 1.77731998 -2.01216998 1.77611004 -2.01516004 0 P 0 ;0
L 1.77611004 -2.01516004 1.77508996 -2.01823002 0 P 0 ;0
L 1.77508996 -2.01823002 1.77436998 -2.02111004 0 P 0 ;0
L 1.77436998 -2.02111004 1.77388996 -2.02406004 0 P 0 ;0
L 1.77388996 -2.02406004 1.77371998 -2.02603996 0 P 0 ;0
L 1.77371998 -2.02603996 1.77368996 -2.02801998 0 P 0 ;0
L 1.77368996 -2.02801998 1.7738 -2.03001998 0 P 0 ;0
L 1.7738 -2.03001998 1.7742 -2.03338996 0 P 0 ;0
L 1.7742 -2.03338996 1.77485 -2.03671004 0 P 0 ;0
L 1.77485 -2.03671004 1.77573002 -2.03993996 0 P 0 ;0
L 1.77573002 -2.03993996 1.77683996 -2.04308002 0 P 0 ;0
L 1.77683996 -2.04308002 1.7776 -2.04481998 0 P 0 ;0
L 1.7776 -2.04481998 1.7785 -2.04648996 0 P 0 ;0
L 1.7785 -2.04648996 1.77953002 -2.04808996 0 P 0 ;0
L 1.77953002 -2.04808996 1.78061004 -2.04953996 0 P 0 ;0
L 1.78061004 -2.04953996 1.78181004 -2.05091004 0 P 0 ;0
L 1.78181004 -2.05091004 1.78311004 -2.05218996 0 P 0 ;0
L 1.78311004 -2.05218996 1.78988996 -2.05801998 0 P 0 ;0
L 1.78988996 -2.05801998 1.79883996 -2.06491004 0 P 0 ;0
L 1.79883996 -2.06491004 1.80976998 -2.07261004 0 P 0 ;0
L 1.80976998 -2.07261004 1.81753002 -2.07823002 0 P 0 ;0
L 1.81753002 -2.07823002 1.81896998 -2.07943002 0 P 0 ;0
L 1.81896998 -2.07943002 1.82033002 -2.08073002 0 P 0 ;0
L 1.82033002 -2.08073002 1.82156998 -2.08213996 0 P 0 ;0
L 1.82156998 -2.08213996 1.82186004 -2.08251004 0 P 0 ;0
L 1.82186004 -2.08251004 1.82211004 -2.0829 0 P 0 ;0
L 1.82211004 -2.0829 1.82233002 -2.08331004 0 P 0 ;0
L 1.82233002 -2.08331004 1.82253002 -2.08373996 0 P 0 ;0
L 1.82253002 -2.08373996 1.82268002 -2.08418002 0 P 0 ;0
L 1.82268002 -2.08418002 1.82281004 -2.08463002 0 P 0 ;0
L 1.82281004 -2.08463002 1.8229 -2.0851 0 P 0 ;0
L 1.8229 -2.0851 1.82293002 -2.08533996 0 P 0 ;0
L 1.82293002 -2.08533996 1.82293996 -2.08558996 0 P 0 ;0
L 1.82293996 -2.08558996 1.82291998 -2.08583996 0 P 0 ;0
L 1.82291998 -2.08583996 1.82288002 -2.08608002 0 P 0 ;0
L 1.82288002 -2.08608002 1.82283002 -2.08631998 0 P 0 ;0
L 1.82283002 -2.08631998 1.82275 -2.08656004 0 P 0 ;0
L 1.82275 -2.08656004 1.82265 -2.08678996 0 P 0 ;0
L 1.82265 -2.08678996 1.82253996 -2.087 0 P 0 ;0
L 1.82253996 -2.087 1.8224 -2.08721004 0 P 0 ;0
L 1.8224 -2.08721004 1.82225 -2.08741004 0 P 0 ;0
L 1.82225 -2.08741004 1.82208996 -2.08758996 0 P 0 ;0
L 1.82208996 -2.08758996 1.8216 -2.08803996 0 P 0 ;0
L 1.8216 -2.08803996 1.82106998 -2.08845 0 P 0 ;0
L 1.82106998 -2.08845 1.82051004 -2.08881004 0 P 0 ;0
L 1.82051004 -2.08881004 1.81991998 -2.08911998 0 P 0 ;0
L 1.81991998 -2.08911998 1.81931004 -2.08936998 0 P 0 ;0
L 1.81931004 -2.08936998 1.81868002 -2.08958002 0 P 0 ;0
L 1.81868002 -2.08958002 1.81803002 -2.08973002 0 P 0 ;0
L 1.81803002 -2.08973002 1.81736004 -2.08981998 0 P 0 ;0
L 1.81736004 -2.08981998 1.81293002 -2.09001998 0 P 0 ;0
L 1.81293002 -2.09001998 1.80846998 -2.08986004 0 P 0 ;0
L 1.80846998 -2.08986004 1.80256998 -2.08923002 0 P 0 ;0
L 1.80256998 -2.08923002 1.79668002 -2.08818996 0 P 0 ;0
L 1.79668002 -2.08818996 1.78223002 -2.08458002 0 P 0 ;0
L 1.78223002 -2.08458002 1.77788996 -2.08338002 0 P 0 ;0
L 1.77788996 -2.08338002 1.77415 -2.08246004 0 P 0 ;0
L 1.77415 -2.08246004 1.77095 -2.08175 0 P 0 ;0
L 1.77095 -2.08175 1.7709 -2.08173996 0 P 0 ;0
L 1.7709 -2.08173996 1.77076998 -2.08173996 0 P 0 ;0
L 1.77076998 -2.08173996 1.77068996 -2.08176004 0 P 0 ;0
L 1.77068996 -2.08176004 1.77053002 -2.08183996 0 P 0 ;0
L 1.77053002 -2.08183996 1.77043002 -2.08193996 0 P 0 ;0
L 1.77043002 -2.08193996 1.77036998 -2.08201998 0 P 0 ;0
L 1.77036998 -2.08201998 1.77031998 -2.08211998 0 P 0 ;0
L 1.77031998 -2.08211998 1.7703 -2.08216998 0 P 0 ;0
L 1.7703 -2.08216998 1.77028996 -2.08223002 0 P 0 ;0
L 1.77028996 -2.08223002 1.77028002 -2.08228002 0 P 0 ;0
L 1.77028002 -2.08228002 1.77028002 -2.08238996 0 P 0 ;0
L 1.77028002 -2.08238996 1.77056998 -2.08838996 0 P 0 ;0
L 1.77056998 -2.08838996 1.77096004 -2.09526004 0 P 0 ;0
L 1.77096004 -2.09526004 1.77153996 -2.1033 0 P 0 ;0
L 1.77153996 -2.1033 1.77236004 -2.11291004 0 P 0 ;0
L 1.77236004 -2.11291004 1.77311004 -2.1194 0 P 0 ;0
L 1.77311004 -2.1194 1.77383002 -2.12398002 0 P 0 ;0
L 1.77383002 -2.12398002 1.77386004 -2.12411004 0 P 0 ;0
L 1.77386004 -2.12411004 1.7739 -2.12423002 0 P 0 ;0
L 1.7739 -2.12423002 1.77395 -2.12436004 0 P 0 ;0
L 1.77395 -2.12436004 1.77401004 -2.12448002 0 P 0 ;0
L 1.77401004 -2.12448002 1.77408002 -2.12458996 0 P 0 ;0
L 1.77408002 -2.12458996 1.77416004 -2.1247 0 P 0 ;0
L 1.77416004 -2.1247 1.77425 -2.1248 0 P 0 ;0
L 1.77425 -2.1248 1.77435 -2.12488996 0 P 0 ;0
L 1.77435 -2.12488996 1.77445 -2.12496998 0 P 0 ;0
L 1.77445 -2.12496998 1.77456998 -2.12505 0 P 0 ;0
L 1.77456998 -2.12505 1.77571004 -2.12568996 0 P 0 ;0
L 1.77571004 -2.12568996 1.7769 -2.12623996 0 P 0 ;0
L 1.7769 -2.12623996 1.77813002 -2.12668996 0 P 0 ;0
L 1.77813002 -2.12668996 1.7794 -2.12703996 0 P 0 ;0
L 1.7794 -2.12703996 1.78068996 -2.12728996 0 P 0 ;0
L 1.78068996 -2.12728996 1.79791998 -2.12951004 0 P 0 ;0
L 1.79791998 -2.12951004 1.81536004 -2.13106004 0 P 0 ;0
L 1.81536004 -2.13106004 1.82125 -2.13123996 0 P 0 ;0
L 1.82125 -2.13123996 1.82716004 -2.13098996 0 P 0 ;0
L 1.82716004 -2.13098996 1.83583996 -2.12998002 0 P 0 ;0
L 1.83583996 -2.12998002 1.84445 -2.12836004 0 P 0 ;0
L 1.84445 -2.12836004 1.84911998 -2.12711004 0 P 0 ;0
L 1.84911998 -2.12711004 1.85366004 -2.12548002 0 P 0 ;0
L 1.85366004 -2.12548002 1.85806998 -2.12348002 0 P 0 ;0
L 1.85806998 -2.12348002 1.86078996 -2.12196998 0 P 0 ;0
L 1.86078996 -2.12196998 1.8634 -2.12026998 0 P 0 ;0
L 1.8634 -2.12026998 1.86586998 -2.11836998 0 P 0 ;0
L 1.86586998 -2.11836998 1.86821004 -2.11628002 0 P 0 ;0
L 1.86821004 -2.11628002 1.87026004 -2.11413002 0 P 0 ;0
L 1.87026004 -2.11413002 1.8721 -2.11181998 0 P 0 ;0
L 1.8721 -2.11181998 1.87375 -2.10936004 0 P 0 ;0
L 1.87375 -2.10936004 1.87516998 -2.10673996 0 P 0 ;0
L 1.87516998 -2.10673996 1.87605 -2.10483996 0 P 0 ;0
L 1.87605 -2.10483996 1.87683996 -2.10291004 0 P 0 ;0
L 1.87683996 -2.10291004 1.8772 -2.10188002 0 P 0 ;0
L 1.8772 -2.10188002 1.87748996 -2.10083002 0 P 0 ;0
L 1.87748996 -2.10083002 1.87771004 -2.09976998 0 P 0 ;0
L 1.87771004 -2.09976998 1.87798002 -2.09788996 0 P 0 ;0
L 1.87798002 -2.09788996 1.87811998 -2.09601004 0 P 0 ;0
L 1.87811998 -2.09601004 1.87821004 -2.08966998 0 P 0 ;0
L 1.87821004 -2.08966998 1.8781 -2.08353996 0 P 0 ;0
L 1.8781 -2.08353996 1.87798002 -2.08166004 0 P 0 ;0
L 1.87798002 -2.08166004 1.87773002 -2.07976998 0 P 0 ;0
L 1.87773002 -2.07976998 1.87753002 -2.07873996 0 P 0 ;0
L 1.87753002 -2.07873996 1.87726998 -2.07773996 0 P 0 ;0
L 1.87726998 -2.07773996 1.87695 -2.07673996 0 P 0 ;0
L 1.87695 -2.07673996 1.87628996 -2.07505 0 P 0 ;0
L 1.87628996 -2.07505 1.87553002 -2.07338002 0 P 0 ;0
L 1.87553002 -2.07338002 1.87441004 -2.07133996 0 P 0 ;0
L 1.87441004 -2.07133996 1.87313996 -2.06938002 0 P 0 ;0
L 1.87313996 -2.06938002 1.87171004 -2.06751004 0 P 0 ;0
L 1.87171004 -2.06751004 1.8688 -2.06416004 0 P 0 ;0
L 1.8688 -2.06416004 1.86566998 -2.06095 0 P 0 ;0
L 1.86566998 -2.06095 1.86181998 -2.05741998 0 P 0 ;0
L 1.86181998 -2.05741998 1.85778002 -2.05406998 0 P 0 ;0
L 1.85778002 -2.05406998 1.84833996 -2.04715 0 P 0 ;0
L 1.84833996 -2.04715 1.83913996 -2.0407 0 P 0 ;0
L 1.83913996 -2.0407 1.83686004 -2.0389 0 P 0 ;0
L 1.83686004 -2.0389 1.83471998 -2.03691998 0 P 0 ;0
L 1.83471998 -2.03691998 1.83428002 -2.03643002 0 P 0 ;0
L 1.83428002 -2.03643002 1.83386998 -2.0359 0 P 0 ;0
L 1.83386998 -2.0359 1.83351004 -2.03535 0 P 0 ;0
L 1.83351004 -2.03535 1.83318996 -2.03476004 0 P 0 ;0
L 1.83318996 -2.03476004 1.83291998 -2.03415 0 P 0 ;0
L 1.83291998 -2.03415 1.83283996 -2.03393996 0 P 0 ;0
L 1.83283996 -2.03393996 1.83278002 -2.03371004 0 P 0 ;0
L 1.83278002 -2.03371004 1.83273002 -2.03348996 0 P 0 ;0
L 1.83273002 -2.03348996 1.83271004 -2.03326004 0 P 0 ;0
L 1.83271004 -2.03326004 1.8327 -2.03303002 0 P 0 ;0
L 1.8327 -2.03303002 1.83271004 -2.0328 0 P 0 ;0
L 1.83271004 -2.0328 1.83275 -2.03258002 0 P 0 ;0
L 1.83275 -2.03258002 1.83278996 -2.03235 0 P 0 ;0
L 1.83278996 -2.03235 1.83286004 -2.03213002 0 P 0 ;0
L 1.83286004 -2.03213002 1.83293996 -2.03191998 0 P 0 ;0
L 1.83293996 -2.03191998 1.83305 -2.03171004 0 P 0 ;0
L 1.83305 -2.03171004 1.83325 -2.03135 0 P 0 ;0
L 1.83325 -2.03135 1.83348996 -2.03101998 0 P 0 ;0
L 1.83348996 -2.03101998 1.83375 -2.03071004 0 P 0 ;0
L 1.83375 -2.03071004 1.83403002 -2.03041004 0 P 0 ;0
L 1.83403002 -2.03041004 1.83433996 -2.03015 0 P 0 ;0
L 1.83433996 -2.03015 1.83466998 -2.02991004 0 P 0 ;0
L 1.83466998 -2.02991004 1.83501998 -2.02968996 0 P 0 ;0
L 1.83501998 -2.02968996 1.83538002 -2.02951004 0 P 0 ;0
L 1.83538002 -2.02951004 1.83576004 -2.02936004 0 P 0 ;0
L 1.83576004 -2.02936004 1.83615 -2.02923996 0 P 0 ;0
L 1.83615 -2.02923996 1.83655 -2.02915 0 P 0 ;0
L 1.83655 -2.02915 1.8392 -2.02873996 0 P 0 ;0
L 1.8392 -2.02873996 1.84188002 -2.0285 0 P 0 ;0
L 1.84188002 -2.0285 1.84458002 -2.02841004 0 P 0 ;0
L 1.84458002 -2.02841004 1.84993996 -2.02858002 0 P 0 ;0
L 1.84993996 -2.02858002 1.85526998 -2.02916004 0 P 0 ;0
L 1.85526998 -2.02916004 1.86155 -2.03023002 0 P 0 ;0
L 1.86155 -2.03023002 1.86778002 -2.03158002 0 P 0 ;0
L 1.86778002 -2.03158002 1.8713 -2.03238996 0 P 0 ;0
L 1.8713 -2.03238996 1.87428996 -2.03303002 0 P 0 ;0
L 1.87428996 -2.03303002 1.8769 -2.03356004 0 P 0 ;0
L 1.8769 -2.03356004 1.87691998 -2.03356998 0 P 0 ;0
L 1.87691998 -2.03356998 1.87696004 -2.03356998 0 P 0 ;0
L 1.87696004 -2.03356998 1.87696998 -2.03356004 0 P 0 ;0
L 1.87696998 -2.03356004 1.87701004 -2.03356004 0 P 0 ;0
L 1.87701004 -2.03356004 1.87703996 -2.03353996 0 P 0 ;0
L 1.87703996 -2.03353996 1.87706004 -2.03353002 0 P 0 ;0
L 1.87706004 -2.03353002 1.87706998 -2.03351998 0 P 0 ;0
L 1.87706998 -2.03351998 1.87708996 -2.03351004 0 P 0 ;0
L 1.87708996 -2.03351004 1.8771 -2.03348996 0 P 0 ;0
L 1.8771 -2.03348996 1.87711004 -2.03348002 0 P 0 ;0
L 1.87711004 -2.03348002 1.87721998 -2.0333 0 P 0 ;0
L 1.87721998 -2.0333 1.87731998 -2.0331 0 P 0 ;0
L 1.87731998 -2.0331 1.8774 -2.0329 0 P 0 ;0
L 1.8774 -2.0329 1.87746004 -2.03268996 0 P 0 ;0
L 1.87746004 -2.03268996 1.87751004 -2.03248002 0 P 0 ;0
L 1.87751004 -2.03248002 1.87753002 -2.03226998 0 P 0 ;0
L 1.87753002 -2.03226998 1.87753996 -2.03205 0 P 0 ;0
L 1.87753996 -2.03205 1.87753002 -2.03183002 0 P 0 ;0
L 1.87753002 -2.03183002 1.87565 -2.01323996 0 P 0 ;0
L 1.87565 -2.01323996 1.87371004 -1.99451998 0 P 0 ;0
L 1.87371004 -1.99451998 1.8737 -1.99438996 0 P 0 ;0
L 1.8737 -1.99438996 1.87366998 -1.99426998 0 P 0 ;0
L 1.87366998 -1.99426998 1.87363002 -1.99415 0 P 0 ;0
L 1.87363002 -1.99415 1.87358002 -1.99403002 0 P 0 ;0
L 1.87358002 -1.99403002 1.87351998 -1.99391004 0 P 0 ;0
L 1.87351998 -1.99391004 1.87346004 -1.9938 0 P 0 ;0
L 1.87346004 -1.9938 1.87338002 -1.9937 0 P 0 ;0
L 1.87338002 -1.9937 1.87328996 -1.9936 0 P 0 ;0
L 1.87328996 -1.9936 1.8732 -1.99351004 0 P 0 ;0
L 1.8732 -1.99351004 1.8731 -1.99343002 0 P 0 ;0
L 1.8731 -1.99343002 1.87298996 -1.99335 0 P 0 ;0
L 1.87298996 -1.99335 1.87248002 -1.99305 0 P 0 ;0
L 1.87248002 -1.99305 1.87193996 -1.99278002 0 P 0 ;0
L 1.87193996 -1.99278002 1.87136998 -1.99256998 0 P 0 ;0
L 1.87136998 -1.99256998 1.87078996 -1.99241004 0 P 0 ;0
L 1.87078996 -1.99241004 1.8702 -1.9923 0 P 0 ;0
L 1.8702 -1.9923 1.85876004 -1.99076004 0 P 0 ;0
L 1.85876004 -1.99076004 1.84691998 -1.98943002 0 P 0 ;0
L 1.84691998 -1.98943002 1.83693002 -1.98876004 0 P 0 ;0
L 1.83693002 -1.98876004 1.8318 -1.98863002 0 P 0 ;0
L 1.8318 -1.98863002 1.82623002 -1.98866998 0 P 0 ;0
L 1.82623002 -1.98866998 1.82106004 -1.98883996 0 P 0 ;0
L 1.82106004 -1.98883996 1.81726998 -1.98915 0 P 0 ;0
L 1.78061004 -2.12523996 1.84838002 -2.12523996 0 P 0 ;0
L 1.77733002 -2.12423996 1.85121004 -2.12423996 0 P 0 ;0
L 1.77573996 -2.12323996 1.85376998 -2.12323996 0 P 0 ;0
L 1.77558002 -2.12223996 1.85596998 -2.12223996 0 P 0 ;0
L 1.77541998 -2.12123996 1.85798996 -2.12123996 0 P 0 ;0
L 1.77526998 -2.12023996 1.85978996 -2.12023996 0 P 0 ;0
L 1.77511004 -2.11923996 1.86131998 -2.11923996 0 P 0 ;0
L 1.77498996 -2.11823996 1.86276004 -2.11823996 0 P 0 ;0
L 1.77486998 -2.11723996 1.86406998 -2.11723996 0 P 0 ;0
L 1.77475 -2.11623996 1.86526004 -2.11623996 0 P 0 ;0
L 1.77463996 -2.11523996 1.86638002 -2.11523996 0 P 0 ;0
L 1.77451998 -2.11423996 1.8674 -2.11423996 0 P 0 ;0
L 1.77441004 -2.11323996 1.86835 -2.11323996 0 P 0 ;0
L 1.77431004 -2.11223996 1.86921004 -2.11223996 0 P 0 ;0
L 1.77421998 -2.11123996 1.87001004 -2.11123996 0 P 0 ;0
L 1.77413996 -2.11023996 1.87075 -2.11023996 0 P 0 ;0
L 1.77405 -2.10923996 1.87141998 -2.10923996 0 P 0 ;0
L 1.77396998 -2.10823996 1.87208002 -2.10823996 0 P 0 ;0
L 1.77388002 -2.10723996 1.87261998 -2.10723996 0 P 0 ;0
L 1.7738 -2.10623996 1.87316998 -2.10623996 0 P 0 ;0
L 1.77371004 -2.10523996 1.87366004 -2.10523996 0 P 0 ;0
L 1.77363002 -2.10423996 1.87411998 -2.10423996 0 P 0 ;0
L 1.77353996 -2.10323996 1.87453996 -2.10323996 0 P 0 ;0
L 1.77346998 -2.10223996 1.87495 -2.10223996 0 P 0 ;0
L 1.7734 -2.10123996 1.8753 -2.10123996 0 P 0 ;0
L 1.77333002 -2.10023996 1.87556998 -2.10023996 0 P 0 ;0
L 1.77325 -2.09923996 1.87576998 -2.09923996 0 P 0 ;0
L 1.77318002 -2.09823996 1.87591998 -2.09823996 0 P 0 ;0
L 1.77311004 -2.09723996 1.87603002 -2.09723996 0 P 0 ;0
L 1.77303996 -2.09623996 1.8761 -2.09623996 0 P 0 ;0
L 1.77296998 -2.09523996 1.87613002 -2.09523996 0 P 0 ;0
L 1.77291004 -2.09423996 1.87613996 -2.09423996 0 P 0 ;0
L 1.77285 -2.09323996 1.87616004 -2.09323996 0 P 0 ;0
L 1.77278996 -2.09223996 1.87616998 -2.09223996 0 P 0 ;0
L 1.77273002 -2.09123996 1.80256998 -2.09123996 0 P 0 ;0
L 1.77268002 -2.09023996 1.7968 -2.09023996 0 P 0 ;0
L 1.77261998 -2.08923996 1.79263002 -2.08923996 0 P 0 ;0
L 1.77256004 -2.08823996 1.78861998 -2.08823996 0 P 0 ;0
L 1.77251004 -2.08723996 1.7846 -2.08723996 0 P 0 ;0
L 1.77246004 -2.08623996 1.7807 -2.08623996 0 P 0 ;0
L 1.77241998 -2.08523996 1.77705 -2.08523996 0 P 0 ;0
L 1.77236998 -2.08423996 1.77293996 -2.08423996 0 P 0 ;0
L 1.62463996 -2.18195 1.65948996 -2.18195 0 P 0 ;0
L 1.61963996 -2.18095 1.66483002 -2.18095 0 P 0 ;0
L 1.61818002 -1.99795 1.6724 -1.99795 0 P 0 ;0
L 1.61778996 -1.99695 1.67218002 -1.99695 0 P 0 ;0
L 1.6174 -1.99595 1.67196004 -1.99595 0 P 0 ;0
L 1.61701004 -1.99495 1.67173996 -1.99495 0 P 0 ;0
L 1.61391998 -2.15695 1.70026004 -2.15695 0 P 0 ;0
L 1.61386004 -2.15595 1.70088002 -2.15595 0 P 0 ;0
L 1.61381004 -2.15495 1.70151004 -2.15495 0 P 0 ;0
L 1.61375 -2.15395 1.70213996 -2.15395 0 P 0 ;0
L 1.6137 -2.15295 1.70276004 -2.15295 0 P 0 ;0
L 1.61365 -2.15195 1.70338996 -2.15195 0 P 0 ;0
L 1.6136 -2.15095 1.70401004 -2.15095 0 P 0 ;0
L 1.61355 -2.14995 1.70456998 -2.14995 0 P 0 ;0
L 1.61348996 -2.14895 1.70511998 -2.14895 0 P 0 ;0
L 1.61343996 -2.14795 1.61738002 -2.14795 0 P 0 ;0
L 1.55341004 -2.08286998 1.60538002 -2.08286998 0 P 0 ;0
L 1.55286004 -2.08186998 1.60526998 -2.08186998 0 P 0 ;0
L 1.5521 -2.08086998 1.6051 -2.08086998 0 P 0 ;0
L 1.55126998 -2.07986998 1.6049 -2.07986998 0 P 0 ;0
L 1.55033996 -2.07886998 1.60463996 -2.07886998 0 P 0 ;0
L 1.54928996 -2.07786998 1.60433002 -2.07786998 0 P 0 ;0
L 1.54806998 -2.07686998 1.60398996 -2.07686998 0 P 0 ;0
L 1.5467 -2.07586998 1.60356998 -2.07586998 0 P 0 ;0
L 1.54531004 -2.07486998 1.6031 -2.07486998 0 P 0 ;0
L 1.54391004 -2.07386998 1.60258996 -2.07386998 0 P 0 ;0
L 1.54251004 -2.07286998 1.60201004 -2.07286998 0 P 0 ;0
L 1.54111998 -2.07186998 1.60138002 -2.07186998 0 P 0 ;0
L 1.53971998 -2.07086998 1.60068002 -2.07086998 0 P 0 ;0
L 1.53833002 -2.06986998 1.59993002 -2.06986998 0 P 0 ;0
L 1.53693002 -2.06886998 1.59908002 -2.06886998 0 P 0 ;0
L 1.53556004 -2.06786998 1.59821004 -2.06786998 0 P 0 ;0
L 1.53418996 -2.06686998 1.59733996 -2.06686998 0 P 0 ;0
L 1.53281998 -2.06586998 1.59646998 -2.06586998 0 P 0 ;0
L 1.53145 -2.06486998 1.5955 -2.06486998 0 P 0 ;0
L 1.53008002 -2.06386998 1.59453002 -2.06386998 0 P 0 ;0
L 1.52871004 -2.06286998 1.59356004 -2.06286998 0 P 0 ;0
L 1.52733996 -2.06186998 1.59253002 -2.06186998 0 P 0 ;0
L 1.52596998 -2.06086998 1.59145 -2.06086998 0 P 0 ;0
L 1.5246 -2.05986998 1.59038002 -2.05986998 0 P 0 ;0
L 1.52323002 -2.05886998 1.5893 -2.05886998 0 P 0 ;0
L 1.52186004 -2.05786998 1.58813996 -2.05786998 0 P 0 ;0
L 1.52053996 -2.05686998 1.58696004 -2.05686998 0 P 0 ;0
L 1.51935 -2.05586998 1.58576998 -2.05586998 0 P 0 ;0
L 1.51816004 -2.05486998 1.58456998 -2.05486998 0 P 0 ;0
L 1.51706998 -2.05386998 1.58321004 -2.05386998 0 P 0 ;0
L 1.51603996 -2.05286998 1.58185 -2.05286998 0 P 0 ;0
L 1.51501998 -2.05186998 1.58048996 -2.05186998 0 P 0 ;0
L 1.51408996 -2.05086998 1.57913002 -2.05086998 0 P 0 ;0
L 1.5132 -2.04986998 1.57776998 -2.04986998 0 P 0 ;0
L 1.51231998 -2.04886998 1.57641998 -2.04886998 0 P 0 ;0
L 1.51151004 -2.04786998 1.57505 -2.04786998 0 P 0 ;0
L 1.51075 -2.04686998 1.57365 -2.04686998 0 P 0 ;0
L 1.51008002 -2.04586998 1.57223002 -2.04586998 0 P 0 ;0
L 1.50945 -2.04486998 1.57081004 -2.04486998 0 P 0 ;0
L 1.50888002 -2.04386998 1.56938996 -2.04386998 0 P 0 ;0
L 1.50836004 -2.04286998 1.56796998 -2.04286998 0 P 0 ;0
L 1.5079 -2.04186998 1.56655 -2.04186998 0 P 0 ;0
L 1.50748002 -2.04086998 1.56518996 -2.04086998 0 P 0 ;0
L 1.50708996 -2.03986998 1.564 -2.03986998 0 P 0 ;0
L 1.50676004 -2.03886998 1.56296998 -2.03886998 0 P 0 ;0
L 1.50641998 -2.03786998 1.56206004 -2.03786998 0 P 0 ;0
L 1.50616998 -2.03686998 1.56125 -2.03686998 0 P 0 ;0
L 1.50591004 -2.03586998 1.56066998 -2.03586998 0 P 0 ;0
L 1.5057 -2.03486998 1.56031998 -2.03486998 0 P 0 ;0
L 1.50551998 -2.03386998 1.56016004 -2.03386998 0 P 0 ;0
L 1.50533996 -2.03286998 1.56016998 -2.03286998 0 P 0 ;0
L 1.50523996 -2.03186998 1.56036004 -2.03186998 0 P 0 ;0
L 1.50513002 -2.03086998 1.56071998 -2.03086998 0 P 0 ;0
L 1.50506998 -2.02986998 1.56131004 -2.02986998 0 P 0 ;0
L 1.50503996 -2.02886998 1.5622 -2.02886998 0 P 0 ;0
L 1.50501004 -2.02786998 1.56355 -2.02786998 0 P 0 ;0
L 1.50501998 -2.02686998 1.5657 -2.02686998 0 P 0 ;0
L 1.50506998 -2.02586998 1.60378996 -2.02586998 0 P 0 ;0
L 1.50511998 -2.02486998 1.60371004 -2.02486998 0 P 0 ;0
L 1.50521004 -2.02386998 1.60363996 -2.02386998 0 P 0 ;0
L 1.50533996 -2.02286998 1.60356998 -2.02286998 0 P 0 ;0
L 1.50546998 -2.02186998 1.6035 -2.02186998 0 P 0 ;0
L 1.50563996 -2.02086998 1.60343002 -2.02086998 0 P 0 ;0
L 1.50585 -2.01986998 1.60336004 -2.01986998 0 P 0 ;0
L 1.50606004 -2.01886998 1.60328996 -2.01886998 0 P 0 ;0
L 1.50633002 -2.01786998 1.60321998 -2.01786998 0 P 0 ;0
L 1.50661998 -2.01686998 1.60315 -2.01686998 0 P 0 ;0
L 1.50691004 -2.01586998 1.60308002 -2.01586998 0 P 0 ;0
L 1.50726998 -2.01486998 1.603 -2.01486998 0 P 0 ;0
L 1.50766004 -2.01386998 1.60293002 -2.01386998 0 P 0 ;0
L 1.50808996 -2.01286998 1.60285 -2.01286998 0 P 0 ;0
L 1.50856998 -2.01186998 1.60278002 -2.01186998 0 P 0 ;0
L 1.50908996 -2.01086998 1.6027 -2.01086998 0 P 0 ;0
L 1.50966004 -2.00986998 1.60261998 -2.00986998 0 P 0 ;0
L 1.51028996 -2.00886998 1.60255 -2.00886998 0 P 0 ;0
L 1.51096998 -2.00786998 1.60246998 -2.00786998 0 P 0 ;0
L 1.51171998 -2.00686998 1.6024 -2.00686998 0 P 0 ;0
L 1.51253996 -2.00586998 1.60233002 -2.00586998 0 P 0 ;0
L 1.51343996 -2.00486998 1.60225 -2.00486998 0 P 0 ;0
L 1.5144 -2.00386998 1.60218002 -2.00386998 0 P 0 ;0
L 1.51551998 -2.00286998 1.6021 -2.00286998 0 P 0 ;0
L 1.51663996 -2.00186998 1.60203002 -2.00186998 0 P 0 ;0
L 1.51795 -2.00086998 1.60195 -2.00086998 0 P 0 ;0
L 1.51928996 -1.99986998 1.60183996 -1.99986998 0 P 0 ;0
L 1.52086998 -1.99886998 1.60173002 -1.99886998 0 P 0 ;0
L 1.52258996 -1.99786998 1.60156998 -1.99786998 0 P 0 ;0
L 1.52451004 -1.99686998 1.60138996 -1.99686998 0 P 0 ;0
L 1.52686998 -1.99586998 1.60106998 -1.99586998 0 P 0 ;0
L 1.52976004 -1.99486998 1.59943996 -1.99486998 0 P 0 ;0
L 1.53283002 -1.99386998 1.59543002 -1.99386998 0 P 0 ;0
L 1.53678996 -1.99286998 1.59003996 -1.99286998 0 P 0 ;0
L 1.54173996 -1.99186998 1.58073996 -1.99186998 0 P 0 ;0
L 1.55036998 -1.99086998 1.56493002 -1.99086998 0 P 0 ;0
L 1.6036 -2.03086998 1.60413996 -2.03086998 0 P 0 ;0
L 1.59891004 -2.02986998 1.60406998 -2.02986998 0 P 0 ;0
L 1.59435 -2.02886998 1.604 -2.02886998 0 P 0 ;0
L 1.58838996 -2.02786998 1.60393002 -2.02786998 0 P 0 ;0
L 1.57981004 -2.02686998 1.60386004 -2.02686998 0 P 0 ;0
L 1.54575 -1.98923996 1.53931998 -1.99021998 0 P 0 ;0
L 1.53931998 -1.99021998 1.53298996 -1.99171998 0 P 0 ;0
L 1.53298996 -1.99171998 1.52678996 -1.99373996 0 P 0 ;0
L 1.52678996 -1.99373996 1.52376998 -1.995 0 P 0 ;0
L 1.52376998 -1.995 1.52086998 -1.99651004 0 P 0 ;0
L 1.52086998 -1.99651004 1.5181 -1.99826004 0 P 0 ;0
L 1.5181 -1.99826004 1.51548002 -2.00023002 0 P 0 ;0
L 1.51548002 -2.00023002 1.51301004 -2.00243002 0 P 0 ;0
L 1.51301004 -2.00243002 1.51128996 -2.00423002 0 P 0 ;0
L 1.51128996 -2.00423002 1.50971998 -2.00616004 0 P 0 ;0
L 1.50971998 -2.00616004 1.50831004 -2.00821004 0 P 0 ;0
L 1.50831004 -2.00821004 1.50706998 -2.01036998 0 P 0 ;0
L 1.50706998 -2.01036998 1.50598996 -2.01261998 0 P 0 ;0
L 1.50598996 -2.01261998 1.50508996 -2.01496998 0 P 0 ;0
L 1.50508996 -2.01496998 1.5042 -2.01801004 0 P 0 ;0
L 1.5042 -2.01801004 1.50355 -2.02111004 0 P 0 ;0
L 1.50355 -2.02111004 1.50313996 -2.02426004 0 P 0 ;0
L 1.50313996 -2.02426004 1.50298996 -2.02743002 0 P 0 ;0
L 1.50298996 -2.02743002 1.50308996 -2.03063002 0 P 0 ;0
L 1.50308996 -2.03063002 1.50338002 -2.03326998 0 P 0 ;0
L 1.50338002 -2.03326998 1.50385 -2.03588002 0 P 0 ;0
L 1.50385 -2.03588002 1.50451004 -2.03845 0 P 0 ;0
L 1.50451004 -2.03845 1.50535 -2.04096998 0 P 0 ;0
L 1.50535 -2.04096998 1.50633002 -2.0433 0 P 0 ;0
L 1.50633002 -2.0433 1.5075 -2.04553002 0 P 0 ;0
L 1.5075 -2.04553002 1.50883996 -2.04766998 0 P 0 ;0
L 1.50883996 -2.04766998 1.51036998 -2.04968996 0 P 0 ;0
L 1.51036998 -2.04968996 1.51323002 -2.05291998 0 P 0 ;0
L 1.51323002 -2.05291998 1.51631998 -2.05593996 0 P 0 ;0
L 1.51631998 -2.05593996 1.51961998 -2.05871004 0 P 0 ;0
L 1.51961998 -2.05871004 1.53591004 -2.0706 0 P 0 ;0
L 1.53591004 -2.0706 1.54668002 -2.07831004 0 P 0 ;0
L 1.54668002 -2.07831004 1.54793996 -2.07933996 0 P 0 ;0
L 1.54793996 -2.07933996 1.54911998 -2.08046998 0 P 0 ;0
L 1.54911998 -2.08046998 1.55021004 -2.08168002 0 P 0 ;0
L 1.55021004 -2.08168002 1.5512 -2.08298996 0 P 0 ;0
L 1.5512 -2.08298996 1.55136004 -2.08323002 0 P 0 ;0
L 1.55136004 -2.08323002 1.5515 -2.08348002 0 P 0 ;0
L 1.5515 -2.08348002 1.55161004 -2.08373996 0 P 0 ;0
L 1.55161004 -2.08373996 1.5517 -2.08401998 0 P 0 ;0
L 1.5517 -2.08401998 1.55176998 -2.0843 0 P 0 ;0
L 1.55176998 -2.0843 1.55181004 -2.08458002 0 P 0 ;0
L 1.55181004 -2.08458002 1.55183002 -2.08486998 0 P 0 ;0
L 1.55183002 -2.08486998 1.55181998 -2.08516004 0 P 0 ;0
L 1.55181998 -2.08516004 1.55178996 -2.08545 0 P 0 ;0
L 1.55178996 -2.08545 1.55173996 -2.08573002 0 P 0 ;0
L 1.55173996 -2.08573002 1.55166004 -2.086 0 P 0 ;0
L 1.55166004 -2.086 1.55156004 -2.08628002 0 P 0 ;0
L 1.55156004 -2.08628002 1.55136998 -2.08666998 0 P 0 ;0
L 1.55136998 -2.08666998 1.55115 -2.08703996 0 P 0 ;0
L 1.55115 -2.08703996 1.5509 -2.08738996 0 P 0 ;0
L 1.5509 -2.08738996 1.55063002 -2.08771998 0 P 0 ;0
L 1.55063002 -2.08771998 1.55033002 -2.08803002 0 P 0 ;0
L 1.55033002 -2.08803002 1.55 -2.08831004 0 P 0 ;0
L 1.55 -2.08831004 1.54966004 -2.08856004 0 P 0 ;0
L 1.54966004 -2.08856004 1.54928996 -2.08878996 0 P 0 ;0
L 1.54928996 -2.08878996 1.5489 -2.08898996 0 P 0 ;0
L 1.5489 -2.08898996 1.54786004 -2.08941004 0 P 0 ;0
L 1.54786004 -2.08941004 1.54678996 -2.08973996 0 P 0 ;0
L 1.54678996 -2.08973996 1.54568002 -2.08998002 0 P 0 ;0
L 1.54568002 -2.08998002 1.54456998 -2.09011998 0 P 0 ;0
L 1.54456998 -2.09011998 1.54343996 -2.09016998 0 P 0 ;0
L 1.54343996 -2.09016998 1.53906998 -2.09003002 0 P 0 ;0
L 1.53906998 -2.09003002 1.53468002 -2.08961998 0 P 0 ;0
L 1.53468002 -2.08961998 1.52908996 -2.08878996 0 P 0 ;0
L 1.52908996 -2.08878996 1.52351004 -2.08766004 0 P 0 ;0
L 1.52351004 -2.08766004 1.51005 -2.08418996 0 P 0 ;0
L 1.51005 -2.08418996 1.50631004 -2.08318002 0 P 0 ;0
L 1.50631004 -2.08318002 1.50308002 -2.08238996 0 P 0 ;0
L 1.50308002 -2.08238996 1.50033996 -2.08183002 0 P 0 ;0
L 1.50033996 -2.08183002 1.5003 -2.08181998 0 P 0 ;0
L 1.5003 -2.08181998 1.50016004 -2.08181998 0 P 0 ;0
L 1.50016004 -2.08181998 1.50011998 -2.08183002 0 P 0 ;0
L 1.50011998 -2.08183002 1.50006998 -2.08183996 0 P 0 ;0
L 1.50006998 -2.08183996 1.50003002 -2.08186004 0 P 0 ;0
L 1.50003002 -2.08186004 1.49998996 -2.08186998 0 P 0 ;0
L 1.49998996 -2.08186998 1.49995 -2.08188996 0 P 0 ;0
L 1.49995 -2.08188996 1.49991004 -2.08191998 0 P 0 ;0
L 1.49991004 -2.08191998 1.49988002 -2.08195 0 P 0 ;0
L 1.49988002 -2.08195 1.49983996 -2.08198002 0 P 0 ;0
L 1.49983996 -2.08198002 1.4997 -2.08213996 0 P 0 ;0
L 1.4997 -2.08213996 1.49956004 -2.08231998 0 P 0 ;0
L 1.49956004 -2.08231998 1.49943996 -2.0825 0 P 0 ;0
L 1.49943996 -2.0825 1.49933996 -2.0827 0 P 0 ;0
L 1.49933996 -2.0827 1.49925 -2.0829 0 P 0 ;0
L 1.49925 -2.0829 1.49918996 -2.08311004 0 P 0 ;0
L 1.49918996 -2.08311004 1.49913996 -2.08333002 0 P 0 ;0
L 1.49913996 -2.08333002 1.49911004 -2.08355 0 P 0 ;0
L 1.49911004 -2.08355 1.4991 -2.08376998 0 P 0 ;0
L 1.4991 -2.08376998 1.49911004 -2.08398996 0 P 0 ;0
L 1.49911004 -2.08398996 1.50071004 -2.10395 0 P 0 ;0
L 1.50071004 -2.10395 1.5024 -2.12403996 0 P 0 ;0
L 1.5024 -2.12403996 1.50241998 -2.12418002 0 P 0 ;0
L 1.50241998 -2.12418002 1.50246004 -2.12431004 0 P 0 ;0
L 1.50246004 -2.12431004 1.50248996 -2.12445 0 P 0 ;0
L 1.50248996 -2.12445 1.50255 -2.12456998 0 P 0 ;0
L 1.50255 -2.12456998 1.50261004 -2.1247 0 P 0 ;0
L 1.50261004 -2.1247 1.50276998 -2.12491998 0 P 0 ;0
L 1.50276998 -2.12491998 1.50286004 -2.12501998 0 P 0 ;0
L 1.50286004 -2.12501998 1.50296998 -2.12511998 0 P 0 ;0
L 1.50296998 -2.12511998 1.50308002 -2.12521004 0 P 0 ;0
L 1.50308002 -2.12521004 1.50318996 -2.12528002 0 P 0 ;0
L 1.50318996 -2.12528002 1.50331998 -2.12535 0 P 0 ;0
L 1.50331998 -2.12535 1.50343996 -2.1254 0 P 0 ;0
L 1.50343996 -2.1254 1.50391998 -2.12556004 0 P 0 ;0
L 1.50391998 -2.12556004 1.5044 -2.12568996 0 P 0 ;0
L 1.5044 -2.12568996 1.50848002 -2.12648996 0 P 0 ;0
L 1.50848002 -2.12648996 1.51328996 -2.12738002 0 P 0 ;0
L 1.51328996 -2.12738002 1.51873996 -2.12833996 0 P 0 ;0
L 1.51873996 -2.12833996 1.52606004 -2.12945 0 P 0 ;0
L 1.52606004 -2.12945 1.53343996 -2.13023002 0 P 0 ;0
L 1.53343996 -2.13023002 1.54886998 -2.13086998 0 P 0 ;0
L 1.54886998 -2.13086998 1.56305 -2.1303 0 P 0 ;0
L 1.56305 -2.1303 1.56666004 -2.12988996 0 P 0 ;0
L 1.56666004 -2.12988996 1.57023002 -2.12926998 0 P 0 ;0
L 1.57023002 -2.12926998 1.5738 -2.12843002 0 P 0 ;0
L 1.5738 -2.12843002 1.57945 -2.12668996 0 P 0 ;0
L 1.57945 -2.12668996 1.58498002 -2.12456998 0 P 0 ;0
L 1.58498002 -2.12456998 1.58793996 -2.12318002 0 P 0 ;0
L 1.58793996 -2.12318002 1.59078996 -2.12156004 0 P 0 ;0
L 1.59078996 -2.12156004 1.59348996 -2.11971998 0 P 0 ;0
L 1.59348996 -2.11971998 1.59525 -2.11833002 0 P 0 ;0
L 1.59525 -2.11833002 1.5969 -2.11681998 0 P 0 ;0
L 1.5969 -2.11681998 1.59846004 -2.11521004 0 P 0 ;0
L 1.59846004 -2.11521004 1.59991004 -2.11348002 0 P 0 ;0
L 1.59991004 -2.11348002 1.60175 -2.11093996 0 P 0 ;0
L 1.60175 -2.11093996 1.60338002 -2.10826998 0 P 0 ;0
L 1.60338002 -2.10826998 1.60481004 -2.10548002 0 P 0 ;0
L 1.60481004 -2.10548002 1.60573002 -2.10321004 0 P 0 ;0
L 1.60573002 -2.10321004 1.60646004 -2.10088002 0 P 0 ;0
L 1.60646004 -2.10088002 1.60698002 -2.09848996 0 P 0 ;0
L 1.60698002 -2.09848996 1.60756004 -2.09421998 0 P 0 ;0
L 1.60756004 -2.09421998 1.6078 -2.08991004 0 P 0 ;0
L 1.6078 -2.08991004 1.60768996 -2.08565 0 P 0 ;0
L 1.60768996 -2.08565 1.60723002 -2.08141998 0 P 0 ;0
L 1.60723002 -2.08141998 1.60691998 -2.07968002 0 P 0 ;0
L 1.60691998 -2.07968002 1.60646998 -2.07796998 0 P 0 ;0
L 1.60646998 -2.07796998 1.60591998 -2.0763 0 P 0 ;0
L 1.60591998 -2.0763 1.60523002 -2.07466998 0 P 0 ;0
L 1.60523002 -2.07466998 1.60411998 -2.07246998 0 P 0 ;0
L 1.60411998 -2.07246998 1.60281004 -2.07038002 0 P 0 ;0
L 1.60281004 -2.07038002 1.60131998 -2.06838996 0 P 0 ;0
L 1.60131998 -2.06838996 1.59803996 -2.06461998 0 P 0 ;0
L 1.59803996 -2.06461998 1.59455 -2.06101998 0 P 0 ;0
L 1.59455 -2.06101998 1.59031998 -2.05708996 0 P 0 ;0
L 1.59031998 -2.05708996 1.58586004 -2.05333996 0 P 0 ;0
L 1.58586004 -2.05333996 1.57588002 -2.04598996 0 P 0 ;0
L 1.57588002 -2.04598996 1.56685 -2.03963996 0 P 0 ;0
L 1.56685 -2.03963996 1.56578002 -2.03878996 0 P 0 ;0
L 1.56578002 -2.03878996 1.56476998 -2.03786004 0 P 0 ;0
L 1.56476998 -2.03786004 1.56383002 -2.03686998 0 P 0 ;0
L 1.56383002 -2.03686998 1.56295 -2.0358 0 P 0 ;0
L 1.56295 -2.0358 1.56276998 -2.03555 0 P 0 ;0
L 1.56276998 -2.03555 1.56261004 -2.03528002 0 P 0 ;0
L 1.56261004 -2.03528002 1.56246998 -2.035 0 P 0 ;0
L 1.56246998 -2.035 1.56236004 -2.03471998 0 P 0 ;0
L 1.56236004 -2.03471998 1.56226998 -2.03441998 0 P 0 ;0
L 1.56226998 -2.03441998 1.5622 -2.03411998 0 P 0 ;0
L 1.5622 -2.03411998 1.56216004 -2.03381998 0 P 0 ;0
L 1.56216004 -2.03381998 1.56213996 -2.03351004 0 P 0 ;0
L 1.56213996 -2.03351004 1.56215 -2.0332 0 P 0 ;0
L 1.56215 -2.0332 1.56218002 -2.03288996 0 P 0 ;0
L 1.56218002 -2.03288996 1.56225 -2.03253996 0 P 0 ;0
L 1.56225 -2.03253996 1.56233996 -2.03221004 0 P 0 ;0
L 1.56233996 -2.03221004 1.56246004 -2.03186998 0 P 0 ;0
L 1.56246004 -2.03186998 1.56261004 -2.03156004 0 P 0 ;0
L 1.56261004 -2.03156004 1.56278996 -2.03125 0 P 0 ;0
L 1.56278996 -2.03125 1.56298002 -2.03096004 0 P 0 ;0
L 1.56298002 -2.03096004 1.56321004 -2.03068996 0 P 0 ;0
L 1.56321004 -2.03068996 1.56345 -2.03043996 0 P 0 ;0
L 1.56345 -2.03043996 1.56371004 -2.0302 0 P 0 ;0
L 1.56371004 -2.0302 1.56416004 -2.02986004 0 P 0 ;0
L 1.56416004 -2.02986004 1.56463002 -2.02955 0 P 0 ;0
L 1.56463002 -2.02955 1.56511998 -2.02928002 0 P 0 ;0
L 1.56511998 -2.02928002 1.56561998 -2.02903002 0 P 0 ;0
L 1.56561998 -2.02903002 1.56611998 -2.02883996 0 P 0 ;0
L 1.56611998 -2.02883996 1.56663996 -2.02866998 0 P 0 ;0
L 1.56663996 -2.02866998 1.56716004 -2.02855 0 P 0 ;0
L 1.56716004 -2.02855 1.5677 -2.02846998 0 P 0 ;0
L 1.5677 -2.02846998 1.56926998 -2.02835 0 P 0 ;0
L 1.56926998 -2.02835 1.57085 -2.02833996 0 P 0 ;0
L 1.57085 -2.02833996 1.57725 -2.02866998 0 P 0 ;0
L 1.57725 -2.02866998 1.58205 -2.02906004 0 P 0 ;0
L 1.58205 -2.02906004 1.58746998 -2.02975 0 P 0 ;0
L 1.58746998 -2.02975 1.59271004 -2.03056998 0 P 0 ;0
L 1.59271004 -2.03056998 1.59681004 -2.03143002 0 P 0 ;0
L 1.59681004 -2.03143002 1.60016004 -2.03221998 0 P 0 ;0
L 1.60016004 -2.03221998 1.60308002 -2.03281004 0 P 0 ;0
L 1.60308002 -2.03281004 1.60553996 -2.03323996 0 P 0 ;0
L 1.60553996 -2.03323996 1.60568996 -2.03323996 0 P 0 ;0
L 1.60568996 -2.03323996 1.60576998 -2.03321998 0 P 0 ;0
L 1.60576998 -2.03321998 1.60586004 -2.03316004 0 P 0 ;0
L 1.60586004 -2.03316004 1.6059 -2.03313996 0 P 0 ;0
L 1.6059 -2.03313996 1.60591998 -2.03311004 0 P 0 ;0
L 1.60591998 -2.03311004 1.60598996 -2.03303996 0 P 0 ;0
L 1.60598996 -2.03303996 1.60605 -2.03296998 0 P 0 ;0
L 1.60605 -2.03296998 1.6061 -2.03288996 0 P 0 ;0
L 1.6061 -2.03288996 1.60618002 -2.03273002 0 P 0 ;0
L 1.60618002 -2.03273002 1.60621004 -2.03263002 0 P 0 ;0
L 1.60621004 -2.03263002 1.60623002 -2.03253996 0 P 0 ;0
L 1.60623002 -2.03253996 1.60625 -2.03236004 0 P 0 ;0
L 1.60625 -2.03236004 1.60623996 -2.03226004 0 P 0 ;0
L 1.60623996 -2.03226004 1.60508002 -2.01578002 0 P 0 ;0
L 1.60508002 -2.01578002 1.60393996 -2.00068002 0 P 0 ;0
L 1.60393996 -2.00068002 1.60368002 -1.99833996 0 P 0 ;0
L 1.60368002 -1.99833996 1.60326998 -1.99601004 0 P 0 ;0
L 1.60326998 -1.99601004 1.60321004 -1.99576998 0 P 0 ;0
L 1.60321004 -1.99576998 1.60313996 -1.99553002 0 P 0 ;0
L 1.60313996 -1.99553002 1.60303996 -1.9953 0 P 0 ;0
L 1.60303996 -1.9953 1.60293002 -1.99508002 0 P 0 ;0
L 1.60293002 -1.99508002 1.60281004 -1.99486004 0 P 0 ;0
L 1.60281004 -1.99486004 1.60261998 -1.9946 0 P 0 ;0
L 1.60261998 -1.9946 1.60241004 -1.99435 0 P 0 ;0
L 1.60241004 -1.99435 1.60218002 -1.99411998 0 P 0 ;0
L 1.60218002 -1.99411998 1.60191998 -1.99391004 0 P 0 ;0
L 1.60191998 -1.99391004 1.60161004 -1.99368996 0 P 0 ;0
L 1.60161004 -1.99368996 1.60128996 -1.99348996 0 P 0 ;0
L 1.60128996 -1.99348996 1.60095 -1.99331998 0 P 0 ;0
L 1.60095 -1.99331998 1.6006 -1.99316004 0 P 0 ;0
L 1.6006 -1.99316004 1.59966004 -1.99283002 0 P 0 ;0
L 1.59966004 -1.99283002 1.59871004 -1.99255 0 P 0 ;0
L 1.59871004 -1.99255 1.5933 -1.99135 0 P 0 ;0
L 1.5933 -1.99135 1.5878 -1.9905 0 P 0 ;0
L 1.5878 -1.9905 1.57285 -1.98915 0 P 0 ;0
L 1.57285 -1.98915 1.55763996 -1.98861004 0 P 0 ;0
L 1.55763996 -1.98861004 1.55171004 -1.98876004 0 P 0 ;0
L 1.55171004 -1.98876004 1.54575 -1.98923996 0 P 0 ;0
L 1.53011998 -2.12786998 1.5666 -2.12786998 0 P 0 ;0
L 1.52236004 -2.12686998 1.57168002 -2.12686998 0 P 0 ;0
L 1.51621998 -2.12586998 1.5753 -2.12586998 0 P 0 ;0
L 1.51071004 -2.12486998 1.57856004 -2.12486998 0 P 0 ;0
L 1.50553002 -2.12386998 1.58121004 -2.12386998 0 P 0 ;0
L 1.50431004 -2.12286998 1.58381998 -2.12286998 0 P 0 ;0
L 1.50423002 -2.12186998 1.58601998 -2.12186998 0 P 0 ;0
L 1.50413996 -2.12086998 1.58796004 -2.12086998 0 P 0 ;0
L 1.50406004 -2.11986998 1.58971004 -2.11986998 0 P 0 ;0
L 1.50396998 -2.11886998 1.59118002 -2.11886998 0 P 0 ;0
L 1.50388996 -2.11786998 1.5926 -2.11786998 0 P 0 ;0
L 1.50381004 -2.11686998 1.59386004 -2.11686998 0 P 0 ;0
L 1.50371998 -2.11586998 1.59496998 -2.11586998 0 P 0 ;0
L 1.50363996 -2.11486998 1.59601004 -2.11486998 0 P 0 ;0
L 1.50355 -2.11386998 1.59696998 -2.11386998 0 P 0 ;0
L 1.50346998 -2.11286998 1.59781004 -2.11286998 0 P 0 ;0
L 1.50338002 -2.11186998 1.5986 -2.11186998 0 P 0 ;0
L 1.5033 -2.11086998 1.59933002 -2.11086998 0 P 0 ;0
L 1.50321004 -2.10986998 1.60005 -2.10986998 0 P 0 ;0
L 1.50313002 -2.10886998 1.60066998 -2.10886998 0 P 0 ;0
L 1.50305 -2.10786998 1.60128002 -2.10786998 0 P 0 ;0
L 1.50296004 -2.10686998 1.60185 -2.10686998 0 P 0 ;0
L 1.50288002 -2.10586998 1.60236004 -2.10586998 0 P 0 ;0
L 1.50278996 -2.10486998 1.60286998 -2.10486998 0 P 0 ;0
L 1.50271004 -2.10386998 1.6033 -2.10386998 0 P 0 ;0
L 1.50263002 -2.10286998 1.60371004 -2.10286998 0 P 0 ;0
L 1.50255 -2.10186998 1.60405 -2.10186998 0 P 0 ;0
L 1.50246998 -2.10086998 1.60436004 -2.10086998 0 P 0 ;0
L 1.50238996 -2.09986998 1.60463002 -2.09986998 0 P 0 ;0
L 1.50231004 -2.09886998 1.60485 -2.09886998 0 P 0 ;0
L 1.50223002 -2.09786998 1.60505 -2.09786998 0 P 0 ;0
L 1.50215 -2.09686998 1.60518002 -2.09686998 0 P 0 ;0
L 1.50206998 -2.09586998 1.60531998 -2.09586998 0 P 0 ;0
L 1.50198996 -2.09486998 1.60545 -2.09486998 0 P 0 ;0
L 1.50191004 -2.09386998 1.60558002 -2.09386998 0 P 0 ;0
L 1.50183002 -2.09286998 1.60563002 -2.09286998 0 P 0 ;0
L 1.50175 -2.09186998 1.53725 -2.09186998 0 P 0 ;0
L 1.54638996 -2.09186998 1.60568996 -2.09186998 0 P 0 ;0
L 1.50166998 -2.09086998 1.5295 -2.09086998 0 P 0 ;0
L 1.54956998 -2.09086998 1.60573996 -2.09086998 0 P 0 ;0
L 1.50158996 -2.08986998 1.52436004 -2.08986998 0 P 0 ;0
L 1.55125 -2.08986998 1.60578996 -2.08986998 0 P 0 ;0
L 1.50151004 -2.08886998 1.52021004 -2.08886998 0 P 0 ;0
L 1.55226998 -2.08886998 1.60576998 -2.08886998 0 P 0 ;0
L 1.50143002 -2.08786998 1.51633002 -2.08786998 0 P 0 ;0
L 1.55298002 -2.08786998 1.60573996 -2.08786998 0 P 0 ;0
L 1.50133996 -2.08686998 1.51246004 -2.08686998 0 P 0 ;0
L 1.55346998 -2.08686998 1.60571998 -2.08686998 0 P 0 ;0
L 1.50126998 -2.08586998 1.50861998 -2.08586998 0 P 0 ;0
L 1.55375 -2.08586998 1.60568996 -2.08586998 0 P 0 ;0
L 1.50118002 -2.08486998 1.50481004 -2.08486998 0 P 0 ;0
L 1.55383002 -2.08486998 1.60558996 -2.08486998 0 P 0 ;0
L 1.55371998 -2.08386998 1.60548996 -2.08386998 0 P 0 ;0
L 1.54886998 -2.12886998 1.53358996 -2.12823996 0 P 0 ;0
L 1.53358996 -2.12823996 1.52631998 -2.12746998 0 P 0 ;0
L 1.52631998 -2.12746998 1.51906004 -2.12636998 0 P 0 ;0
L 1.51906004 -2.12636998 1.51363002 -2.12541004 0 P 0 ;0
L 1.51363002 -2.12541004 1.50886998 -2.12451998 0 P 0 ;0
L 1.50886998 -2.12451998 1.50483996 -2.12373996 0 P 0 ;0
L 1.50483996 -2.12373996 1.50448996 -2.12365 0 P 0 ;0
L 1.50448996 -2.12365 1.50438002 -2.12361004 0 P 0 ;0
L 1.50438002 -2.12361004 1.5027 -2.10378002 0 P 0 ;0
L 1.5027 -2.10378002 1.50111998 -2.08403002 0 P 0 ;0
L 1.50111998 -2.08403002 1.50263996 -2.08433996 0 P 0 ;0
L 1.50263996 -2.08433996 1.50581004 -2.08511004 0 P 0 ;0
L 1.50581004 -2.08511004 1.50955 -2.08611998 0 P 0 ;0
L 1.50955 -2.08611998 1.52306004 -2.08961004 0 P 0 ;0
L 1.52306004 -2.08961004 1.52311004 -2.08961998 0 P 0 ;0
L 1.52311004 -2.08961998 1.52875 -2.09076004 0 P 0 ;0
L 1.52875 -2.09076004 1.5288 -2.09076004 0 P 0 ;0
L 1.5288 -2.09076004 1.53443996 -2.09161004 0 P 0 ;0
L 1.53443996 -2.09161004 1.53893996 -2.09203002 0 P 0 ;0
L 1.53893996 -2.09203002 1.54346004 -2.09216998 0 P 0 ;0
L 1.54346004 -2.09216998 1.54473996 -2.09211004 0 P 0 ;0
L 1.54473996 -2.09211004 1.54603002 -2.09195 0 P 0 ;0
L 1.54603002 -2.09195 1.54728996 -2.09166998 0 P 0 ;0
L 1.54728996 -2.09166998 1.54853002 -2.09128996 0 P 0 ;0
L 1.54853002 -2.09128996 1.54973002 -2.09081004 0 P 0 ;0
L 1.54973002 -2.09081004 1.55026998 -2.09053996 0 P 0 ;0
L 1.55026998 -2.09053996 1.55076998 -2.09023002 0 P 0 ;0
L 1.55076998 -2.09023002 1.55118002 -2.08991998 0 P 0 ;0
L 1.55118002 -2.08991998 1.55118002 -2.08991004 0 P 0 ;0
L 1.55118002 -2.08991004 1.5512 -2.08991004 0 P 0 ;0
L 1.5512 -2.08991004 1.55125 -2.08986998 0 P 0 ;0
L 1.55125 -2.08986998 1.55131004 -2.08981998 0 P 0 ;0
L 1.55131004 -2.08981998 1.55126998 -2.08978002 0 P 0 ;0
L 1.55126998 -2.08978002 1.55136004 -2.08978002 0 P 0 ;0
L 1.55136004 -2.08978002 1.5517 -2.08948996 0 P 0 ;0
L 1.5517 -2.08948996 1.55206004 -2.08911998 0 P 0 ;0
L 1.55206004 -2.08911998 1.55205 -2.08911004 0 P 0 ;0
L 1.55205 -2.08911004 1.55206004 -2.08911004 0 P 0 ;0
L 1.55206004 -2.08911004 1.55211998 -2.08906004 0 P 0 ;0
L 1.55211998 -2.08906004 1.55248996 -2.08861004 0 P 0 ;0
L 1.55248996 -2.08861004 1.55283996 -2.08811998 0 P 0 ;0
L 1.55283996 -2.08811998 1.55313996 -2.08761004 0 P 0 ;0
L 1.55313996 -2.08761004 1.5534 -2.08706998 0 P 0 ;0
L 1.5534 -2.08706998 1.55356004 -2.08663002 0 P 0 ;0
L 1.55356004 -2.08663002 1.55368996 -2.08618996 0 P 0 ;0
L 1.55368996 -2.08618996 1.55376998 -2.08573996 0 P 0 ;0
L 1.55376998 -2.08573996 1.55378002 -2.08565 0 P 0 ;0
L 1.55378002 -2.08565 1.55381998 -2.08528002 0 P 0 ;0
L 1.55381998 -2.08528002 1.55383002 -2.08481998 0 P 0 ;0
L 1.55383002 -2.08481998 1.5538 -2.08436998 0 P 0 ;0
L 1.5538 -2.08436998 1.55373002 -2.08391998 0 P 0 ;0
L 1.55373002 -2.08391998 1.55361998 -2.08346998 0 P 0 ;0
L 1.55361998 -2.08346998 1.55348002 -2.08303996 0 P 0 ;0
L 1.55348002 -2.08303996 1.5533 -2.08261004 0 P 0 ;0
L 1.5533 -2.08261004 1.55308996 -2.08221004 0 P 0 ;0
L 1.55308996 -2.08221004 1.55283996 -2.08183002 0 P 0 ;0
L 1.55283996 -2.08183002 1.55175 -2.0804 0 P 0 ;0
L 1.55175 -2.0804 1.55055 -2.07908002 0 P 0 ;0
L 1.55055 -2.07908002 1.54926004 -2.07783996 0 P 0 ;0
L 1.54926004 -2.07783996 1.54788996 -2.07671998 0 P 0 ;0
L 1.54788996 -2.07671998 1.53706998 -2.06898002 0 P 0 ;0
L 1.53706998 -2.06898002 1.52085 -2.05713996 0 P 0 ;0
L 1.52085 -2.05713996 1.51766004 -2.05445 0 P 0 ;0
L 1.51766004 -2.05445 1.51468002 -2.05153996 0 P 0 ;0
L 1.51468002 -2.05153996 1.51191998 -2.04841998 0 P 0 ;0
L 1.51191998 -2.04841998 1.51048996 -2.04651998 0 P 0 ;0
L 1.51048996 -2.04651998 1.50923002 -2.04453002 0 P 0 ;0
L 1.50923002 -2.04453002 1.50813996 -2.04245 0 P 0 ;0
L 1.50813996 -2.04245 1.50721998 -2.04026004 0 P 0 ;0
L 1.50721998 -2.04026004 1.50643002 -2.03788002 0 P 0 ;0
L 1.50643002 -2.03788002 1.50581004 -2.03545 0 P 0 ;0
L 1.50581004 -2.03545 1.50536004 -2.03298996 0 P 0 ;0
L 1.50536004 -2.03298996 1.50508996 -2.0305 0 P 0 ;0
L 1.50508996 -2.0305 1.50498996 -2.02745 0 P 0 ;0
L 1.50498996 -2.02745 1.50513996 -2.02443996 0 P 0 ;0
L 1.50513996 -2.02443996 1.50551998 -2.02145 0 P 0 ;0
L 1.50551998 -2.02145 1.50613996 -2.0185 0 P 0 ;0
L 1.50613996 -2.0185 1.50698996 -2.01561004 0 P 0 ;0
L 1.50698996 -2.01561004 1.50783002 -2.01341004 0 P 0 ;0
L 1.50783002 -2.01341004 1.50883002 -2.0113 0 P 0 ;0
L 1.50883002 -2.0113 1.51 -2.00928002 0 P 0 ;0
L 1.51 -2.00928002 1.51133002 -2.00736004 0 P 0 ;0
L 1.51133002 -2.00736004 1.5128 -2.00555 0 P 0 ;0
L 1.5128 -2.00555 1.5144 -2.00386004 0 P 0 ;0
L 1.5144 -2.00386004 1.51675 -2.00176998 0 P 0 ;0
L 1.51675 -2.00176998 1.51923002 -1.9999 0 P 0 ;0
L 1.51923002 -1.9999 1.52186004 -1.99823996 0 P 0 ;0
L 1.52186004 -1.99823996 1.52461998 -1.99681004 0 P 0 ;0
L 1.52461998 -1.99681004 1.52748996 -1.99561004 0 P 0 ;0
L 1.52748996 -1.99561004 1.53353002 -1.99363996 0 P 0 ;0
L 1.53353002 -1.99363996 1.5397 -1.99218002 0 P 0 ;0
L 1.5397 -1.99218002 1.54598002 -1.99123002 0 P 0 ;0
L 1.54598002 -1.99123002 1.55181004 -1.99075 0 P 0 ;0
L 1.55181004 -1.99075 1.55763002 -1.99061998 0 P 0 ;0
L 1.55763002 -1.99061998 1.57273002 -1.99113996 0 P 0 ;0
L 1.57273002 -1.99113996 1.58755 -1.99248996 0 P 0 ;0
L 1.58755 -1.99248996 1.59293002 -1.99331998 0 P 0 ;0
L 1.59293002 -1.99331998 1.59821004 -1.99448996 0 P 0 ;0
L 1.59821004 -1.99448996 1.59905 -1.99473002 0 P 0 ;0
L 1.59905 -1.99473002 1.59986004 -1.99501998 0 P 0 ;0
L 1.59986004 -1.99501998 1.60008002 -1.99511998 0 P 0 ;0
L 1.60008002 -1.99511998 1.6003 -1.99523002 0 P 0 ;0
L 1.6003 -1.99523002 1.60051004 -1.99536004 0 P 0 ;0
L 1.60051004 -1.99536004 1.60071004 -1.9955 0 P 0 ;0
L 1.60071004 -1.9955 1.60083002 -1.99561004 0 P 0 ;0
L 1.60083002 -1.99561004 1.60093996 -1.99571004 0 P 0 ;0
L 1.60093996 -1.99571004 1.60103996 -1.99583002 0 P 0 ;0
L 1.60103996 -1.99583002 1.60111998 -1.99595 0 P 0 ;0
L 1.60111998 -1.99595 1.60116998 -1.99601998 0 P 0 ;0
L 1.60116998 -1.99601998 1.60121004 -1.99611004 0 P 0 ;0
L 1.60121004 -1.99611004 1.60125 -1.99621004 0 P 0 ;0
L 1.60125 -1.99621004 1.60128002 -1.9963 0 P 0 ;0
L 1.60128002 -1.9963 1.60131004 -1.99641004 0 P 0 ;0
L 1.60131004 -1.99641004 1.6017 -1.99861998 0 P 0 ;0
L 1.6017 -1.99861998 1.60195 -2.00086998 0 P 0 ;0
L 1.60195 -2.00086998 1.60308002 -2.01593002 0 P 0 ;0
L 1.60308002 -2.01593002 1.60415 -2.03096998 0 P 0 ;0
L 1.60415 -2.03096998 1.60345 -2.03083996 0 P 0 ;0
L 1.60345 -2.03083996 1.60058996 -2.03026004 0 P 0 ;0
L 1.60058996 -2.03026004 1.59723002 -2.02948002 0 P 0 ;0
L 1.59723002 -2.02948002 1.59721998 -2.02948002 0 P 0 ;0
L 1.59721998 -2.02948002 1.59306998 -2.0286 0 P 0 ;0
L 1.59306998 -2.0286 1.58776004 -2.02776998 0 P 0 ;0
L 1.58776004 -2.02776998 1.58226004 -2.02708002 0 P 0 ;0
L 1.58226004 -2.02708002 1.57738002 -2.02666998 0 P 0 ;0
L 1.57738002 -2.02666998 1.5709 -2.02633996 0 P 0 ;0
L 1.5709 -2.02633996 1.56918996 -2.02635 0 P 0 ;0
L 1.56918996 -2.02635 1.56746998 -2.02648996 0 P 0 ;0
L 1.56746998 -2.02648996 1.56678996 -2.02658996 0 P 0 ;0
L 1.56678996 -2.02658996 1.56611998 -2.02673996 0 P 0 ;0
L 1.56611998 -2.02673996 1.56546004 -2.02695 0 P 0 ;0
L 1.56546004 -2.02695 1.56481998 -2.0272 0 P 0 ;0
L 1.56481998 -2.0272 1.56418996 -2.0275 0 P 0 ;0
L 1.56418996 -2.0275 1.56358002 -2.02785 0 P 0 ;0
L 1.56358002 -2.02785 1.563 -2.02823002 0 P 0 ;0
L 1.563 -2.02823002 1.56245 -2.02865 0 P 0 ;0
L 1.56245 -2.02865 1.56206998 -2.02898996 0 P 0 ;0
L 1.56206998 -2.02898996 1.56171004 -2.02936004 0 P 0 ;0
L 1.56171004 -2.02936004 1.56138002 -2.02976004 0 P 0 ;0
L 1.56138002 -2.02976004 1.56108996 -2.03018996 0 P 0 ;0
L 1.56108996 -2.03018996 1.56083002 -2.03063996 0 P 0 ;0
L 1.56083002 -2.03063996 1.56061998 -2.0311 0 P 0 ;0
L 1.56061998 -2.0311 1.56043996 -2.03158996 0 P 0 ;0
L 1.56043996 -2.03158996 1.5603 -2.03208002 0 P 0 ;0
L 1.5603 -2.03208002 1.5602 -2.0326 0 P 0 ;0
L 1.5602 -2.0326 1.56015 -2.03308002 0 P 0 ;0
L 1.56015 -2.03308002 1.56013996 -2.03353996 0 P 0 ;0
L 1.56013996 -2.03353996 1.56016004 -2.03391004 0 P 0 ;0
L 1.56016004 -2.03391004 1.56048002 -2.03391004 0 P 0 ;0
L 1.56048002 -2.03391004 1.56016004 -2.03393002 0 P 0 ;0
L 1.56016004 -2.03393002 1.56016998 -2.03401004 0 P 0 ;0
L 1.56016998 -2.03401004 1.56023002 -2.03448002 0 P 0 ;0
L 1.56023002 -2.03448002 1.56025 -2.03456004 0 P 0 ;0
L 1.56025 -2.03456004 1.56033002 -2.03493002 0 P 0 ;0
L 1.56033002 -2.03493002 1.56046998 -2.03538002 0 P 0 ;0
L 1.56046998 -2.03538002 1.56063996 -2.03581998 0 P 0 ;0
L 1.56063996 -2.03581998 1.56085 -2.03623996 0 P 0 ;0
L 1.56085 -2.03623996 1.56108996 -2.03663996 0 P 0 ;0
L 1.56108996 -2.03663996 1.56136004 -2.03701998 0 P 0 ;0
L 1.56136004 -2.03701998 1.56233002 -2.03818996 0 P 0 ;0
L 1.56233002 -2.03818996 1.56336998 -2.03928996 0 P 0 ;0
L 1.56336998 -2.03928996 1.56448002 -2.04031004 0 P 0 ;0
L 1.56448002 -2.04031004 1.56566004 -2.04123996 0 P 0 ;0
L 1.56566004 -2.04123996 1.57471004 -2.04761998 0 P 0 ;0
L 1.57471004 -2.04761998 1.58461998 -2.05491004 0 P 0 ;0
L 1.58461998 -2.05491004 1.58898996 -2.05858996 0 P 0 ;0
L 1.58898996 -2.05858996 1.59315 -2.06245 0 P 0 ;0
L 1.59315 -2.06245 1.59656998 -2.06596998 0 P 0 ;0
L 1.59656998 -2.06596998 1.59976004 -2.06965 0 P 0 ;0
L 1.59976004 -2.06965 1.60116004 -2.07151004 0 P 0 ;0
L 1.60116004 -2.07151004 1.60238002 -2.07346004 0 P 0 ;0
L 1.60238002 -2.07346004 1.60341998 -2.0755 0 P 0 ;0
L 1.60341998 -2.0755 1.60403996 -2.077 0 P 0 ;0
L 1.60403996 -2.077 1.60456004 -2.07853996 0 P 0 ;0
L 1.60456004 -2.07853996 1.60496004 -2.08011004 0 P 0 ;0
L 1.60496004 -2.08011004 1.60525 -2.0817 0 P 0 ;0
L 1.60525 -2.0817 1.60568996 -2.08578002 0 P 0 ;0
L 1.60568996 -2.08578002 1.60578996 -2.08988002 0 P 0 ;0
L 1.60578996 -2.08988002 1.60556998 -2.09403002 0 P 0 ;0
L 1.60556998 -2.09403002 1.60501004 -2.09813996 0 P 0 ;0
L 1.60501004 -2.09813996 1.60451998 -2.10036998 0 P 0 ;0
L 1.60451998 -2.10036998 1.60383996 -2.10253996 0 P 0 ;0
L 1.60383996 -2.10253996 1.60298996 -2.10465 0 P 0 ;0
L 1.60298996 -2.10465 1.60163996 -2.1073 0 P 0 ;0
L 1.60163996 -2.1073 1.60008002 -2.10983002 0 P 0 ;0
L 1.60008002 -2.10983002 1.59833002 -2.11225 0 P 0 ;0
L 1.59833002 -2.11225 1.59696998 -2.11386998 0 P 0 ;0
L 1.59696998 -2.11386998 1.59551004 -2.11538996 0 P 0 ;0
L 1.59551004 -2.11538996 1.59395 -2.1168 0 P 0 ;0
L 1.59395 -2.1168 1.59231004 -2.11811004 0 P 0 ;0
L 1.59231004 -2.11811004 1.58973002 -2.11986004 0 P 0 ;0
L 1.58973002 -2.11986004 1.58701998 -2.1214 0 P 0 ;0
L 1.58701998 -2.1214 1.5842 -2.12273002 0 P 0 ;0
L 1.5842 -2.12273002 1.5788 -2.1248 0 P 0 ;0
L 1.5788 -2.1248 1.57326998 -2.12648996 0 P 0 ;0
L 1.57326998 -2.12648996 1.56983002 -2.12731004 0 P 0 ;0
L 1.56983002 -2.12731004 1.56638002 -2.12791004 0 P 0 ;0
L 1.56638002 -2.12791004 1.56288996 -2.1283 0 P 0 ;0
L 1.56288996 -2.1283 1.54886998 -2.12886998 0 P 0 ;0
L 1.35851998 -2.06545 1.47866004 -2.06545 0 P 0 ;0
L 1.35936004 -2.06445 1.47871004 -2.06445 0 P 0 ;0
L 1.36041004 -2.06345 1.47875 -2.06345 0 P 0 ;0
L 1.36163996 -2.06245 1.4788 -2.06245 0 P 0 ;0
L 1.36293996 -2.06145 1.47883996 -2.06145 0 P 0 ;0
L 1.36436004 -2.06045 1.47888996 -2.06045 0 P 0 ;0
L 1.36598002 -2.05945 1.47893996 -2.05945 0 P 0 ;0
L 1.36776004 -2.05845 1.47898996 -2.05845 0 P 0 ;0
L 1.36971004 -2.05745 1.47903002 -2.05745 0 P 0 ;0
L 1.37166004 -2.05645 1.47908002 -2.05645 0 P 0 ;0
L 1.37391004 -2.05545 1.47911998 -2.05545 0 P 0 ;0
L 1.37616998 -2.05445 1.47916998 -2.05445 0 P 0 ;0
L 1.37873002 -2.05345 1.47921004 -2.05345 0 P 0 ;0
L 1.38136004 -2.05245 1.47926004 -2.05245 0 P 0 ;0
L 1.36875 -2.03345 1.37108996 -2.03345 0 P 0 ;0
L 1.36886004 -2.03245 1.37385 -2.03245 0 P 0 ;0
L 1.36896998 -2.03145 1.37678002 -2.03145 0 P 0 ;0
L 1.36908996 -2.03045 1.3797 -2.03045 0 P 0 ;0
L 1.36921004 -2.02945 1.38261998 -2.02945 0 P 0 ;0
L 1.36933002 -2.02845 1.38638996 -2.02845 0 P 0 ;0
L 1.36946004 -2.02745 1.39023996 -2.02745 0 P 0 ;0
L 1.36958002 -2.02645 1.39503002 -2.02645 0 P 0 ;0
L 1.3697 -2.02545 1.40068002 -2.02545 0 P 0 ;0
L 1.36981998 -2.02445 1.41053996 -2.02445 0 P 0 ;0
L 1.36993996 -2.02345 1.47993996 -2.02345 0 P 0 ;0
L 1.37008002 -2.02245 1.47988002 -2.02245 0 P 0 ;0
L 1.37021004 -2.02145 1.47978002 -2.02145 0 P 0 ;0
L 1.37033996 -2.02045 1.47968002 -2.02045 0 P 0 ;0
L 1.37046998 -2.01945 1.47953002 -2.01945 0 P 0 ;0
L 1.3706 -2.01845 1.47936004 -2.01845 0 P 0 ;0
L 1.37073002 -2.01745 1.47918002 -2.01745 0 P 0 ;0
L 1.37086004 -2.01645 1.47893002 -2.01645 0 P 0 ;0
L 1.37098996 -2.01545 1.47868002 -2.01545 0 P 0 ;0
L 1.37113002 -2.01445 1.4784 -2.01445 0 P 0 ;0
L 1.37126998 -2.01345 1.47806004 -2.01345 0 P 0 ;0
L 1.3714 -2.01245 1.47773002 -2.01245 0 P 0 ;0
L 1.37153996 -2.01145 1.47733002 -2.01145 0 P 0 ;0
L 1.37168002 -2.01045 1.47691004 -2.01045 0 P 0 ;0
L 1.37181004 -2.00945 1.47641004 -2.00945 0 P 0 ;0
L 1.37195 -2.00845 1.47588996 -2.00845 0 P 0 ;0
L 1.37208002 -2.00745 1.47528002 -2.00745 0 P 0 ;0
L 1.37221004 -2.00645 1.47463996 -2.00645 0 P 0 ;0
L 1.37235 -2.00545 1.47391998 -2.00545 0 P 0 ;0
L 1.37248996 -2.00445 1.47311004 -2.00445 0 P 0 ;0
L 1.37261998 -2.00345 1.47225 -2.00345 0 P 0 ;0
L 1.37276004 -2.00245 1.47126998 -2.00245 0 P 0 ;0
L 1.3729 -2.00145 1.4702 -2.00145 0 P 0 ;0
L 1.37303002 -2.00045 1.46903996 -2.00045 0 P 0 ;0
L 1.37316998 -1.99945 1.46775 -1.99945 0 P 0 ;0
L 1.3733 -1.99845 1.46625 -1.99845 0 P 0 ;0
L 1.37343996 -1.99745 1.46455 -1.99745 0 P 0 ;0
L 1.37356998 -1.99645 1.46253996 -1.99645 0 P 0 ;0
L 1.37753002 -1.99545 1.46041004 -1.99545 0 P 0 ;0
L 1.38218996 -1.99445 1.45781004 -1.99445 0 P 0 ;0
L 1.42925 -2.08345 1.47785 -2.08345 0 P 0 ;0
L 1.42931998 -2.08245 1.47788996 -2.08245 0 P 0 ;0
L 1.42938002 -2.08145 1.47793002 -2.08145 0 P 0 ;0
L 1.42945 -2.08045 1.47796998 -2.08045 0 P 0 ;0
L 1.42951004 -2.07945 1.47801004 -2.07945 0 P 0 ;0
L 1.42958002 -2.07845 1.47806004 -2.07845 0 P 0 ;0
L 1.42963996 -2.07745 1.4781 -2.07745 0 P 0 ;0
L 1.4297 -2.07645 1.47815 -2.07645 0 P 0 ;0
L 1.42976998 -2.07545 1.4782 -2.07545 0 P 0 ;0
L 1.42983002 -2.07445 1.47825 -2.07445 0 P 0 ;0
L 1.4299 -2.07345 1.47828996 -2.07345 0 P 0 ;0
L 1.42963996 -2.07245 1.47833996 -2.07245 0 P 0 ;0
L 1.42918996 -2.07145 1.47838002 -2.07145 0 P 0 ;0
L 1.38425 -2.05145 1.47931004 -2.05145 0 P 0 ;0
L 1.38731998 -2.05045 1.47933996 -2.05045 0 P 0 ;0
L 1.39088002 -2.04945 1.47938002 -2.04945 0 P 0 ;0
L 1.3947 -2.04845 1.47941004 -2.04845 0 P 0 ;0
L 1.39851004 -2.04745 1.47945 -2.04745 0 P 0 ;0
L 1.40233002 -2.04645 1.47948002 -2.04645 0 P 0 ;0
L 1.40608002 -2.04545 1.47951004 -2.04545 0 P 0 ;0
L 1.40983002 -2.04445 1.47955 -2.04445 0 P 0 ;0
L 1.41306998 -2.04345 1.47958996 -2.04345 0 P 0 ;0
L 1.41591998 -2.04245 1.47961998 -2.04245 0 P 0 ;0
L 1.41876998 -2.04145 1.47965 -2.04145 0 P 0 ;0
L 1.42133996 -2.04045 1.47968996 -2.04045 0 P 0 ;0
L 1.42361998 -2.03945 1.47971998 -2.03945 0 P 0 ;0
L 1.42591004 -2.03845 1.47975 -2.03845 0 P 0 ;0
L 1.42805 -2.03745 1.47978002 -2.03745 0 P 0 ;0
L 1.42936004 -2.03645 1.47981004 -2.03645 0 P 0 ;0
L 1.43003002 -2.03545 1.47983002 -2.03545 0 P 0 ;0
L 1.43081998 -2.03445 1.47986004 -2.03445 0 P 0 ;0
L 1.43121004 -2.03345 1.47988002 -2.03345 0 P 0 ;0
L 1.43141998 -2.03245 1.4799 -2.03245 0 P 0 ;0
L 1.43146998 -2.03145 1.47993002 -2.03145 0 P 0 ;0
L 1.43136004 -2.03045 1.47996004 -2.03045 0 P 0 ;0
L 1.43108002 -2.02945 1.47998002 -2.02945 0 P 0 ;0
L 1.4306 -2.02845 1.48001004 -2.02845 0 P 0 ;0
L 1.42986998 -2.02745 1.48001004 -2.02745 0 P 0 ;0
L 1.42875 -2.02645 1.47998996 -2.02645 0 P 0 ;0
L 1.42658996 -2.02545 1.47996998 -2.02545 0 P 0 ;0
L 1.42203996 -2.02445 1.47996004 -2.02445 0 P 0 ;0
L 1.38748002 -1.99345 1.45483002 -1.99345 0 P 0 ;0
L 1.39331998 -1.99245 1.45108996 -1.99245 0 P 0 ;0
L 1.40051004 -1.99145 1.44503002 -1.99145 0 P 0 ;0
L 1.38096998 -2.12745 1.4051 -2.12745 0 P 0 ;0
L 1.37671004 -2.12645 1.41113996 -2.12645 0 P 0 ;0
L 1.3736 -2.12545 1.41238996 -2.12545 0 P 0 ;0
L 1.37096998 -2.12445 1.41268002 -2.12445 0 P 0 ;0
L 1.36876998 -2.12345 1.41296998 -2.12345 0 P 0 ;0
L 1.36685 -2.12245 1.41326998 -2.12245 0 P 0 ;0
L 1.36516004 -2.12145 1.41356004 -2.12145 0 P 0 ;0
L 1.36366004 -2.12045 1.41385 -2.12045 0 P 0 ;0
L 1.36225 -2.11945 1.41413996 -2.11945 0 P 0 ;0
L 1.361 -2.11845 1.41443002 -2.11845 0 P 0 ;0
L 1.35983002 -2.11745 1.41471998 -2.11745 0 P 0 ;0
L 1.35876004 -2.11645 1.41501004 -2.11645 0 P 0 ;0
L 1.42661998 -2.12445 1.47693002 -2.12445 0 P 0 ;0
L 1.42665 -2.12345 1.47693002 -2.12345 0 P 0 ;0
L 1.4267 -2.12245 1.47693002 -2.12245 0 P 0 ;0
L 1.42675 -2.12145 1.47693002 -2.12145 0 P 0 ;0
L 1.42681004 -2.12045 1.47693002 -2.12045 0 P 0 ;0
L 1.42686998 -2.11945 1.47693002 -2.11945 0 P 0 ;0
L 1.42691998 -2.11845 1.47693002 -2.11845 0 P 0 ;0
L 1.42698996 -2.11745 1.47693002 -2.11745 0 P 0 ;0
L 1.42705 -2.11645 1.47693002 -2.11645 0 P 0 ;0
L 1.42711004 -2.11545 1.47693002 -2.11545 0 P 0 ;0
L 1.42716998 -2.11445 1.47693002 -2.11445 0 P 0 ;0
L 1.42723002 -2.11345 1.47693996 -2.11345 0 P 0 ;0
L 1.4273 -2.11245 1.47695 -2.11245 0 P 0 ;0
L 1.42736998 -2.11145 1.47696004 -2.11145 0 P 0 ;0
L 1.42743996 -2.11045 1.47698002 -2.11045 0 P 0 ;0
L 1.42751004 -2.10945 1.47698996 -2.10945 0 P 0 ;0
L 1.42758002 -2.10845 1.47701004 -2.10845 0 P 0 ;0
L 1.42765 -2.10745 1.47703002 -2.10745 0 P 0 ;0
L 1.42771004 -2.10645 1.47703996 -2.10645 0 P 0 ;0
L 1.42778002 -2.10545 1.47706998 -2.10545 0 P 0 ;0
L 1.42783996 -2.10445 1.4771 -2.10445 0 P 0 ;0
L 1.42791004 -2.10345 1.47713002 -2.10345 0 P 0 ;0
L 1.42798002 -2.10245 1.47716004 -2.10245 0 P 0 ;0
L 1.42805 -2.10145 1.4772 -2.10145 0 P 0 ;0
L 1.42811004 -2.10045 1.47723002 -2.10045 0 P 0 ;0
L 1.40953002 -2.09945 1.41973002 -2.09945 0 P 0 ;0
L 1.42818002 -2.09945 1.47726004 -2.09945 0 P 0 ;0
L 1.41618002 -2.09845 1.41996998 -2.09845 0 P 0 ;0
L 1.42825 -2.09845 1.47728996 -2.09845 0 P 0 ;0
L 1.42831998 -2.09745 1.47733002 -2.09745 0 P 0 ;0
L 1.42838996 -2.09645 1.47736004 -2.09645 0 P 0 ;0
L 1.42846004 -2.09545 1.47738996 -2.09545 0 P 0 ;0
L 1.42851998 -2.09445 1.47741998 -2.09445 0 P 0 ;0
L 1.42858996 -2.09345 1.47746004 -2.09345 0 P 0 ;0
L 1.42866004 -2.09245 1.4775 -2.09245 0 P 0 ;0
L 1.42873002 -2.09145 1.47753996 -2.09145 0 P 0 ;0
L 1.42878996 -2.09045 1.47758002 -2.09045 0 P 0 ;0
L 1.42886004 -2.08945 1.47761998 -2.08945 0 P 0 ;0
L 1.42893002 -2.08845 1.47766004 -2.08845 0 P 0 ;0
L 1.42898996 -2.08745 1.4777 -2.08745 0 P 0 ;0
L 1.42906004 -2.08645 1.47773002 -2.08645 0 P 0 ;0
L 1.42911998 -2.08545 1.47776998 -2.08545 0 P 0 ;0
L 1.42918996 -2.08445 1.47781004 -2.08445 0 P 0 ;0
L 1.61686004 -2.17995 1.66846004 -2.17995 0 P 0 ;0
L 1.61591004 -2.17895 1.67158996 -2.17895 0 P 0 ;0
L 1.61553996 -2.17795 1.67431998 -2.17795 0 P 0 ;0
L 1.61526998 -2.17695 1.67675 -2.17695 0 P 0 ;0
L 1.61508002 -2.17595 1.67903996 -2.17595 0 P 0 ;0
L 1.61496998 -2.17495 1.68108002 -2.17495 0 P 0 ;0
L 1.61491004 -2.17395 1.68295 -2.17395 0 P 0 ;0
L 1.61485 -2.17295 1.68458996 -2.17295 0 P 0 ;0
L 1.61478996 -2.17195 1.6861 -2.17195 0 P 0 ;0
L 1.61473002 -2.17095 1.6875 -2.17095 0 P 0 ;0
L 1.61466998 -2.16995 1.68876998 -2.16995 0 P 0 ;0
L 1.61461004 -2.16895 1.68998002 -2.16895 0 P 0 ;0
L 1.61455 -2.16795 1.69108002 -2.16795 0 P 0 ;0
L 1.61448996 -2.16695 1.69211998 -2.16695 0 P 0 ;0
L 1.61443002 -2.16595 1.69316004 -2.16595 0 P 0 ;0
L 1.61436998 -2.16495 1.69411998 -2.16495 0 P 0 ;0
L 1.61431004 -2.16395 1.69498996 -2.16395 0 P 0 ;0
L 1.61425 -2.16295 1.69586004 -2.16295 0 P 0 ;0
L 1.61418996 -2.16195 1.69673002 -2.16195 0 P 0 ;0
L 1.61413002 -2.16095 1.69746998 -2.16095 0 P 0 ;0
L 1.61406998 -2.15995 1.6982 -2.15995 0 P 0 ;0
L 1.61401998 -2.15895 1.69893996 -2.15895 0 P 0 ;0
L 1.61396998 -2.15795 1.69963002 -2.15795 0 P 0 ;0
L 1.64433002 -2.18295 1.63151004 -2.18271004 0 P 0 ;0
L 1.63151004 -2.18271004 1.62658002 -2.18226998 0 P 0 ;0
L 1.62658002 -2.18226998 1.62168996 -2.18146998 0 P 0 ;0
L 1.62168996 -2.18146998 1.6201 -2.1811 0 P 0 ;0
L 1.6201 -2.1811 1.61853996 -2.18061004 0 P 0 ;0
L 1.61853996 -2.18061004 1.61701004 -2.18001998 0 P 0 ;0
L 1.61701004 -2.18001998 1.61686004 -2.17995 0 P 0 ;0
L 1.61686004 -2.17995 1.61671004 -2.17986998 0 P 0 ;0
L 1.61671004 -2.17986998 1.61656998 -2.17976998 0 P 0 ;0
L 1.61656998 -2.17976998 1.61643996 -2.17966998 0 P 0 ;0
L 1.61643996 -2.17966998 1.61631998 -2.17955 0 P 0 ;0
L 1.61631998 -2.17955 1.61621004 -2.17943002 0 P 0 ;0
L 1.61621004 -2.17943002 1.6161 -2.1793 0 P 0 ;0
L 1.6161 -2.1793 1.61601004 -2.17915 0 P 0 ;0
L 1.61601004 -2.17915 1.61593002 -2.179 0 P 0 ;0
L 1.61593002 -2.179 1.61586004 -2.17885 0 P 0 ;0
L 1.61586004 -2.17885 1.61553002 -2.17791004 0 P 0 ;0
L 1.61553002 -2.17791004 1.61526998 -2.17696004 0 P 0 ;0
L 1.61526998 -2.17696004 1.61508996 -2.17598996 0 P 0 ;0
L 1.61508996 -2.17598996 1.61496998 -2.17496998 0 P 0 ;0
L 1.61496998 -2.17496998 1.61408002 -2.16011004 0 P 0 ;0
L 1.61408002 -2.16011004 1.61341998 -2.14758996 0 P 0 ;0
L 1.61341998 -2.14758996 1.6202 -2.14821004 0 P 0 ;0
L 1.6202 -2.14821004 1.62023002 -2.14821004 0 P 0 ;0
L 1.62023002 -2.14821004 1.63216998 -2.14893996 0 P 0 ;0
L 1.63216998 -2.14893996 1.6349 -2.14893002 0 P 0 ;0
L 1.6349 -2.14893002 1.63761998 -2.14873002 0 P 0 ;0
L 1.63761998 -2.14873002 1.64031998 -2.14835 0 P 0 ;0
L 1.64031998 -2.14835 1.64198996 -2.14798996 0 P 0 ;0
L 1.64198996 -2.14798996 1.64363002 -2.14751998 0 P 0 ;0
L 1.64363002 -2.14751998 1.64523002 -2.14693002 0 P 0 ;0
L 1.64523002 -2.14693002 1.64678996 -2.14623002 0 P 0 ;0
L 1.64678996 -2.14623002 1.64888002 -2.14506998 0 P 0 ;0
L 1.64888002 -2.14506998 1.65086998 -2.14376004 0 P 0 ;0
L 1.65086998 -2.14376004 1.65093996 -2.14371004 0 P 0 ;0
L 1.65093996 -2.14371004 1.65275 -2.14228996 0 P 0 ;0
L 1.65275 -2.14228996 1.6539 -2.14123996 0 P 0 ;0
L 1.6539 -2.14123996 1.65496004 -2.14011004 0 P 0 ;0
L 1.65496004 -2.14011004 1.65591998 -2.13891004 0 P 0 ;0
L 1.65591998 -2.13891004 1.65755 -2.13653996 0 P 0 ;0
L 1.65755 -2.13653996 1.65901998 -2.13415 0 P 0 ;0
L 1.65901998 -2.13415 1.65903002 -2.13413002 0 P 0 ;0
L 1.65903002 -2.13413002 1.66035 -2.13171998 0 P 0 ;0
L 1.66035 -2.13171998 1.66155 -2.12925 0 P 0 ;0
L 1.66155 -2.12925 1.66183996 -2.12851998 0 P 0 ;0
L 1.66183996 -2.12851998 1.66206998 -2.12776004 0 P 0 ;0
L 1.66206998 -2.12776004 1.66223996 -2.12696998 0 P 0 ;0
L 1.66223996 -2.12696998 1.66233996 -2.12618002 0 P 0 ;0
L 1.66233996 -2.12618002 1.66236998 -2.12538996 0 P 0 ;0
L 1.66236998 -2.12538996 1.66233002 -2.12436004 0 P 0 ;0
L 1.66233002 -2.12436004 1.66221004 -2.12335 0 P 0 ;0
L 1.66221004 -2.12335 1.662 -2.12235 0 P 0 ;0
L 1.662 -2.12235 1.66171004 -2.12141004 0 P 0 ;0
L 1.66171004 -2.12141004 1.64438996 -2.07113002 0 P 0 ;0
L 1.64438996 -2.07113002 1.62871998 -2.02606004 0 P 0 ;0
L 1.62871998 -2.02606004 1.62116004 -2.00558996 0 P 0 ;0
L 1.62116004 -2.00558996 1.62116004 -2.00556998 0 P 0 ;0
L 1.62116004 -2.00556998 1.61681004 -1.99443996 0 P 0 ;0
L 1.61681004 -1.99443996 1.67163002 -1.99443996 0 P 0 ;0
L 1.67163002 -1.99443996 1.67301004 -2.00076004 0 P 0 ;0
L 1.67301004 -2.00076004 1.67613002 -2.01341998 0 P 0 ;0
L 1.67613002 -2.01341998 1.68331004 -2.03931998 0 P 0 ;0
L 1.68331004 -2.03931998 1.69153002 -2.06856998 0 P 0 ;0
L 1.69153002 -2.06856998 1.6916 -2.06876004 0 P 0 ;0
L 1.6916 -2.06876004 1.69168996 -2.06896998 0 P 0 ;0
L 1.69168996 -2.06896998 1.69181004 -2.06918002 0 P 0 ;0
L 1.69181004 -2.06918002 1.69193002 -2.06936998 0 P 0 ;0
L 1.69193002 -2.06936998 1.69208002 -2.06956004 0 P 0 ;0
L 1.69208002 -2.06956004 1.69223996 -2.06973002 0 P 0 ;0
L 1.69223996 -2.06973002 1.69241998 -2.06988002 0 P 0 ;0
L 1.69241998 -2.06988002 1.6926 -2.07001998 0 P 0 ;0
L 1.6926 -2.07001998 1.6928 -2.07015 0 P 0 ;0
L 1.6928 -2.07015 1.69301004 -2.07025 0 P 0 ;0
L 1.69301004 -2.07025 1.69323002 -2.07033996 0 P 0 ;0
L 1.69323002 -2.07033996 1.69346004 -2.07041004 0 P 0 ;0
L 1.69346004 -2.07041004 1.69368002 -2.07045 0 P 0 ;0
L 1.69368002 -2.07045 1.69391998 -2.07048002 0 P 0 ;0
L 1.69391998 -2.07048002 1.69413996 -2.07048996 0 P 0 ;0
L 1.69413996 -2.07048996 1.6944 -2.07048002 0 P 0 ;0
L 1.6944 -2.07048002 1.69465 -2.07045 0 P 0 ;0
L 1.69465 -2.07045 1.69488996 -2.07038996 0 P 0 ;0
L 1.69488996 -2.07038996 1.69513996 -2.07031998 0 P 0 ;0
L 1.69513996 -2.07031998 1.69536998 -2.07021998 0 P 0 ;0
L 1.69536998 -2.07021998 1.69558996 -2.0701 0 P 0 ;0
L 1.69558996 -2.0701 1.69581004 -2.06996998 0 P 0 ;0
L 1.69581004 -2.06996998 1.69601004 -2.06981998 0 P 0 ;0
L 1.69601004 -2.06981998 1.6962 -2.06965 0 P 0 ;0
L 1.6962 -2.06965 1.69636998 -2.06946004 0 P 0 ;0
L 1.69636998 -2.06946004 1.69653002 -2.06926004 0 P 0 ;0
L 1.69653002 -2.06926004 1.69666004 -2.06905 0 P 0 ;0
L 1.69666004 -2.06905 1.69678996 -2.06883002 0 P 0 ;0
L 1.69678996 -2.06883002 1.69688002 -2.0686 0 P 0 ;0
L 1.69688002 -2.0686 1.69695 -2.0684 0 P 0 ;0
L 1.69695 -2.0684 1.70426004 -2.04365 0 P 0 ;0
L 1.70426004 -2.04365 1.70426004 -2.04363002 0 P 0 ;0
L 1.70426004 -2.04363002 1.71066998 -2.0213 0 P 0 ;0
L 1.71066998 -2.0213 1.71068002 -2.02126004 0 P 0 ;0
L 1.71068002 -2.02126004 1.71431998 -2.00693996 0 P 0 ;0
L 1.71431998 -2.00693996 1.71706004 -1.99496998 0 P 0 ;0
L 1.71706004 -1.99496998 1.74335 -1.9947 0 P 0 ;0
L 1.74335 -1.9947 1.75403002 -1.99461004 0 P 0 ;0
L 1.75403002 -1.99461004 1.76301004 -1.99465 0 P 0 ;0
L 1.76301004 -1.99465 1.76886004 -1.99471004 0 P 0 ;0
L 1.76886004 -1.99471004 1.76883996 -1.99476004 0 P 0 ;0
L 1.76883996 -1.99476004 1.74021004 -2.06556004 0 P 0 ;0
L 1.74021004 -2.06556004 1.71298002 -2.13276998 0 P 0 ;0
L 1.71298002 -2.13276998 1.70836998 -2.14293996 0 P 0 ;0
L 1.70836998 -2.14293996 1.70413996 -2.15076004 0 P 0 ;0
L 1.70413996 -2.15076004 1.69941998 -2.15828996 0 P 0 ;0
L 1.69941998 -2.15828996 1.6967 -2.16198996 0 P 0 ;0
L 1.6967 -2.16198996 1.6937 -2.16541998 0 P 0 ;0
L 1.6937 -2.16541998 1.69041998 -2.1686 0 P 0 ;0
L 1.69041998 -2.1686 1.68793996 -2.17063002 0 P 0 ;0
L 1.68793996 -2.17063002 1.68535 -2.17248002 0 P 0 ;0
L 1.68535 -2.17248002 1.68263996 -2.17413996 0 P 0 ;0
L 1.68263996 -2.17413996 1.67981004 -2.17561004 0 P 0 ;0
L 1.67981004 -2.17561004 1.67525 -2.17761004 0 P 0 ;0
L 1.67525 -2.17761004 1.6706 -2.17931998 0 P 0 ;0
L 1.6706 -2.17931998 1.66586004 -2.18073002 0 P 0 ;0
L 1.66586004 -2.18073002 1.66141998 -2.1817 0 P 0 ;0
L 1.66141998 -2.1817 1.65691998 -2.18228996 0 P 0 ;0
L 1.65691998 -2.18228996 1.64433002 -2.18295 0 P 0 ;0
L 1.61928996 -2.00628002 1.62683996 -2.02673002 0 P 0 ;0
L 1.62683996 -2.02673002 1.6425 -2.07178002 0 P 0 ;0
L 1.6425 -2.07178002 1.65981004 -2.12201998 0 P 0 ;0
L 1.65981004 -2.12201998 1.66006004 -2.12283996 0 P 0 ;0
L 1.66006004 -2.12283996 1.66023002 -2.12368002 0 P 0 ;0
L 1.66023002 -2.12368002 1.66033996 -2.12451998 0 P 0 ;0
L 1.66033996 -2.12451998 1.66036998 -2.12538002 0 P 0 ;0
L 1.66036998 -2.12538002 1.66033996 -2.12601004 0 P 0 ;0
L 1.66033996 -2.12601004 1.66026998 -2.12663996 0 P 0 ;0
L 1.66026998 -2.12663996 1.66013996 -2.12725 0 P 0 ;0
L 1.66013996 -2.12725 1.65995 -2.12786004 0 P 0 ;0
L 1.65995 -2.12786004 1.65971004 -2.12843996 0 P 0 ;0
L 1.65971004 -2.12843996 1.65856998 -2.1308 0 P 0 ;0
L 1.65856998 -2.1308 1.6573 -2.13313002 0 P 0 ;0
L 1.6573 -2.13313002 1.65586998 -2.13545 0 P 0 ;0
L 1.65586998 -2.13545 1.65431004 -2.13771998 0 P 0 ;0
L 1.65431004 -2.13771998 1.65343996 -2.1388 0 P 0 ;0
L 1.65343996 -2.1388 1.65248996 -2.13981998 0 P 0 ;0
L 1.65248996 -2.13981998 1.65146004 -2.14076004 0 P 0 ;0
L 1.65146004 -2.14076004 1.64971004 -2.14213002 0 P 0 ;0
L 1.64971004 -2.14213002 1.64785 -2.14336004 0 P 0 ;0
L 1.64785 -2.14336004 1.64588996 -2.14443996 0 P 0 ;0
L 1.64588996 -2.14443996 1.64446998 -2.14508002 0 P 0 ;0
L 1.64446998 -2.14508002 1.64301004 -2.14561998 0 P 0 ;0
L 1.64301004 -2.14561998 1.64151004 -2.14605 0 P 0 ;0
L 1.64151004 -2.14605 1.63996998 -2.14636998 0 P 0 ;0
L 1.63996998 -2.14636998 1.63741004 -2.14673996 0 P 0 ;0
L 1.63741004 -2.14673996 1.63483002 -2.14693002 0 P 0 ;0
L 1.63483002 -2.14693002 1.63223002 -2.14693996 0 P 0 ;0
L 1.63223002 -2.14693996 1.62036004 -2.14621998 0 P 0 ;0
L 1.62036004 -2.14621998 1.6113 -2.14538002 0 P 0 ;0
L 1.6113 -2.14538002 1.61208996 -2.16023002 0 P 0 ;0
L 1.61208996 -2.16023002 1.61298002 -2.17515 0 P 0 ;0
L 1.61298002 -2.17515 1.6131 -2.17628002 0 P 0 ;0
L 1.6131 -2.17628002 1.61331998 -2.17741004 0 P 0 ;0
L 1.61331998 -2.17741004 1.61361998 -2.17851004 0 P 0 ;0
L 1.61361998 -2.17851004 1.614 -2.17958996 0 P 0 ;0
L 1.614 -2.17958996 1.61413996 -2.17988996 0 P 0 ;0
L 1.61413996 -2.17988996 1.61428996 -2.18018002 0 P 0 ;0
L 1.61428996 -2.18018002 1.61446998 -2.18045 0 P 0 ;0
L 1.61446998 -2.18045 1.61466998 -2.18071004 0 P 0 ;0
L 1.61466998 -2.18071004 1.61488996 -2.18095 0 P 0 ;0
L 1.61488996 -2.18095 1.61511998 -2.18116998 0 P 0 ;0
L 1.61511998 -2.18116998 1.61538002 -2.18138002 0 P 0 ;0
L 1.61538002 -2.18138002 1.61565 -2.18156004 0 P 0 ;0
L 1.61565 -2.18156004 1.61593002 -2.18173002 0 P 0 ;0
L 1.61593002 -2.18173002 1.61623002 -2.18186004 0 P 0 ;0
L 1.61623002 -2.18186004 1.61788002 -2.1825 0 P 0 ;0
L 1.61788002 -2.1825 1.61956998 -2.18301998 0 P 0 ;0
L 1.61956998 -2.18301998 1.6213 -2.18343002 0 P 0 ;0
L 1.6213 -2.18343002 1.62633002 -2.18426004 0 P 0 ;0
L 1.62633002 -2.18426004 1.6314 -2.18471004 0 P 0 ;0
L 1.6314 -2.18471004 1.64436004 -2.18495 0 P 0 ;0
L 1.64436004 -2.18495 1.65711004 -2.18428002 0 P 0 ;0
L 1.65711004 -2.18428002 1.66176998 -2.18366998 0 P 0 ;0
L 1.66176998 -2.18366998 1.66636004 -2.18266998 0 P 0 ;0
L 1.66636004 -2.18266998 1.67123002 -2.18121004 0 P 0 ;0
L 1.67123002 -2.18121004 1.676 -2.17946998 0 P 0 ;0
L 1.676 -2.17946998 1.68068002 -2.17741998 0 P 0 ;0
L 1.68068002 -2.17741998 1.68361998 -2.17588002 0 P 0 ;0
L 1.68361998 -2.17588002 1.68646004 -2.17415 0 P 0 ;0
L 1.68646004 -2.17415 1.68916004 -2.17221998 0 P 0 ;0
L 1.68916004 -2.17221998 1.69175 -2.17008996 0 P 0 ;0
L 1.69175 -2.17008996 1.69515 -2.1668 0 P 0 ;0
L 1.69515 -2.1668 1.69826004 -2.16323996 0 P 0 ;0
L 1.69826004 -2.16323996 1.70108002 -2.15941998 0 P 0 ;0
L 1.70108002 -2.15941998 1.70586004 -2.15176998 0 P 0 ;0
L 1.70586004 -2.15176998 1.71016004 -2.14383002 0 P 0 ;0
L 1.71016004 -2.14383002 1.71481998 -2.13356004 0 P 0 ;0
L 1.71481998 -2.13356004 1.74206998 -2.06631004 0 P 0 ;0
L 1.74206998 -2.06631004 1.77071004 -1.99548002 0 P 0 ;0
L 1.77071004 -1.99548002 1.77088002 -1.99498996 0 P 0 ;0
L 1.77088002 -1.99498996 1.77101998 -1.99448996 0 P 0 ;0
L 1.77101998 -1.99448996 1.77111998 -1.99398996 0 P 0 ;0
L 1.77111998 -1.99398996 1.77118002 -1.99346998 0 P 0 ;0
L 1.77118002 -1.99346998 1.7712 -1.99295 0 P 0 ;0
L 1.7712 -1.99295 1.7712 -1.99293002 0 P 0 ;0
L 1.7712 -1.99293002 1.77118996 -1.99286998 0 P 0 ;0
L 1.77118996 -1.99286998 1.77118002 -1.99286004 0 P 0 ;0
L 1.77118002 -1.99286004 1.77118002 -1.99283996 0 P 0 ;0
L 1.77118002 -1.99283996 1.77111004 -1.99276998 0 P 0 ;0
L 1.77111004 -1.99276998 1.77106998 -1.99275 0 P 0 ;0
L 1.77106998 -1.99275 1.77106004 -1.99273996 0 P 0 ;0
L 1.77106004 -1.99273996 1.771 -1.99273002 0 P 0 ;0
L 1.771 -1.99273002 1.77098002 -1.99273002 0 P 0 ;0
L 1.77098002 -1.99273002 1.76301004 -1.99265 0 P 0 ;0
L 1.76301004 -1.99265 1.75401998 -1.99261004 0 P 0 ;0
L 1.75401998 -1.99261004 1.74333002 -1.9927 0 P 0 ;0
L 1.74333002 -1.9927 1.71546004 -1.99298996 0 P 0 ;0
L 1.71546004 -1.99298996 1.71236998 -2.00646998 0 P 0 ;0
L 1.71236998 -2.00646998 1.70873996 -2.02078002 0 P 0 ;0
L 1.70873996 -2.02078002 1.70233996 -2.04308002 0 P 0 ;0
L 1.70233996 -2.04308002 1.69505 -2.0678 0 P 0 ;0
L 1.69505 -2.0678 1.69501998 -2.06788002 0 P 0 ;0
L 1.69501998 -2.06788002 1.69498996 -2.06795 0 P 0 ;0
L 1.69498996 -2.06795 1.69495 -2.06801998 0 P 0 ;0
L 1.69495 -2.06801998 1.69485 -2.06816004 0 P 0 ;0
L 1.69485 -2.06816004 1.69478996 -2.06821998 0 P 0 ;0
L 1.69478996 -2.06821998 1.69466998 -2.06831998 0 P 0 ;0
L 1.69466998 -2.06831998 1.69453002 -2.0684 0 P 0 ;0
L 1.69453002 -2.0684 1.69445 -2.06843002 0 P 0 ;0
L 1.69445 -2.06843002 1.69438002 -2.06846004 0 P 0 ;0
L 1.69438002 -2.06846004 1.69428996 -2.06846998 0 P 0 ;0
L 1.69428996 -2.06846998 1.69421004 -2.06848996 0 P 0 ;0
L 1.69421004 -2.06848996 1.69406998 -2.06848996 0 P 0 ;0
L 1.69406998 -2.06848996 1.69395 -2.06846998 0 P 0 ;0
L 1.69395 -2.06846998 1.69383002 -2.06843002 0 P 0 ;0
L 1.69383002 -2.06843002 1.69373002 -2.06836998 0 P 0 ;0
L 1.69373002 -2.06836998 1.69363002 -2.06828996 0 P 0 ;0
L 1.69363002 -2.06828996 1.69358996 -2.06823996 0 P 0 ;0
L 1.69358996 -2.06823996 1.69355 -2.0682 0 P 0 ;0
L 1.69355 -2.0682 1.69351998 -2.06815 0 P 0 ;0
L 1.69351998 -2.06815 1.69346004 -2.06803996 0 P 0 ;0
L 1.69346004 -2.06803996 1.69343996 -2.06798002 0 P 0 ;0
L 1.69343996 -2.06798002 1.68523002 -2.03878002 0 P 0 ;0
L 1.68523002 -2.03878002 1.67806998 -2.01291998 0 P 0 ;0
L 1.67806998 -2.01291998 1.67496004 -2.00031004 0 P 0 ;0
L 1.67496004 -2.00031004 1.67323002 -1.99243996 0 P 0 ;0
L 1.67323002 -1.99243996 1.61388002 -1.99243996 0 P 0 ;0
L 1.61388002 -1.99243996 1.61928996 -2.00628002 0 P 0 ;0
L 1.35018002 -2.08345 1.39488996 -2.08345 0 P 0 ;0
L 1.35026004 -2.08245 1.39586004 -2.08245 0 P 0 ;0
L 1.35041004 -2.08145 1.39708996 -2.08145 0 P 0 ;0
L 1.35058996 -2.08045 1.39853002 -2.08045 0 P 0 ;0
L 1.35083996 -2.07945 1.40031998 -2.07945 0 P 0 ;0
L 1.35116998 -2.07845 1.40271004 -2.07845 0 P 0 ;0
L 1.35158002 -2.07745 1.40561998 -2.07745 0 P 0 ;0
L 1.35203002 -2.07645 1.4092 -2.07645 0 P 0 ;0
L 1.35248002 -2.07545 1.41288996 -2.07545 0 P 0 ;0
L 1.35293002 -2.07445 1.4164 -2.07445 0 P 0 ;0
L 1.35338996 -2.07345 1.41975 -2.07345 0 P 0 ;0
L 1.35393996 -2.07245 1.42293996 -2.07245 0 P 0 ;0
L 1.35448996 -2.07145 1.42606998 -2.07145 0 P 0 ;0
L 1.35505 -2.07045 1.47843002 -2.07045 0 P 0 ;0
L 1.3557 -2.06945 1.47846998 -2.06945 0 P 0 ;0
L 1.35635 -2.06845 1.47851998 -2.06845 0 P 0 ;0
L 1.35701998 -2.06745 1.47856998 -2.06745 0 P 0 ;0
L 1.35776998 -2.06645 1.47861004 -2.06645 0 P 0 ;0
L 1.29346998 -2.00516004 1.33388996 -2.00516004 0 P 0 ;0
L 1.29448996 -2.00416004 1.33385 -2.00416004 0 P 0 ;0
L 1.29551004 -2.00316004 1.33381004 -2.00316004 0 P 0 ;0
L 1.29653996 -2.00216004 1.33376004 -2.00216004 0 P 0 ;0
L 1.29756004 -2.00116004 1.33371004 -2.00116004 0 P 0 ;0
L 1.29861998 -2.00016004 1.33366004 -2.00016004 0 P 0 ;0
L 1.29973002 -1.99916004 1.3336 -1.99916004 0 P 0 ;0
L 1.30101004 -1.99816004 1.33355 -1.99816004 0 P 0 ;0
L 1.30238996 -1.99716004 1.3335 -1.99716004 0 P 0 ;0
L 1.30393996 -1.99616004 1.33345 -1.99616004 0 P 0 ;0
L 1.30571004 -1.99516004 1.33338996 -1.99516004 0 P 0 ;0
L 1.3077 -1.99416004 1.33333002 -1.99416004 0 P 0 ;0
L 1.31001004 -1.99316004 1.33328002 -1.99316004 0 P 0 ;0
L 1.31288002 -1.99216004 1.33321998 -1.99216004 0 P 0 ;0
L 1.31688996 -1.99116004 1.33316004 -1.99116004 0 P 0 ;0
L 1.39798996 -1.98971998 1.39326998 -1.99043002 0 P 0 ;0
L 1.39326998 -1.99043002 1.38806998 -1.9913 0 P 0 ;0
L 1.38806998 -1.9913 1.38316004 -1.9922 0 P 0 ;0
L 1.38316004 -1.9922 1.37946004 -1.99296998 0 P 0 ;0
L 1.37946004 -1.99296998 1.3718 -1.99466998 0 P 0 ;0
L 1.3718 -1.99466998 1.36896004 -2.01553996 0 P 0 ;0
L 1.36896004 -2.01553996 1.36791004 -2.02358996 0 P 0 ;0
L 1.36791004 -2.02358996 1.36708002 -2.03043002 0 P 0 ;0
L 1.36708002 -2.03043002 1.36638996 -2.03646004 0 P 0 ;0
L 1.36638996 -2.03646004 1.36638002 -2.03648996 0 P 0 ;0
L 1.36638002 -2.03648996 1.36638996 -2.03653002 0 P 0 ;0
L 1.36638996 -2.03653002 1.36638996 -2.03656998 0 P 0 ;0
L 1.36638996 -2.03656998 1.3664 -2.03663996 0 P 0 ;0
L 1.3664 -2.03663996 1.36641998 -2.03666998 0 P 0 ;0
L 1.36641998 -2.03666998 1.36643002 -2.03671004 0 P 0 ;0
L 1.36643002 -2.03671004 1.36648996 -2.0368 0 P 0 ;0
L 1.36648996 -2.0368 1.36656004 -2.03686004 0 P 0 ;0
L 1.36656004 -2.03686004 1.3666 -2.03688996 0 P 0 ;0
L 1.3666 -2.03688996 1.36663002 -2.03691004 0 P 0 ;0
L 1.36663002 -2.03691004 1.36666004 -2.03691004 0 P 0 ;0
L 1.36666004 -2.03691004 1.36671004 -2.03693002 0 P 0 ;0
L 1.36671004 -2.03693002 1.36676998 -2.03693002 0 P 0 ;0
L 1.36676998 -2.03693002 1.36685 -2.03691998 0 P 0 ;0
L 1.36685 -2.03691998 1.36895 -2.03628002 0 P 0 ;0
L 1.36895 -2.03628002 1.37143002 -2.03545 0 P 0 ;0
L 1.37143002 -2.03545 1.37428996 -2.03441004 0 P 0 ;0
L 1.37428996 -2.03441004 1.38346004 -2.03126998 0 P 0 ;0
L 1.38346004 -2.03126998 1.39251998 -2.02891998 0 P 0 ;0
L 1.39251998 -2.02891998 1.40156004 -2.02731998 0 P 0 ;0
L 1.40156004 -2.02731998 1.41068002 -2.02643996 0 P 0 ;0
L 1.41068002 -2.02643996 1.41566998 -2.02628002 0 P 0 ;0
L 1.41566998 -2.02628002 1.42066004 -2.02633996 0 P 0 ;0
L 1.42066004 -2.02633996 1.42221004 -2.02646998 0 P 0 ;0
L 1.42221004 -2.02646998 1.42375 -2.02671998 0 P 0 ;0
L 1.42375 -2.02671998 1.42525 -2.0271 0 P 0 ;0
L 1.42525 -2.0271 1.42671998 -2.02761004 0 P 0 ;0
L 1.42671998 -2.02761004 1.42706004 -2.02776004 0 P 0 ;0
L 1.42706004 -2.02776004 1.42738002 -2.02793002 0 P 0 ;0
L 1.42738002 -2.02793002 1.42768002 -2.02813996 0 P 0 ;0
L 1.42768002 -2.02813996 1.42796998 -2.02836004 0 P 0 ;0
L 1.42796998 -2.02836004 1.42823002 -2.02861004 0 P 0 ;0
L 1.42823002 -2.02861004 1.42848002 -2.02888996 0 P 0 ;0
L 1.42848002 -2.02888996 1.4287 -2.02918002 0 P 0 ;0
L 1.4287 -2.02918002 1.42888996 -2.02948996 0 P 0 ;0
L 1.42888996 -2.02948996 1.42906004 -2.02981004 0 P 0 ;0
L 1.42906004 -2.02981004 1.4292 -2.03015 0 P 0 ;0
L 1.4292 -2.03015 1.42931998 -2.0305 0 P 0 ;0
L 1.42931998 -2.0305 1.4294 -2.03086004 0 P 0 ;0
L 1.4294 -2.03086004 1.42945 -2.03121998 0 P 0 ;0
L 1.42945 -2.03121998 1.42946998 -2.03158002 0 P 0 ;0
L 1.42946998 -2.03158002 1.42946004 -2.03195 0 P 0 ;0
L 1.42946004 -2.03195 1.42941998 -2.03231004 0 P 0 ;0
L 1.42941998 -2.03231004 1.42935 -2.03266998 0 P 0 ;0
L 1.42935 -2.03266998 1.42925 -2.03301998 0 P 0 ;0
L 1.42925 -2.03301998 1.42911998 -2.03336004 0 P 0 ;0
L 1.42911998 -2.03336004 1.42896004 -2.03368996 0 P 0 ;0
L 1.42896004 -2.03368996 1.42875 -2.03405 0 P 0 ;0
L 1.42875 -2.03405 1.42851004 -2.03438996 0 P 0 ;0
L 1.42851004 -2.03438996 1.42825 -2.03471004 0 P 0 ;0
L 1.42825 -2.03471004 1.42796004 -2.03501004 0 P 0 ;0
L 1.42796004 -2.03501004 1.42765 -2.03528996 0 P 0 ;0
L 1.42765 -2.03528996 1.42731998 -2.03553996 0 P 0 ;0
L 1.42731998 -2.03553996 1.42696998 -2.03576004 0 P 0 ;0
L 1.42696998 -2.03576004 1.4266 -2.03596004 0 P 0 ;0
L 1.4266 -2.03596004 1.41951004 -2.03906004 0 P 0 ;0
L 1.41951004 -2.03906004 1.4109 -2.04208996 0 P 0 ;0
L 1.4109 -2.04208996 1.40178002 -2.04451998 0 P 0 ;0
L 1.40178002 -2.04451998 1.3878 -2.04818996 0 P 0 ;0
L 1.3878 -2.04818996 1.38176998 -2.05015 0 P 0 ;0
L 1.38176998 -2.05015 1.3758 -2.05243002 0 P 0 ;0
L 1.3758 -2.05243002 1.37086998 -2.0546 0 P 0 ;0
L 1.37086998 -2.0546 1.36603996 -2.05708002 0 P 0 ;0
L 1.36603996 -2.05708002 1.36356004 -2.05856004 0 P 0 ;0
L 1.36356004 -2.05856004 1.36118996 -2.06023002 0 P 0 ;0
L 1.36118996 -2.06023002 1.35895 -2.06206004 0 P 0 ;0
L 1.35895 -2.06206004 1.35805 -2.06291004 0 P 0 ;0
L 1.35805 -2.06291004 1.35721998 -2.06385 0 P 0 ;0
L 1.35721998 -2.06385 1.35518996 -2.06655 0 P 0 ;0
L 1.35518996 -2.06655 1.3532 -2.06961998 0 P 0 ;0
L 1.3532 -2.06961998 1.35156004 -2.07263002 0 P 0 ;0
L 1.35156004 -2.07263002 1.34951004 -2.07718002 0 P 0 ;0
L 1.34951004 -2.07718002 1.34911004 -2.07825 0 P 0 ;0
L 1.34911004 -2.07825 1.34878996 -2.07935 0 P 0 ;0
L 1.34878996 -2.07935 1.34853002 -2.08046998 0 P 0 ;0
L 1.34853002 -2.08046998 1.34825 -2.08238002 0 P 0 ;0
L 1.34825 -2.08238002 1.34811998 -2.08431004 0 P 0 ;0
L 1.34811998 -2.08431004 1.348 -2.09128996 0 P 0 ;0
L 1.348 -2.09128996 1.3481 -2.09761004 0 P 0 ;0
L 1.3481 -2.09761004 1.34823002 -2.09961004 0 P 0 ;0
L 1.34823002 -2.09961004 1.34846998 -2.10161004 0 P 0 ;0
L 1.34846998 -2.10161004 1.34876998 -2.10321998 0 P 0 ;0
L 1.34876998 -2.10321998 1.3492 -2.10478996 0 P 0 ;0
L 1.3492 -2.10478996 1.3498 -2.10648996 0 P 0 ;0
L 1.3498 -2.10648996 1.3505 -2.10815 0 P 0 ;0
L 1.3505 -2.10815 1.35178996 -2.11066004 0 P 0 ;0
L 1.35178996 -2.11066004 1.35328002 -2.11305 0 P 0 ;0
L 1.35328002 -2.11305 1.35496998 -2.1153 0 P 0 ;0
L 1.35496998 -2.1153 1.35685 -2.1174 0 P 0 ;0
L 1.35685 -2.1174 1.35891998 -2.11933996 0 P 0 ;0
L 1.35891998 -2.11933996 1.36126998 -2.12121998 0 P 0 ;0
L 1.36126998 -2.12121998 1.36373996 -2.12293002 0 P 0 ;0
L 1.36373996 -2.12293002 1.36633002 -2.12446004 0 P 0 ;0
L 1.36633002 -2.12446004 1.36901004 -2.1258 0 P 0 ;0
L 1.36901004 -2.1258 1.3718 -2.12695 0 P 0 ;0
L 1.3718 -2.12695 1.37578996 -2.12828002 0 P 0 ;0
L 1.37578996 -2.12828002 1.37986998 -2.12928996 0 P 0 ;0
L 1.37986998 -2.12928996 1.38401998 -2.12998996 0 P 0 ;0
L 1.38401998 -2.12998996 1.3882 -2.13036004 0 P 0 ;0
L 1.3882 -2.13036004 1.39443002 -2.13045 0 P 0 ;0
L 1.39443002 -2.13045 1.40066004 -2.13006998 0 P 0 ;0
L 1.40066004 -2.13006998 1.40685 -2.12923002 0 P 0 ;0
L 1.40685 -2.12923002 1.41371004 -2.12801998 0 P 0 ;0
L 1.41371004 -2.12801998 1.41583002 -2.12081004 0 P 0 ;0
L 1.41583002 -2.12081004 1.41953996 -2.10798996 0 P 0 ;0
L 1.41953996 -2.10798996 1.42135 -2.10126998 0 P 0 ;0
L 1.42135 -2.10126998 1.42236998 -2.097 0 P 0 ;0
L 1.42236998 -2.097 1.42238996 -2.09691004 0 P 0 ;0
L 1.42238996 -2.09691004 1.4224 -2.09681998 0 P 0 ;0
L 1.4224 -2.09681998 1.4224 -2.09673996 0 P 0 ;0
L 1.4224 -2.09673996 1.42238002 -2.09656004 0 P 0 ;0
L 1.42238002 -2.09656004 1.42235 -2.09648002 0 P 0 ;0
L 1.42235 -2.09648002 1.42233002 -2.09638996 0 P 0 ;0
L 1.42233002 -2.09638996 1.42225 -2.09623002 0 P 0 ;0
L 1.42225 -2.09623002 1.4222 -2.09616004 0 P 0 ;0
L 1.4222 -2.09616004 1.42213996 -2.09608996 0 P 0 ;0
L 1.42213996 -2.09608996 1.42208996 -2.09601998 0 P 0 ;0
L 1.42208996 -2.09601998 1.42203996 -2.09598996 0 P 0 ;0
L 1.42203996 -2.09598996 1.42198996 -2.09595 0 P 0 ;0
L 1.42198996 -2.09595 1.42188996 -2.09588996 0 P 0 ;0
L 1.42188996 -2.09588996 1.42183002 -2.09586004 0 P 0 ;0
L 1.42183002 -2.09586004 1.42178002 -2.09585 0 P 0 ;0
L 1.42178002 -2.09585 1.42171998 -2.09583002 0 P 0 ;0
L 1.42171998 -2.09583002 1.42166004 -2.09581998 0 P 0 ;0
L 1.42166004 -2.09581998 1.42153996 -2.09581998 0 P 0 ;0
L 1.42153996 -2.09581998 1.41978002 -2.09591004 0 P 0 ;0
L 1.41978002 -2.09591004 1.41763996 -2.09615 0 P 0 ;0
L 1.41763996 -2.09615 1.41521998 -2.09658002 0 P 0 ;0
L 1.41521998 -2.09658002 1.4107 -2.09733002 0 P 0 ;0
L 1.4107 -2.09733002 1.40613002 -2.09775 0 P 0 ;0
L 1.40613002 -2.09775 1.40481004 -2.09778002 0 P 0 ;0
L 1.40481004 -2.09778002 1.40348996 -2.09771998 0 P 0 ;0
L 1.40348996 -2.09771998 1.40216998 -2.09756004 0 P 0 ;0
L 1.40216998 -2.09756004 1.40086998 -2.0973 0 P 0 ;0
L 1.40086998 -2.0973 1.39958996 -2.09695 0 P 0 ;0
L 1.39958996 -2.09695 1.39895 -2.09671998 0 P 0 ;0
L 1.39895 -2.09671998 1.39831998 -2.09643002 0 P 0 ;0
L 1.39831998 -2.09643002 1.39773002 -2.0961 0 P 0 ;0
L 1.39773002 -2.0961 1.39716004 -2.09571004 0 P 0 ;0
L 1.39716004 -2.09571004 1.39663002 -2.09528002 0 P 0 ;0
L 1.39663002 -2.09528002 1.39613996 -2.0948 0 P 0 ;0
L 1.39613996 -2.0948 1.39568002 -2.09428002 0 P 0 ;0
L 1.39568002 -2.09428002 1.39533996 -2.09381998 0 P 0 ;0
L 1.39533996 -2.09381998 1.39505 -2.09333996 0 P 0 ;0
L 1.39505 -2.09333996 1.39478996 -2.09281998 0 P 0 ;0
L 1.39478996 -2.09281998 1.39456998 -2.09228996 0 P 0 ;0
L 1.39456998 -2.09228996 1.3944 -2.09173996 0 P 0 ;0
L 1.3944 -2.09173996 1.39428002 -2.09118996 0 P 0 ;0
L 1.39428002 -2.09118996 1.39421004 -2.09061998 0 P 0 ;0
L 1.39421004 -2.09061998 1.39418002 -2.09003996 0 P 0 ;0
L 1.39418002 -2.09003996 1.39421004 -2.08943002 0 P 0 ;0
L 1.39421004 -2.08943002 1.39428002 -2.08883002 0 P 0 ;0
L 1.39428002 -2.08883002 1.39441004 -2.08823002 0 P 0 ;0
L 1.39441004 -2.08823002 1.3946 -2.08765 0 P 0 ;0
L 1.3946 -2.08765 1.39483002 -2.08708002 0 P 0 ;0
L 1.39483002 -2.08708002 1.39511004 -2.08653996 0 P 0 ;0
L 1.39511004 -2.08653996 1.39555 -2.08583996 0 P 0 ;0
L 1.39555 -2.08583996 1.39603996 -2.08518002 0 P 0 ;0
L 1.39603996 -2.08518002 1.39658002 -2.08456004 0 P 0 ;0
L 1.39658002 -2.08456004 1.39716004 -2.08396998 0 P 0 ;0
L 1.39716004 -2.08396998 1.39778002 -2.08343002 0 P 0 ;0
L 1.39778002 -2.08343002 1.39878996 -2.08266998 0 P 0 ;0
L 1.39878996 -2.08266998 1.39985 -2.08196998 0 P 0 ;0
L 1.39985 -2.08196998 1.40096004 -2.08135 0 P 0 ;0
L 1.40096004 -2.08135 1.40211998 -2.08081004 0 P 0 ;0
L 1.40211998 -2.08081004 1.40503002 -2.07971004 0 P 0 ;0
L 1.40503002 -2.07971004 1.40801998 -2.07881998 0 P 0 ;0
L 1.40801998 -2.07881998 1.41128996 -2.07796004 0 P 0 ;0
L 1.41128996 -2.07796004 1.41506004 -2.07691998 0 P 0 ;0
L 1.41506004 -2.07691998 1.41871998 -2.07585 0 P 0 ;0
L 1.41871998 -2.07585 1.42165 -2.07495 0 P 0 ;0
L 1.42165 -2.07495 1.42791998 -2.07295 0 P 0 ;0
L 1.42791998 -2.07295 1.42731998 -2.08241004 0 P 0 ;0
L 1.42731998 -2.08241004 1.42701004 -2.08708002 0 P 0 ;0
L 1.42701004 -2.08708002 1.42658002 -2.09353996 0 P 0 ;0
L 1.42658002 -2.09353996 1.4261 -2.10055 0 P 0 ;0
L 1.4261 -2.10055 1.42566998 -2.10706004 0 P 0 ;0
L 1.42566998 -2.10706004 1.42525 -2.11306004 0 P 0 ;0
L 1.42525 -2.11306004 1.42491998 -2.11851998 0 P 0 ;0
L 1.42491998 -2.11851998 1.42466004 -2.1231 0 P 0 ;0
L 1.42466004 -2.1231 1.42461004 -2.12471004 0 P 0 ;0
L 1.42461004 -2.12471004 1.4246 -2.12716004 0 P 0 ;0
L 1.4246 -2.12716004 1.47893002 -2.12716004 0 P 0 ;0
L 1.47893002 -2.12716004 1.47893002 -2.11358002 0 P 0 ;0
L 1.47893002 -2.11358002 1.47905 -2.10616998 0 P 0 ;0
L 1.47905 -2.10616998 1.47943996 -2.09385 0 P 0 ;0
L 1.47943996 -2.09385 1.48 -2.07968996 0 P 0 ;0
L 1.48 -2.07968996 1.48066004 -2.0655 0 P 0 ;0
L 1.48066004 -2.0655 1.4813 -2.05168996 0 P 0 ;0
L 1.4813 -2.05168996 1.48175 -2.03873996 0 P 0 ;0
L 1.48175 -2.03873996 1.48201998 -2.02785 0 P 0 ;0
L 1.48201998 -2.02785 1.48191998 -2.02286004 0 P 0 ;0
L 1.48191998 -2.02286004 1.48165 -2.01995 0 P 0 ;0
L 1.48165 -2.01995 1.48115 -2.01708002 0 P 0 ;0
L 1.48115 -2.01708002 1.48043996 -2.01425 0 P 0 ;0
L 1.48043996 -2.01425 1.47951004 -2.01146998 0 P 0 ;0
L 1.47951004 -2.01146998 1.47866998 -2.00946998 0 P 0 ;0
L 1.47866998 -2.00946998 1.47768002 -2.00753996 0 P 0 ;0
L 1.47768002 -2.00753996 1.47655 -2.00568002 0 P 0 ;0
L 1.47655 -2.00568002 1.47528002 -2.00391998 0 P 0 ;0
L 1.47528002 -2.00391998 1.47388002 -2.00225 0 P 0 ;0
L 1.47388002 -2.00225 1.47228996 -2.00063002 0 P 0 ;0
L 1.47228996 -2.00063002 1.4706 -1.99911998 0 P 0 ;0
L 1.4706 -1.99911998 1.4688 -1.99773002 0 P 0 ;0
L 1.4688 -1.99773002 1.46691004 -1.99648002 0 P 0 ;0
L 1.46691004 -1.99648002 1.46491998 -1.99535 0 P 0 ;0
L 1.46491998 -1.99535 1.46098996 -1.99351004 0 P 0 ;0
L 1.46098996 -1.99351004 1.45693002 -1.99196998 0 P 0 ;0
L 1.45693002 -1.99196998 1.45276004 -1.99076004 0 P 0 ;0
L 1.45276004 -1.99076004 1.44953996 -1.99006004 0 P 0 ;0
L 1.44953996 -1.99006004 1.44628996 -1.98956004 0 P 0 ;0
L 1.44628996 -1.98956004 1.44298002 -1.98923996 0 P 0 ;0
L 1.44298002 -1.98923996 1.42695 -1.98856998 0 P 0 ;0
L 1.42695 -1.98856998 1.41038996 -1.98865 0 P 0 ;0
L 1.41038996 -1.98865 1.4042 -1.98901004 0 P 0 ;0
L 1.4042 -1.98901004 1.39798996 -1.98971998 0 P 0 ;0
L 1.35778996 -2.11545 1.4153 -2.11545 0 P 0 ;0
L 1.35688996 -2.11445 1.41558996 -2.11445 0 P 0 ;0
L 1.35608002 -2.11345 1.41588002 -2.11345 0 P 0 ;0
L 1.35533002 -2.11245 1.41616998 -2.11245 0 P 0 ;0
L 1.35463996 -2.11145 1.41646004 -2.11145 0 P 0 ;0
L 1.35401004 -2.11045 1.41675 -2.11045 0 P 0 ;0
L 1.35341004 -2.10945 1.41703996 -2.10945 0 P 0 ;0
L 1.3529 -2.10845 1.41733002 -2.10845 0 P 0 ;0
L 1.35238002 -2.10745 1.41761998 -2.10745 0 P 0 ;0
L 1.35195 -2.10645 1.41788002 -2.10645 0 P 0 ;0
L 1.35155 -2.10545 1.41816004 -2.10545 0 P 0 ;0
L 1.3512 -2.10445 1.41841998 -2.10445 0 P 0 ;0
L 1.35091004 -2.10345 1.41868996 -2.10345 0 P 0 ;0
L 1.35066004 -2.10245 1.41896004 -2.10245 0 P 0 ;0
L 1.35046998 -2.10145 1.41923002 -2.10145 0 P 0 ;0
L 1.35033996 -2.10045 1.41948996 -2.10045 0 P 0 ;0
L 1.35021998 -2.09945 1.40141004 -2.09945 0 P 0 ;0
L 1.35016004 -2.09845 1.39791004 -2.09845 0 P 0 ;0
L 1.3501 -2.09745 1.39616004 -2.09745 0 P 0 ;0
L 1.35008002 -2.09645 1.39496004 -2.09645 0 P 0 ;0
L 1.35006998 -2.09545 1.39406004 -2.09545 0 P 0 ;0
L 1.35005 -2.09445 1.39338002 -2.09445 0 P 0 ;0
L 1.35003996 -2.09345 1.39288002 -2.09345 0 P 0 ;0
L 1.35001998 -2.09245 1.39253002 -2.09245 0 P 0 ;0
L 1.35001004 -2.09145 1.3923 -2.09145 0 P 0 ;0
L 1.35001998 -2.09045 1.3922 -2.09045 0 P 0 ;0
L 1.35003002 -2.08945 1.3922 -2.08945 0 P 0 ;0
L 1.35005 -2.08845 1.39231998 -2.08845 0 P 0 ;0
L 1.35006998 -2.08745 1.39256004 -2.08745 0 P 0 ;0
L 1.35008002 -2.08645 1.39293002 -2.08645 0 P 0 ;0
L 1.3501 -2.08545 1.39343002 -2.08545 0 P 0 ;0
L 1.35011004 -2.08445 1.39408996 -2.08445 0 P 0 ;0
L 1.39438002 -2.12845 1.3883 -2.12836004 0 P 0 ;0
L 1.3883 -2.12836004 1.38426998 -2.128 0 P 0 ;0
L 1.38426998 -2.128 1.38028002 -2.12733002 0 P 0 ;0
L 1.38028002 -2.12733002 1.37635 -2.12636004 0 P 0 ;0
L 1.37635 -2.12636004 1.37248996 -2.12508002 0 P 0 ;0
L 1.37248996 -2.12508002 1.36983996 -2.12398002 0 P 0 ;0
L 1.36983996 -2.12398002 1.36728996 -2.1227 0 P 0 ;0
L 1.36728996 -2.1227 1.36481998 -2.12123996 0 P 0 ;0
L 1.36481998 -2.12123996 1.36246004 -2.11961004 0 P 0 ;0
L 1.36246004 -2.11961004 1.36023002 -2.11781998 0 P 0 ;0
L 1.36023002 -2.11781998 1.35828996 -2.116 0 P 0 ;0
L 1.35828996 -2.116 1.35651998 -2.11403002 0 P 0 ;0
L 1.35651998 -2.11403002 1.35493002 -2.11191004 0 P 0 ;0
L 1.35493002 -2.11191004 1.35353002 -2.10966998 0 P 0 ;0
L 1.35353002 -2.10966998 1.35231004 -2.10731004 0 P 0 ;0
L 1.35231004 -2.10731004 1.35166998 -2.10576998 0 P 0 ;0
L 1.35166998 -2.10576998 1.35111004 -2.1042 0 P 0 ;0
L 1.35111004 -2.1042 1.35071998 -2.10276004 0 P 0 ;0
L 1.35071998 -2.10276004 1.35045 -2.1013 0 P 0 ;0
L 1.35045 -2.1013 1.35021998 -2.09943002 0 P 0 ;0
L 1.35021998 -2.09943002 1.3501 -2.09753002 0 P 0 ;0
L 1.3501 -2.09753002 1.35001004 -2.09128002 0 P 0 ;0
L 1.35001004 -2.09128002 1.35011998 -2.0844 0 P 0 ;0
L 1.35011998 -2.0844 1.35023996 -2.08258996 0 P 0 ;0
L 1.35023996 -2.08258996 1.3505 -2.08083996 0 P 0 ;0
L 1.3505 -2.08083996 1.35071998 -2.07985 0 P 0 ;0
L 1.35071998 -2.07985 1.35101004 -2.07888002 0 P 0 ;0
L 1.35101004 -2.07888002 1.35136004 -2.07793002 0 P 0 ;0
L 1.35136004 -2.07793002 1.35335 -2.07351998 0 P 0 ;0
L 1.35335 -2.07351998 1.35491998 -2.07065 0 P 0 ;0
L 1.35491998 -2.07065 1.35683002 -2.0677 0 P 0 ;0
L 1.35683002 -2.0677 1.35876998 -2.06511004 0 P 0 ;0
L 1.35876998 -2.06511004 1.35948996 -2.0643 0 P 0 ;0
L 1.35948996 -2.0643 1.36026998 -2.06356004 0 P 0 ;0
L 1.36026998 -2.06356004 1.3624 -2.06181998 0 P 0 ;0
L 1.3624 -2.06181998 1.36465 -2.06023996 0 P 0 ;0
L 1.36465 -2.06023996 1.36701004 -2.05883002 0 P 0 ;0
L 1.36701004 -2.05883002 1.37173002 -2.05641004 0 P 0 ;0
L 1.37173002 -2.05641004 1.37656004 -2.05426998 0 P 0 ;0
L 1.37656004 -2.05426998 1.38243002 -2.05203996 0 P 0 ;0
L 1.38243002 -2.05203996 1.38836004 -2.0501 0 P 0 ;0
L 1.38836004 -2.0501 1.4023 -2.04645 0 P 0 ;0
L 1.4023 -2.04645 1.41148996 -2.044 0 P 0 ;0
L 1.41148996 -2.044 1.42016998 -2.04095 0 P 0 ;0
L 1.42016998 -2.04095 1.42016998 -2.04093996 0 P 0 ;0
L 1.42016998 -2.04093996 1.42021004 -2.04093996 0 P 0 ;0
L 1.42021004 -2.04093996 1.42023996 -2.04093002 0 P 0 ;0
L 1.42023996 -2.04093002 1.42746998 -2.03776004 0 P 0 ;0
L 1.42746998 -2.03776004 1.42753002 -2.03773002 0 P 0 ;0
L 1.42753002 -2.03773002 1.42796998 -2.03748996 0 P 0 ;0
L 1.42796998 -2.03748996 1.42846004 -2.03718996 0 P 0 ;0
L 1.42846004 -2.03718996 1.42891998 -2.03683996 0 P 0 ;0
L 1.42891998 -2.03683996 1.42935 -2.03646004 0 P 0 ;0
L 1.42935 -2.03646004 1.42975 -2.03603996 0 P 0 ;0
L 1.42975 -2.03603996 1.43011004 -2.0356 0 P 0 ;0
L 1.43011004 -2.0356 1.43016004 -2.03553002 0 P 0 ;0
L 1.43016004 -2.03553002 1.4299 -2.03535 0 P 0 ;0
L 1.4299 -2.03535 1.43028002 -2.03535 0 P 0 ;0
L 1.43028002 -2.03535 1.43043996 -2.03513002 0 P 0 ;0
L 1.43043996 -2.03513002 1.43048002 -2.03506004 0 P 0 ;0
L 1.43048002 -2.03506004 1.43041998 -2.03501998 0 P 0 ;0
L 1.43041998 -2.03501998 1.4305 -2.03501998 0 P 0 ;0
L 1.4305 -2.03501998 1.43073002 -2.03463002 0 P 0 ;0
L 1.43073002 -2.03463002 1.43096004 -2.03415 0 P 0 ;0
L 1.43096004 -2.03415 1.43115 -2.03365 0 P 0 ;0
L 1.43115 -2.03365 1.4313 -2.03313002 0 P 0 ;0
L 1.4313 -2.03313002 1.4314 -2.03261004 0 P 0 ;0
L 1.4314 -2.03261004 1.43146004 -2.03208002 0 P 0 ;0
L 1.43146004 -2.03208002 1.43146998 -2.03155 0 P 0 ;0
L 1.43146998 -2.03155 1.43143996 -2.03101004 0 P 0 ;0
L 1.43143996 -2.03101004 1.43143002 -2.03093002 0 P 0 ;0
L 1.43143002 -2.03093002 1.43136004 -2.03048996 0 P 0 ;0
L 1.43136004 -2.03048996 1.43125 -2.02996998 0 P 0 ;0
L 1.43125 -2.02996998 1.43108002 -2.02946004 0 P 0 ;0
L 1.43108002 -2.02946004 1.43086998 -2.02896004 0 P 0 ;0
L 1.43086998 -2.02896004 1.43063002 -2.02848996 0 P 0 ;0
L 1.43063002 -2.02848996 1.43033996 -2.02803996 0 P 0 ;0
L 1.43033996 -2.02803996 1.43001998 -2.02761004 0 P 0 ;0
L 1.43001998 -2.02761004 1.42966004 -2.02721004 0 P 0 ;0
L 1.42966004 -2.02721004 1.42928002 -2.02685 0 P 0 ;0
L 1.42928002 -2.02685 1.42886004 -2.02651998 0 P 0 ;0
L 1.42886004 -2.02651998 1.42841998 -2.02623002 0 P 0 ;0
L 1.42841998 -2.02623002 1.42795 -2.02596998 0 P 0 ;0
L 1.42795 -2.02596998 1.42746004 -2.02575 0 P 0 ;0
L 1.42746004 -2.02575 1.42583002 -2.02518002 0 P 0 ;0
L 1.42583002 -2.02518002 1.42416004 -2.02476004 0 P 0 ;0
L 1.42416004 -2.02476004 1.42245 -2.02448002 0 P 0 ;0
L 1.42245 -2.02448002 1.42075 -2.02435 0 P 0 ;0
L 1.42075 -2.02435 1.41565 -2.02428002 0 P 0 ;0
L 1.41565 -2.02428002 1.4156 -2.02428002 0 P 0 ;0
L 1.4156 -2.02428002 1.41055 -2.02445 0 P 0 ;0
L 1.41055 -2.02445 1.41048002 -2.02445 0 P 0 ;0
L 1.41048002 -2.02445 1.40128996 -2.02533996 0 P 0 ;0
L 1.40128996 -2.02533996 1.39208996 -2.02696998 0 P 0 ;0
L 1.39208996 -2.02696998 1.38288002 -2.02936004 0 P 0 ;0
L 1.38288002 -2.02936004 1.37363002 -2.03251998 0 P 0 ;0
L 1.37363002 -2.03251998 1.37076998 -2.03356004 0 P 0 ;0
L 1.37076998 -2.03356004 1.36865 -2.03426998 0 P 0 ;0
L 1.36865 -2.03426998 1.36906004 -2.03066998 0 P 0 ;0
L 1.36906004 -2.03066998 1.36988996 -2.02383996 0 P 0 ;0
L 1.36988996 -2.02383996 1.37095 -2.01581004 0 P 0 ;0
L 1.37095 -2.01581004 1.37358996 -1.99631998 0 P 0 ;0
L 1.37358996 -1.99631998 1.37988002 -1.99491998 0 P 0 ;0
L 1.37988002 -1.99491998 1.38353996 -1.99416998 0 P 0 ;0
L 1.38353996 -1.99416998 1.38841998 -1.99326998 0 P 0 ;0
L 1.38841998 -1.99326998 1.39358002 -1.9924 0 P 0 ;0
L 1.39358002 -1.9924 1.39825 -1.9917 0 P 0 ;0
L 1.39825 -1.9917 1.40436998 -1.991 0 P 0 ;0
L 1.40436998 -1.991 1.41045 -1.99065 0 P 0 ;0
L 1.41045 -1.99065 1.42691004 -1.99056998 0 P 0 ;0
L 1.42691004 -1.99056998 1.44283996 -1.99123996 0 P 0 ;0
L 1.44283996 -1.99123996 1.44603996 -1.99153996 0 P 0 ;0
L 1.44603996 -1.99153996 1.44918002 -1.99203002 0 P 0 ;0
L 1.44918002 -1.99203002 1.45226004 -1.9927 0 P 0 ;0
L 1.45226004 -1.9927 1.4563 -1.99386998 0 P 0 ;0
L 1.4563 -1.99386998 1.46021004 -1.99535 0 P 0 ;0
L 1.46021004 -1.99535 1.464 -1.99713002 0 P 0 ;0
L 1.464 -1.99713002 1.46586004 -1.99818996 0 P 0 ;0
L 1.46586004 -1.99818996 1.46763996 -1.99936004 0 P 0 ;0
L 1.46763996 -1.99936004 1.46931998 -2.00066004 0 P 0 ;0
L 1.46931998 -2.00066004 1.47091004 -2.00206998 0 P 0 ;0
L 1.47091004 -2.00206998 1.47238996 -2.00358996 0 P 0 ;0
L 1.47238996 -2.00358996 1.4737 -2.00515 0 P 0 ;0
L 1.4737 -2.00515 1.47488002 -2.00678996 0 P 0 ;0
L 1.47488002 -2.00678996 1.47593996 -2.00851004 0 P 0 ;0
L 1.47593996 -2.00851004 1.47686004 -2.01031004 0 P 0 ;0
L 1.47686004 -2.01031004 1.47763996 -2.01216998 0 P 0 ;0
L 1.47763996 -2.01216998 1.47851998 -2.01481004 0 P 0 ;0
L 1.47851998 -2.01481004 1.47918996 -2.01748996 0 P 0 ;0
L 1.47918996 -2.01748996 1.47966004 -2.02021998 0 P 0 ;0
L 1.47966004 -2.02021998 1.47993002 -2.02296998 0 P 0 ;0
L 1.47993002 -2.02296998 1.48001998 -2.02783996 0 P 0 ;0
L 1.48001998 -2.02783996 1.47975 -2.03868996 0 P 0 ;0
L 1.47975 -2.03868996 1.4793 -2.05161004 0 P 0 ;0
L 1.4793 -2.05161004 1.47866004 -2.06543002 0 P 0 ;0
L 1.47866004 -2.06543002 1.47801004 -2.07961004 0 P 0 ;0
L 1.47801004 -2.07961004 1.47743996 -2.09378996 0 P 0 ;0
L 1.47743996 -2.09378996 1.47705 -2.10613002 0 P 0 ;0
L 1.47705 -2.10613002 1.47693002 -2.11356004 0 P 0 ;0
L 1.47693002 -2.11356004 1.47693002 -2.12516004 0 P 0 ;0
L 1.47693002 -2.12516004 1.42661004 -2.12516004 0 P 0 ;0
L 1.42661004 -2.12516004 1.42661004 -2.12473996 0 P 0 ;0
L 1.42661004 -2.12473996 1.42666004 -2.12318002 0 P 0 ;0
L 1.42666004 -2.12318002 1.42691004 -2.11863996 0 P 0 ;0
L 1.42691004 -2.11863996 1.42725 -2.1132 0 P 0 ;0
L 1.42725 -2.1132 1.42766004 -2.1072 0 P 0 ;0
L 1.42766004 -2.1072 1.42766004 -2.10718996 0 P 0 ;0
L 1.42766004 -2.10718996 1.4281 -2.10068996 0 P 0 ;0
L 1.4281 -2.10068996 1.42858002 -2.09368002 0 P 0 ;0
L 1.42858002 -2.09368002 1.42901004 -2.08721004 0 P 0 ;0
L 1.42901004 -2.08721004 1.42901004 -2.0872 0 P 0 ;0
L 1.42901004 -2.0872 1.42931004 -2.08256004 0 P 0 ;0
L 1.42931004 -2.08256004 1.42991998 -2.07308002 0 P 0 ;0
L 1.42991998 -2.07308002 1.42916004 -2.07136998 0 P 0 ;0
L 1.42916004 -2.07136998 1.42731998 -2.07105 0 P 0 ;0
L 1.42731998 -2.07105 1.42105 -2.07303996 0 P 0 ;0
L 1.42105 -2.07303996 1.41815 -2.07393002 0 P 0 ;0
L 1.41815 -2.07393002 1.41451004 -2.075 0 P 0 ;0
L 1.41451004 -2.075 1.41076004 -2.07603002 0 P 0 ;0
L 1.41076004 -2.07603002 1.40748002 -2.0769 0 P 0 ;0
L 1.40748002 -2.0769 1.40438996 -2.07781004 0 P 0 ;0
L 1.40438996 -2.07781004 1.40431998 -2.07783996 0 P 0 ;0
L 1.40431998 -2.07783996 1.40133996 -2.07896998 0 P 0 ;0
L 1.40133996 -2.07896998 1.40005 -2.07956998 0 P 0 ;0
L 1.40005 -2.07956998 1.39881998 -2.08026004 0 P 0 ;0
L 1.39881998 -2.08026004 1.39763996 -2.08103002 0 P 0 ;0
L 1.39763996 -2.08103002 1.39651998 -2.08188002 0 P 0 ;0
L 1.39651998 -2.08188002 1.39578996 -2.08251004 0 P 0 ;0
L 1.39578996 -2.08251004 1.39573996 -2.08256004 0 P 0 ;0
L 1.39573996 -2.08256004 1.3951 -2.08318996 0 P 0 ;0
L 1.3951 -2.08318996 1.39446998 -2.08393002 0 P 0 ;0
L 1.39446998 -2.08393002 1.3939 -2.08471004 0 P 0 ;0
L 1.3939 -2.08471004 1.39336998 -2.08553996 0 P 0 ;0
L 1.39336998 -2.08553996 1.39301004 -2.08623996 0 P 0 ;0
L 1.39301004 -2.08623996 1.39271004 -2.08696998 0 P 0 ;0
L 1.39271004 -2.08696998 1.39248002 -2.08771998 0 P 0 ;0
L 1.39248002 -2.08771998 1.39231004 -2.08848996 0 P 0 ;0
L 1.39231004 -2.08848996 1.39221004 -2.08926004 0 P 0 ;0
L 1.39221004 -2.08926004 1.39218002 -2.09003996 0 P 0 ;0
L 1.39218002 -2.09003996 1.39221004 -2.0908 0 P 0 ;0
L 1.39221004 -2.0908 1.39231004 -2.09153002 0 P 0 ;0
L 1.39231004 -2.09153002 1.39246998 -2.09226004 0 P 0 ;0
L 1.39246998 -2.09226004 1.39268996 -2.09296998 0 P 0 ;0
L 1.39268996 -2.09296998 1.39296004 -2.09365 0 P 0 ;0
L 1.39296004 -2.09365 1.3933 -2.09431004 0 P 0 ;0
L 1.3933 -2.09431004 1.39368996 -2.09493996 0 P 0 ;0
L 1.39368996 -2.09493996 1.39411998 -2.09553996 0 P 0 ;0
L 1.39411998 -2.09553996 1.39468996 -2.09618002 0 P 0 ;0
L 1.39468996 -2.09618002 1.3953 -2.09678002 0 P 0 ;0
L 1.3953 -2.09678002 1.39596004 -2.09731998 0 P 0 ;0
L 1.39596004 -2.09731998 1.39666998 -2.0978 0 P 0 ;0
L 1.39666998 -2.0978 1.39673996 -2.09783996 0 P 0 ;0
L 1.39673996 -2.09783996 1.39741004 -2.09821998 0 P 0 ;0
L 1.39741004 -2.09821998 1.39748996 -2.09825 0 P 0 ;0
L 1.39748996 -2.09825 1.39818996 -2.09856998 0 P 0 ;0
L 1.39818996 -2.09856998 1.39898996 -2.09886004 0 P 0 ;0
L 1.39898996 -2.09886004 1.39906998 -2.09888002 0 P 0 ;0
L 1.39906998 -2.09888002 1.40043996 -2.09888002 0 P 0 ;0
L 1.40043996 -2.09888002 1.40033996 -2.09923002 0 P 0 ;0
L 1.40033996 -2.09923002 1.40041998 -2.09925 0 P 0 ;0
L 1.40041998 -2.09925 1.40186004 -2.09953002 0 P 0 ;0
L 1.40186004 -2.09953002 1.40331004 -2.09971004 0 P 0 ;0
L 1.40331004 -2.09971004 1.40478002 -2.09978002 0 P 0 ;0
L 1.40478002 -2.09978002 1.40625 -2.09975 0 P 0 ;0
L 1.40625 -2.09975 1.41096004 -2.09931004 0 P 0 ;0
L 1.41096004 -2.09931004 1.41556998 -2.09855 0 P 0 ;0
L 1.41556998 -2.09855 1.41791998 -2.09813002 0 P 0 ;0
L 1.41791998 -2.09813002 1.41995 -2.09791004 0 P 0 ;0
L 1.41995 -2.09791004 1.4201 -2.0979 0 P 0 ;0
L 1.4201 -2.0979 1.41941004 -2.10078002 0 P 0 ;0
L 1.41941004 -2.10078002 1.41761004 -2.10745 0 P 0 ;0
L 1.41761004 -2.10745 1.41391004 -2.12025 0 P 0 ;0
L 1.41391004 -2.12025 1.41215 -2.12626998 0 P 0 ;0
L 1.41215 -2.12626998 1.40655 -2.12725 0 P 0 ;0
L 1.40655 -2.12725 1.40046004 -2.12808002 0 P 0 ;0
L 1.40046004 -2.12808002 1.39438002 -2.12845 0 P 0 ;0
L 1.15303002 -2.08283002 1.20788996 -2.08283002 0 P 0 ;0
L 1.15398996 -2.08183002 1.20795 -2.08183002 0 P 0 ;0
L 1.15483002 -2.08083002 1.208 -2.08083002 0 P 0 ;0
L 1.15555 -2.07983002 1.20805 -2.07983002 0 P 0 ;0
L 1.15621998 -2.07883002 1.2081 -2.07883002 0 P 0 ;0
L 1.15681998 -2.07783002 1.20816004 -2.07783002 0 P 0 ;0
L 1.15733002 -2.07683002 1.20821004 -2.07683002 0 P 0 ;0
L 1.15778996 -2.07583002 1.20826004 -2.07583002 0 P 0 ;0
L 1.15818002 -2.07483002 1.20831004 -2.07483002 0 P 0 ;0
L 1.15853996 -2.07383002 1.20836998 -2.07383002 0 P 0 ;0
L 1.15881998 -2.07283002 1.20841998 -2.07283002 0 P 0 ;0
L 1.1591 -2.07183002 1.20846998 -2.07183002 0 P 0 ;0
L 1.15938002 -2.07083002 1.20853002 -2.07083002 0 P 0 ;0
L 1.1596 -2.06983002 1.20858002 -2.06983002 0 P 0 ;0
L 1.15981004 -2.06883002 1.20863996 -2.06883002 0 P 0 ;0
L 1.16001004 -2.06783002 1.20868996 -2.06783002 0 P 0 ;0
L 1.1602 -2.06683002 1.20875 -2.06683002 0 P 0 ;0
L 1.16033996 -2.06583002 1.2088 -2.06583002 0 P 0 ;0
L 1.16048996 -2.06483002 1.20886004 -2.06483002 0 P 0 ;0
L 1.16063996 -2.06383002 1.20891998 -2.06383002 0 P 0 ;0
L 1.16078002 -2.06283002 1.20896998 -2.06283002 0 P 0 ;0
L 1.16088996 -2.06183002 1.20903002 -2.06183002 0 P 0 ;0
L 1.16098996 -2.06083002 1.20908002 -2.06083002 0 P 0 ;0
L 1.16108996 -2.05983002 1.20913996 -2.05983002 0 P 0 ;0
L 1.16118002 -2.05883002 1.20918996 -2.05883002 0 P 0 ;0
L 1.16128002 -2.05783002 1.20925 -2.05783002 0 P 0 ;0
L 1.16133996 -2.05683002 1.2093 -2.05683002 0 P 0 ;0
L 1.1614 -2.05583002 1.20936004 -2.05583002 0 P 0 ;0
L 1.16146004 -2.05483002 1.20941004 -2.05483002 0 P 0 ;0
L 1.16151998 -2.05383002 1.20946998 -2.05383002 0 P 0 ;0
L 1.16158002 -2.05283002 1.20951998 -2.05283002 0 P 0 ;0
L 1.16163996 -2.05183002 1.20958002 -2.05183002 0 P 0 ;0
L 1.1617 -2.05083002 1.20963996 -2.05083002 0 P 0 ;0
L 1.16175 -2.04983002 1.2097 -2.04983002 0 P 0 ;0
L 1.16181004 -2.04883002 1.20975 -2.04883002 0 P 0 ;0
L 1.16186998 -2.04783002 1.20981004 -2.04783002 0 P 0 ;0
L 1.16193002 -2.04683002 1.20986998 -2.04683002 0 P 0 ;0
L 1.16198996 -2.04583002 1.20993002 -2.04583002 0 P 0 ;0
L 1.16205 -2.04483002 1.20998996 -2.04483002 0 P 0 ;0
L 1.16211004 -2.04383002 1.21005 -2.04383002 0 P 0 ;0
L 1.16215 -2.04283002 1.2101 -2.04283002 0 P 0 ;0
L 1.1622 -2.04183002 1.21016004 -2.04183002 0 P 0 ;0
L 1.16225 -2.04083002 1.21021998 -2.04083002 0 P 0 ;0
L 1.16228996 -2.03983002 1.21028002 -2.03983002 0 P 0 ;0
L 1.16233996 -2.03883002 1.21033996 -2.03883002 0 P 0 ;0
L 1.16238002 -2.03783002 1.2104 -2.03783002 0 P 0 ;0
L 1.16243002 -2.03683002 1.21046004 -2.03683002 0 P 0 ;0
L 1.16246998 -2.03583002 1.21051004 -2.03583002 0 P 0 ;0
L 1.16251998 -2.03483002 1.21056998 -2.03483002 0 P 0 ;0
L 1.16256998 -2.03383002 1.21063996 -2.03383002 0 P 0 ;0
L 1.16261004 -2.03283002 1.2107 -2.03283002 0 P 0 ;0
L 1.16266004 -2.03183002 1.21076004 -2.03183002 0 P 0 ;0
L 1.1627 -2.03083002 1.21083002 -2.03083002 0 P 0 ;0
L 1.16015 -1.97631004 1.17066004 -1.97631004 0 P 0 ;0
L 1.15961998 -1.97531004 1.17026004 -1.97531004 0 P 0 ;0
L 1.1591 -1.97431004 1.16986998 -1.97431004 0 P 0 ;0
L 1.15856998 -1.97331004 1.16946998 -1.97331004 0 P 0 ;0
L 1.15803996 -1.97231004 1.16903002 -1.97231004 0 P 0 ;0
L 1.15746998 -1.97131004 1.16858996 -1.97131004 0 P 0 ;0
L 1.1569 -1.97031004 1.16815 -1.97031004 0 P 0 ;0
L 1.15631998 -1.96931004 1.16771004 -1.96931004 0 P 0 ;0
L 1.15573996 -1.96831004 1.16726998 -1.96831004 0 P 0 ;0
L 1.15516004 -1.96731004 1.16681998 -1.96731004 0 P 0 ;0
L 1.15458996 -1.96631004 1.16638002 -1.96631004 0 P 0 ;0
L 1.15398002 -1.96531004 1.16593996 -1.96531004 0 P 0 ;0
L 1.1533 -1.96431004 1.16548996 -1.96431004 0 P 0 ;0
L 1.15261998 -1.96331004 1.16503002 -1.96331004 0 P 0 ;0
L 1.15193996 -1.96231004 1.16448002 -1.96231004 0 P 0 ;0
L 1.15126004 -1.96131004 1.16393002 -1.96131004 0 P 0 ;0
L 1.15058002 -1.96031004 1.16338002 -1.96031004 0 P 0 ;0
L 1.1499 -1.95931004 1.16283002 -1.95931004 0 P 0 ;0
L 1.1491 -1.95831004 1.16228996 -1.95831004 0 P 0 ;0
L 1.14831004 -1.95731004 1.16173996 -1.95731004 0 P 0 ;0
L 1.14751004 -1.95631004 1.16118996 -1.95631004 0 P 0 ;0
L 1.14671004 -1.95531004 1.16063996 -1.95531004 0 P 0 ;0
L 1.14591998 -1.95431004 1.16008996 -1.95431004 0 P 0 ;0
L 1.14511998 -1.95331004 1.15943996 -1.95331004 0 P 0 ;0
L 1.1442 -1.95231004 1.15878002 -1.95231004 0 P 0 ;0
L 1.14326998 -1.95131004 1.15811004 -1.95131004 0 P 0 ;0
L 1.14233996 -1.95031004 1.15745 -1.95031004 0 P 0 ;0
L 1.14141004 -1.94931004 1.15678002 -1.94931004 0 P 0 ;0
L 1.14048996 -1.94831004 1.15611998 -1.94831004 0 P 0 ;0
L 1.1395 -1.94731004 1.15545 -1.94731004 0 P 0 ;0
L 1.13843002 -1.94631004 1.15478996 -1.94631004 0 P 0 ;0
L 1.13736004 -1.94531004 1.15411998 -1.94531004 0 P 0 ;0
L 1.13628996 -1.94431004 1.15333002 -1.94431004 0 P 0 ;0
L 1.13521004 -1.94331004 1.15253002 -1.94331004 0 P 0 ;0
L 1.13413996 -1.94231004 1.15173996 -1.94231004 0 P 0 ;0
L 1.13306998 -1.94131004 1.15093996 -1.94131004 0 P 0 ;0
L 1.132 -1.94031004 1.15013996 -1.94031004 0 P 0 ;0
L 1.13081004 -1.93931004 1.14935 -1.93931004 0 P 0 ;0
L 1.12958002 -1.93831004 1.14855 -1.93831004 0 P 0 ;0
L 1.12833996 -1.93731004 1.14775 -1.93731004 0 P 0 ;0
L 1.1271 -1.93631004 1.14688996 -1.93631004 0 P 0 ;0
L 1.12586004 -1.93531004 1.14593996 -1.93531004 0 P 0 ;0
L 1.12461998 -1.93431004 1.14498996 -1.93431004 0 P 0 ;0
L 1.12338002 -1.93331004 1.14405 -1.93331004 0 P 0 ;0
L 1.12203002 -1.93231004 1.1431 -1.93231004 0 P 0 ;0
L 1.1206 -1.93131004 1.14216004 -1.93131004 0 P 0 ;0
L 1.11916004 -1.93031004 1.14121004 -1.93031004 0 P 0 ;0
L 1.11771998 -1.92931004 1.14026998 -1.92931004 0 P 0 ;0
L 1.11628996 -1.92831004 1.13931998 -1.92831004 0 P 0 ;0
L 1.11483996 -1.92731004 1.13838002 -1.92731004 0 P 0 ;0
L 1.11338996 -1.92631004 1.13743002 -1.92631004 0 P 0 ;0
L 1.11171998 -1.92531004 1.13648996 -1.92531004 0 P 0 ;0
L 1.11005 -1.92431004 1.13538002 -1.92431004 0 P 0 ;0
L 1.10838002 -1.92331004 1.13426998 -1.92331004 0 P 0 ;0
L 1.1067 -1.92231004 1.13315 -1.92231004 0 P 0 ;0
L 1.10503002 -1.92131004 1.13203002 -1.92131004 0 P 0 ;0
L 1.10336004 -1.92031004 1.13091998 -1.92031004 0 P 0 ;0
L 1.1015 -1.91931004 1.1298 -1.91931004 0 P 0 ;0
L 1.09955 -1.91831004 1.12868002 -1.91831004 0 P 0 ;0
L 1.16275 -2.02983002 1.21088996 -2.02983002 0 P 0 ;0
L 1.16278996 -2.02883002 1.21095 -2.02883002 0 P 0 ;0
L 1.16283996 -2.02783002 1.21101004 -2.02783002 0 P 0 ;0
L 1.16226998 -2.02683002 1.21108002 -2.02683002 0 P 0 ;0
L 1.16153996 -2.02583002 1.21113996 -2.02583002 0 P 0 ;0
L 1.15846004 -2.02483002 1.2112 -2.02483002 0 P 0 ;0
L 1.10036004 -2.00383002 1.21255 -2.00383002 0 P 0 ;0
L 1.10226004 -2.00283002 1.2126 -2.00283002 0 P 0 ;0
L 1.10433996 -2.00183002 1.21266998 -2.00183002 0 P 0 ;0
L 1.1065 -2.00083002 1.21273002 -2.00083002 0 P 0 ;0
L 1.10886998 -1.99983002 1.21278996 -1.99983002 0 P 0 ;0
L 1.11138002 -1.99883002 1.21285 -1.99883002 0 P 0 ;0
L 1.11436998 -1.99783002 1.21288002 -1.99783002 0 P 0 ;0
L 1.11748996 -1.99683002 1.21255 -1.99683002 0 P 0 ;0
L 1.12061998 -1.99583002 1.2089 -1.99583002 0 P 0 ;0
L 1.12433996 -1.99483002 1.2036 -1.99483002 0 P 0 ;0
L 1.12863996 -1.99383002 1.19728002 -1.99383002 0 P 0 ;0
L 1.13295 -1.99283002 1.19096998 -1.99283002 0 P 0 ;0
L 1.13985 -1.99183002 1.18111998 -1.99183002 0 P 0 ;0
L 1.14948002 -1.99083002 1.1651 -1.99083002 0 P 0 ;0
L 1.24218002 -2.08316004 1.29143996 -2.08316004 0 P 0 ;0
L 1.24223002 -2.08216004 1.29151004 -2.08216004 0 P 0 ;0
L 1.24228002 -2.08116004 1.29158996 -2.08116004 0 P 0 ;0
L 1.24233996 -2.08016004 1.29166004 -2.08016004 0 P 0 ;0
L 1.24238996 -2.07916004 1.29173002 -2.07916004 0 P 0 ;0
L 1.24245 -2.07816004 1.29181004 -2.07816004 0 P 0 ;0
L 1.2425 -2.07716004 1.29188002 -2.07716004 0 P 0 ;0
L 1.24256004 -2.07616004 1.29195 -2.07616004 0 P 0 ;0
L 1.24261004 -2.07516004 1.29203002 -2.07516004 0 P 0 ;0
L 1.24266998 -2.07416004 1.2921 -2.07416004 0 P 0 ;0
L 1.24271998 -2.07316004 1.29216998 -2.07316004 0 P 0 ;0
L 1.24278002 -2.07216004 1.29223996 -2.07216004 0 P 0 ;0
L 1.24283002 -2.07116004 1.29231998 -2.07116004 0 P 0 ;0
L 1.24288002 -2.07016004 1.29238996 -2.07016004 0 P 0 ;0
L 1.24293002 -2.06916004 1.29246004 -2.06916004 0 P 0 ;0
L 1.24296998 -2.06816004 1.29253002 -2.06816004 0 P 0 ;0
L 1.24301998 -2.06716004 1.29261004 -2.06716004 0 P 0 ;0
L 1.24306004 -2.06616004 1.2927 -2.06616004 0 P 0 ;0
L 1.24311004 -2.06516004 1.29281004 -2.06516004 0 P 0 ;0
L 1.24315 -2.06416004 1.29291998 -2.06416004 0 P 0 ;0
L 1.2432 -2.06316004 1.29303002 -2.06316004 0 P 0 ;0
L 1.24323996 -2.06216004 1.29315 -2.06216004 0 P 0 ;0
L 1.24328996 -2.06116004 1.29331998 -2.06116004 0 P 0 ;0
L 1.24333002 -2.06016004 1.2935 -2.06016004 0 P 0 ;0
L 1.24338002 -2.05916004 1.29366998 -2.05916004 0 P 0 ;0
L 1.24341998 -2.05816004 1.29385 -2.05816004 0 P 0 ;0
L 1.24346998 -2.05716004 1.29408996 -2.05716004 0 P 0 ;0
L 1.24351004 -2.05616004 1.29433996 -2.05616004 0 P 0 ;0
L 1.24355 -2.05516004 1.29458996 -2.05516004 0 P 0 ;0
L 1.2436 -2.05416004 1.29485 -2.05416004 0 P 0 ;0
L 1.24363996 -2.05316004 1.29516998 -2.05316004 0 P 0 ;0
L 1.24368996 -2.05216004 1.29551998 -2.05216004 0 P 0 ;0
L 1.24373002 -2.05116004 1.29586004 -2.05116004 0 P 0 ;0
L 1.24378002 -2.05016004 1.29621004 -2.05016004 0 P 0 ;0
L 1.24383002 -2.04916004 1.29663996 -2.04916004 0 P 0 ;0
L 1.24386998 -2.04816004 1.29708002 -2.04816004 0 P 0 ;0
L 1.24391004 -2.04716004 1.29753002 -2.04716004 0 P 0 ;0
L 1.24396004 -2.04616004 1.29796998 -2.04616004 0 P 0 ;0
L 1.244 -2.04516004 1.29851004 -2.04516004 0 P 0 ;0
L 1.24405 -2.04416004 1.2991 -2.04416004 0 P 0 ;0
L 1.24408996 -2.04316004 1.29975 -2.04316004 0 P 0 ;0
L 1.24413996 -2.04216004 1.3005 -2.04216004 0 P 0 ;0
L 1.24418002 -2.04116004 1.30131998 -2.04116004 0 P 0 ;0
L 1.24423002 -2.04016004 1.30223002 -2.04016004 0 P 0 ;0
L 1.24426998 -2.03916004 1.30326998 -2.03916004 0 P 0 ;0
L 1.24431998 -2.03816004 1.30446004 -2.03816004 0 P 0 ;0
L 1.24436004 -2.03716004 1.30581998 -2.03716004 0 P 0 ;0
L 1.24441004 -2.03616004 1.30738002 -2.03616004 0 P 0 ;0
L 1.24445 -2.03516004 1.30923002 -2.03516004 0 P 0 ;0
L 1.24448996 -2.03416004 1.31156004 -2.03416004 0 P 0 ;0
L 1.24453996 -2.03316004 1.31478996 -2.03316004 0 P 0 ;0
L 1.24458996 -2.03216004 1.32013002 -2.03216004 0 P 0 ;0
L 1.24461998 -2.03116004 1.33481004 -2.03116004 0 P 0 ;0
L 1.24463996 -2.03016004 1.33478002 -2.03016004 0 P 0 ;0
L 1.24466004 -2.02916004 1.33473996 -2.02916004 0 P 0 ;0
L 1.24468002 -2.02816004 1.33471004 -2.02816004 0 P 0 ;0
L 1.2447 -2.02716004 1.33468002 -2.02716004 0 P 0 ;0
L 1.24471998 -2.02616004 1.33463996 -2.02616004 0 P 0 ;0
L 1.24473996 -2.02516004 1.3346 -2.02516004 0 P 0 ;0
L 1.24476004 -2.02416004 1.33456998 -2.02416004 0 P 0 ;0
L 1.24478002 -2.02316004 1.33453002 -2.02316004 0 P 0 ;0
L 1.2448 -2.02216004 1.3345 -2.02216004 0 P 0 ;0
L 1.24481998 -2.02116004 1.33446998 -2.02116004 0 P 0 ;0
L 1.24483996 -2.02016004 1.33443002 -2.02016004 0 P 0 ;0
L 1.24486004 -2.01916004 1.3344 -2.01916004 0 P 0 ;0
L 1.24488002 -2.01816004 1.33436004 -2.01816004 0 P 0 ;0
L 1.2449 -2.01716004 1.33433002 -2.01716004 0 P 0 ;0
L 1.24491998 -2.01616004 1.33428996 -2.01616004 0 P 0 ;0
L 1.24493996 -2.01516004 1.33426004 -2.01516004 0 P 0 ;0
L 1.24496004 -2.01416004 1.33421998 -2.01416004 0 P 0 ;0
L 1.24498002 -2.01316004 1.33418996 -2.01316004 0 P 0 ;0
L 1.245 -2.01216004 1.33415 -2.01216004 0 P 0 ;0
L 1.24501998 -2.01116004 1.33411998 -2.01116004 0 P 0 ;0
L 1.24503996 -2.01016004 1.33408002 -2.01016004 0 P 0 ;0
L 1.24506004 -2.00916004 1.33403996 -2.00916004 0 P 0 ;0
L 1.24508002 -2.00816004 1.334 -2.00816004 0 P 0 ;0
L 1.2451 -2.00716004 1.33396004 -2.00716004 0 P 0 ;0
L 1.24511998 -2.00616004 1.33393002 -2.00616004 0 P 0 ;0
L 1.24513996 -2.00516004 1.29098996 -2.00516004 0 P 0 ;0
L 1.24513996 -2.00416004 1.29033002 -2.00416004 0 P 0 ;0
L 1.24513996 -2.00316004 1.29005 -2.00316004 0 P 0 ;0
L 1.24513996 -2.00216004 1.29005 -2.00216004 0 P 0 ;0
L 1.24513996 -2.00116004 1.29005 -2.00116004 0 P 0 ;0
L 1.24515 -2.00016004 1.29005 -2.00016004 0 P 0 ;0
L 1.24515 -1.99916004 1.29005 -1.99916004 0 P 0 ;0
L 1.24515 -1.99816004 1.29005 -1.99816004 0 P 0 ;0
L 1.24515 -1.99716004 1.29005 -1.99716004 0 P 0 ;0
L 1.24515 -1.99616004 1.29005 -1.99616004 0 P 0 ;0
L 1.24515 -1.99516004 1.29005 -1.99516004 0 P 0 ;0
L 1.16085 -2.02753002 1.1601 -2.04393002 0 P 0 ;0
L 1.1601 -2.04393002 1.15928996 -2.05771998 0 P 0 ;0
L 1.15928996 -2.05771998 1.15883996 -2.06228002 0 P 0 ;0
L 1.15883996 -2.06228002 1.15818002 -2.06681998 0 P 0 ;0
L 1.15818002 -2.06681998 1.15751004 -2.07006998 0 P 0 ;0
L 1.15751004 -2.07006998 1.15661004 -2.07328996 0 P 0 ;0
L 1.15661004 -2.07328996 1.15616004 -2.07453996 0 P 0 ;0
L 1.15616004 -2.07453996 1.15563002 -2.07576998 0 P 0 ;0
L 1.15563002 -2.07576998 1.15501998 -2.07696004 0 P 0 ;0
L 1.15501998 -2.07696004 1.15433002 -2.0781 0 P 0 ;0
L 1.15433002 -2.0781 1.1534 -2.07941998 0 P 0 ;0
L 1.1534 -2.07941998 1.15236004 -2.08066004 0 P 0 ;0
L 1.15236004 -2.08066004 1.15123002 -2.08181998 0 P 0 ;0
L 1.15123002 -2.08181998 1.15001004 -2.08286998 0 P 0 ;0
L 1.15001004 -2.08286998 1.14871004 -2.08383002 0 P 0 ;0
L 1.14871004 -2.08383002 1.14733002 -2.08468002 0 P 0 ;0
L 1.14733002 -2.08468002 1.14591004 -2.0854 0 P 0 ;0
L 1.14591004 -2.0854 1.14443996 -2.086 0 P 0 ;0
L 1.14443996 -2.086 1.14291004 -2.08648002 0 P 0 ;0
L 1.14291004 -2.08648002 1.14136004 -2.08683002 0 P 0 ;0
L 1.14136004 -2.08683002 1.13976998 -2.08703996 0 P 0 ;0
L 1.13976998 -2.08703996 1.13816004 -2.08713002 0 P 0 ;0
L 1.13816004 -2.08713002 1.13656998 -2.08708002 0 P 0 ;0
L 1.13656998 -2.08708002 1.13498996 -2.0869 0 P 0 ;0
L 1.13498996 -2.0869 1.13341998 -2.08658996 0 P 0 ;0
L 1.13341998 -2.08658996 1.13188996 -2.08615 0 P 0 ;0
L 1.13188996 -2.08615 1.1304 -2.08558996 0 P 0 ;0
L 1.1304 -2.08558996 1.12895 -2.08488996 0 P 0 ;0
L 1.12895 -2.08488996 1.12756998 -2.08408002 0 P 0 ;0
L 1.12756998 -2.08408002 1.12625 -2.08315 0 P 0 ;0
L 1.12625 -2.08315 1.12501004 -2.08211998 0 P 0 ;0
L 1.12501004 -2.08211998 1.12386004 -2.081 0 P 0 ;0
L 1.12386004 -2.081 1.12281004 -2.07978002 0 P 0 ;0
L 1.12281004 -2.07978002 1.12183996 -2.07846998 0 P 0 ;0
L 1.12183996 -2.07846998 1.1211 -2.07726004 0 P 0 ;0
L 1.1211 -2.07726004 1.12046998 -2.07598996 0 P 0 ;0
L 1.12046998 -2.07598996 1.11996004 -2.07466998 0 P 0 ;0
L 1.11996004 -2.07466998 1.11955 -2.07331004 0 P 0 ;0
L 1.11955 -2.07331004 1.11926998 -2.07191004 0 P 0 ;0
L 1.11926998 -2.07191004 1.11868002 -2.06693996 0 P 0 ;0
L 1.11868002 -2.06693996 1.11848002 -2.06191004 0 P 0 ;0
L 1.11848002 -2.06191004 1.11871004 -2.05668002 0 P 0 ;0
L 1.11871004 -2.05668002 1.11936004 -2.05148002 0 P 0 ;0
L 1.11936004 -2.05148002 1.11978996 -2.04936998 0 P 0 ;0
L 1.11978996 -2.04936998 1.12036998 -2.0473 0 P 0 ;0
L 1.12036998 -2.0473 1.12108996 -2.04528002 0 P 0 ;0
L 1.12108996 -2.04528002 1.12196004 -2.04331998 0 P 0 ;0
L 1.12196004 -2.04331998 1.1229 -2.04153996 0 P 0 ;0
L 1.1229 -2.04153996 1.12396998 -2.03985 0 P 0 ;0
L 1.12396998 -2.03985 1.12516998 -2.03823002 0 P 0 ;0
L 1.12516998 -2.03823002 1.12735 -2.03573996 0 P 0 ;0
L 1.12735 -2.03573996 1.12973002 -2.03345 0 P 0 ;0
L 1.12973002 -2.03345 1.13223996 -2.03141998 0 P 0 ;0
L 1.13223996 -2.03141998 1.13491998 -2.02961004 0 P 0 ;0
L 1.13491998 -2.02961004 1.13611004 -2.02893002 0 P 0 ;0
L 1.13611004 -2.02893002 1.13735 -2.02833996 0 P 0 ;0
L 1.13735 -2.02833996 1.13861998 -2.02781998 0 P 0 ;0
L 1.13861998 -2.02781998 1.13993996 -2.0274 0 P 0 ;0
L 1.13993996 -2.0274 1.14191004 -2.02693002 0 P 0 ;0
L 1.14191004 -2.02693002 1.14391004 -2.02663002 0 P 0 ;0
L 1.14391004 -2.02663002 1.14935 -2.02626004 0 P 0 ;0
L 1.14935 -2.02626004 1.15471004 -2.0263 0 P 0 ;0
L 1.15471004 -2.0263 1.15591004 -2.02638996 0 P 0 ;0
L 1.15591004 -2.02638996 1.1571 -2.02656998 0 P 0 ;0
L 1.1571 -2.02656998 1.15828002 -2.02683996 0 P 0 ;0
L 1.15828002 -2.02683996 1.16085 -2.02753002 0 P 0 ;0
L 1.13876998 -2.14783002 1.20233002 -2.14783002 0 P 0 ;0
L 1.14236998 -2.14683002 1.20266004 -2.14683002 0 P 0 ;0
L 1.14481004 -2.14583002 1.20296004 -2.14583002 0 P 0 ;0
L 1.1467 -2.14483002 1.20325 -2.14483002 0 P 0 ;0
L 1.14826004 -2.14383002 1.20353002 -2.14383002 0 P 0 ;0
L 1.1496 -2.14283002 1.20373996 -2.14283002 0 P 0 ;0
L 1.15078996 -2.14183002 1.20395 -2.14183002 0 P 0 ;0
L 1.15186004 -2.14083002 1.20415 -2.14083002 0 P 0 ;0
L 1.15278996 -2.13983002 1.20431998 -2.13983002 0 P 0 ;0
L 1.15361998 -2.13883002 1.20446004 -2.13883002 0 P 0 ;0
L 1.15436004 -2.13783002 1.20458002 -2.13783002 0 P 0 ;0
L 1.155 -2.13683002 1.20466998 -2.13683002 0 P 0 ;0
L 1.15556998 -2.13583002 1.20475 -2.13583002 0 P 0 ;0
L 1.15608996 -2.13483002 1.20481998 -2.13483002 0 P 0 ;0
L 1.15653996 -2.13383002 1.20488996 -2.13383002 0 P 0 ;0
L 1.15691004 -2.13283002 1.20496004 -2.13283002 0 P 0 ;0
L 1.15723996 -2.13183002 1.20503002 -2.13183002 0 P 0 ;0
L 1.15751998 -2.13083002 1.2051 -2.13083002 0 P 0 ;0
L 1.15773002 -2.12983002 1.20516004 -2.12983002 0 P 0 ;0
L 1.15793002 -2.12883002 1.20523002 -2.12883002 0 P 0 ;0
L 1.15806004 -2.12783002 1.2053 -2.12783002 0 P 0 ;0
L 1.15816998 -2.12683002 1.20536998 -2.12683002 0 P 0 ;0
L 1.15821004 -2.12583002 1.20543996 -2.12583002 0 P 0 ;0
L 1.11716004 -2.12483002 1.12726004 -2.12483002 0 P 0 ;0
L 1.15823996 -2.12483002 1.20551004 -2.12483002 0 P 0 ;0
L 1.10911998 -2.12383002 1.1352 -2.12383002 0 P 0 ;0
L 1.15821998 -2.12383002 1.20556998 -2.12383002 0 P 0 ;0
L 1.10468996 -2.12283002 1.14018996 -2.12283002 0 P 0 ;0
L 1.1582 -2.12283002 1.20563996 -2.12283002 0 P 0 ;0
L 1.10131004 -2.12183002 1.14366998 -2.12183002 0 P 0 ;0
L 1.15818002 -2.12183002 1.2057 -2.12183002 0 P 0 ;0
L 1.15808996 -2.12083002 1.20576004 -2.12083002 0 P 0 ;0
L 1.15781004 -2.11983002 1.20583002 -2.11983002 0 P 0 ;0
L 1.15721004 -2.11883002 1.20588002 -2.11883002 0 P 0 ;0
L 1.14146004 -2.08883002 1.20758002 -2.08883002 0 P 0 ;0
L 1.14525 -2.08783002 1.20763002 -2.08783002 0 P 0 ;0
L 1.14751004 -2.08683002 1.20768002 -2.08683002 0 P 0 ;0
L 1.14928002 -2.08583002 1.20773002 -2.08583002 0 P 0 ;0
L 1.15073002 -2.08483002 1.20778996 -2.08483002 0 P 0 ;0
L 1.15196004 -2.08383002 1.20783996 -2.08383002 0 P 0 ;0
L 1.13818996 -2.08913002 1.13826998 -2.08913002 0 P 0 ;0
L 1.13826998 -2.08913002 1.13988002 -2.08903996 0 P 0 ;0
L 1.13988002 -2.08903996 1.13996004 -2.08903996 0 P 0 ;0
L 1.13996004 -2.08903996 1.14001004 -2.08903002 0 P 0 ;0
L 1.14001004 -2.08903002 1.14005 -2.08901998 0 P 0 ;0
L 1.14005 -2.08901998 1.14163002 -2.08881004 0 P 0 ;0
L 1.14163002 -2.08881004 1.14166998 -2.0888 0 P 0 ;0
L 1.14166998 -2.0888 1.14171004 -2.0888 0 P 0 ;0
L 1.14171004 -2.0888 1.14178996 -2.08878002 0 P 0 ;0
L 1.14178996 -2.08878002 1.14335 -2.08843002 0 P 0 ;0
L 1.14335 -2.08843002 1.14351004 -2.08838996 0 P 0 ;0
L 1.14351004 -2.08838996 1.14503002 -2.08791004 0 P 0 ;0
L 1.14503002 -2.08791004 1.14511004 -2.08788996 0 P 0 ;0
L 1.14511004 -2.08788996 1.14515 -2.08786998 0 P 0 ;0
L 1.14515 -2.08786998 1.14518996 -2.08786004 0 P 0 ;0
L 1.14518996 -2.08786004 1.14666004 -2.08725 0 P 0 ;0
L 1.14666004 -2.08725 1.14673996 -2.08721998 0 P 0 ;0
L 1.14673996 -2.08721998 1.14678002 -2.0872 0 P 0 ;0
L 1.14678002 -2.0872 1.14681998 -2.08718996 0 P 0 ;0
L 1.14681998 -2.08718996 1.14823996 -2.08646998 0 P 0 ;0
L 1.14823996 -2.08646998 1.14826998 -2.08645 0 P 0 ;0
L 1.14826998 -2.08645 1.14835 -2.08641004 0 P 0 ;0
L 1.14835 -2.08641004 1.14838002 -2.08638002 0 P 0 ;0
L 1.14838002 -2.08638002 1.14976004 -2.08553002 0 P 0 ;0
L 1.14976004 -2.08553002 1.14978996 -2.08551004 0 P 0 ;0
L 1.14978996 -2.08551004 1.14983002 -2.08548996 0 P 0 ;0
L 1.14983002 -2.08548996 1.14988996 -2.08543996 0 P 0 ;0
L 1.14988996 -2.08543996 1.1512 -2.08448996 0 P 0 ;0
L 1.1512 -2.08448996 1.15126004 -2.08443996 0 P 0 ;0
L 1.15126004 -2.08443996 1.15128996 -2.08441004 0 P 0 ;0
L 1.15128996 -2.08441004 1.15131998 -2.08438996 0 P 0 ;0
L 1.15131998 -2.08438996 1.15253996 -2.08333002 0 P 0 ;0
L 1.15253996 -2.08333002 1.15256998 -2.0833 0 P 0 ;0
L 1.15256998 -2.0833 1.1526 -2.08328002 0 P 0 ;0
L 1.1526 -2.08328002 1.15263002 -2.08323996 0 P 0 ;0
L 1.15263002 -2.08323996 1.15266004 -2.08321998 0 P 0 ;0
L 1.15266004 -2.08321998 1.15378996 -2.08206004 0 P 0 ;0
L 1.15378996 -2.08206004 1.15376004 -2.08203996 0 P 0 ;0
L 1.15376004 -2.08203996 1.15381998 -2.08203996 0 P 0 ;0
L 1.15381998 -2.08203996 1.15383996 -2.082 0 P 0 ;0
L 1.15383996 -2.082 1.15386998 -2.08196998 0 P 0 ;0
L 1.15386998 -2.08196998 1.1539 -2.08195 0 P 0 ;0
L 1.1539 -2.08195 1.15493002 -2.08071004 0 P 0 ;0
L 1.15493002 -2.08071004 1.15493002 -2.0807 0 P 0 ;0
L 1.15493002 -2.0807 1.15496004 -2.08066998 0 P 0 ;0
L 1.15496004 -2.08066998 1.15498002 -2.08063996 0 P 0 ;0
L 1.15498002 -2.08063996 1.15501004 -2.08061004 0 P 0 ;0
L 1.15501004 -2.08061004 1.15503002 -2.08058002 0 P 0 ;0
L 1.15503002 -2.08058002 1.15596004 -2.07926004 0 P 0 ;0
L 1.15596004 -2.07926004 1.15603996 -2.07913996 0 P 0 ;0
L 1.15603996 -2.07913996 1.15673002 -2.07798996 0 P 0 ;0
L 1.15673002 -2.07798996 1.15676998 -2.07793002 0 P 0 ;0
L 1.15676998 -2.07793002 1.15678996 -2.07786998 0 P 0 ;0
L 1.15678996 -2.07786998 1.15741004 -2.07668996 0 P 0 ;0
L 1.15741004 -2.07668996 1.15743996 -2.07663002 0 P 0 ;0
L 1.15743996 -2.07663002 1.15746004 -2.07656998 0 P 0 ;0
L 1.15746004 -2.07656998 1.15746998 -2.07656998 0 P 0 ;0
L 1.15746998 -2.07656998 1.158 -2.07533996 0 P 0 ;0
L 1.158 -2.07533996 1.15801004 -2.07531004 0 P 0 ;0
L 1.15801004 -2.07531004 1.15803002 -2.07528002 0 P 0 ;0
L 1.15803002 -2.07528002 1.15805 -2.07521998 0 P 0 ;0
L 1.15805 -2.07521998 1.15848996 -2.07396004 0 P 0 ;0
L 1.15848996 -2.07396004 1.15841004 -2.07393002 0 P 0 ;0
L 1.15841004 -2.07393002 1.15851004 -2.07393002 0 P 0 ;0
L 1.15851004 -2.07393002 1.15851998 -2.0739 0 P 0 ;0
L 1.15851998 -2.0739 1.15853002 -2.07386004 0 P 0 ;0
L 1.15853002 -2.07386004 1.15853996 -2.07383002 0 P 0 ;0
L 1.15853996 -2.07383002 1.15943996 -2.07061004 0 P 0 ;0
L 1.15943996 -2.07061004 1.15945 -2.07058002 0 P 0 ;0
L 1.15945 -2.07058002 1.15946004 -2.07053996 0 P 0 ;0
L 1.15946004 -2.07053996 1.15946998 -2.07051004 0 P 0 ;0
L 1.15946998 -2.07051004 1.15946998 -2.07046998 0 P 0 ;0
L 1.15946998 -2.07046998 1.16013996 -2.06723002 0 P 0 ;0
L 1.16013996 -2.06723002 1.16013996 -2.0672 0 P 0 ;0
L 1.16013996 -2.0672 1.16016004 -2.06713996 0 P 0 ;0
L 1.16016004 -2.06713996 1.16016004 -2.06711004 0 P 0 ;0
L 1.16016004 -2.06711004 1.16081998 -2.06256004 0 P 0 ;0
L 1.16081998 -2.06256004 1.16081998 -2.06253996 0 P 0 ;0
L 1.16081998 -2.06253996 1.16083002 -2.0625 0 P 0 ;0
L 1.16083002 -2.0625 1.16083002 -2.06246998 0 P 0 ;0
L 1.16083002 -2.06246998 1.16126998 -2.05791004 0 P 0 ;0
L 1.16126998 -2.05791004 1.16128002 -2.0579 0 P 0 ;0
L 1.16128002 -2.0579 1.16128002 -2.05783996 0 P 0 ;0
L 1.16128002 -2.05783996 1.1621 -2.04405 0 P 0 ;0
L 1.1621 -2.04405 1.1621 -2.04401998 0 P 0 ;0
L 1.1621 -2.04401998 1.16285 -2.02761998 0 P 0 ;0
L 1.16285 -2.02761998 1.16136998 -2.0256 0 P 0 ;0
L 1.16136998 -2.0256 1.15878996 -2.02491004 0 P 0 ;0
L 1.15878996 -2.02491004 1.15878002 -2.0249 0 P 0 ;0
L 1.15878002 -2.0249 1.15871998 -2.02488996 0 P 0 ;0
L 1.15871998 -2.02488996 1.15755 -2.02461998 0 P 0 ;0
L 1.15755 -2.02461998 1.15746998 -2.0246 0 P 0 ;0
L 1.15746998 -2.0246 1.1574 -2.0246 0 P 0 ;0
L 1.1574 -2.0246 1.15621004 -2.02441004 0 P 0 ;0
L 1.15621004 -2.02441004 1.15616998 -2.02441004 0 P 0 ;0
L 1.15616998 -2.02441004 1.1561 -2.0244 0 P 0 ;0
L 1.1561 -2.0244 1.15606004 -2.02438996 0 P 0 ;0
L 1.15606004 -2.02438996 1.15486004 -2.0243 0 P 0 ;0
L 1.15486004 -2.0243 1.15471998 -2.0243 0 P 0 ;0
L 1.15471998 -2.0243 1.14936004 -2.02426004 0 P 0 ;0
L 1.14936004 -2.02426004 1.14928996 -2.02426004 0 P 0 ;0
L 1.14928996 -2.02426004 1.14925 -2.02426998 0 P 0 ;0
L 1.14925 -2.02426998 1.14921004 -2.02426998 0 P 0 ;0
L 1.14921004 -2.02426998 1.14376998 -2.02463996 0 P 0 ;0
L 1.14376998 -2.02463996 1.1437 -2.02463996 0 P 0 ;0
L 1.1437 -2.02463996 1.14365 -2.02465 0 P 0 ;0
L 1.14365 -2.02465 1.14361004 -2.02465 0 P 0 ;0
L 1.14361004 -2.02465 1.14161998 -2.02495 0 P 0 ;0
L 1.14161998 -2.02495 1.14161004 -2.02495 0 P 0 ;0
L 1.14161004 -2.02495 1.14153002 -2.02496998 0 P 0 ;0
L 1.14153002 -2.02496998 1.14148996 -2.02496998 0 P 0 ;0
L 1.14148996 -2.02496998 1.14143996 -2.02498996 0 P 0 ;0
L 1.14143996 -2.02498996 1.13946998 -2.02545 0 P 0 ;0
L 1.13946998 -2.02545 1.13943996 -2.02546998 0 P 0 ;0
L 1.13943996 -2.02546998 1.1394 -2.02546998 0 P 0 ;0
L 1.1394 -2.02546998 1.13933002 -2.0255 0 P 0 ;0
L 1.13933002 -2.0255 1.13801004 -2.02591998 0 P 0 ;0
L 1.13801004 -2.02591998 1.13798002 -2.02593002 0 P 0 ;0
L 1.13798002 -2.02593002 1.13793996 -2.02593996 0 P 0 ;0
L 1.13793996 -2.02593996 1.13788002 -2.02596998 0 P 0 ;0
L 1.13788002 -2.02596998 1.1366 -2.02648002 0 P 0 ;0
L 1.1366 -2.02648002 1.13653996 -2.0265 0 P 0 ;0
L 1.13653996 -2.0265 1.13648002 -2.02653002 0 P 0 ;0
L 1.13648002 -2.02653002 1.13523996 -2.02713002 0 P 0 ;0
L 1.13523996 -2.02713002 1.13518002 -2.02716004 0 P 0 ;0
L 1.13518002 -2.02716004 1.13515 -2.02716998 0 P 0 ;0
L 1.13515 -2.02716998 1.13511998 -2.02718996 0 P 0 ;0
L 1.13511998 -2.02718996 1.13393002 -2.02786998 0 P 0 ;0
L 1.13393002 -2.02786998 1.13388996 -2.02788996 0 P 0 ;0
L 1.13388996 -2.02788996 1.1338 -2.02795 0 P 0 ;0
L 1.1338 -2.02795 1.13111998 -2.02976004 0 P 0 ;0
L 1.13111998 -2.02976004 1.13105 -2.02981004 0 P 0 ;0
L 1.13105 -2.02981004 1.13101004 -2.02983996 0 P 0 ;0
L 1.13101004 -2.02983996 1.13098002 -2.02986004 0 P 0 ;0
L 1.13098002 -2.02986004 1.12846998 -2.03188996 0 P 0 ;0
L 1.12846998 -2.03188996 1.12838002 -2.03198002 0 P 0 ;0
L 1.12838002 -2.03198002 1.12833996 -2.03201004 0 P 0 ;0
L 1.12833996 -2.03201004 1.12596004 -2.0343 0 P 0 ;0
L 1.12596004 -2.0343 1.12593996 -2.03433002 0 P 0 ;0
L 1.12593996 -2.03433002 1.1259 -2.03436004 0 P 0 ;0
L 1.1259 -2.03436004 1.12588002 -2.03438996 0 P 0 ;0
L 1.12588002 -2.03438996 1.12585 -2.03443002 0 P 0 ;0
L 1.12585 -2.03443002 1.12366998 -2.03691004 0 P 0 ;0
L 1.12366998 -2.03691004 1.12363996 -2.03695 0 P 0 ;0
L 1.12363996 -2.03695 1.12361998 -2.03698002 0 P 0 ;0
L 1.12361998 -2.03698002 1.12358996 -2.03701004 0 P 0 ;0
L 1.12358996 -2.03701004 1.12356998 -2.03703996 0 P 0 ;0
L 1.12356998 -2.03703996 1.12236998 -2.03865 0 P 0 ;0
L 1.12236998 -2.03865 1.12233996 -2.03868996 0 P 0 ;0
L 1.12233996 -2.03868996 1.12233002 -2.03871004 0 P 0 ;0
L 1.12233002 -2.03871004 1.12228996 -2.03878002 0 P 0 ;0
L 1.12228996 -2.03878002 1.12121004 -2.04046998 0 P 0 ;0
L 1.12121004 -2.04046998 1.12118996 -2.0405 0 P 0 ;0
L 1.12118996 -2.0405 1.12116998 -2.04053996 0 P 0 ;0
L 1.12116998 -2.04053996 1.12115 -2.04056998 0 P 0 ;0
L 1.12115 -2.04056998 1.12113996 -2.04061004 0 P 0 ;0
L 1.12113996 -2.04061004 1.12018996 -2.04238002 0 P 0 ;0
L 1.12018996 -2.04238002 1.12016004 -2.04245 0 P 0 ;0
L 1.12016004 -2.04245 1.12013996 -2.04248002 0 P 0 ;0
L 1.12013996 -2.04248002 1.12013002 -2.04251004 0 P 0 ;0
L 1.12013002 -2.04251004 1.11926004 -2.04446998 0 P 0 ;0
L 1.11926004 -2.04446998 1.11925 -2.0445 0 P 0 ;0
L 1.11925 -2.0445 1.11923002 -2.04453996 0 P 0 ;0
L 1.11923002 -2.04453996 1.11921998 -2.04458002 0 P 0 ;0
L 1.11921998 -2.04458002 1.11921004 -2.04461004 0 P 0 ;0
L 1.11921004 -2.04461004 1.11848002 -2.04663002 0 P 0 ;0
L 1.11848002 -2.04663002 1.11846998 -2.04666004 0 P 0 ;0
L 1.11846998 -2.04666004 1.11846004 -2.0467 0 P 0 ;0
L 1.11846004 -2.0467 1.11843996 -2.04676998 0 P 0 ;0
L 1.11843996 -2.04676998 1.11786004 -2.04883996 0 P 0 ;0
L 1.11786004 -2.04883996 1.11785 -2.04886998 0 P 0 ;0
L 1.11785 -2.04886998 1.11783996 -2.04891004 0 P 0 ;0
L 1.11783996 -2.04891004 1.11783996 -2.04893996 0 P 0 ;0
L 1.11783996 -2.04893996 1.11783002 -2.04896998 0 P 0 ;0
L 1.11783002 -2.04896998 1.11783002 -2.04898002 0 P 0 ;0
L 1.11783002 -2.04898002 1.1174 -2.05108002 0 P 0 ;0
L 1.1174 -2.05108002 1.1174 -2.05111998 0 P 0 ;0
L 1.1174 -2.05111998 1.11738996 -2.05116004 0 P 0 ;0
L 1.11738996 -2.05116004 1.11738002 -2.05118996 0 P 0 ;0
L 1.11738002 -2.05118996 1.11738002 -2.05123002 0 P 0 ;0
L 1.11738002 -2.05123002 1.11673002 -2.05643002 0 P 0 ;0
L 1.11673002 -2.05643002 1.11671998 -2.05646998 0 P 0 ;0
L 1.11671998 -2.05646998 1.11671998 -2.05655 0 P 0 ;0
L 1.11671998 -2.05655 1.11671004 -2.05658996 0 P 0 ;0
L 1.11671004 -2.05658996 1.11648996 -2.06181998 0 P 0 ;0
L 1.11648996 -2.06181998 1.11648002 -2.06186998 0 P 0 ;0
L 1.11648002 -2.06186998 1.11648002 -2.06195 0 P 0 ;0
L 1.11648002 -2.06195 1.11648996 -2.06198996 0 P 0 ;0
L 1.11648996 -2.06198996 1.11668002 -2.06696998 0 P 0 ;0
L 1.11668002 -2.06696998 1.11768002 -2.06696998 0 P 0 ;0
L 1.11768002 -2.06696998 1.11668002 -2.06701004 0 P 0 ;0
L 1.11668002 -2.06701004 1.11668002 -2.06713002 0 P 0 ;0
L 1.11668002 -2.06713002 1.11668996 -2.06716998 0 P 0 ;0
L 1.11668996 -2.06716998 1.11728002 -2.07215 0 P 0 ;0
L 1.11728002 -2.07215 1.11728996 -2.07218996 0 P 0 ;0
L 1.11728996 -2.07218996 1.11728996 -2.07223002 0 P 0 ;0
L 1.11728996 -2.07223002 1.11731004 -2.07231004 0 P 0 ;0
L 1.11731004 -2.07231004 1.11758996 -2.07371004 0 P 0 ;0
L 1.11758996 -2.07371004 1.1176 -2.07375 0 P 0 ;0
L 1.1176 -2.07375 1.11761004 -2.0738 0 P 0 ;0
L 1.11761004 -2.0738 1.11761998 -2.07383996 0 P 0 ;0
L 1.11761998 -2.07383996 1.11763996 -2.07388002 0 P 0 ;0
L 1.11763996 -2.07388002 1.11803996 -2.07523996 0 P 0 ;0
L 1.11803996 -2.07523996 1.11806004 -2.07531998 0 P 0 ;0
L 1.11806004 -2.07531998 1.11808002 -2.07536004 0 P 0 ;0
L 1.11808002 -2.07536004 1.11808996 -2.07541004 0 P 0 ;0
L 1.11808996 -2.07541004 1.11861004 -2.07673002 0 P 0 ;0
L 1.11861004 -2.07673002 1.11863996 -2.07681004 0 P 0 ;0
L 1.11863996 -2.07681004 1.11866004 -2.07683996 0 P 0 ;0
L 1.11866004 -2.07683996 1.11868002 -2.07688002 0 P 0 ;0
L 1.11868002 -2.07688002 1.11931004 -2.07815 0 P 0 ;0
L 1.11931004 -2.07815 1.11935 -2.07823002 0 P 0 ;0
L 1.11935 -2.07823002 1.1194 -2.0783 0 P 0 ;0
L 1.1194 -2.0783 1.12013996 -2.07951998 0 P 0 ;0
L 1.12013996 -2.07951998 1.12021004 -2.07961998 0 P 0 ;0
L 1.12021004 -2.07961998 1.12023002 -2.07965 0 P 0 ;0
L 1.12023002 -2.07965 1.12023002 -2.07966004 0 P 0 ;0
L 1.12023002 -2.07966004 1.1212 -2.08096998 0 P 0 ;0
L 1.1212 -2.08096998 1.12123996 -2.08103002 0 P 0 ;0
L 1.12123996 -2.08103002 1.12126998 -2.08106004 0 P 0 ;0
L 1.12126998 -2.08106004 1.12128996 -2.08108996 0 P 0 ;0
L 1.12128996 -2.08108996 1.12235 -2.08231004 0 P 0 ;0
L 1.12235 -2.08231004 1.12238002 -2.08233996 0 P 0 ;0
L 1.12238002 -2.08233996 1.1224 -2.08236998 0 P 0 ;0
L 1.1224 -2.08236998 1.12246004 -2.08243002 0 P 0 ;0
L 1.12246004 -2.08243002 1.12361004 -2.08355 0 P 0 ;0
L 1.12361004 -2.08355 1.12366998 -2.08361004 0 P 0 ;0
L 1.12366998 -2.08361004 1.1237 -2.08363002 0 P 0 ;0
L 1.1237 -2.08363002 1.12373002 -2.08366004 0 P 0 ;0
L 1.12373002 -2.08366004 1.12496998 -2.08468996 0 P 0 ;0
L 1.12496998 -2.08468996 1.125 -2.08471004 0 P 0 ;0
L 1.125 -2.08471004 1.12503002 -2.08473996 0 P 0 ;0
L 1.12503002 -2.08473996 1.12506998 -2.08476004 0 P 0 ;0
L 1.12506998 -2.08476004 1.1251 -2.08478996 0 P 0 ;0
L 1.1251 -2.08478996 1.12641998 -2.08571004 0 P 0 ;0
L 1.12641998 -2.08571004 1.12645 -2.08573002 0 P 0 ;0
L 1.12645 -2.08573002 1.12648002 -2.08576004 0 P 0 ;0
L 1.12648002 -2.08576004 1.12651004 -2.08578002 0 P 0 ;0
L 1.12651004 -2.08578002 1.12655 -2.0858 0 P 0 ;0
L 1.12655 -2.0858 1.12793996 -2.08661004 0 P 0 ;0
L 1.12793996 -2.08661004 1.12801004 -2.08665 0 P 0 ;0
L 1.12801004 -2.08665 1.12805 -2.08666998 0 P 0 ;0
L 1.12805 -2.08666998 1.12808002 -2.08668996 0 P 0 ;0
L 1.12808002 -2.08668996 1.12808996 -2.08668996 0 P 0 ;0
L 1.12808996 -2.08668996 1.12953996 -2.08738996 0 P 0 ;0
L 1.12953996 -2.08738996 1.12961998 -2.08743002 0 P 0 ;0
L 1.12961998 -2.08743002 1.12965 -2.08743996 0 P 0 ;0
L 1.12965 -2.08743996 1.1297 -2.08746004 0 P 0 ;0
L 1.1297 -2.08746004 1.13118002 -2.08801998 0 P 0 ;0
L 1.13118002 -2.08801998 1.13133996 -2.08808002 0 P 0 ;0
L 1.13133996 -2.08808002 1.13286998 -2.08851004 0 P 0 ;0
L 1.13286998 -2.08851004 1.13295 -2.08853996 0 P 0 ;0
L 1.13295 -2.08853996 1.13303996 -2.08855 0 P 0 ;0
L 1.13303996 -2.08855 1.1346 -2.08886004 0 P 0 ;0
L 1.1346 -2.08886004 1.13471998 -2.08888996 0 P 0 ;0
L 1.13471998 -2.08888996 1.13476004 -2.08888996 0 P 0 ;0
L 1.13476004 -2.08888996 1.13633996 -2.08906998 0 P 0 ;0
L 1.13633996 -2.08906998 1.13638996 -2.08908002 0 P 0 ;0
L 1.13638996 -2.08908002 1.13651004 -2.08908002 0 P 0 ;0
L 1.13651004 -2.08908002 1.1381 -2.08913002 0 P 0 ;0
L 1.1381 -2.08913002 1.13818996 -2.08913002 0 P 0 ;0
L 1.31623996 -1.98923996 1.3135 -1.98988002 0 P 0 ;0
L 1.3135 -1.98988002 1.31078996 -1.99071004 0 P 0 ;0
L 1.31078996 -1.99071004 1.30813002 -1.99175 0 P 0 ;0
L 1.30813002 -1.99175 1.30553996 -1.99296998 0 P 0 ;0
L 1.30553996 -1.99296998 1.30308996 -1.99431998 0 P 0 ;0
L 1.30308996 -1.99431998 1.30073996 -1.99585 0 P 0 ;0
L 1.30073996 -1.99585 1.29863996 -1.99746004 0 P 0 ;0
L 1.29863996 -1.99746004 1.29666004 -1.99923996 0 P 0 ;0
L 1.29666004 -1.99923996 1.29205 -2.00375 0 P 0 ;0
L 1.29205 -2.00375 1.29205 -1.99243996 0 P 0 ;0
L 1.29205 -1.99243996 1.24316004 -1.99243996 0 P 0 ;0
L 1.24316004 -1.99243996 1.24313996 -2.00521004 0 P 0 ;0
L 1.24313996 -2.00521004 1.24261004 -2.03151004 0 P 0 ;0
L 1.24261004 -2.03151004 1.24086998 -2.07046004 0 P 0 ;0
L 1.24086998 -2.07046004 1.23873996 -2.10921004 0 P 0 ;0
L 1.23873996 -2.10921004 1.23811998 -2.11641998 0 P 0 ;0
L 1.23811998 -2.11641998 1.23711998 -2.12361998 0 P 0 ;0
L 1.23711998 -2.12361998 1.23655 -2.12716004 0 P 0 ;0
L 1.23655 -2.12716004 1.29205 -2.12716004 0 P 0 ;0
L 1.29205 -2.12716004 1.29206998 -2.11766004 0 P 0 ;0
L 1.29206998 -2.11766004 1.29238996 -2.10283996 0 P 0 ;0
L 1.29238996 -2.10283996 1.29336004 -2.08431004 0 P 0 ;0
L 1.29336004 -2.08431004 1.29463996 -2.06673002 0 P 0 ;0
L 1.29463996 -2.06673002 1.29511004 -2.06253002 0 P 0 ;0
L 1.29511004 -2.06253002 1.29583996 -2.05836004 0 P 0 ;0
L 1.29583996 -2.05836004 1.29683002 -2.05446998 0 P 0 ;0
L 1.29683002 -2.05446998 1.29813996 -2.05068996 0 P 0 ;0
L 1.29813996 -2.05068996 1.29978002 -2.04701998 0 P 0 ;0
L 1.29978002 -2.04701998 1.30056998 -2.04556998 0 P 0 ;0
L 1.30056998 -2.04556998 1.30146998 -2.04418996 0 P 0 ;0
L 1.30146998 -2.04418996 1.30246998 -2.04288002 0 P 0 ;0
L 1.30246998 -2.04288002 1.30356998 -2.04165 0 P 0 ;0
L 1.30356998 -2.04165 1.30475 -2.0405 0 P 0 ;0
L 1.30475 -2.0405 1.30603996 -2.03945 0 P 0 ;0
L 1.30603996 -2.03945 1.30773996 -2.03826004 0 P 0 ;0
L 1.30773996 -2.03826004 1.30953002 -2.03723002 0 P 0 ;0
L 1.30953002 -2.03723002 1.31141004 -2.03635 0 P 0 ;0
L 1.31141004 -2.03635 1.31335 -2.03563002 0 P 0 ;0
L 1.31335 -2.03563002 1.31535 -2.03508002 0 P 0 ;0
L 1.31535 -2.03508002 1.31973996 -2.03423002 0 P 0 ;0
L 1.31973996 -2.03423002 1.32416004 -2.03366998 0 P 0 ;0
L 1.32416004 -2.03366998 1.32863002 -2.0334 0 P 0 ;0
L 1.32863002 -2.0334 1.33688002 -2.03318002 0 P 0 ;0
L 1.33688002 -2.03318002 1.33613002 -2.01151004 0 P 0 ;0
L 1.33613002 -2.01151004 1.33581004 -2.00315 0 P 0 ;0
L 1.33581004 -2.00315 1.33543996 -1.99596004 0 P 0 ;0
L 1.33543996 -1.99596004 1.33508002 -1.98971004 0 P 0 ;0
L 1.33508002 -1.98971004 1.33503996 -1.98945 0 P 0 ;0
L 1.33503996 -1.98945 1.335 -1.98931998 0 P 0 ;0
L 1.335 -1.98931998 1.33496004 -1.9892 0 P 0 ;0
L 1.33496004 -1.9892 1.3349 -1.98908002 0 P 0 ;0
L 1.3349 -1.98908002 1.33483996 -1.98896998 0 P 0 ;0
L 1.33483996 -1.98896998 1.33476998 -1.98886004 0 P 0 ;0
L 1.33476998 -1.98886004 1.33468996 -1.98876004 0 P 0 ;0
L 1.33468996 -1.98876004 1.3346 -1.98866998 0 P 0 ;0
L 1.3346 -1.98866998 1.33451004 -1.98858996 0 P 0 ;0
L 1.33451004 -1.98858996 1.3344 -1.98851998 0 P 0 ;0
L 1.3344 -1.98851998 1.3343 -1.98845 0 P 0 ;0
L 1.3343 -1.98845 1.33418002 -1.98838996 0 P 0 ;0
L 1.33418002 -1.98838996 1.33406998 -1.98833996 0 P 0 ;0
L 1.33406998 -1.98833996 1.33395 -1.9883 0 P 0 ;0
L 1.33395 -1.9883 1.33383002 -1.98828002 0 P 0 ;0
L 1.33383002 -1.98828002 1.3337 -1.98826004 0 P 0 ;0
L 1.3337 -1.98826004 1.33356998 -1.98825 0 P 0 ;0
L 1.33356998 -1.98825 1.32756998 -1.98823002 0 P 0 ;0
L 1.32756998 -1.98823002 1.32135 -1.98853996 0 P 0 ;0
L 1.32135 -1.98853996 1.31878996 -1.98881998 0 P 0 ;0
L 1.31878996 -1.98881998 1.31623996 -1.98923996 0 P 0 ;0
L 1.2389 -2.12516004 1.29006004 -2.12516004 0 P 0 ;0
L 1.23906998 -2.12416004 1.29006004 -2.12416004 0 P 0 ;0
L 1.23921004 -2.12316004 1.29006004 -2.12316004 0 P 0 ;0
L 1.23933996 -2.12216004 1.29006004 -2.12216004 0 P 0 ;0
L 1.23948996 -2.12116004 1.29006004 -2.12116004 0 P 0 ;0
L 1.23961998 -2.12016004 1.29006998 -2.12016004 0 P 0 ;0
L 1.23976004 -2.11916004 1.29006998 -2.11916004 0 P 0 ;0
L 1.2399 -2.11816004 1.29006998 -2.11816004 0 P 0 ;0
L 1.24003996 -2.11716004 1.29008002 -2.11716004 0 P 0 ;0
L 1.24015 -2.11616004 1.2901 -2.11616004 0 P 0 ;0
L 1.24023996 -2.11516004 1.29011998 -2.11516004 0 P 0 ;0
L 1.24033002 -2.11416004 1.29013996 -2.11416004 0 P 0 ;0
L 1.24041004 -2.11316004 1.29016004 -2.11316004 0 P 0 ;0
L 1.24048996 -2.11216004 1.29018996 -2.11216004 0 P 0 ;0
L 1.24058002 -2.11116004 1.29021004 -2.11116004 0 P 0 ;0
L 1.24066998 -2.11016004 1.29023002 -2.11016004 0 P 0 ;0
L 1.24075 -2.10916004 1.29025 -2.10916004 0 P 0 ;0
L 1.2408 -2.10816004 1.29026998 -2.10816004 0 P 0 ;0
L 1.24086004 -2.10716004 1.29028996 -2.10716004 0 P 0 ;0
L 1.24091004 -2.10616004 1.29031998 -2.10616004 0 P 0 ;0
L 1.24096998 -2.10516004 1.29033996 -2.10516004 0 P 0 ;0
L 1.24101998 -2.10416004 1.29036004 -2.10416004 0 P 0 ;0
L 1.24108002 -2.10316004 1.29038002 -2.10316004 0 P 0 ;0
L 1.24113002 -2.10216004 1.29041998 -2.10216004 0 P 0 ;0
L 1.24118002 -2.10116004 1.29046998 -2.10116004 0 P 0 ;0
L 1.24123996 -2.10016004 1.29053002 -2.10016004 0 P 0 ;0
L 1.24128996 -2.09916004 1.29058002 -2.09916004 0 P 0 ;0
L 1.24135 -2.09816004 1.29063002 -2.09816004 0 P 0 ;0
L 1.2414 -2.09716004 1.29068002 -2.09716004 0 P 0 ;0
L 1.24146004 -2.09616004 1.29073996 -2.09616004 0 P 0 ;0
L 1.24151004 -2.09516004 1.29078996 -2.09516004 0 P 0 ;0
L 1.24156998 -2.09416004 1.29083996 -2.09416004 0 P 0 ;0
L 1.24161998 -2.09316004 1.2909 -2.09316004 0 P 0 ;0
L 1.24168002 -2.09216004 1.29095 -2.09216004 0 P 0 ;0
L 1.24173002 -2.09116004 1.291 -2.09116004 0 P 0 ;0
L 1.24178996 -2.09016004 1.29105 -2.09016004 0 P 0 ;0
L 1.24183996 -2.08916004 1.2911 -2.08916004 0 P 0 ;0
L 1.2419 -2.08816004 1.29116004 -2.08816004 0 P 0 ;0
L 1.24196004 -2.08716004 1.29121004 -2.08716004 0 P 0 ;0
L 1.24201004 -2.08616004 1.29126998 -2.08616004 0 P 0 ;0
L 1.24206998 -2.08516004 1.29131998 -2.08516004 0 P 0 ;0
L 1.24211998 -2.08416004 1.29136998 -2.08416004 0 P 0 ;0
L 1.2389 -2.12516004 1.2391 -2.12393002 0 P 0 ;0
L 1.2391 -2.12393002 1.2391 -2.1239 0 P 0 ;0
L 1.2391 -2.1239 1.24011004 -2.11665 0 P 0 ;0
L 1.24011004 -2.11665 1.24073002 -2.10935 0 P 0 ;0
L 1.24073002 -2.10935 1.24073996 -2.10931998 0 P 0 ;0
L 1.24073996 -2.10931998 1.24286004 -2.07056004 0 P 0 ;0
L 1.24286004 -2.07056004 1.24461004 -2.03158002 0 P 0 ;0
L 1.24461004 -2.03158002 1.24513996 -2.00523002 0 P 0 ;0
L 1.24513996 -2.00523002 1.24515 -1.99443996 0 P 0 ;0
L 1.24515 -1.99443996 1.29005 -1.99443996 0 P 0 ;0
L 1.29005 -1.99443996 1.29005 -2.00375 0 P 0 ;0
L 1.29005 -2.00375 1.29128002 -2.0056 0 P 0 ;0
L 1.29128002 -2.0056 1.29345 -2.00518002 0 P 0 ;0
L 1.29345 -2.00518002 1.29803002 -2.0007 0 P 0 ;0
L 1.29803002 -2.0007 1.29991998 -1.999 0 P 0 ;0
L 1.29991998 -1.999 1.30188996 -1.99748996 0 P 0 ;0
L 1.30188996 -1.99748996 1.30411998 -1.99603996 0 P 0 ;0
L 1.30411998 -1.99603996 1.30645 -1.99475 0 P 0 ;0
L 1.30645 -1.99475 1.30891998 -1.99358996 0 P 0 ;0
L 1.30891998 -1.99358996 1.31145 -1.9926 0 P 0 ;0
L 1.31145 -1.9926 1.31401998 -1.99181004 0 P 0 ;0
L 1.31401998 -1.99181004 1.31663996 -1.9912 0 P 0 ;0
L 1.31663996 -1.9912 1.31906004 -1.9908 0 P 0 ;0
L 1.31906004 -1.9908 1.32151004 -1.99053002 0 P 0 ;0
L 1.32151004 -1.99053002 1.32761998 -1.99023002 0 P 0 ;0
L 1.32761998 -1.99023002 1.3331 -1.99025 0 P 0 ;0
L 1.3331 -1.99025 1.33345 -1.99608002 0 P 0 ;0
L 1.33345 -1.99608002 1.33381004 -2.00323002 0 P 0 ;0
L 1.33381004 -2.00323002 1.33413002 -2.01158996 0 P 0 ;0
L 1.33413002 -2.01158996 1.33413002 -2.0116 0 P 0 ;0
L 1.33413002 -2.0116 1.33481998 -2.03123002 0 P 0 ;0
L 1.33481998 -2.03123002 1.32853996 -2.0314 0 P 0 ;0
L 1.32853996 -2.0314 1.32398002 -2.03166998 0 P 0 ;0
L 1.32398002 -2.03166998 1.31941998 -2.03225 0 P 0 ;0
L 1.31941998 -2.03225 1.31488996 -2.03313002 0 P 0 ;0
L 1.31488996 -2.03313002 1.31273996 -2.03373002 0 P 0 ;0
L 1.31273996 -2.03373002 1.31063996 -2.0345 0 P 0 ;0
L 1.31063996 -2.0345 1.3086 -2.03545 0 P 0 ;0
L 1.3086 -2.03545 1.30666004 -2.03656998 0 P 0 ;0
L 1.30666004 -2.03656998 1.30658996 -2.03661998 0 P 0 ;0
L 1.30658996 -2.03661998 1.30483002 -2.03786004 0 P 0 ;0
L 1.30483002 -2.03786004 1.30341998 -2.03901004 0 P 0 ;0
L 1.30341998 -2.03901004 1.30336998 -2.03906004 0 P 0 ;0
L 1.30336998 -2.03906004 1.30211998 -2.04026004 0 P 0 ;0
L 1.30211998 -2.04026004 1.30093002 -2.0416 0 P 0 ;0
L 1.30093002 -2.0416 1.29983002 -2.04303996 0 P 0 ;0
L 1.29983002 -2.04303996 1.29978996 -2.0431 0 P 0 ;0
L 1.29978996 -2.0431 1.29885 -2.04453996 0 P 0 ;0
L 1.29885 -2.04453996 1.29798996 -2.04613002 0 P 0 ;0
L 1.29798996 -2.04613002 1.29631998 -2.04986998 0 P 0 ;0
L 1.29631998 -2.04986998 1.29628002 -2.04995 0 P 0 ;0
L 1.29628002 -2.04995 1.29625 -2.05003002 0 P 0 ;0
L 1.29625 -2.05003002 1.29491998 -2.0539 0 P 0 ;0
L 1.29491998 -2.0539 1.29388996 -2.05793996 0 P 0 ;0
L 1.29388996 -2.05793996 1.29386998 -2.05801998 0 P 0 ;0
L 1.29386998 -2.05801998 1.29313996 -2.06221004 0 P 0 ;0
L 1.29313996 -2.06221004 1.29313002 -2.06223996 0 P 0 ;0
L 1.29313002 -2.06223996 1.29311998 -2.0623 0 P 0 ;0
L 1.29311998 -2.0623 1.29265 -2.06655 0 P 0 ;0
L 1.29265 -2.06655 1.29136998 -2.08418996 0 P 0 ;0
L 1.29136998 -2.08418996 1.29038996 -2.10276998 0 P 0 ;0
L 1.29038996 -2.10276998 1.29006998 -2.11763002 0 P 0 ;0
L 1.29006998 -2.11763002 1.29006004 -2.12516004 0 P 0 ;0
L 1.29006004 -2.12516004 1.2389 -2.12516004 0 P 0 ;0
L 1.09846998 -2.00483002 1.21248002 -2.00483002 0 P 0 ;0
L 1.09838002 -2.12083002 1.14708002 -2.12083002 0 P 0 ;0
L 1.11933002 -2.18283002 1.15161998 -2.18283002 0 P 0 ;0
L 1.11001998 -2.18183002 1.15838002 -2.18183002 0 P 0 ;0
L 1.10246998 -2.18083002 1.16333996 -2.18083002 0 P 0 ;0
L 1.04061004 -1.89731004 1.09978002 -1.89731004 0 P 0 ;0
L 1.03565 -1.89631004 1.09821004 -1.89631004 0 P 0 ;0
L 1.03068996 -1.89531004 1.09661004 -1.89531004 0 P 0 ;0
L 1.02573002 -1.89431004 1.09475 -1.89431004 0 P 0 ;0
L 1.019 -1.89331004 1.09288002 -1.89331004 0 P 0 ;0
L 1.01163996 -1.89231004 1.09101998 -1.89231004 0 P 0 ;0
L 0.99518996 -1.89131004 1.08916004 -1.89131004 0 P 0 ;0
L 0.87011998 -1.88331004 1.07278996 -1.88331004 0 P 0 ;0
L 0.86963996 -1.88231004 1.07053002 -1.88231004 0 P 0 ;0
L 0.86916004 -1.88131004 1.06828002 -1.88131004 0 P 0 ;0
L 0.86863002 -1.88031004 1.06603002 -1.88031004 0 P 0 ;0
L 0.86806998 -1.87931004 1.06351004 -1.87931004 0 P 0 ;0
L 0.8675 -1.87831004 1.06076998 -1.87831004 0 P 0 ;0
L 0.86693002 -1.87731004 1.05803996 -1.87731004 0 P 0 ;0
L 0.86631004 -1.87631004 1.05531004 -1.87631004 0 P 0 ;0
L 0.86563996 -1.87531004 1.05256998 -1.87531004 0 P 0 ;0
L 0.86498002 -1.87431004 1.04983996 -1.87431004 0 P 0 ;0
L 0.86431998 -1.87331004 1.0471 -1.87331004 0 P 0 ;0
L 0.86356004 -1.87231004 1.04376004 -1.87231004 0 P 0 ;0
L 0.86278996 -1.87131004 1.04041998 -1.87131004 0 P 0 ;0
L 0.86203002 -1.87031004 1.03708002 -1.87031004 0 P 0 ;0
L 0.86118996 -1.86931004 1.03373996 -1.86931004 0 P 0 ;0
L 0.8603 -1.86831004 1.0304 -1.86831004 0 P 0 ;0
L 0.85941004 -1.86731004 1.02656998 -1.86731004 0 P 0 ;0
L 0.8585 -1.86631004 1.02231998 -1.86631004 0 P 0 ;0
L 0.85756998 -1.86531004 1.01806998 -1.86531004 0 P 0 ;0
L 0.85663002 -1.86431004 1.01381998 -1.86431004 0 P 0 ;0
L 0.85568996 -1.86331004 1.00931998 -1.86331004 0 P 0 ;0
L 0.85481004 -1.86231004 1.00335 -1.86231004 0 P 0 ;0
L 0.85916998 -1.86131004 0.99738002 -1.86131004 0 P 0 ;0
L 0.86716998 -1.86031004 0.99141998 -1.86031004 0 P 0 ;0
L 0.87476998 -1.89731004 0.89943002 -1.89731004 0 P 0 ;0
L 0.87453996 -1.89631004 0.90426004 -1.89631004 0 P 0 ;0
L 0.87431004 -1.89531004 0.9097 -1.89531004 0 P 0 ;0
L 0.87406998 -1.89431004 0.91608002 -1.89431004 0 P 0 ;0
L 0.87383002 -1.89331004 0.92246004 -1.89331004 0 P 0 ;0
L 0.87355 -1.89231004 0.93086004 -1.89231004 0 P 0 ;0
L 0.87323002 -1.89131004 0.95553002 -1.89131004 0 P 0 ;0
L 0.87291004 -1.89031004 1.08728996 -1.89031004 0 P 0 ;0
L 0.87258996 -1.88931004 1.08543002 -1.88931004 0 P 0 ;0
L 0.87223002 -1.88831004 1.08356998 -1.88831004 0 P 0 ;0
L 0.87183002 -1.88731004 1.0817 -1.88731004 0 P 0 ;0
L 0.87143002 -1.88631004 1.07955 -1.88631004 0 P 0 ;0
L 0.87103002 -1.88531004 1.07728996 -1.88531004 0 P 0 ;0
L 0.8706 -1.88431004 1.07503996 -1.88431004 0 P 0 ;0
L 0.87525 -1.85931004 0.98545 -1.85931004 0 P 0 ;0
L 0.88421004 -1.85831004 0.97621004 -1.85831004 0 P 0 ;0
L 0.89393002 -1.85731004 0.96606998 -1.85731004 0 P 0 ;0
L 0.9106 -1.85631004 0.95203002 -1.85631004 0 P 0 ;0
L 1.08716004 -1.91231004 1.12151004 -1.91231004 0 P 0 ;0
L 1.08486004 -1.91131004 1.12018996 -1.91131004 0 P 0 ;0
L 1.08256004 -1.91031004 1.11886004 -1.91031004 0 P 0 ;0
L 1.08023002 -1.90931004 1.11753996 -1.90931004 0 P 0 ;0
L 1.07738002 -1.90831004 1.11621004 -1.90831004 0 P 0 ;0
L 1.07453002 -1.90731004 1.11488996 -1.90731004 0 P 0 ;0
L 1.07168996 -1.90631004 1.11356998 -1.90631004 0 P 0 ;0
L 1.06883996 -1.90531004 1.11223996 -1.90531004 0 P 0 ;0
L 1.066 -1.90431004 1.11076998 -1.90431004 0 P 0 ;0
L 1.06315 -1.90331004 1.1092 -1.90331004 0 P 0 ;0
L 1.0599 -1.90231004 1.10763002 -1.90231004 0 P 0 ;0
L 1.05611998 -1.90131004 1.10606004 -1.90131004 0 P 0 ;0
L 1.05235 -1.90031004 1.10448996 -1.90031004 0 P 0 ;0
L 1.04856998 -1.89931004 1.10291998 -1.89931004 0 P 0 ;0
L 1.04478996 -1.89831004 1.10135 -1.89831004 0 P 0 ;0
L 0.98815 -2.08316004 1.03726998 -2.08316004 0 P 0 ;0
L 0.98818002 -2.08216004 1.03731004 -2.08216004 0 P 0 ;0
L 0.98821998 -2.08116004 1.03735 -2.08116004 0 P 0 ;0
L 0.98825 -2.08016004 1.03738996 -2.08016004 0 P 0 ;0
L 0.98828002 -2.07916004 1.03743002 -2.07916004 0 P 0 ;0
L 0.98831998 -2.07816004 1.03746998 -2.07816004 0 P 0 ;0
L 0.98835 -2.07716004 1.03751004 -2.07716004 0 P 0 ;0
L 0.98838002 -2.07616004 1.03755 -2.07616004 0 P 0 ;0
L 0.98841998 -2.07516004 1.03758002 -2.07516004 0 P 0 ;0
L 0.98845 -2.07416004 1.03761004 -2.07416004 0 P 0 ;0
L 0.98848002 -2.07316004 1.03763996 -2.07316004 0 P 0 ;0
L 0.98851004 -2.07216004 1.03768002 -2.07216004 0 P 0 ;0
L 0.98855 -2.07116004 1.03771004 -2.07116004 0 P 0 ;0
L 0.98858002 -2.07016004 1.03773996 -2.07016004 0 P 0 ;0
L 0.98858996 -2.06916004 1.03776998 -2.06916004 0 P 0 ;0
L 0.98858996 -2.06816004 1.0378 -2.06816004 0 P 0 ;0
L 0.98858996 -2.06716004 1.03783002 -2.06716004 0 P 0 ;0
L 0.98858002 -2.06616004 1.03786004 -2.06616004 0 P 0 ;0
L 0.98856998 -2.06516004 1.0379 -2.06516004 0 P 0 ;0
L 0.98856998 -2.06416004 1.03793002 -2.06416004 0 P 0 ;0
L 0.98856998 -2.06316004 1.03796004 -2.06316004 0 P 0 ;0
L 0.98856004 -2.06216004 1.03798996 -2.06216004 0 P 0 ;0
L 0.98855 -2.06116004 1.03801998 -2.06116004 0 P 0 ;0
L 0.98855 -2.06016004 1.03805 -2.06016004 0 P 0 ;0
L 0.98853996 -2.05916004 1.03808002 -2.05916004 0 P 0 ;0
L 0.98853996 -2.05816004 1.0381 -2.05816004 0 P 0 ;0
L 0.98853002 -2.05716004 1.03811998 -2.05716004 0 P 0 ;0
L 0.98848002 -2.05616004 1.03815 -2.05616004 0 P 0 ;0
L 0.98841004 -2.05516004 1.03818002 -2.05516004 0 P 0 ;0
L 0.98835 -2.05416004 1.0382 -2.05416004 0 P 0 ;0
L 0.98828002 -2.05316004 1.03821998 -2.05316004 0 P 0 ;0
L 0.98821004 -2.05216004 1.03825 -2.05216004 0 P 0 ;0
L 0.98815 -2.05116004 1.03826998 -2.05116004 0 P 0 ;0
L 0.98808996 -2.05016004 1.03828996 -2.05016004 0 P 0 ;0
L 0.98801998 -2.04916004 1.03831998 -2.04916004 0 P 0 ;0
L 0.98796004 -2.04816004 1.03833996 -2.04816004 0 P 0 ;0
L 0.98788996 -2.04716004 1.03836004 -2.04716004 0 P 0 ;0
L 0.98783002 -2.04616004 1.03838996 -2.04616004 0 P 0 ;0
L 0.98768996 -2.04516004 1.0384 -2.04516004 0 P 0 ;0
L 0.98756004 -2.04416004 1.03841004 -2.04416004 0 P 0 ;0
L 0.98738002 -2.04316004 1.03841998 -2.04316004 0 P 0 ;0
L 0.98716004 -2.04216004 1.03843002 -2.04216004 0 P 0 ;0
L 0.98691998 -2.04116004 1.03843996 -2.04116004 0 P 0 ;0
L 0.98661998 -2.04016004 1.03845 -2.04016004 0 P 0 ;0
L 0.98631998 -2.03916004 1.03846004 -2.03916004 0 P 0 ;0
L 0.98593996 -2.03816004 1.03846998 -2.03816004 0 P 0 ;0
L 0.98546998 -2.03716004 1.03848002 -2.03716004 0 P 0 ;0
L 0.98491004 -2.03616004 1.03846998 -2.03616004 0 P 0 ;0
L 0.98425 -2.03516004 1.03846004 -2.03516004 0 P 0 ;0
L 0.98346004 -2.03416004 1.03846004 -2.03416004 0 P 0 ;0
L 0.98251998 -2.03316004 1.03843996 -2.03316004 0 P 0 ;0
L 0.98138002 -2.03216004 1.03843002 -2.03216004 0 P 0 ;0
L 0.97998996 -2.03116004 1.03841998 -2.03116004 0 P 0 ;0
L 0.97813996 -2.03016004 1.03841004 -2.03016004 0 P 0 ;0
L 0.97491004 -2.02916004 1.0384 -2.02916004 0 P 0 ;0
L 0.94763996 -2.00716004 1.03293996 -2.00716004 0 P 0 ;0
L 0.94978996 -2.00616004 1.03231998 -2.00616004 0 P 0 ;0
L 0.95081004 -2.00516004 1.0317 -2.00516004 0 P 0 ;0
L 0.95183002 -2.00416004 1.03098002 -2.00416004 0 P 0 ;0
L 0.95285 -2.00316004 1.03023002 -2.00316004 0 P 0 ;0
L 0.95388996 -2.00216004 1.02936004 -2.00216004 0 P 0 ;0
L 0.95498002 -2.00116004 1.02841998 -2.00116004 0 P 0 ;0
L 0.95621998 -2.00016004 1.02738996 -2.00016004 0 P 0 ;0
L 0.95761998 -1.99916004 1.0262 -1.99916004 0 P 0 ;0
L 0.9592 -1.99816004 1.02486004 -1.99816004 0 P 0 ;0
L 0.96083996 -1.99716004 1.02335 -1.99716004 0 P 0 ;0
L 0.9627 -1.99616004 1.02161004 -1.99616004 0 P 0 ;0
L 0.96468996 -1.99516004 1.01951998 -1.99516004 0 P 0 ;0
L 0.96685 -1.99416004 1.01683002 -1.99416004 0 P 0 ;0
L 0.96936998 -1.99316004 1.01378002 -1.99316004 0 P 0 ;0
L 0.97236998 -1.99216004 1.00981004 -1.99216004 0 P 0 ;0
L 0.97676004 -1.99116004 1.00456998 -1.99116004 0 P 0 ;0
L 1.06713996 -2.08283002 1.12288002 -2.08283002 0 P 0 ;0
L 1.06698996 -2.08183002 1.12193996 -2.08183002 0 P 0 ;0
L 1.06686004 -2.08083002 1.12108996 -2.08083002 0 P 0 ;0
L 1.06673996 -2.07983002 1.12036004 -2.07983002 0 P 0 ;0
L 1.06661998 -2.07883002 1.11971998 -2.07883002 0 P 0 ;0
L 1.06653002 -2.07783002 1.11916004 -2.07783002 0 P 0 ;0
L 1.06648002 -2.07683002 1.11866004 -2.07683002 0 P 0 ;0
L 1.06641998 -2.07583002 1.11826004 -2.07583002 0 P 0 ;0
L 1.06636998 -2.07483002 1.11791998 -2.07483002 0 P 0 ;0
L 1.06631998 -2.07383002 1.11761998 -2.07383002 0 P 0 ;0
L 1.06626004 -2.07283002 1.11741998 -2.07283002 0 P 0 ;0
L 1.06621004 -2.07183002 1.11723996 -2.07183002 0 P 0 ;0
L 1.06616004 -2.07083002 1.11711998 -2.07083002 0 P 0 ;0
L 1.06616004 -2.06983002 1.11701004 -2.06983002 0 P 0 ;0
L 1.06616004 -2.06883002 1.11688996 -2.06883002 0 P 0 ;0
L 1.06616998 -2.06783002 1.11676998 -2.06783002 0 P 0 ;0
L 1.06618002 -2.06683002 1.11666998 -2.06683002 0 P 0 ;0
L 1.06618996 -2.06583002 1.11663002 -2.06583002 0 P 0 ;0
L 1.0662 -2.06483002 1.11658996 -2.06483002 0 P 0 ;0
L 1.06621004 -2.06383002 1.11656004 -2.06383002 0 P 0 ;0
L 1.06623002 -2.06283002 1.11651998 -2.06283002 0 P 0 ;0
L 1.06631004 -2.06183002 1.11648996 -2.06183002 0 P 0 ;0
L 1.06638002 -2.06083002 1.11653002 -2.06083002 0 P 0 ;0
L 1.06645 -2.05983002 1.11656998 -2.05983002 0 P 0 ;0
L 1.06651998 -2.05883002 1.11661998 -2.05883002 0 P 0 ;0
L 1.06658996 -2.05783002 1.11666004 -2.05783002 0 P 0 ;0
L 1.06666998 -2.05683002 1.11671004 -2.05683002 0 P 0 ;0
L 1.06673996 -2.05583002 1.11681004 -2.05583002 0 P 0 ;0
L 1.06686004 -2.05483002 1.11693002 -2.05483002 0 P 0 ;0
L 1.067 -2.05383002 1.11705 -2.05383002 0 P 0 ;0
L 1.06713996 -2.05283002 1.11718002 -2.05283002 0 P 0 ;0
L 1.06728002 -2.05183002 1.11731004 -2.05183002 0 P 0 ;0
L 1.06741998 -2.05083002 1.11746004 -2.05083002 0 P 0 ;0
L 1.06756004 -2.04983002 1.11766004 -2.04983002 0 P 0 ;0
L 1.0677 -2.04883002 1.11786004 -2.04883002 0 P 0 ;0
L 1.06786004 -2.04783002 1.11813996 -2.04783002 0 P 0 ;0
L 1.06806998 -2.04683002 1.11841998 -2.04683002 0 P 0 ;0
L 1.06828002 -2.04583002 1.11876998 -2.04583002 0 P 0 ;0
L 1.06848996 -2.04483002 1.11913002 -2.04483002 0 P 0 ;0
L 1.06871004 -2.04383002 1.11955 -2.04383002 0 P 0 ;0
L 1.06898996 -2.04283002 1.11998996 -2.04283002 0 P 0 ;0
L 1.06928002 -2.04183002 1.12048002 -2.04183002 0 P 0 ;0
L 1.06956004 -2.04083002 1.12101004 -2.04083002 0 P 0 ;0
L 1.06985 -2.03983002 1.12161998 -2.03983002 0 P 0 ;0
L 1.07021004 -2.03883002 1.12225 -2.03883002 0 P 0 ;0
L 1.07056998 -2.03783002 1.12298002 -2.03783002 0 P 0 ;0
L 1.07093002 -2.03683002 1.12373996 -2.03683002 0 P 0 ;0
L 1.07128996 -2.03583002 1.12461998 -2.03583002 0 P 0 ;0
L 1.07173002 -2.03483002 1.12548996 -2.03483002 0 P 0 ;0
L 1.07216998 -2.03383002 1.12646004 -2.03383002 0 P 0 ;0
L 1.07261998 -2.03283002 1.12748996 -2.03283002 0 P 0 ;0
L 1.07308002 -2.03183002 1.12855 -2.03183002 0 P 0 ;0
L 1.07361998 -2.03083002 1.12978996 -2.03083002 0 P 0 ;0
L 1.09761004 -1.91731004 1.12756998 -1.91731004 0 P 0 ;0
L 1.09566004 -1.91631004 1.12645 -1.91631004 0 P 0 ;0
L 1.09371004 -1.91531004 1.12533002 -1.91531004 0 P 0 ;0
L 1.09176004 -1.91431004 1.12416004 -1.91431004 0 P 0 ;0
L 1.08946004 -1.91331004 1.12283996 -1.91331004 0 P 0 ;0
L 1.07415 -2.02983002 1.13101998 -2.02983002 0 P 0 ;0
L 1.07468996 -2.02883002 1.13248996 -2.02883002 0 P 0 ;0
L 1.07528996 -2.02783002 1.134 -2.02783002 0 P 0 ;0
L 1.07591998 -2.02683002 1.13586004 -2.02683002 0 P 0 ;0
L 1.07656004 -2.02583002 1.13828996 -2.02583002 0 P 0 ;0
L 1.07721004 -2.02483002 1.14243002 -2.02483002 0 P 0 ;0
L 1.07795 -2.02383002 1.21126998 -2.02383002 0 P 0 ;0
L 1.07868002 -2.02283002 1.21133002 -2.02283002 0 P 0 ;0
L 1.07941998 -2.02183002 1.2114 -2.02183002 0 P 0 ;0
L 1.08021004 -2.02083002 1.21146004 -2.02083002 0 P 0 ;0
L 1.08103996 -2.01983002 1.21153002 -2.01983002 0 P 0 ;0
L 1.08186998 -2.01883002 1.2116 -2.01883002 0 P 0 ;0
L 1.08273002 -2.01783002 1.21166004 -2.01783002 0 P 0 ;0
L 1.08366998 -2.01683002 1.21173002 -2.01683002 0 P 0 ;0
L 1.0846 -2.01583002 1.2118 -2.01583002 0 P 0 ;0
L 1.08555 -2.01483002 1.21186004 -2.01483002 0 P 0 ;0
L 1.08661004 -2.01383002 1.21193002 -2.01383002 0 P 0 ;0
L 1.08766998 -2.01283002 1.21198996 -2.01283002 0 P 0 ;0
L 1.08873002 -2.01183002 1.21205 -2.01183002 0 P 0 ;0
L 1.0898 -2.01083002 1.21211998 -2.01083002 0 P 0 ;0
L 1.09098996 -2.00983002 1.21218002 -2.00983002 0 P 0 ;0
L 1.09225 -2.00883002 1.21223996 -2.00883002 0 P 0 ;0
L 1.09358996 -2.00783002 1.2123 -2.00783002 0 P 0 ;0
L 1.09506998 -2.00683002 1.21236004 -2.00683002 0 P 0 ;0
L 1.09668996 -2.00583002 1.21241998 -2.00583002 0 P 0 ;0
L 0.98546998 -2.12516004 1.03548996 -2.12516004 0 P 0 ;0
L 0.98558996 -2.12416004 1.03553996 -2.12416004 0 P 0 ;0
L 0.9857 -2.12316004 1.03558002 -2.12316004 0 P 0 ;0
L 0.98581004 -2.12216004 1.03561998 -2.12216004 0 P 0 ;0
L 0.98591004 -2.12116004 1.03566998 -2.12116004 0 P 0 ;0
L 0.98598996 -2.12016004 1.03571004 -2.12016004 0 P 0 ;0
L 0.98608002 -2.11916004 1.03575 -2.11916004 0 P 0 ;0
L 0.98616998 -2.11816004 1.0358 -2.11816004 0 P 0 ;0
L 0.98625 -2.11716004 1.03583996 -2.11716004 0 P 0 ;0
L 0.98633996 -2.11616004 1.03588002 -2.11616004 0 P 0 ;0
L 0.98641998 -2.11516004 1.03593002 -2.11516004 0 P 0 ;0
L 0.98651004 -2.11416004 1.03596998 -2.11416004 0 P 0 ;0
L 0.9866 -2.11316004 1.03601004 -2.11316004 0 P 0 ;0
L 0.98668002 -2.11216004 1.03605 -2.11216004 0 P 0 ;0
L 0.98676998 -2.11116004 1.0361 -2.11116004 0 P 0 ;0
L 0.98685 -2.11016004 1.03613996 -2.11016004 0 P 0 ;0
L 0.98693996 -2.10916004 1.03618002 -2.10916004 0 P 0 ;0
L 0.987 -2.10816004 1.03623002 -2.10816004 0 P 0 ;0
L 0.98705 -2.10716004 1.03626998 -2.10716004 0 P 0 ;0
L 0.9871 -2.10616004 1.03631004 -2.10616004 0 P 0 ;0
L 0.98716004 -2.10516004 1.03636004 -2.10516004 0 P 0 ;0
L 0.9872 -2.10416004 1.0364 -2.10416004 0 P 0 ;0
L 0.98725 -2.10316004 1.03643996 -2.10316004 0 P 0 ;0
L 0.98731004 -2.10216004 1.03648002 -2.10216004 0 P 0 ;0
L 0.98735 -2.10116004 1.03653002 -2.10116004 0 P 0 ;0
L 0.9874 -2.10016004 1.03656998 -2.10016004 0 P 0 ;0
L 0.98746004 -2.09916004 1.03661004 -2.09916004 0 P 0 ;0
L 0.98751004 -2.09816004 1.03666004 -2.09816004 0 P 0 ;0
L 0.98755 -2.09716004 1.0367 -2.09716004 0 P 0 ;0
L 0.9876 -2.09616004 1.03673996 -2.09616004 0 P 0 ;0
L 0.98766004 -2.09516004 1.03678996 -2.09516004 0 P 0 ;0
L 0.9877 -2.09416004 1.03683002 -2.09416004 0 P 0 ;0
L 0.98775 -2.09316004 1.03686998 -2.09316004 0 P 0 ;0
L 0.98781004 -2.09216004 1.03691998 -2.09216004 0 P 0 ;0
L 0.98785 -2.09116004 1.03696004 -2.09116004 0 P 0 ;0
L 0.9879 -2.09016004 1.037 -2.09016004 0 P 0 ;0
L 0.98796004 -2.08916004 1.03703996 -2.08916004 0 P 0 ;0
L 0.98798996 -2.08816004 1.03706998 -2.08816004 0 P 0 ;0
L 0.98801998 -2.08716004 1.03711004 -2.08716004 0 P 0 ;0
L 0.98805 -2.08616004 1.03715 -2.08616004 0 P 0 ;0
L 0.98808996 -2.08516004 1.03718996 -2.08516004 0 P 0 ;0
L 0.98811998 -2.08416004 1.03723002 -2.08416004 0 P 0 ;0
L 1.08216998 -2.15683002 1.19803996 -2.15683002 0 P 0 ;0
L 1.0821 -2.15583002 1.19861004 -2.15583002 0 P 0 ;0
L 1.08201998 -2.15483002 1.19918002 -2.15483002 0 P 0 ;0
L 1.08195 -2.15383002 1.1997 -2.15383002 0 P 0 ;0
L 1.08188996 -2.15283002 1.20018002 -2.15283002 0 P 0 ;0
L 1.08183002 -2.15183002 1.20066004 -2.15183002 0 P 0 ;0
L 1.08176998 -2.15083002 1.20113996 -2.15083002 0 P 0 ;0
L 1.08171998 -2.14983002 1.20153996 -2.14983002 0 P 0 ;0
L 1.08166004 -2.14883002 1.20193002 -2.14883002 0 P 0 ;0
L 1.0816 -2.14783002 1.11538996 -2.14783002 0 P 0 ;0
L 1.08155 -2.14683002 1.10903002 -2.14683002 0 P 0 ;0
L 1.0815 -2.14583002 1.10415 -2.14583002 0 P 0 ;0
L 1.08146004 -2.14483002 1.09953002 -2.14483002 0 P 0 ;0
L 1.08141004 -2.14383002 1.09563996 -2.14383002 0 P 0 ;0
L 1.08136004 -2.14283002 1.09183996 -2.14283002 0 P 0 ;0
L 1.08131004 -2.14183002 1.08821004 -2.14183002 0 P 0 ;0
L 1.08133002 -2.14083002 1.08471998 -2.14083002 0 P 0 ;0
L 1.09586998 -2.11983002 1.14965 -2.11983002 0 P 0 ;0
L 1.09361998 -2.11883002 1.15221998 -2.11883002 0 P 0 ;0
L 1.09158996 -2.11783002 1.20595 -2.11783002 0 P 0 ;0
L 1.08988002 -2.11683002 1.20601004 -2.11683002 0 P 0 ;0
L 1.08823996 -2.11583002 1.20606998 -2.11583002 0 P 0 ;0
L 1.08678996 -2.11483002 1.20613002 -2.11483002 0 P 0 ;0
L 1.08541004 -2.11383002 1.20618996 -2.11383002 0 P 0 ;0
L 1.08416998 -2.11283002 1.20625 -2.11283002 0 P 0 ;0
L 1.08295 -2.11183002 1.20631004 -2.11183002 0 P 0 ;0
L 1.08188002 -2.11083002 1.20638002 -2.11083002 0 P 0 ;0
L 1.08081998 -2.10983002 1.20643996 -2.10983002 0 P 0 ;0
L 1.07986004 -2.10883002 1.2065 -2.10883002 0 P 0 ;0
L 1.07895 -2.10783002 1.20656004 -2.10783002 0 P 0 ;0
L 1.07803002 -2.10683002 1.20661998 -2.10683002 0 P 0 ;0
L 1.07723996 -2.10583002 1.20666998 -2.10583002 0 P 0 ;0
L 1.07646004 -2.10483002 1.20671998 -2.10483002 0 P 0 ;0
L 1.07568002 -2.10383002 1.20678002 -2.10383002 0 P 0 ;0
L 1.075 -2.10283002 1.20683002 -2.10283002 0 P 0 ;0
L 1.07433002 -2.10183002 1.20688002 -2.10183002 0 P 0 ;0
L 1.07366998 -2.10083002 1.20693996 -2.10083002 0 P 0 ;0
L 1.07308996 -2.09983002 1.20698996 -2.09983002 0 P 0 ;0
L 1.07253002 -2.09883002 1.20705 -2.09883002 0 P 0 ;0
L 1.07198002 -2.09783002 1.2071 -2.09783002 0 P 0 ;0
L 1.07146998 -2.09683002 1.20715 -2.09683002 0 P 0 ;0
L 1.07101998 -2.09583002 1.2072 -2.09583002 0 P 0 ;0
L 1.07056998 -2.09483002 1.20726004 -2.09483002 0 P 0 ;0
L 1.07013002 -2.09383002 1.20731004 -2.09383002 0 P 0 ;0
L 1.06976998 -2.09283002 1.20736004 -2.09283002 0 P 0 ;0
L 1.06941998 -2.09183002 1.20741998 -2.09183002 0 P 0 ;0
L 1.06906004 -2.09083002 1.20746998 -2.09083002 0 P 0 ;0
L 1.06876004 -2.08983002 1.20753002 -2.08983002 0 P 0 ;0
L 1.06848996 -2.08883002 1.13443002 -2.08883002 0 P 0 ;0
L 1.06821998 -2.08783002 1.13068002 -2.08783002 0 P 0 ;0
L 1.06795 -2.08683002 1.12836998 -2.08683002 0 P 0 ;0
L 1.06771998 -2.08583002 1.1266 -2.08583002 0 P 0 ;0
L 1.06753002 -2.08483002 1.12516004 -2.08483002 0 P 0 ;0
L 1.06733002 -2.08383002 1.12393996 -2.08383002 0 P 0 ;0
L 0.90273996 -1.85456998 0.89068996 -1.85558002 0 P 0 ;0
L 0.89068996 -1.85558002 0.87421004 -1.85741998 0 P 0 ;0
L 0.87421004 -1.85741998 0.85783002 -1.85946998 0 P 0 ;0
L 0.85783002 -1.85946998 0.85526998 -1.8599 0 P 0 ;0
L 0.85526998 -1.8599 0.85276004 -1.86055 0 P 0 ;0
L 0.85276004 -1.86055 0.85255 -1.86063996 0 P 0 ;0
L 0.85255 -1.86063996 0.85248996 -1.86068996 0 P 0 ;0
L 0.85248996 -1.86068996 0.85243002 -1.86073002 0 P 0 ;0
L 0.85243002 -1.86073002 0.85238002 -1.86078002 0 P 0 ;0
L 0.85238002 -1.86078002 0.85233002 -1.86083996 0 P 0 ;0
L 0.85233002 -1.86083996 0.85225 -1.86096004 0 P 0 ;0
L 0.85225 -1.86096004 0.85218002 -1.8611 0 P 0 ;0
L 0.85218002 -1.8611 0.85216004 -1.86116998 0 P 0 ;0
L 0.85216004 -1.86116998 0.85215 -1.86123996 0 P 0 ;0
L 0.85215 -1.86123996 0.85213996 -1.86136998 0 P 0 ;0
L 0.85213996 -1.86136998 0.85213002 -1.86148996 0 P 0 ;0
L 0.85213002 -1.86148996 0.85213996 -1.86161998 0 P 0 ;0
L 0.85213996 -1.86161998 0.85215 -1.86173996 0 P 0 ;0
L 0.85215 -1.86173996 0.85218002 -1.86186998 0 P 0 ;0
L 0.85218002 -1.86186998 0.85221004 -1.86198996 0 P 0 ;0
L 0.85221004 -1.86198996 0.85225 -1.8621 0 P 0 ;0
L 0.85225 -1.8621 0.85231004 -1.86221998 0 P 0 ;0
L 0.85231004 -1.86221998 0.85236998 -1.86233002 0 P 0 ;0
L 0.85236998 -1.86233002 0.85281998 -1.863 0 P 0 ;0
L 0.85281998 -1.863 0.8533 -1.86363996 0 P 0 ;0
L 0.8533 -1.86363996 0.85383002 -1.86425 0 P 0 ;0
L 0.85383002 -1.86425 0.85736004 -1.86801998 0 P 0 ;0
L 0.85736004 -1.86801998 0.86013002 -1.87113002 0 P 0 ;0
L 0.86013002 -1.87113002 0.86266004 -1.87443002 0 P 0 ;0
L 0.86266004 -1.87443002 0.86501004 -1.87798996 0 P 0 ;0
L 0.86501004 -1.87798996 0.86711998 -1.88171004 0 P 0 ;0
L 0.86711998 -1.88171004 0.86896998 -1.88553996 0 P 0 ;0
L 0.86896998 -1.88553996 0.87055 -1.8895 0 P 0 ;0
L 0.87055 -1.8895 0.8718 -1.89343002 0 P 0 ;0
L 0.8718 -1.89343002 0.87276004 -1.89745 0 P 0 ;0
L 0.87276004 -1.89745 0.87371004 -1.90195 0 P 0 ;0
L 0.87371004 -1.90195 0.87383002 -1.90236004 0 P 0 ;0
L 0.87383002 -1.90236004 0.87396998 -1.90276004 0 P 0 ;0
L 0.87396998 -1.90276004 0.87416004 -1.90313996 0 P 0 ;0
L 0.87416004 -1.90313996 0.87436998 -1.90351004 0 P 0 ;0
L 0.87436998 -1.90351004 0.87443002 -1.9036 0 P 0 ;0
L 0.87443002 -1.9036 0.87456998 -1.90376004 0 P 0 ;0
L 0.87456998 -1.90376004 0.87465 -1.90381998 0 P 0 ;0
L 0.87465 -1.90381998 0.87473002 -1.90388996 0 P 0 ;0
L 0.87473002 -1.90388996 0.87481998 -1.90393996 0 P 0 ;0
L 0.87481998 -1.90393996 0.87491998 -1.90398996 0 P 0 ;0
L 0.87491998 -1.90398996 0.87501004 -1.90403002 0 P 0 ;0
L 0.87501004 -1.90403002 0.87521004 -1.90408996 0 P 0 ;0
L 0.87521004 -1.90408996 0.87531998 -1.9041 0 P 0 ;0
L 0.87531998 -1.9041 0.87573002 -1.90413002 0 P 0 ;0
L 0.87573002 -1.90413002 0.87613996 -1.90411998 0 P 0 ;0
L 0.87613996 -1.90411998 0.87653996 -1.90408002 0 P 0 ;0
L 0.87653996 -1.90408002 0.87695 -1.90401004 0 P 0 ;0
L 0.87695 -1.90401004 0.90756004 -1.89766998 0 P 0 ;0
L 0.90756004 -1.89766998 0.92603996 -1.89478002 0 P 0 ;0
L 0.92603996 -1.89478002 0.93486004 -1.89393996 0 P 0 ;0
L 0.93486004 -1.89393996 0.94371004 -1.8935 0 P 0 ;0
L 0.94371004 -1.8935 0.97045 -1.89308002 0 P 0 ;0
L 0.97045 -1.89308002 0.99468996 -1.89328996 0 P 0 ;0
L 0.99468996 -1.89328996 1.01021004 -1.89413996 0 P 0 ;0
L 1.01021004 -1.89413996 1.0241 -1.89601998 0 P 0 ;0
L 1.0241 -1.89601998 1.04188002 -1.89961004 0 P 0 ;0
L 1.04188002 -1.89961004 1.06095 -1.90466004 0 P 0 ;0
L 1.06095 -1.90466004 1.07963996 -1.91123002 0 P 0 ;0
L 1.07963996 -1.91123002 1.09093996 -1.91613002 0 P 0 ;0
L 1.09093996 -1.91613002 1.10186998 -1.92175 0 P 0 ;0
L 1.10186998 -1.92175 1.11243996 -1.92806998 0 P 0 ;0
L 1.11243996 -1.92806998 1.12163002 -1.93446998 0 P 0 ;0
L 1.12163002 -1.93446998 1.13033002 -1.94148996 0 P 0 ;0
L 1.13033002 -1.94148996 1.1385 -1.94911004 0 P 0 ;0
L 1.1385 -1.94911004 1.14358996 -1.9546 0 P 0 ;0
L 1.14358996 -1.9546 1.14825 -1.96045 0 P 0 ;0
L 1.14825 -1.96045 1.15246998 -1.96663002 0 P 0 ;0
L 1.15246998 -1.96663002 1.15623002 -1.97316004 0 P 0 ;0
L 1.15623002 -1.97316004 1.15895 -1.97831004 0 P 0 ;0
L 1.15895 -1.97831004 1.17358996 -1.97831004 0 P 0 ;0
L 1.17358996 -1.97831004 1.17135 -1.9726 0 P 0 ;0
L 1.17135 -1.9726 1.16696004 -1.96266998 0 P 0 ;0
L 1.16696004 -1.96266998 1.16171998 -1.95313002 0 P 0 ;0
L 1.16171998 -1.95313002 1.1557 -1.94406998 0 P 0 ;0
L 1.1557 -1.94406998 1.14885 -1.93548002 0 P 0 ;0
L 1.14885 -1.93548002 1.13778996 -1.92378002 0 P 0 ;0
L 1.13778996 -1.92378002 1.12576998 -1.91301998 0 P 0 ;0
L 1.12576998 -1.91301998 1.11283996 -1.90326004 0 P 0 ;0
L 1.11283996 -1.90326004 1.09783002 -1.89368996 0 P 0 ;0
L 1.09783002 -1.89368996 1.08213002 -1.88526998 0 P 0 ;0
L 1.08213002 -1.88526998 1.06576998 -1.87801004 0 P 0 ;0
L 1.06576998 -1.87801004 1.04776004 -1.87141998 0 P 0 ;0
L 1.04776004 -1.87141998 1.02938002 -1.86591998 0 P 0 ;0
L 1.02938002 -1.86591998 1.01058002 -1.8615 0 P 0 ;0
L 1.01058002 -1.8615 0.98441998 -1.85711004 0 P 0 ;0
L 0.98441998 -1.85711004 0.95781004 -1.85448996 0 P 0 ;0
L 0.95781004 -1.85448996 0.93061004 -1.85366004 0 P 0 ;0
L 0.93061004 -1.85366004 0.90273996 -1.85456998 0 P 0 ;0
L 1.16015 -1.97631004 1.15798002 -1.97218996 0 P 0 ;0
L 1.15798002 -1.97218996 1.15796004 -1.97216004 0 P 0 ;0
L 1.15796004 -1.97216004 1.15416004 -1.96556998 0 P 0 ;0
L 1.15416004 -1.96556998 1.15411998 -1.96551004 0 P 0 ;0
L 1.15411998 -1.96551004 1.14986004 -1.95926004 0 P 0 ;0
L 1.14986004 -1.95926004 1.14981998 -1.95921004 0 P 0 ;0
L 1.14981998 -1.95921004 1.14511004 -1.9533 0 P 0 ;0
L 1.14511004 -1.9533 1.13991998 -1.9477 0 P 0 ;0
L 1.13991998 -1.9477 1.13986004 -1.94765 0 P 0 ;0
L 1.13986004 -1.94765 1.13163996 -1.93998002 0 P 0 ;0
L 1.13163996 -1.93998002 1.12283002 -1.93286004 0 P 0 ;0
L 1.12283002 -1.93286004 1.11351998 -1.92638996 0 P 0 ;0
L 1.11351998 -1.92638996 1.10283996 -1.92 0 P 0 ;0
L 1.10283996 -1.92 1.0918 -1.91433002 0 P 0 ;0
L 1.0918 -1.91433002 1.08036998 -1.90936004 0 P 0 ;0
L 1.08036998 -1.90936004 1.06153002 -1.90273996 0 P 0 ;0
L 1.06153002 -1.90273996 1.06146004 -1.90273002 0 P 0 ;0
L 1.06146004 -1.90273002 1.04233002 -1.89766004 0 P 0 ;0
L 1.04233002 -1.89766004 1.02443002 -1.89405 0 P 0 ;0
L 1.02443002 -1.89405 1.0104 -1.89213996 0 P 0 ;0
L 1.0104 -1.89213996 0.99475 -1.89128996 0 P 0 ;0
L 0.99475 -1.89128996 0.97045 -1.89108002 0 P 0 ;0
L 0.97045 -1.89108002 0.94365 -1.8915 0 P 0 ;0
L 0.94365 -1.8915 0.94361998 -1.8915 0 P 0 ;0
L 0.94361998 -1.8915 0.93471998 -1.89195 0 P 0 ;0
L 0.93471998 -1.89195 0.92578996 -1.89278996 0 P 0 ;0
L 0.92578996 -1.89278996 0.9072 -1.89571004 0 P 0 ;0
L 0.9072 -1.89571004 0.87656998 -1.90203996 0 P 0 ;0
L 0.87656998 -1.90203996 0.87626998 -1.9021 0 P 0 ;0
L 0.87626998 -1.9021 0.87601998 -1.90211998 0 P 0 ;0
L 0.87601998 -1.90211998 0.87588996 -1.90213002 0 P 0 ;0
L 0.87588996 -1.90213002 0.87583002 -1.90198996 0 P 0 ;0
L 0.87583002 -1.90198996 0.87573002 -1.90175 0 P 0 ;0
L 0.87573002 -1.90175 0.87566004 -1.90146998 0 P 0 ;0
L 0.87566004 -1.90146998 0.87471004 -1.89701004 0 P 0 ;0
L 0.87471004 -1.89701004 0.8747 -1.89698996 0 P 0 ;0
L 0.8747 -1.89698996 0.87373002 -1.89288996 0 P 0 ;0
L 0.87373002 -1.89288996 0.87243002 -1.88881998 0 P 0 ;0
L 0.87243002 -1.88881998 0.8724 -1.88876004 0 P 0 ;0
L 0.8724 -1.88876004 0.8708 -1.88473996 0 P 0 ;0
L 0.8708 -1.88473996 0.8689 -1.88078002 0 P 0 ;0
L 0.8689 -1.88078002 0.86671998 -1.87693996 0 P 0 ;0
L 0.86671998 -1.87693996 0.86428996 -1.87326004 0 P 0 ;0
L 0.86428996 -1.87326004 0.86166998 -1.86985 0 P 0 ;0
L 0.86166998 -1.86985 0.85883996 -1.86668002 0 P 0 ;0
L 0.85883996 -1.86668002 0.85883002 -1.86666004 0 P 0 ;0
L 0.85883002 -1.86666004 0.85531998 -1.86291004 0 P 0 ;0
L 0.85531998 -1.86291004 0.85486004 -1.86238002 0 P 0 ;0
L 0.85486004 -1.86238002 0.85466004 -1.86211998 0 P 0 ;0
L 0.85466004 -1.86211998 0.8557 -1.86186004 0 P 0 ;0
L 0.8557 -1.86186004 0.85811998 -1.86145 0 P 0 ;0
L 0.85811998 -1.86145 0.87443996 -1.85941004 0 P 0 ;0
L 0.87443996 -1.85941004 0.89088996 -1.85756998 0 P 0 ;0
L 0.89088996 -1.85756998 0.90286004 -1.85656998 0 P 0 ;0
L 0.90286004 -1.85656998 0.93061004 -1.85566004 0 P 0 ;0
L 0.93061004 -1.85566004 0.95768002 -1.85648996 0 P 0 ;0
L 0.95768002 -1.85648996 0.98416004 -1.8591 0 P 0 ;0
L 0.98416004 -1.8591 1.01018996 -1.86346004 0 P 0 ;0
L 1.01018996 -1.86346004 1.02886004 -1.86785 0 P 0 ;0
L 1.02886004 -1.86785 1.04711998 -1.87331998 0 P 0 ;0
L 1.04711998 -1.87331998 1.06501004 -1.87986004 0 P 0 ;0
L 1.06501004 -1.87986004 1.08125 -1.88706998 0 P 0 ;0
L 1.08125 -1.88706998 1.09681004 -1.89541998 0 P 0 ;0
L 1.09681004 -1.89541998 1.1117 -1.9049 0 P 0 ;0
L 1.1117 -1.9049 1.1245 -1.91456998 0 P 0 ;0
L 1.1245 -1.91456998 1.13638996 -1.92521004 0 P 0 ;0
L 1.13638996 -1.92521004 1.14733996 -1.93678996 0 P 0 ;0
L 1.14733996 -1.93678996 1.15408002 -1.94525 0 P 0 ;0
L 1.15408002 -1.94525 1.16001004 -1.95416998 0 P 0 ;0
L 1.16001004 -1.95416998 1.16516004 -1.96355 0 P 0 ;0
L 1.16516004 -1.96355 1.1695 -1.97336998 0 P 0 ;0
L 1.1695 -1.97336998 1.17066004 -1.97631004 0 P 0 ;0
L 1.17066004 -1.97631004 1.16015 -1.97631004 0 P 0 ;0
L 0.87563002 -1.90131004 0.8801 -1.90131004 0 P 0 ;0
L 0.87541004 -1.90031004 0.88493996 -1.90031004 0 P 0 ;0
L 0.8752 -1.89931004 0.88976998 -1.89931004 0 P 0 ;0
L 0.87498996 -1.89831004 0.8946 -1.89831004 0 P 0 ;0
L 0.89423002 -2.08316004 0.94355 -2.08316004 0 P 0 ;0
L 0.89428996 -2.08216004 0.9436 -2.08216004 0 P 0 ;0
L 0.89435 -2.08116004 0.94365 -2.08116004 0 P 0 ;0
L 0.89441004 -2.08016004 0.9437 -2.08016004 0 P 0 ;0
L 0.89446004 -2.07916004 0.94375 -2.07916004 0 P 0 ;0
L 0.89451998 -2.07816004 0.94378996 -2.07816004 0 P 0 ;0
L 0.89458002 -2.07716004 0.94383996 -2.07716004 0 P 0 ;0
L 0.89463996 -2.07616004 0.94388996 -2.07616004 0 P 0 ;0
L 0.8947 -2.07516004 0.94393996 -2.07516004 0 P 0 ;0
L 0.89475 -2.07416004 0.94398002 -2.07416004 0 P 0 ;0
L 0.89481004 -2.07316004 0.94403002 -2.07316004 0 P 0 ;0
L 0.89486998 -2.07216004 0.94408002 -2.07216004 0 P 0 ;0
L 0.89493002 -2.07116004 0.94415 -2.07116004 0 P 0 ;0
L 0.89498996 -2.07016004 0.94426004 -2.07016004 0 P 0 ;0
L 0.89505 -2.06916004 0.94436998 -2.06916004 0 P 0 ;0
L 0.8951 -2.06816004 0.94448002 -2.06816004 0 P 0 ;0
L 0.89516004 -2.06716004 0.94458996 -2.06716004 0 P 0 ;0
L 0.89521998 -2.06616004 0.9447 -2.06616004 0 P 0 ;0
L 0.89526998 -2.06516004 0.94481004 -2.06516004 0 P 0 ;0
L 0.89531004 -2.06416004 0.94491998 -2.06416004 0 P 0 ;0
L 0.89535 -2.06316004 0.94503002 -2.06316004 0 P 0 ;0
L 0.8954 -2.06216004 0.94513996 -2.06216004 0 P 0 ;0
L 0.89543996 -2.06116004 0.94531998 -2.06116004 0 P 0 ;0
L 0.89548996 -2.06016004 0.94551004 -2.06016004 0 P 0 ;0
L 0.89553002 -2.05916004 0.9457 -2.05916004 0 P 0 ;0
L 0.89558002 -2.05816004 0.94588996 -2.05816004 0 P 0 ;0
L 0.89561998 -2.05716004 0.94608002 -2.05716004 0 P 0 ;0
L 0.89566998 -2.05616004 0.94626998 -2.05616004 0 P 0 ;0
L 0.89571004 -2.05516004 0.94646998 -2.05516004 0 P 0 ;0
L 0.89575 -2.05416004 0.94666004 -2.05416004 0 P 0 ;0
L 0.8958 -2.05316004 0.94685 -2.05316004 0 P 0 ;0
L 0.89583996 -2.05216004 0.94708002 -2.05216004 0 P 0 ;0
L 0.89588996 -2.05116004 0.94735 -2.05116004 0 P 0 ;0
L 0.89593996 -2.05016004 0.94761998 -2.05016004 0 P 0 ;0
L 0.89598002 -2.04916004 0.9479 -2.04916004 0 P 0 ;0
L 0.89601998 -2.04816004 0.94825 -2.04816004 0 P 0 ;0
L 0.89606998 -2.04716004 0.94858996 -2.04716004 0 P 0 ;0
L 0.89611004 -2.04616004 0.94893002 -2.04616004 0 P 0 ;0
L 0.89616004 -2.04516004 0.94935 -2.04516004 0 P 0 ;0
L 0.8962 -2.04416004 0.94976998 -2.04416004 0 P 0 ;0
L 0.89625 -2.04316004 0.9502 -2.04316004 0 P 0 ;0
L 0.89628002 -2.04216004 0.95068996 -2.04216004 0 P 0 ;0
L 0.89631004 -2.04116004 0.95118996 -2.04116004 0 P 0 ;0
L 0.89633996 -2.04016004 0.95168996 -2.04016004 0 P 0 ;0
L 0.89638002 -2.03916004 0.95228002 -2.03916004 0 P 0 ;0
L 0.89641004 -2.03816004 0.95291004 -2.03816004 0 P 0 ;0
L 0.89643996 -2.03716004 0.95363002 -2.03716004 0 P 0 ;0
L 0.89646998 -2.03616004 0.95445 -2.03616004 0 P 0 ;0
L 0.89651004 -2.03516004 0.95535 -2.03516004 0 P 0 ;0
L 0.89653996 -2.03416004 0.95636998 -2.03416004 0 P 0 ;0
L 0.89656998 -2.03316004 0.95756998 -2.03316004 0 P 0 ;0
L 0.8966 -2.03216004 0.95893996 -2.03216004 0 P 0 ;0
L 0.89663996 -2.03116004 0.96055 -2.03116004 0 P 0 ;0
L 0.89666998 -2.03016004 0.96278002 -2.03016004 0 P 0 ;0
L 0.8967 -2.02916004 0.96676004 -2.02916004 0 P 0 ;0
L 0.89673996 -2.02816004 1.03838996 -2.02816004 0 P 0 ;0
L 0.89676998 -2.02716004 1.03838002 -2.02716004 0 P 0 ;0
L 0.8968 -2.02616004 1.03833996 -2.02616004 0 P 0 ;0
L 0.89683996 -2.02516004 1.03828996 -2.02516004 0 P 0 ;0
L 0.89686998 -2.02416004 1.03823002 -2.02416004 0 P 0 ;0
L 0.8969 -2.02316004 1.03816004 -2.02316004 0 P 0 ;0
L 0.89693996 -2.02216004 1.0381 -2.02216004 0 P 0 ;0
L 0.89696998 -2.02116004 1.03803996 -2.02116004 0 P 0 ;0
L 0.897 -2.02016004 1.0379 -2.02016004 0 P 0 ;0
L 0.89703002 -2.01916004 1.03773996 -2.01916004 0 P 0 ;0
L 0.89706004 -2.01816004 1.03751998 -2.01816004 0 P 0 ;0
L 0.89708996 -2.01716004 1.03728002 -2.01716004 0 P 0 ;0
L 0.89711998 -2.01616004 1.03698996 -2.01616004 0 P 0 ;0
L 0.89713996 -2.01516004 1.03668002 -2.01516004 0 P 0 ;0
L 0.89716998 -2.01416004 1.03631004 -2.01416004 0 P 0 ;0
L 0.8972 -2.01316004 1.03591998 -2.01316004 0 P 0 ;0
L 0.89721998 -2.01216004 1.03548996 -2.01216004 0 P 0 ;0
L 0.89725 -2.01116004 1.03505 -2.01116004 0 P 0 ;0
L 0.89726998 -2.01016004 1.03458002 -2.01016004 0 P 0 ;0
L 0.8973 -2.00916004 1.03405 -2.00916004 0 P 0 ;0
L 0.89733002 -2.00816004 1.03351998 -2.00816004 0 P 0 ;0
L 0.89736004 -2.00716004 0.94676004 -2.00716004 0 P 0 ;0
L 0.89738002 -2.00616004 0.9461 -2.00616004 0 P 0 ;0
L 0.89741004 -2.00516004 0.94563996 -2.00516004 0 P 0 ;0
L 0.89743996 -2.00416004 0.94563996 -2.00416004 0 P 0 ;0
L 0.89746004 -2.00316004 0.94563996 -2.00316004 0 P 0 ;0
L 0.89748996 -2.00216004 0.94563996 -2.00216004 0 P 0 ;0
L 0.89751004 -2.00116004 0.94563996 -2.00116004 0 P 0 ;0
L 0.89753996 -2.00016004 0.94563996 -2.00016004 0 P 0 ;0
L 0.89756998 -1.99916004 0.94563996 -1.99916004 0 P 0 ;0
L 0.8976 -1.99816004 0.94563996 -1.99816004 0 P 0 ;0
L 0.89761998 -1.99716004 0.94563996 -1.99716004 0 P 0 ;0
L 0.89765 -1.99616004 0.94563996 -1.99616004 0 P 0 ;0
L 0.89768002 -1.99516004 0.94563996 -1.99516004 0 P 0 ;0
L 0.97546998 -1.98933996 0.97236998 -1.99006004 0 P 0 ;0
L 0.97236998 -1.99006004 0.96931998 -1.99103002 0 P 0 ;0
L 0.96931998 -1.99103002 0.96603002 -1.99233002 0 P 0 ;0
L 0.96603002 -1.99233002 0.96281004 -1.99383002 0 P 0 ;0
L 0.96281004 -1.99383002 0.95976004 -1.99546998 0 P 0 ;0
L 0.95976004 -1.99546998 0.95681004 -1.99728996 0 P 0 ;0
L 0.95681004 -1.99728996 0.95521004 -1.99841004 0 P 0 ;0
L 0.95521004 -1.99841004 0.95368996 -1.99963002 0 P 0 ;0
L 0.95368996 -1.99963002 0.95223996 -2.00095 0 P 0 ;0
L 0.95223996 -2.00095 0.94763996 -2.00546998 0 P 0 ;0
L 0.94763996 -2.00546998 0.94763996 -1.99243996 0 P 0 ;0
L 0.94763996 -1.99243996 0.89575 -1.99243996 0 P 0 ;0
L 0.89575 -1.99243996 0.89505 -2.01878002 0 P 0 ;0
L 0.89505 -2.01878002 0.89423996 -2.04316004 0 P 0 ;0
L 0.89423996 -2.04316004 0.89321998 -2.0661 0 P 0 ;0
L 0.89321998 -2.0661 0.89198996 -2.08728996 0 P 0 ;0
L 0.89198996 -2.08728996 0.89055 -2.1063 0 P 0 ;0
L 0.89055 -2.1063 0.88993996 -2.11358002 0 P 0 ;0
L 0.88993996 -2.11358002 0.88943002 -2.11988002 0 P 0 ;0
L 0.88943002 -2.11988002 0.88898996 -2.12533996 0 P 0 ;0
L 0.88898996 -2.12533996 0.88896004 -2.12613002 0 P 0 ;0
L 0.88896004 -2.12613002 0.88896998 -2.12621004 0 P 0 ;0
L 0.88896998 -2.12621004 0.88898002 -2.12625 0 P 0 ;0
L 0.88898002 -2.12625 0.88898996 -2.12628002 0 P 0 ;0
L 0.88898996 -2.12628002 0.88901998 -2.12636004 0 P 0 ;0
L 0.88901998 -2.12636004 0.88903996 -2.12638996 0 P 0 ;0
L 0.88903996 -2.12638996 0.88906998 -2.12641998 0 P 0 ;0
L 0.88906998 -2.12641998 0.88908996 -2.12645 0 P 0 ;0
L 0.88908996 -2.12645 0.88911998 -2.12646998 0 P 0 ;0
L 0.88911998 -2.12646998 0.88915 -2.1265 0 P 0 ;0
L 0.88915 -2.1265 0.88921004 -2.12653996 0 P 0 ;0
L 0.88921004 -2.12653996 0.88925 -2.12655 0 P 0 ;0
L 0.88925 -2.12655 0.88928002 -2.12656004 0 P 0 ;0
L 0.88928002 -2.12656004 0.88931998 -2.12658002 0 P 0 ;0
L 0.88931998 -2.12658002 0.8894 -2.12658002 0 P 0 ;0
L 0.8894 -2.12658002 0.89648002 -2.12686998 0 P 0 ;0
L 0.89648002 -2.12686998 0.90518996 -2.1271 0 P 0 ;0
L 0.90518996 -2.1271 0.9165 -2.12716004 0 P 0 ;0
L 0.9165 -2.12716004 0.94403996 -2.12716004 0 P 0 ;0
L 0.94403996 -2.12716004 0.94468996 -2.10135 0 P 0 ;0
L 0.94468996 -2.10135 0.9461 -2.07171998 0 P 0 ;0
L 0.9461 -2.07171998 0.94713002 -2.06233002 0 P 0 ;0
L 0.94713002 -2.06233002 0.9489 -2.05308002 0 P 0 ;0
L 0.9489 -2.05308002 0.94975 -2.04995 0 P 0 ;0
L 0.94975 -2.04995 0.9508 -2.04688996 0 P 0 ;0
L 0.9508 -2.04688996 0.95205 -2.0439 0 P 0 ;0
L 0.95205 -2.0439 0.95351004 -2.041 0 P 0 ;0
L 0.95351004 -2.041 0.9544 -2.03951004 0 P 0 ;0
L 0.9544 -2.03951004 0.95541998 -2.03811004 0 P 0 ;0
L 0.95541998 -2.03811004 0.95655 -2.03678996 0 P 0 ;0
L 0.95655 -2.03678996 0.95778996 -2.03556998 0 P 0 ;0
L 0.95778996 -2.03556998 0.95911998 -2.03446998 0 P 0 ;0
L 0.95911998 -2.03446998 0.96056998 -2.03346998 0 P 0 ;0
L 0.96056998 -2.03346998 0.96151004 -2.03291004 0 P 0 ;0
L 0.96151004 -2.03291004 0.96248996 -2.03243002 0 P 0 ;0
L 0.96248996 -2.03243002 0.96351004 -2.03201998 0 P 0 ;0
L 0.96351004 -2.03201998 0.96455 -2.03168996 0 P 0 ;0
L 0.96455 -2.03168996 0.96613002 -2.0313 0 P 0 ;0
L 0.96613002 -2.0313 0.96773002 -2.03101998 0 P 0 ;0
L 0.96773002 -2.03101998 0.96935 -2.03086004 0 P 0 ;0
L 0.96935 -2.03086004 0.97095 -2.03081004 0 P 0 ;0
L 0.97095 -2.03081004 0.97255 -2.03086998 0 P 0 ;0
L 0.97255 -2.03086998 0.97413002 -2.03105 0 P 0 ;0
L 0.97413002 -2.03105 0.97513002 -2.03123996 0 P 0 ;0
L 0.97513002 -2.03123996 0.9761 -2.03151004 0 P 0 ;0
L 0.9761 -2.03151004 0.97706004 -2.03186004 0 P 0 ;0
L 0.97706004 -2.03186004 0.97796998 -2.0323 0 P 0 ;0
L 0.97796998 -2.0323 0.97885 -2.0328 0 P 0 ;0
L 0.97885 -2.0328 0.97968002 -2.03336998 0 P 0 ;0
L 0.97968002 -2.03336998 0.98046998 -2.03398996 0 P 0 ;0
L 0.98046998 -2.03398996 0.98121998 -2.03468002 0 P 0 ;0
L 0.98121998 -2.03468002 0.98191004 -2.03541998 0 P 0 ;0
L 0.98191004 -2.03541998 0.98253996 -2.0362 0 P 0 ;0
L 0.98253996 -2.0362 0.9831 -2.03703002 0 P 0 ;0
L 0.9831 -2.03703002 0.9836 -2.03788996 0 P 0 ;0
L 0.9836 -2.03788996 0.98403996 -2.0388 0 P 0 ;0
L 0.98403996 -2.0388 0.9844 -2.03973996 0 P 0 ;0
L 0.9844 -2.03973996 0.98505 -2.04188996 0 P 0 ;0
L 0.98505 -2.04188996 0.98553002 -2.04408002 0 P 0 ;0
L 0.98553002 -2.04408002 0.98583002 -2.0463 0 P 0 ;0
L 0.98583002 -2.0463 0.98653002 -2.05705 0 P 0 ;0
L 0.98653002 -2.05705 0.9866 -2.06961004 0 P 0 ;0
L 0.9866 -2.06961004 0.98596004 -2.08908002 0 P 0 ;0
L 0.98596004 -2.08908002 0.98498002 -2.10858002 0 P 0 ;0
L 0.98498002 -2.10858002 0.98388002 -2.12146998 0 P 0 ;0
L 0.98388002 -2.12146998 0.98323002 -2.12716004 0 P 0 ;0
L 0.98323002 -2.12716004 1.03741004 -2.12716004 0 P 0 ;0
L 1.03741004 -2.12716004 1.03896004 -2.09103002 0 P 0 ;0
L 1.03896004 -2.09103002 1.03956004 -2.0759 0 P 0 ;0
L 1.03956004 -2.0759 1.04005 -2.06025 0 P 0 ;0
L 1.04005 -2.06025 1.04038996 -2.04626004 0 P 0 ;0
L 1.04038996 -2.04626004 1.04048002 -2.03698996 0 P 0 ;0
L 1.04048002 -2.03698996 1.04036998 -2.02651998 0 P 0 ;0
L 1.04036998 -2.02651998 1.04003996 -2.02096998 0 P 0 ;0
L 1.04003996 -2.02096998 1.03975 -2.01895 0 P 0 ;0
L 1.03975 -2.01895 1.0393 -2.01693996 0 P 0 ;0
L 1.0393 -2.01693996 1.03868996 -2.01483996 0 P 0 ;0
L 1.03868996 -2.01483996 1.03793996 -2.01278002 0 P 0 ;0
L 1.03793996 -2.01278002 1.03658996 -2.00968002 0 P 0 ;0
L 1.03658996 -2.00968002 1.03501004 -2.00668996 0 P 0 ;0
L 1.03501004 -2.00668996 1.0332 -2.0038 0 P 0 ;0
L 1.0332 -2.0038 1.03186998 -2.002 0 P 0 ;0
L 1.03186998 -2.002 1.0304 -2.0003 0 P 0 ;0
L 1.0304 -2.0003 1.0288 -1.99873002 0 P 0 ;0
L 1.0288 -1.99873002 1.02708002 -1.99728996 0 P 0 ;0
L 1.02708002 -1.99728996 1.02518002 -1.99593002 0 P 0 ;0
L 1.02518002 -1.99593002 1.02318002 -1.99471998 0 P 0 ;0
L 1.02318002 -1.99471998 1.0211 -1.99365 0 P 0 ;0
L 1.0211 -1.99365 1.01893002 -1.99273996 0 P 0 ;0
L 1.01893002 -1.99273996 1.01358996 -1.99098996 0 P 0 ;0
L 1.01358996 -1.99098996 1.0081 -1.98971004 0 P 0 ;0
L 1.0081 -1.98971004 1.00428996 -1.98908996 0 P 0 ;0
L 1.00428996 -1.98908996 1.00043996 -1.98868002 0 P 0 ;0
L 1.00043996 -1.98868002 0.99138002 -1.98826004 0 P 0 ;0
L 0.99138002 -1.98826004 0.98251998 -1.98846998 0 P 0 ;0
L 0.98251998 -1.98846998 0.97898996 -1.98878996 0 P 0 ;0
L 0.97898996 -1.98878996 0.97546998 -1.98933996 0 P 0 ;0
L 0.91651004 -2.12516004 0.94208996 -2.12516004 0 P 0 ;0
L 0.8911 -2.12416004 0.94211004 -2.12416004 0 P 0 ;0
L 0.89118002 -2.12316004 0.94213996 -2.12316004 0 P 0 ;0
L 0.89125 -2.12216004 0.94216004 -2.12216004 0 P 0 ;0
L 0.89133002 -2.12116004 0.94218996 -2.12116004 0 P 0 ;0
L 0.89141004 -2.12016004 0.94221004 -2.12016004 0 P 0 ;0
L 0.89148996 -2.11916004 0.94223996 -2.11916004 0 P 0 ;0
L 0.89156998 -2.11816004 0.94226998 -2.11816004 0 P 0 ;0
L 0.89166004 -2.11716004 0.94228996 -2.11716004 0 P 0 ;0
L 0.89173996 -2.11616004 0.94231004 -2.11616004 0 P 0 ;0
L 0.89181998 -2.11516004 0.94233996 -2.11516004 0 P 0 ;0
L 0.8919 -2.11416004 0.94236004 -2.11416004 0 P 0 ;0
L 0.89198002 -2.11316004 0.94238996 -2.11316004 0 P 0 ;0
L 0.89206998 -2.11216004 0.94241998 -2.11216004 0 P 0 ;0
L 0.89215 -2.11116004 0.94243996 -2.11116004 0 P 0 ;0
L 0.89223002 -2.11016004 0.94246998 -2.11016004 0 P 0 ;0
L 0.89231998 -2.10916004 0.94248996 -2.10916004 0 P 0 ;0
L 0.8924 -2.10816004 0.94251998 -2.10816004 0 P 0 ;0
L 0.89248002 -2.10716004 0.94255 -2.10716004 0 P 0 ;0
L 0.89256998 -2.10616004 0.94256998 -2.10616004 0 P 0 ;0
L 0.89263996 -2.10516004 0.94258996 -2.10516004 0 P 0 ;0
L 0.89271004 -2.10416004 0.94261998 -2.10416004 0 P 0 ;0
L 0.89278996 -2.10316004 0.94263996 -2.10316004 0 P 0 ;0
L 0.89286998 -2.10216004 0.94266998 -2.10216004 0 P 0 ;0
L 0.89293996 -2.10116004 0.9427 -2.10116004 0 P 0 ;0
L 0.89301998 -2.10016004 0.94275 -2.10016004 0 P 0 ;0
L 0.89308996 -2.09916004 0.94278996 -2.09916004 0 P 0 ;0
L 0.89316998 -2.09816004 0.94283996 -2.09816004 0 P 0 ;0
L 0.89325 -2.09716004 0.94288996 -2.09716004 0 P 0 ;0
L 0.89331998 -2.09616004 0.94293996 -2.09616004 0 P 0 ;0
L 0.8934 -2.09516004 0.94298002 -2.09516004 0 P 0 ;0
L 0.89346998 -2.09416004 0.94303002 -2.09416004 0 P 0 ;0
L 0.89355 -2.09316004 0.94308002 -2.09316004 0 P 0 ;0
L 0.89361998 -2.09216004 0.94313002 -2.09216004 0 P 0 ;0
L 0.8937 -2.09116004 0.94318002 -2.09116004 0 P 0 ;0
L 0.89378002 -2.09016004 0.94321998 -2.09016004 0 P 0 ;0
L 0.89385 -2.08916004 0.94326998 -2.08916004 0 P 0 ;0
L 0.89393002 -2.08816004 0.94331998 -2.08816004 0 P 0 ;0
L 0.894 -2.08716004 0.94336004 -2.08716004 0 P 0 ;0
L 0.89406004 -2.08616004 0.94341004 -2.08616004 0 P 0 ;0
L 0.89411998 -2.08516004 0.94346004 -2.08516004 0 P 0 ;0
L 0.89418002 -2.08416004 0.94351004 -2.08416004 0 P 0 ;0
L 0.91651004 -2.12516004 0.90521998 -2.1251 0 P 0 ;0
L 0.90521998 -2.1251 0.89655 -2.12486998 0 P 0 ;0
L 0.89655 -2.12486998 0.89106004 -2.12465 0 P 0 ;0
L 0.89106004 -2.12465 0.89141998 -2.12003996 0 P 0 ;0
L 0.89141998 -2.12003996 0.89193996 -2.11373996 0 P 0 ;0
L 0.89193996 -2.11373996 0.89253996 -2.10645 0 P 0 ;0
L 0.89253996 -2.10645 0.89398002 -2.08741998 0 P 0 ;0
L 0.89398002 -2.08741998 0.89521998 -2.06621998 0 P 0 ;0
L 0.89521998 -2.06621998 0.89521998 -2.06618996 0 P 0 ;0
L 0.89521998 -2.06618996 0.89623996 -2.04323002 0 P 0 ;0
L 0.89623996 -2.04323002 0.89703996 -2.01883002 0 P 0 ;0
L 0.89703996 -2.01883002 0.8977 -1.99443996 0 P 0 ;0
L 0.8977 -1.99443996 0.94563996 -1.99443996 0 P 0 ;0
L 0.94563996 -1.99443996 0.94563996 -2.00546998 0 P 0 ;0
L 0.94563996 -2.00546998 0.94686004 -2.00731004 0 P 0 ;0
L 0.94686004 -2.00731004 0.94903002 -2.00688996 0 P 0 ;0
L 0.94903002 -2.00688996 0.95361998 -2.00241004 0 P 0 ;0
L 0.95361998 -2.00241004 0.95498996 -2.00115 0 P 0 ;0
L 0.95498996 -2.00115 0.95641998 -2.00001004 0 P 0 ;0
L 0.95641998 -2.00001004 0.9579 -1.99896004 0 P 0 ;0
L 0.9579 -1.99896004 0.96076004 -1.9972 0 P 0 ;0
L 0.96076004 -1.9972 0.9637 -1.99561998 0 P 0 ;0
L 0.9637 -1.99561998 0.96683002 -1.99416998 0 P 0 ;0
L 0.96683002 -1.99416998 0.96998996 -1.99291998 0 P 0 ;0
L 0.96998996 -1.99291998 0.9729 -1.99198996 0 P 0 ;0
L 0.9729 -1.99198996 0.97586004 -1.9913 0 P 0 ;0
L 0.97586004 -1.9913 0.97923002 -1.99076998 0 P 0 ;0
L 0.97923002 -1.99076998 0.98263002 -1.99046998 0 P 0 ;0
L 0.98263002 -1.99046998 0.99136004 -1.99026004 0 P 0 ;0
L 0.99136004 -1.99026004 1.00028996 -1.99066998 0 P 0 ;0
L 1.00028996 -1.99066998 1.00403002 -1.99108002 0 P 0 ;0
L 1.00403002 -1.99108002 1.00771004 -1.99166998 0 P 0 ;0
L 1.00771004 -1.99166998 1.01305 -1.99291998 0 P 0 ;0
L 1.01305 -1.99291998 1.01823002 -1.99461998 0 P 0 ;0
L 1.01823002 -1.99461998 1.02026004 -1.99546998 0 P 0 ;0
L 1.02026004 -1.99546998 1.02221004 -1.99646998 0 P 0 ;0
L 1.02221004 -1.99646998 1.02408002 -1.9976 0 P 0 ;0
L 1.02408002 -1.9976 1.02585 -1.99886998 0 P 0 ;0
L 1.02585 -1.99886998 1.02746004 -2.00021004 0 P 0 ;0
L 1.02746004 -2.00021004 1.02893996 -2.00166998 0 P 0 ;0
L 1.02893996 -2.00166998 1.03031004 -2.00325 0 P 0 ;0
L 1.03031004 -2.00325 1.03155 -2.00493002 0 P 0 ;0
L 1.03155 -2.00493002 1.03326998 -2.00768002 0 P 0 ;0
L 1.03326998 -2.00768002 1.03478002 -2.01055 0 P 0 ;0
L 1.03478002 -2.01055 1.03608002 -2.01351998 0 P 0 ;0
L 1.03608002 -2.01351998 1.03678996 -2.01546998 0 P 0 ;0
L 1.03678996 -2.01546998 1.03736004 -2.01743002 0 P 0 ;0
L 1.03736004 -2.01743002 1.03778002 -2.0193 0 P 0 ;0
L 1.03778002 -2.0193 1.03805 -2.02116998 0 P 0 ;0
L 1.03805 -2.02116998 1.03836998 -2.02658996 0 P 0 ;0
L 1.03836998 -2.02658996 1.03848002 -2.03698996 0 P 0 ;0
L 1.03848002 -2.03698996 1.03838996 -2.04623002 0 P 0 ;0
L 1.03838996 -2.04623002 1.03805 -2.06018996 0 P 0 ;0
L 1.03805 -2.06018996 1.03756004 -2.07583002 0 P 0 ;0
L 1.03756004 -2.07583002 1.03696998 -2.09095 0 P 0 ;0
L 1.03696998 -2.09095 1.03548996 -2.12516004 0 P 0 ;0
L 1.03548996 -2.12516004 0.98546998 -2.12516004 0 P 0 ;0
L 0.98546998 -2.12516004 0.98586998 -2.12166004 0 P 0 ;0
L 0.98586998 -2.12166004 0.98696998 -2.10871998 0 P 0 ;0
L 0.98696998 -2.10871998 0.98796004 -2.08916004 0 P 0 ;0
L 0.98796004 -2.08916004 0.9886 -2.06963002 0 P 0 ;0
L 0.9886 -2.06963002 0.98853002 -2.05698002 0 P 0 ;0
L 0.98853002 -2.05698002 0.98781998 -2.0461 0 P 0 ;0
L 0.98781998 -2.0461 0.9875 -2.04373002 0 P 0 ;0
L 0.9875 -2.04373002 0.98748002 -2.04365 0 P 0 ;0
L 0.98748002 -2.04365 0.98698996 -2.04138996 0 P 0 ;0
L 0.98698996 -2.04138996 0.9863 -2.03908002 0 P 0 ;0
L 0.9863 -2.03908002 0.98588002 -2.038 0 P 0 ;0
L 0.98588002 -2.038 0.98538002 -2.03696004 0 P 0 ;0
L 0.98538002 -2.03696004 0.9848 -2.03596004 0 P 0 ;0
L 0.9848 -2.03596004 0.98413996 -2.03501004 0 P 0 ;0
L 0.98413996 -2.03501004 0.98341998 -2.03411004 0 P 0 ;0
L 0.98341998 -2.03411004 0.98336998 -2.03405 0 P 0 ;0
L 0.98336998 -2.03405 0.98263002 -2.03326004 0 P 0 ;0
L 0.98263002 -2.03326004 0.98176998 -2.03246998 0 P 0 ;0
L 0.98176998 -2.03246998 0.98086998 -2.03175 0 P 0 ;0
L 0.98086998 -2.03175 0.97991004 -2.0311 0 P 0 ;0
L 0.97991004 -2.0311 0.9789 -2.03051998 0 P 0 ;0
L 0.9789 -2.03051998 0.97783002 -2.03001998 0 P 0 ;0
L 0.97783002 -2.03001998 0.97673002 -2.02961004 0 P 0 ;0
L 0.97673002 -2.02961004 0.97663996 -2.02958002 0 P 0 ;0
L 0.97663996 -2.02958002 0.97558996 -2.02928996 0 P 0 ;0
L 0.97558996 -2.02928996 0.97443002 -2.02906998 0 P 0 ;0
L 0.97443002 -2.02906998 0.9727 -2.02888002 0 P 0 ;0
L 0.9727 -2.02888002 0.97261998 -2.02886998 0 P 0 ;0
L 0.97261998 -2.02886998 0.97096004 -2.02881004 0 P 0 ;0
L 0.97096004 -2.02881004 0.96921004 -2.02886004 0 P 0 ;0
L 0.96921004 -2.02886004 0.96745 -2.02903996 0 P 0 ;0
L 0.96745 -2.02903996 0.96571004 -2.02933996 0 P 0 ;0
L 0.96571004 -2.02933996 0.964 -2.02976004 0 P 0 ;0
L 0.964 -2.02976004 0.96283002 -2.03013996 0 P 0 ;0
L 0.96283002 -2.03013996 0.96168002 -2.0306 0 P 0 ;0
L 0.96168002 -2.0306 0.96056998 -2.03115 0 P 0 ;0
L 0.96056998 -2.03115 0.95948996 -2.03178002 0 P 0 ;0
L 0.95948996 -2.03178002 0.95791004 -2.03286998 0 P 0 ;0
L 0.95791004 -2.03286998 0.95645 -2.03408996 0 P 0 ;0
L 0.95645 -2.03408996 0.95508996 -2.03541998 0 P 0 ;0
L 0.95508996 -2.03541998 0.95383996 -2.03686998 0 P 0 ;0
L 0.95383996 -2.03686998 0.9538 -2.03693002 0 P 0 ;0
L 0.9538 -2.03693002 0.95273002 -2.03841004 0 P 0 ;0
L 0.95273002 -2.03841004 0.95175 -2.04003996 0 P 0 ;0
L 0.95175 -2.04003996 0.95023002 -2.04306004 0 P 0 ;0
L 0.95023002 -2.04306004 0.94896004 -2.04611004 0 P 0 ;0
L 0.94896004 -2.04611004 0.94893002 -2.04616998 0 P 0 ;0
L 0.94893002 -2.04616998 0.94783002 -2.04936004 0 P 0 ;0
L 0.94783002 -2.04936004 0.94695 -2.05263002 0 P 0 ;0
L 0.94695 -2.05263002 0.94515 -2.06203002 0 P 0 ;0
L 0.94515 -2.06203002 0.9441 -2.07156004 0 P 0 ;0
L 0.9441 -2.07156004 0.9427 -2.10128002 0 P 0 ;0
L 0.9427 -2.10128002 0.94208996 -2.12516004 0 P 0 ;0
L 0.94208996 -2.12516004 0.91651004 -2.12516004 0 P 0 ;0
L 0.93143002 -2.21261998 1.00578996 -2.21261998 0 P 0 ;0
L 0.94051004 -2.21161998 1.00803002 -2.21161998 0 P 0 ;0
L 0.94941998 -2.21061998 1.01026004 -2.21061998 0 P 0 ;0
L 0.9555 -2.20961998 1.0125 -2.20961998 0 P 0 ;0
L 0.96158002 -2.20861998 1.01473996 -2.20861998 0 P 0 ;0
L 0.96766004 -2.20761998 1.01696998 -2.20761998 0 P 0 ;0
L 0.97373002 -2.20661998 1.01921004 -2.20661998 0 P 0 ;0
L 0.97981004 -2.20561998 1.02145 -2.20561998 0 P 0 ;0
L 0.98498996 -2.20461998 1.02368996 -2.20461998 0 P 0 ;0
L 0.98973996 -2.20361998 1.02591998 -2.20361998 0 P 0 ;0
L 0.99448996 -2.20261998 1.02816004 -2.20261998 0 P 0 ;0
L 0.99923996 -2.20161998 1.0304 -2.20161998 0 P 0 ;0
L 1.00398996 -2.20061998 1.03243996 -2.20061998 0 P 0 ;0
L 1.00875 -2.19961998 1.0344 -2.19961998 0 P 0 ;0
L 1.01348996 -2.19861998 1.03636998 -2.19861998 0 P 0 ;0
L 1.0178 -2.19761998 1.03833996 -2.19761998 0 P 0 ;0
L 1.02168996 -2.19661998 1.04031004 -2.19661998 0 P 0 ;0
L 1.02558002 -2.19561998 1.04228002 -2.19561998 0 P 0 ;0
L 1.02946998 -2.19461998 1.04415 -2.19461998 0 P 0 ;0
L 1.03336004 -2.19361998 1.04596998 -2.19361998 0 P 0 ;0
L 1.03725 -2.19261998 1.04778996 -2.19261998 0 P 0 ;0
L 1.04113996 -2.19161998 1.0496 -2.19161998 0 P 0 ;0
L 1.14356998 -1.98926998 1.13261004 -1.99086004 0 P 0 ;0
L 1.13261004 -1.99086004 1.12165 -1.9934 0 P 0 ;0
L 1.12165 -1.9934 1.11125 -1.99673002 0 P 0 ;0
L 1.11125 -1.99673002 1.10658002 -1.99858996 0 P 0 ;0
L 1.10658002 -1.99858996 1.10198996 -2.00071004 0 P 0 ;0
L 1.10198996 -2.00071004 1.09653002 -2.00358996 0 P 0 ;0
L 1.09653002 -2.00358996 1.09436998 -2.00488996 0 P 0 ;0
L 1.09436998 -2.00488996 1.09226004 -2.00631004 0 P 0 ;0
L 1.09226004 -2.00631004 1.09028002 -2.00781004 0 P 0 ;0
L 1.09028002 -2.00781004 1.08836998 -2.00941998 0 P 0 ;0
L 1.08836998 -2.00941998 1.08405 -2.0135 0 P 0 ;0
L 1.08405 -2.0135 1.08096998 -2.01678996 0 P 0 ;0
L 1.08096998 -2.01678996 1.07808002 -2.02026998 0 P 0 ;0
L 1.07808002 -2.02026998 1.0754 -2.02393002 0 P 0 ;0
L 1.0754 -2.02393002 1.07313996 -2.02748002 0 P 0 ;0
L 1.07313996 -2.02748002 1.07116004 -2.03118996 0 P 0 ;0
L 1.07116004 -2.03118996 1.06943996 -2.03505 0 P 0 ;0
L 1.06943996 -2.03505 1.06795 -2.03918996 0 P 0 ;0
L 1.06795 -2.03918996 1.06673996 -2.04343996 0 P 0 ;0
L 1.06673996 -2.04343996 1.06583002 -2.04778002 0 P 0 ;0
L 1.06583002 -2.04778002 1.06476998 -2.05538996 0 P 0 ;0
L 1.06476998 -2.05538996 1.06421004 -2.06306004 0 P 0 ;0
L 1.06421004 -2.06306004 1.06415 -2.07076004 0 P 0 ;0
L 1.06415 -2.07076004 1.06456998 -2.0785 0 P 0 ;0
L 1.06456998 -2.0785 1.06508996 -2.08276004 0 P 0 ;0
L 1.06508996 -2.08276004 1.06591004 -2.08696004 0 P 0 ;0
L 1.06591004 -2.08696004 1.06703002 -2.09108002 0 P 0 ;0
L 1.06703002 -2.09108002 1.06833002 -2.09473002 0 P 0 ;0
L 1.06833002 -2.09473002 1.06991998 -2.09823996 0 P 0 ;0
L 1.06991998 -2.09823996 1.0718 -2.10161998 0 P 0 ;0
L 1.0718 -2.10161998 1.07398002 -2.10491998 0 P 0 ;0
L 1.07398002 -2.10491998 1.07641998 -2.10803002 0 P 0 ;0
L 1.07641998 -2.10803002 1.07908996 -2.11095 0 P 0 ;0
L 1.07908996 -2.11095 1.08175 -2.11345 0 P 0 ;0
L 1.08175 -2.11345 1.08458996 -2.11573996 0 P 0 ;0
L 1.08458996 -2.11573996 1.08758996 -2.1178 0 P 0 ;0
L 1.08758996 -2.1178 1.09073002 -2.11963996 0 P 0 ;0
L 1.09073002 -2.11963996 1.094 -2.12123996 0 P 0 ;0
L 1.094 -2.12123996 1.0986 -2.12306998 0 P 0 ;0
L 1.0986 -2.12306998 1.10331004 -2.12456004 0 P 0 ;0
L 1.10331004 -2.12456004 1.10811004 -2.12568996 0 P 0 ;0
L 1.10811004 -2.12568996 1.11298002 -2.12646998 0 P 0 ;0
L 1.11298002 -2.12646998 1.1182 -2.12693002 0 P 0 ;0
L 1.1182 -2.12693002 1.12343996 -2.12703002 0 P 0 ;0
L 1.12343996 -2.12703002 1.12866998 -2.12676004 0 P 0 ;0
L 1.12866998 -2.12676004 1.13388002 -2.12613002 0 P 0 ;0
L 1.13388002 -2.12613002 1.14086004 -2.12473996 0 P 0 ;0
L 1.14086004 -2.12473996 1.1477 -2.12273996 0 P 0 ;0
L 1.1477 -2.12273996 1.15433996 -2.12015 0 P 0 ;0
L 1.15433996 -2.12015 1.1545 -2.12008996 0 P 0 ;0
L 1.1545 -2.12008996 1.15466004 -2.12003996 0 P 0 ;0
L 1.15466004 -2.12003996 1.15483002 -2.12001004 0 P 0 ;0
L 1.15483002 -2.12001004 1.15498996 -2.11998996 0 P 0 ;0
L 1.15498996 -2.11998996 1.15533002 -2.11998996 0 P 0 ;0
L 1.15533002 -2.11998996 1.15538996 -2.12 0 P 0 ;0
L 1.15538996 -2.12 1.15545 -2.12001998 0 P 0 ;0
L 1.15545 -2.12001998 1.15551004 -2.12003002 0 P 0 ;0
L 1.15551004 -2.12003002 1.15556004 -2.12006004 0 P 0 ;0
L 1.15556004 -2.12006004 1.15561004 -2.12008002 0 P 0 ;0
L 1.15561004 -2.12008002 1.15566004 -2.12011004 0 P 0 ;0
L 1.15566004 -2.12011004 1.15571004 -2.12015 0 P 0 ;0
L 1.15571004 -2.12015 1.15575 -2.12018996 0 P 0 ;0
L 1.15575 -2.12018996 1.15578996 -2.12023996 0 P 0 ;0
L 1.15578996 -2.12023996 1.15583002 -2.12028002 0 P 0 ;0
L 1.15583002 -2.12028002 1.15586004 -2.12033996 0 P 0 ;0
L 1.15586004 -2.12033996 1.15588002 -2.12038996 0 P 0 ;0
L 1.15588002 -2.12038996 1.15591004 -2.12043996 0 P 0 ;0
L 1.15591004 -2.12043996 1.15601998 -2.12076004 0 P 0 ;0
L 1.15601998 -2.12076004 1.1561 -2.12108002 0 P 0 ;0
L 1.1561 -2.12108002 1.15616004 -2.12141998 0 P 0 ;0
L 1.15616004 -2.12141998 1.15618002 -2.12175 0 P 0 ;0
L 1.15618002 -2.12175 1.15623996 -2.12505 0 P 0 ;0
L 1.15623996 -2.12505 1.15616004 -2.12688002 0 P 0 ;0
L 1.15616004 -2.12688002 1.15593002 -2.12871004 0 P 0 ;0
L 1.15593002 -2.12871004 1.15553996 -2.13051998 0 P 0 ;0
L 1.15553996 -2.13051998 1.15516004 -2.1318 0 P 0 ;0
L 1.15516004 -2.1318 1.1547 -2.13305 0 P 0 ;0
L 1.1547 -2.13305 1.15415 -2.13426004 0 P 0 ;0
L 1.15415 -2.13426004 1.15351004 -2.13545 0 P 0 ;0
L 1.15351004 -2.13545 1.15278996 -2.1366 0 P 0 ;0
L 1.15278996 -2.1366 1.15198002 -2.13768996 0 P 0 ;0
L 1.15198002 -2.13768996 1.15111004 -2.13873002 0 P 0 ;0
L 1.15111004 -2.13873002 1.15016004 -2.13971004 0 P 0 ;0
L 1.15016004 -2.13971004 1.14876004 -2.14096004 0 P 0 ;0
L 1.14876004 -2.14096004 1.14726004 -2.1421 0 P 0 ;0
L 1.14726004 -2.1421 1.14566998 -2.14311004 0 P 0 ;0
L 1.14566998 -2.14311004 1.144 -2.144 0 P 0 ;0
L 1.144 -2.144 1.14226004 -2.14476004 0 P 0 ;0
L 1.14226004 -2.14476004 1.14046004 -2.14536998 0 P 0 ;0
L 1.14046004 -2.14536998 1.13863002 -2.14583002 0 P 0 ;0
L 1.13863002 -2.14583002 1.13676004 -2.14613996 0 P 0 ;0
L 1.13676004 -2.14613996 1.13041998 -2.14663996 0 P 0 ;0
L 1.13041998 -2.14663996 1.12403996 -2.1466 0 P 0 ;0
L 1.12403996 -2.1466 1.11621998 -2.14593996 0 P 0 ;0
L 1.11621998 -2.14593996 1.10843996 -2.14471004 0 P 0 ;0
L 1.10843996 -2.14471004 1.09946998 -2.14276998 0 P 0 ;0
L 1.09946998 -2.14276998 1.0905 -2.14041004 0 P 0 ;0
L 1.0905 -2.14041004 1.07963996 -2.13728996 0 P 0 ;0
L 1.07963996 -2.13728996 1.07936004 -2.1401 0 P 0 ;0
L 1.07936004 -2.1401 1.07931004 -2.14103996 0 P 0 ;0
L 1.07931004 -2.14103996 1.07931998 -2.14198002 0 P 0 ;0
L 1.07931998 -2.14198002 1.07956998 -2.14735 0 P 0 ;0
L 1.07956998 -2.14735 1.07993996 -2.15375 0 P 0 ;0
L 1.07993996 -2.15375 1.08045 -2.16081998 0 P 0 ;0
L 1.08045 -2.16081998 1.08181004 -2.17873002 0 P 0 ;0
L 1.08181004 -2.17873002 1.08996004 -2.18061004 0 P 0 ;0
L 1.08996004 -2.18061004 1.09951004 -2.18246004 0 P 0 ;0
L 1.09951004 -2.18246004 1.11243996 -2.18416998 0 P 0 ;0
L 1.11243996 -2.18416998 1.1254 -2.18543002 0 P 0 ;0
L 1.1254 -2.18543002 1.13508002 -2.18583002 0 P 0 ;0
L 1.13508002 -2.18583002 1.14765 -2.18528996 0 P 0 ;0
L 1.14765 -2.18528996 1.15368002 -2.18461004 0 P 0 ;0
L 1.15368002 -2.18461004 1.15971004 -2.18363996 0 P 0 ;0
L 1.15971004 -2.18363996 1.16521004 -2.18248002 0 P 0 ;0
L 1.16521004 -2.18248002 1.17063996 -2.18103002 0 P 0 ;0
L 1.17063996 -2.18103002 1.17528996 -2.17946998 0 P 0 ;0
L 1.17528996 -2.17946998 1.17978002 -2.17753996 0 P 0 ;0
L 1.17978002 -2.17753996 1.18216998 -2.1763 0 P 0 ;0
L 1.18216998 -2.1763 1.18446004 -2.17488996 0 P 0 ;0
L 1.18446004 -2.17488996 1.18663996 -2.17331004 0 P 0 ;0
L 1.18663996 -2.17331004 1.18871004 -2.17156004 0 P 0 ;0
L 1.18871004 -2.17156004 1.19161004 -2.16871998 0 P 0 ;0
L 1.19161004 -2.16871998 1.19431004 -2.16568996 0 P 0 ;0
L 1.19431004 -2.16568996 1.19678996 -2.16246998 0 P 0 ;0
L 1.19678996 -2.16246998 1.19908996 -2.15901998 0 P 0 ;0
L 1.19908996 -2.15901998 1.20113996 -2.15543996 0 P 0 ;0
L 1.20113996 -2.15543996 1.20295 -2.15171004 0 P 0 ;0
L 1.20295 -2.15171004 1.20435 -2.14815 0 P 0 ;0
L 1.20435 -2.14815 1.20543996 -2.14448996 0 P 0 ;0
L 1.20543996 -2.14448996 1.20621004 -2.14073996 0 P 0 ;0
L 1.20621004 -2.14073996 1.20651998 -2.13855 0 P 0 ;0
L 1.20651998 -2.13855 1.20671998 -2.13633996 0 P 0 ;0
L 1.20671998 -2.13633996 1.20761998 -2.12321004 0 P 0 ;0
L 1.20761998 -2.12321004 1.20858002 -2.10753996 0 P 0 ;0
L 1.20858002 -2.10753996 1.20951004 -2.09021998 0 P 0 ;0
L 1.20951004 -2.09021998 1.21048002 -2.07166004 0 P 0 ;0
L 1.21048002 -2.07166004 1.21156004 -2.05228002 0 P 0 ;0
L 1.21156004 -2.05228002 1.21258002 -2.03478996 0 P 0 ;0
L 1.21258002 -2.03478996 1.21333002 -2.02286004 0 P 0 ;0
L 1.21333002 -2.02286004 1.21393996 -2.01373996 0 P 0 ;0
L 1.21393996 -2.01373996 1.21443996 -2.00568996 0 P 0 ;0
L 1.21443996 -2.00568996 1.21485 -1.99883996 0 P 0 ;0
L 1.21485 -1.99883996 1.2149 -1.99721004 0 P 0 ;0
L 1.2149 -1.99721004 1.21488996 -1.99703996 0 P 0 ;0
L 1.21488996 -1.99703996 1.21486998 -1.99686004 0 P 0 ;0
L 1.21486998 -1.99686004 1.21483996 -1.99668996 0 P 0 ;0
L 1.21483996 -1.99668996 1.21478996 -1.99653002 0 P 0 ;0
L 1.21478996 -1.99653002 1.21473002 -1.99636998 0 P 0 ;0
L 1.21473002 -1.99636998 1.21466004 -1.99621004 0 P 0 ;0
L 1.21466004 -1.99621004 1.21458002 -1.99606004 0 P 0 ;0
L 1.21458002 -1.99606004 1.21448002 -1.99591004 0 P 0 ;0
L 1.21448002 -1.99591004 1.21433002 -1.99571998 0 P 0 ;0
L 1.21433002 -1.99571998 1.21416998 -1.99553996 0 P 0 ;0
L 1.21416998 -1.99553996 1.21398996 -1.99538002 0 P 0 ;0
L 1.21398996 -1.99538002 1.21378996 -1.99523996 0 P 0 ;0
L 1.21378996 -1.99523996 1.21358002 -1.99511004 0 P 0 ;0
L 1.21358002 -1.99511004 1.21336004 -1.995 0 P 0 ;0
L 1.21336004 -1.995 1.21261004 -1.99468996 0 P 0 ;0
L 1.21261004 -1.99468996 1.21183996 -1.99443996 0 P 0 ;0
L 1.21183996 -1.99443996 1.21105 -1.99423002 0 P 0 ;0
L 1.21105 -1.99423002 1.20593996 -1.99318002 0 P 0 ;0
L 1.20593996 -1.99318002 1.18996998 -1.99065 0 P 0 ;0
L 1.18996998 -1.99065 1.17318996 -1.98908002 0 P 0 ;0
L 1.17318996 -1.98908002 1.15718996 -1.98858002 0 P 0 ;0
L 1.15718996 -1.98858002 1.1504 -1.98876004 0 P 0 ;0
L 1.1504 -1.98876004 1.14356998 -1.98926998 0 P 0 ;0
L 1.04503996 -2.19061998 1.05141998 -2.19061998 0 P 0 ;0
L 1.04893002 -2.18961998 1.05323002 -2.18961998 0 P 0 ;0
L 1.05263002 -2.18861998 1.05503996 -2.18861998 0 P 0 ;0
L 1.05628996 -2.18761998 1.05676004 -2.18761998 0 P 0 ;0
L 1.09645 -2.17983002 1.16738002 -2.17983002 0 P 0 ;0
L 1.09126004 -2.17883002 1.17091004 -2.17883002 0 P 0 ;0
L 1.0868 -2.17783002 1.17386998 -2.17783002 0 P 0 ;0
L 1.08368002 -2.17683002 1.17636004 -2.17683002 0 P 0 ;0
L 1.0836 -2.17583002 1.1787 -2.17583002 0 P 0 ;0
L 1.08351998 -2.17483002 1.18066998 -2.17483002 0 P 0 ;0
L 1.08345 -2.17383002 1.18236998 -2.17383002 0 P 0 ;0
L 1.08336998 -2.17283002 1.1839 -2.17283002 0 P 0 ;0
L 1.08328996 -2.17183002 1.18526998 -2.17183002 0 P 0 ;0
L 1.08321998 -2.17083002 1.18646998 -2.17083002 0 P 0 ;0
L 1.08313996 -2.16983002 1.18761998 -2.16983002 0 P 0 ;0
L 1.08306998 -2.16883002 1.18863996 -2.16883002 0 P 0 ;0
L 1.08298996 -2.16783002 1.18966004 -2.16783002 0 P 0 ;0
L 1.08291998 -2.16683002 1.19061004 -2.16683002 0 P 0 ;0
L 1.08283996 -2.16583002 1.1915 -2.16583002 0 P 0 ;0
L 1.08276004 -2.16483002 1.19238996 -2.16483002 0 P 0 ;0
L 1.08268996 -2.16383002 1.19321004 -2.16383002 0 P 0 ;0
L 1.08261004 -2.16283002 1.19398002 -2.16283002 0 P 0 ;0
L 1.08253002 -2.16183002 1.19476004 -2.16183002 0 P 0 ;0
L 1.08246004 -2.16083002 1.19548002 -2.16083002 0 P 0 ;0
L 1.08238002 -2.15983002 1.19613996 -2.15983002 0 P 0 ;0
L 1.08231004 -2.15883002 1.19681004 -2.15883002 0 P 0 ;0
L 1.08223996 -2.15783002 1.19746004 -2.15783002 0 P 0 ;0
L 1.13506998 -2.18383002 1.12553002 -2.18343996 0 P 0 ;0
L 1.12553002 -2.18343996 1.11266004 -2.18218002 0 P 0 ;0
L 1.11266004 -2.18218002 1.09983002 -2.18048002 0 P 0 ;0
L 1.09983002 -2.18048002 1.09036998 -2.17866004 0 P 0 ;0
L 1.09036998 -2.17866004 1.0837 -2.17711004 0 P 0 ;0
L 1.0837 -2.17711004 1.08245 -2.16066998 0 P 0 ;0
L 1.08245 -2.16066998 1.08193996 -2.15361998 0 P 0 ;0
L 1.08193996 -2.15361998 1.08156998 -2.14726004 0 P 0 ;0
L 1.08156998 -2.14726004 1.08131998 -2.14191004 0 P 0 ;0
L 1.08131998 -2.14191004 1.08131004 -2.14108996 0 P 0 ;0
L 1.08131004 -2.14108996 1.08136004 -2.14026004 0 P 0 ;0
L 1.08136004 -2.14026004 1.0814 -2.13986998 0 P 0 ;0
L 1.0814 -2.13986998 1.08996004 -2.14233002 0 P 0 ;0
L 1.08996004 -2.14233002 1.08996998 -2.14233996 0 P 0 ;0
L 1.08996998 -2.14233996 1.08998996 -2.14233996 0 P 0 ;0
L 1.08998996 -2.14233996 1.099 -2.14471998 0 P 0 ;0
L 1.099 -2.14471998 1.10806998 -2.14668002 0 P 0 ;0
L 1.10806998 -2.14668002 1.11598002 -2.14791998 0 P 0 ;0
L 1.11598002 -2.14791998 1.12395 -2.1486 0 P 0 ;0
L 1.12395 -2.1486 1.13048996 -2.14863996 0 P 0 ;0
L 1.13048996 -2.14863996 1.137 -2.14811998 0 P 0 ;0
L 1.137 -2.14811998 1.13903002 -2.14778996 0 P 0 ;0
L 1.13903002 -2.14778996 1.14103002 -2.14728996 0 P 0 ;0
L 1.14103002 -2.14728996 1.14298002 -2.14661998 0 P 0 ;0
L 1.14298002 -2.14661998 1.14486998 -2.14581004 0 P 0 ;0
L 1.14486998 -2.14581004 1.14668002 -2.14483996 0 P 0 ;0
L 1.14668002 -2.14483996 1.1484 -2.14373996 0 P 0 ;0
L 1.1484 -2.14373996 1.15003002 -2.1425 0 P 0 ;0
L 1.15003002 -2.1425 1.15155 -2.14115 0 P 0 ;0
L 1.15155 -2.14115 1.1526 -2.14006998 0 P 0 ;0
L 1.1526 -2.14006998 1.15263996 -2.14001998 0 P 0 ;0
L 1.15263996 -2.14001998 1.15356004 -2.13893002 0 P 0 ;0
L 1.15356004 -2.13893002 1.15443996 -2.13771998 0 P 0 ;0
L 1.15443996 -2.13771998 1.15523002 -2.13646004 0 P 0 ;0
L 1.15523002 -2.13646004 1.15593996 -2.13515 0 P 0 ;0
L 1.15593996 -2.13515 1.15655 -2.13381004 0 P 0 ;0
L 1.15655 -2.13381004 1.15706004 -2.13243002 0 P 0 ;0
L 1.15706004 -2.13243002 1.15748002 -2.13101004 0 P 0 ;0
L 1.15748002 -2.13101004 1.1579 -2.12905 0 P 0 ;0
L 1.1579 -2.12905 1.15816004 -2.12706004 0 P 0 ;0
L 1.15816004 -2.12706004 1.15825 -2.12506998 0 P 0 ;0
L 1.15825 -2.12506998 1.15818002 -2.12165 0 P 0 ;0
L 1.15818002 -2.12165 1.15813996 -2.12118002 0 P 0 ;0
L 1.15813996 -2.12118002 1.15813002 -2.1211 0 P 0 ;0
L 1.15813002 -2.1211 1.15806004 -2.12068002 0 P 0 ;0
L 1.15806004 -2.12068002 1.15793996 -2.12018996 0 P 0 ;0
L 1.15793996 -2.12018996 1.15778002 -2.11973002 0 P 0 ;0
L 1.15778002 -2.11973002 1.1577 -2.11953002 0 P 0 ;0
L 1.1577 -2.11953002 1.15758996 -2.11933002 0 P 0 ;0
L 1.15758996 -2.11933002 1.15746998 -2.11913996 0 P 0 ;0
L 1.15746998 -2.11913996 1.15733002 -2.11895 0 P 0 ;0
L 1.15733002 -2.11895 1.15716998 -2.11878002 0 P 0 ;0
L 1.15716998 -2.11878002 1.157 -2.11863002 0 P 0 ;0
L 1.157 -2.11863002 1.15681998 -2.11848996 0 P 0 ;0
L 1.15681998 -2.11848996 1.15663002 -2.11836004 0 P 0 ;0
L 1.15663002 -2.11836004 1.15641998 -2.11825 0 P 0 ;0
L 1.15641998 -2.11825 1.15621004 -2.11816004 0 P 0 ;0
L 1.15621004 -2.11816004 1.15598996 -2.11808996 0 P 0 ;0
L 1.15598996 -2.11808996 1.15576998 -2.11803996 0 P 0 ;0
L 1.15576998 -2.11803996 1.15553002 -2.118 0 P 0 ;0
L 1.15553002 -2.118 1.15518002 -2.11798002 0 P 0 ;0
L 1.15518002 -2.11798002 1.15483996 -2.11798996 0 P 0 ;0
L 1.15483996 -2.11798996 1.15451004 -2.11803002 0 P 0 ;0
L 1.15451004 -2.11803002 1.15418002 -2.1181 0 P 0 ;0
L 1.15418002 -2.1181 1.15386004 -2.1182 0 P 0 ;0
L 1.15386004 -2.1182 1.15361004 -2.11828996 0 P 0 ;0
L 1.15361004 -2.11828996 1.14705 -2.12083996 0 P 0 ;0
L 1.14705 -2.12083996 1.14038996 -2.12278996 0 P 0 ;0
L 1.14038996 -2.12278996 1.13356004 -2.12416004 0 P 0 ;0
L 1.13356004 -2.12416004 1.1285 -2.12476998 0 P 0 ;0
L 1.1285 -2.12476998 1.12341004 -2.12501998 0 P 0 ;0
L 1.12341004 -2.12501998 1.11831004 -2.12493002 0 P 0 ;0
L 1.11831004 -2.12493002 1.11323002 -2.12448996 0 P 0 ;0
L 1.11323002 -2.12448996 1.10848996 -2.12373002 0 P 0 ;0
L 1.10848996 -2.12373002 1.10383996 -2.12263002 0 P 0 ;0
L 1.10383996 -2.12263002 1.09926998 -2.12118996 0 P 0 ;0
L 1.09926998 -2.12118996 1.09481004 -2.11941004 0 P 0 ;0
L 1.09481004 -2.11941004 1.09168002 -2.11788002 0 P 0 ;0
L 1.09168002 -2.11788002 1.08866004 -2.11611998 0 P 0 ;0
L 1.08866004 -2.11611998 1.08578002 -2.11413002 0 P 0 ;0
L 1.08578002 -2.11413002 1.08306998 -2.11193996 0 P 0 ;0
L 1.08306998 -2.11193996 1.08051998 -2.10955 0 P 0 ;0
L 1.08051998 -2.10955 1.07793996 -2.10673002 0 P 0 ;0
L 1.07793996 -2.10673002 1.07561004 -2.10373996 0 P 0 ;0
L 1.07561004 -2.10373996 1.07351004 -2.10058002 0 P 0 ;0
L 1.07351004 -2.10058002 1.07171004 -2.09733996 0 P 0 ;0
L 1.07171004 -2.09733996 1.07018002 -2.09396998 0 P 0 ;0
L 1.07018002 -2.09396998 1.06893996 -2.09048002 0 P 0 ;0
L 1.06893996 -2.09048002 1.06786004 -2.0865 0 P 0 ;0
L 1.06786004 -2.0865 1.06706004 -2.08243996 0 P 0 ;0
L 1.06706004 -2.08243996 1.06656004 -2.07833002 0 P 0 ;0
L 1.06656004 -2.07833002 1.06615 -2.07071004 0 P 0 ;0
L 1.06615 -2.07071004 1.06621004 -2.06313996 0 P 0 ;0
L 1.06621004 -2.06313996 1.06675 -2.0556 0 P 0 ;0
L 1.06675 -2.0556 1.0678 -2.04813002 0 P 0 ;0
L 1.0678 -2.04813002 1.06868996 -2.04391998 0 P 0 ;0
L 1.06868996 -2.04391998 1.06985 -2.03981004 0 P 0 ;0
L 1.06985 -2.03981004 1.0713 -2.03578996 0 P 0 ;0
L 1.0713 -2.03578996 1.07296004 -2.03206998 0 P 0 ;0
L 1.07296004 -2.03206998 1.07486998 -2.02848996 0 P 0 ;0
L 1.07486998 -2.02848996 1.07705 -2.02506004 0 P 0 ;0
L 1.07705 -2.02506004 1.07966004 -2.0215 0 P 0 ;0
L 1.07966004 -2.0215 1.08246998 -2.01811004 0 P 0 ;0
L 1.08246998 -2.01811004 1.08546998 -2.01491004 0 P 0 ;0
L 1.08546998 -2.01491004 1.0897 -2.01091004 0 P 0 ;0
L 1.0897 -2.01091004 1.09153002 -2.00936998 0 P 0 ;0
L 1.09153002 -2.00936998 1.09341998 -2.00793996 0 P 0 ;0
L 1.09341998 -2.00793996 1.09545 -2.00658002 0 P 0 ;0
L 1.09545 -2.00658002 1.09751004 -2.00533996 0 P 0 ;0
L 1.09751004 -2.00533996 1.10288002 -2.0025 0 P 0 ;0
L 1.10288002 -2.0025 1.10736998 -2.00043002 0 P 0 ;0
L 1.10736998 -2.00043002 1.11193002 -1.99861004 0 P 0 ;0
L 1.11193002 -1.99861004 1.12218002 -1.99533002 0 P 0 ;0
L 1.12218002 -1.99533002 1.13298002 -1.99281998 0 P 0 ;0
L 1.13298002 -1.99281998 1.14378996 -1.99126004 0 P 0 ;0
L 1.14378996 -1.99126004 1.1505 -1.99075 0 P 0 ;0
L 1.1505 -1.99075 1.15718002 -1.99058996 0 P 0 ;0
L 1.15718002 -1.99058996 1.17306998 -1.99108002 0 P 0 ;0
L 1.17306998 -1.99108002 1.18971998 -1.99263002 0 P 0 ;0
L 1.18971998 -1.99263002 1.20558002 -1.99515 0 P 0 ;0
L 1.20558002 -1.99515 1.21058996 -1.99618002 0 P 0 ;0
L 1.21058996 -1.99618002 1.21126998 -1.99636004 0 P 0 ;0
L 1.21126998 -1.99636004 1.21191998 -1.99656998 0 P 0 ;0
L 1.21191998 -1.99656998 1.21253002 -1.99681998 0 P 0 ;0
L 1.21253002 -1.99681998 1.21261004 -1.99686004 0 P 0 ;0
L 1.21261004 -1.99686004 1.21266004 -1.99688996 0 P 0 ;0
L 1.21266004 -1.99688996 1.21271998 -1.99693002 0 P 0 ;0
L 1.21271998 -1.99693002 1.21281998 -1.99703002 0 P 0 ;0
L 1.21281998 -1.99703002 1.21286004 -1.99708996 0 P 0 ;0
L 1.21286004 -1.99708996 1.21288002 -1.99711004 0 P 0 ;0
L 1.21288002 -1.99711004 1.21288002 -1.99711998 0 P 0 ;0
L 1.21288002 -1.99711998 1.21288996 -1.99715 0 P 0 ;0
L 1.21288996 -1.99715 1.2129 -1.99716998 0 P 0 ;0
L 1.2129 -1.99716998 1.2129 -1.99721998 0 P 0 ;0
L 1.2129 -1.99721998 1.21285 -1.99875 0 P 0 ;0
L 1.21285 -1.99875 1.21243996 -2.00556998 0 P 0 ;0
L 1.21243996 -2.00556998 1.21193996 -2.01361004 0 P 0 ;0
L 1.21193996 -2.01361004 1.21133996 -2.02273002 0 P 0 ;0
L 1.21133996 -2.02273002 1.21133996 -2.02273996 0 P 0 ;0
L 1.21133996 -2.02273996 1.21058996 -2.03468002 0 P 0 ;0
L 1.21058996 -2.03468002 1.20956004 -2.05216998 0 P 0 ;0
L 1.20956004 -2.05216998 1.20848996 -2.07156004 0 P 0 ;0
L 1.20848996 -2.07156004 1.20848996 -2.07156998 0 P 0 ;0
L 1.20848996 -2.07156998 1.20751004 -2.09011004 0 P 0 ;0
L 1.20751004 -2.09011004 1.20658996 -2.10743996 0 P 0 ;0
L 1.20658996 -2.10743996 1.20561998 -2.12308996 0 P 0 ;0
L 1.20561998 -2.12308996 1.20473002 -2.13618996 0 P 0 ;0
L 1.20473002 -2.13618996 1.20453002 -2.13831998 0 P 0 ;0
L 1.20453002 -2.13831998 1.20423996 -2.14041004 0 P 0 ;0
L 1.20423996 -2.14041004 1.2035 -2.144 0 P 0 ;0
L 1.2035 -2.144 1.20246004 -2.1475 0 P 0 ;0
L 1.20246004 -2.1475 1.20111998 -2.1509 0 P 0 ;0
L 1.20111998 -2.1509 1.19936998 -2.1545 0 P 0 ;0
L 1.19936998 -2.1545 1.19738002 -2.15796998 0 P 0 ;0
L 1.19738002 -2.15796998 1.19516004 -2.1613 0 P 0 ;0
L 1.19516004 -2.1613 1.19276998 -2.16441004 0 P 0 ;0
L 1.19276998 -2.16441004 1.19016004 -2.16733996 0 P 0 ;0
L 1.19016004 -2.16733996 1.18736004 -2.17008002 0 P 0 ;0
L 1.18736004 -2.17008002 1.1854 -2.17173996 0 P 0 ;0
L 1.1854 -2.17173996 1.18335 -2.17323002 0 P 0 ;0
L 1.18335 -2.17323002 1.18118002 -2.17456004 0 P 0 ;0
L 1.18118002 -2.17456004 1.17893002 -2.17573002 0 P 0 ;0
L 1.17893002 -2.17573002 1.17456998 -2.1776 0 P 0 ;0
L 1.17456998 -2.1776 1.17006998 -2.17911998 0 P 0 ;0
L 1.17006998 -2.17911998 1.16473996 -2.18053002 0 P 0 ;0
L 1.16473996 -2.18053002 1.15935 -2.18166998 0 P 0 ;0
L 1.15935 -2.18166998 1.15341998 -2.18263002 0 P 0 ;0
L 1.15341998 -2.18263002 1.1475 -2.18328996 0 P 0 ;0
L 1.1475 -2.18328996 1.13506998 -2.18383002 0 P 0 ;0
L 0.90491998 -2.21461998 1.00131004 -2.21461998 0 P 0 ;0
L 0.92235 -2.21361998 1.00355 -2.21361998 0 P 0 ;0
L 0.76925 -1.8965 0.85586998 -1.8965 0 P 0 ;0
L 0.76958996 -1.8955 0.85556004 -1.8955 0 P 0 ;0
L 0.76995 -1.8945 0.85521004 -1.8945 0 P 0 ;0
L 0.77031004 -1.8935 0.85486004 -1.8935 0 P 0 ;0
L 0.77071004 -1.8925 0.85443996 -1.8925 0 P 0 ;0
L 0.77115 -1.8915 0.85401004 -1.8915 0 P 0 ;0
L 0.7716 -1.8905 0.85355 -1.8905 0 P 0 ;0
L 0.77206004 -1.8895 0.85303002 -1.8895 0 P 0 ;0
L 0.7726 -1.8885 0.85251004 -1.8885 0 P 0 ;0
L 0.77313996 -1.8875 0.85198996 -1.8875 0 P 0 ;0
L 0.77368996 -1.8865 0.85138002 -1.8865 0 P 0 ;0
L 0.77433002 -1.8855 0.85073996 -1.8855 0 P 0 ;0
L 0.77496004 -1.8845 0.85011004 -1.8845 0 P 0 ;0
L 0.77561998 -1.8835 0.84943002 -1.8835 0 P 0 ;0
L 0.77636004 -1.8825 0.84866998 -1.8825 0 P 0 ;0
L 0.77711004 -1.8815 0.84791004 -1.8815 0 P 0 ;0
L 0.7779 -1.8805 0.84713002 -1.8805 0 P 0 ;0
L 0.77876998 -1.8795 0.84623002 -1.8795 0 P 0 ;0
L 0.77963996 -1.8785 0.84533002 -1.8785 0 P 0 ;0
L 0.7806 -1.8775 0.8444 -1.8775 0 P 0 ;0
L 0.78161004 -1.8765 0.84335 -1.8765 0 P 0 ;0
L 0.78265 -1.8755 0.84228996 -1.8755 0 P 0 ;0
L 0.78381998 -1.8745 0.84108996 -1.8745 0 P 0 ;0
L 0.78498996 -1.8735 0.83986998 -1.8735 0 P 0 ;0
L 0.78635 -1.8725 0.83848002 -1.8725 0 P 0 ;0
L 0.78773002 -1.8715 0.83706004 -1.8715 0 P 0 ;0
L 0.78933002 -1.8705 0.83541998 -1.8705 0 P 0 ;0
L 0.791 -1.8695 0.83366004 -1.8695 0 P 0 ;0
L 0.793 -1.8685 0.83171998 -1.8685 0 P 0 ;0
L 0.79525 -1.8675 0.82941998 -1.8675 0 P 0 ;0
L 0.79791998 -1.8665 0.82671004 -1.8665 0 P 0 ;0
L 0.80143996 -1.8655 0.82328996 -1.8655 0 P 0 ;0
L 0.80705 -1.8645 0.81776004 -1.8645 0 P 0 ;0
L 0.74543002 -1.89661998 0.75033002 -1.89661998 0 P 0 ;0
L 0.74751004 -1.89561998 0.75058996 -1.89561998 0 P 0 ;0
L 0.74958996 -1.89461998 0.75086004 -1.89461998 0 P 0 ;0
L 0.76733996 -1.9125 0.85751998 -1.9125 0 P 0 ;0
L 0.76728996 -1.9115 0.85756004 -1.9115 0 P 0 ;0
L 0.76723996 -1.9105 0.85758996 -1.9105 0 P 0 ;0
L 0.76721998 -1.9095 0.85763002 -1.9095 0 P 0 ;0
L 0.76725 -1.9085 0.85761004 -1.9085 0 P 0 ;0
L 0.76728002 -1.9075 0.85756998 -1.9075 0 P 0 ;0
L 0.76731004 -1.9065 0.85753002 -1.9065 0 P 0 ;0
L 0.76741998 -1.9055 0.85748996 -1.9055 0 P 0 ;0
L 0.76753996 -1.9045 0.85738002 -1.9045 0 P 0 ;0
L 0.76766004 -1.9035 0.85726004 -1.9035 0 P 0 ;0
L 0.76781998 -1.9025 0.85713996 -1.9025 0 P 0 ;0
L 0.76801998 -1.9015 0.85701004 -1.9015 0 P 0 ;0
L 0.76821004 -1.9005 0.85683002 -1.9005 0 P 0 ;0
L 0.76841998 -1.8995 0.85661998 -1.8995 0 P 0 ;0
L 0.7687 -1.8985 0.85641004 -1.8985 0 P 0 ;0
L 0.76896998 -1.8975 0.85613996 -1.8975 0 P 0 ;0
L 0.76751004 -2.08325 0.8416 -2.08325 0 P 0 ;0
L 0.76761998 -2.08225 0.84161998 -2.08225 0 P 0 ;0
L 0.76773996 -2.08125 0.84166998 -2.08125 0 P 0 ;0
L 0.76786004 -2.08025 0.84171998 -2.08025 0 P 0 ;0
L 0.76796998 -2.07925 0.84176998 -2.07925 0 P 0 ;0
L 0.76808002 -2.07825 0.84181004 -2.07825 0 P 0 ;0
L 0.76818002 -2.07725 0.84186004 -2.07725 0 P 0 ;0
L 0.76828996 -2.07625 0.8419 -2.07625 0 P 0 ;0
L 0.76838996 -2.07525 0.84195 -2.07525 0 P 0 ;0
L 0.76848996 -2.07425 0.842 -2.07425 0 P 0 ;0
L 0.7686 -2.07325 0.84205 -2.07325 0 P 0 ;0
L 0.7687 -2.07225 0.84208996 -2.07225 0 P 0 ;0
L 0.7688 -2.07125 0.84213996 -2.07125 0 P 0 ;0
L 0.7689 -2.07025 0.84218002 -2.07025 0 P 0 ;0
L 0.76901004 -2.06925 0.84223002 -2.06925 0 P 0 ;0
L 0.76911004 -2.06825 0.84228002 -2.06825 0 P 0 ;0
L 0.76921004 -2.06725 0.84233002 -2.06725 0 P 0 ;0
L 0.76931998 -2.06625 0.84236998 -2.06625 0 P 0 ;0
L 0.76941998 -2.06525 0.84241998 -2.06525 0 P 0 ;0
L 0.76948996 -2.06425 0.84246004 -2.06425 0 P 0 ;0
L 0.76956004 -2.06325 0.84251004 -2.06325 0 P 0 ;0
L 0.76963002 -2.06225 0.84256004 -2.06225 0 P 0 ;0
L 0.7697 -2.06125 0.8426 -2.06125 0 P 0 ;0
L 0.76976998 -2.06025 0.84265 -2.06025 0 P 0 ;0
L 0.76983996 -2.05925 0.8427 -2.05925 0 P 0 ;0
L 0.76991004 -2.05825 0.84273996 -2.05825 0 P 0 ;0
L 0.76996998 -2.05725 0.84278996 -2.05725 0 P 0 ;0
L 0.77001004 -2.05625 0.84283996 -2.05625 0 P 0 ;0
L 0.77003996 -2.05525 0.84288002 -2.05525 0 P 0 ;0
L 0.77008002 -2.05425 0.84295 -2.05425 0 P 0 ;0
L 0.77011998 -2.05325 0.84303996 -2.05325 0 P 0 ;0
L 0.77016004 -2.05225 0.84311998 -2.05225 0 P 0 ;0
L 0.77018996 -2.05125 0.84321004 -2.05125 0 P 0 ;0
L 0.77023002 -2.05025 0.8433 -2.05025 0 P 0 ;0
L 0.77026998 -2.04925 0.84338002 -2.04925 0 P 0 ;0
L 0.77031004 -2.04825 0.84346998 -2.04825 0 P 0 ;0
L 0.77033996 -2.04725 0.84356004 -2.04725 0 P 0 ;0
L 0.77038002 -2.04625 0.84363996 -2.04625 0 P 0 ;0
L 0.77041004 -2.04525 0.84373002 -2.04525 0 P 0 ;0
L 0.77043996 -2.04425 0.84381004 -2.04425 0 P 0 ;0
L 0.77046004 -2.04325 0.8439 -2.04325 0 P 0 ;0
L 0.77048002 -2.04225 0.84398996 -2.04225 0 P 0 ;0
L 0.77051004 -2.04125 0.84406998 -2.04125 0 P 0 ;0
L 0.77053002 -2.04025 0.84416004 -2.04025 0 P 0 ;0
L 0.77055 -2.03925 0.84425 -2.03925 0 P 0 ;0
L 0.77058002 -2.03825 0.84433002 -2.03825 0 P 0 ;0
L 0.7706 -2.03725 0.84441998 -2.03725 0 P 0 ;0
L 0.77061998 -2.03625 0.84451004 -2.03625 0 P 0 ;0
L 0.77065 -2.03525 0.84458996 -2.03525 0 P 0 ;0
L 0.77066998 -2.03425 0.84468002 -2.03425 0 P 0 ;0
L 0.7707 -2.03325 0.84476998 -2.03325 0 P 0 ;0
L 0.77071998 -2.03225 0.84485 -2.03225 0 P 0 ;0
L 0.77073002 -2.03125 0.84493996 -2.03125 0 P 0 ;0
L 0.77073996 -2.03025 0.84503002 -2.03025 0 P 0 ;0
L 0.79986004 -1.8638 0.79643996 -1.86486998 0 P 0 ;0
L 0.79643996 -1.86486998 0.79311998 -1.86621004 0 P 0 ;0
L 0.79311998 -1.86621004 0.78991004 -1.86781004 0 P 0 ;0
L 0.78991004 -1.86781004 0.78683996 -1.86966998 0 P 0 ;0
L 0.78683996 -1.86966998 0.78391998 -1.87178002 0 P 0 ;0
L 0.78391998 -1.87178002 0.78111998 -1.87416998 0 P 0 ;0
L 0.78111998 -1.87416998 0.7785 -1.87676004 0 P 0 ;0
L 0.7785 -1.87676004 0.77608002 -1.87953996 0 P 0 ;0
L 0.77608002 -1.87953996 0.77386998 -1.8825 0 P 0 ;0
L 0.77386998 -1.8825 0.77188002 -1.88561998 0 P 0 ;0
L 0.77188002 -1.88561998 0.77013996 -1.88886004 0 P 0 ;0
L 0.77013996 -1.88886004 0.76863996 -1.89221004 0 P 0 ;0
L 0.76863996 -1.89221004 0.7674 -1.89566998 0 P 0 ;0
L 0.7674 -1.89566998 0.76643002 -1.89921004 0 P 0 ;0
L 0.76643002 -1.89921004 0.76571004 -1.90283996 0 P 0 ;0
L 0.76571004 -1.90283996 0.76531004 -1.90636004 0 P 0 ;0
L 0.76531004 -1.90636004 0.7652 -1.90991004 0 P 0 ;0
L 0.7652 -1.90991004 0.76538996 -1.91345 0 P 0 ;0
L 0.76538996 -1.91345 0.76586998 -1.91696998 0 P 0 ;0
L 0.76586998 -1.91696998 0.76663996 -1.92046004 0 P 0 ;0
L 0.76663996 -1.92046004 0.76803002 -1.92493996 0 P 0 ;0
L 0.76803002 -1.92493996 0.76978002 -1.9293 0 P 0 ;0
L 0.76978002 -1.9293 0.77106998 -1.93193996 0 P 0 ;0
L 0.77106998 -1.93193996 0.77253002 -1.93448002 0 P 0 ;0
L 0.77253002 -1.93448002 0.77416004 -1.93693996 0 P 0 ;0
L 0.77416004 -1.93693996 0.77593002 -1.93923002 0 P 0 ;0
L 0.77593002 -1.93923002 0.77783996 -1.94141004 0 P 0 ;0
L 0.77783996 -1.94141004 0.77988996 -1.94345 0 P 0 ;0
L 0.77988996 -1.94345 0.78216004 -1.94545 0 P 0 ;0
L 0.78216004 -1.94545 0.78453996 -1.9473 0 P 0 ;0
L 0.78453996 -1.9473 0.78703002 -1.94901998 0 P 0 ;0
L 0.78703002 -1.94901998 0.79016998 -1.95088002 0 P 0 ;0
L 0.79016998 -1.95088002 0.79343996 -1.95248996 0 P 0 ;0
L 0.79343996 -1.95248996 0.79683002 -1.95383996 0 P 0 ;0
L 0.79683002 -1.95383996 0.80031998 -1.95491998 0 P 0 ;0
L 0.80031998 -1.95491998 0.80391004 -1.95573996 0 P 0 ;0
L 0.80391004 -1.95573996 0.80751998 -1.95626004 0 P 0 ;0
L 0.80751998 -1.95626004 0.81116004 -1.9565 0 P 0 ;0
L 0.81116004 -1.9565 0.81481004 -1.95646004 0 P 0 ;0
L 0.81481004 -1.95646004 0.81843996 -1.95613002 0 P 0 ;0
L 0.81843996 -1.95613002 0.82205 -1.95551004 0 P 0 ;0
L 0.82205 -1.95551004 0.82561998 -1.95461004 0 P 0 ;0
L 0.82561998 -1.95461004 0.82911004 -1.95345 0 P 0 ;0
L 0.82911004 -1.95345 0.83248996 -1.95201004 0 P 0 ;0
L 0.83248996 -1.95201004 0.83576004 -1.95031998 0 P 0 ;0
L 0.83576004 -1.95031998 0.83891998 -1.94836004 0 P 0 ;0
L 0.83891998 -1.94836004 0.84191998 -1.94616998 0 P 0 ;0
L 0.84191998 -1.94616998 0.84475 -1.94375 0 P 0 ;0
L 0.84475 -1.94375 0.84738996 -1.94113996 0 P 0 ;0
L 0.84738996 -1.94113996 0.84983002 -1.93833996 0 P 0 ;0
L 0.84983002 -1.93833996 0.85206998 -1.93533996 0 P 0 ;0
L 0.85206998 -1.93533996 0.8536 -1.93291998 0 P 0 ;0
L 0.8536 -1.93291998 0.85496004 -1.93041004 0 P 0 ;0
L 0.85496004 -1.93041004 0.85613996 -1.9278 0 P 0 ;0
L 0.85613996 -1.9278 0.85711998 -1.92511004 0 P 0 ;0
L 0.85711998 -1.92511004 0.85823002 -1.92123002 0 P 0 ;0
L 0.85823002 -1.92123002 0.85901998 -1.91726998 0 P 0 ;0
L 0.85901998 -1.91726998 0.85948996 -1.91323996 0 P 0 ;0
L 0.85948996 -1.91323996 0.85963996 -1.90918002 0 P 0 ;0
L 0.85963996 -1.90918002 0.85946998 -1.90513002 0 P 0 ;0
L 0.85946998 -1.90513002 0.85898002 -1.9011 0 P 0 ;0
L 0.85898002 -1.9011 0.85841998 -1.89826004 0 P 0 ;0
L 0.85841998 -1.89826004 0.85766004 -1.89546004 0 P 0 ;0
L 0.85766004 -1.89546004 0.85671004 -1.89273002 0 P 0 ;0
L 0.85671004 -1.89273002 0.85556998 -1.89006004 0 P 0 ;0
L 0.85556998 -1.89006004 0.85361998 -1.88631004 0 P 0 ;0
L 0.85361998 -1.88631004 0.85136004 -1.88273996 0 P 0 ;0
L 0.85136004 -1.88273996 0.84881004 -1.87938002 0 P 0 ;0
L 0.84881004 -1.87938002 0.84596998 -1.87623002 0 P 0 ;0
L 0.84596998 -1.87623002 0.84355 -1.87393996 0 P 0 ;0
L 0.84355 -1.87393996 0.84096998 -1.87181998 0 P 0 ;0
L 0.84096998 -1.87181998 0.83826004 -1.86988996 0 P 0 ;0
L 0.83826004 -1.86988996 0.83541004 -1.86815 0 P 0 ;0
L 0.83541004 -1.86815 0.83243996 -1.86661004 0 P 0 ;0
L 0.83243996 -1.86661004 0.82938996 -1.86531004 0 P 0 ;0
L 0.82938996 -1.86531004 0.82625 -1.86423002 0 P 0 ;0
L 0.82625 -1.86423002 0.82303996 -1.86336004 0 P 0 ;0
L 0.82303996 -1.86336004 0.81978002 -1.86273002 0 P 0 ;0
L 0.81978002 -1.86273002 0.81646998 -1.86233002 0 P 0 ;0
L 0.81646998 -1.86233002 0.81228996 -1.86215 0 P 0 ;0
L 0.81228996 -1.86215 0.80811004 -1.86233996 0 P 0 ;0
L 0.80811004 -1.86233996 0.80396004 -1.86288996 0 P 0 ;0
L 0.80396004 -1.86288996 0.79986004 -1.8638 0 P 0 ;0
L 0.80308996 -1.9535 0.82186004 -1.9535 0 P 0 ;0
L 0.79926004 -1.9525 0.82563996 -1.9525 0 P 0 ;0
L 0.79636004 -1.9515 0.82856998 -1.9515 0 P 0 ;0
L 0.79393002 -1.9505 0.83093996 -1.9505 0 P 0 ;0
L 0.7919 -1.9495 0.83298996 -1.9495 0 P 0 ;0
L 0.79008002 -1.9485 0.8349 -1.9485 0 P 0 ;0
L 0.78838996 -1.9475 0.83651004 -1.9475 0 P 0 ;0
L 0.7869 -1.9465 0.83806998 -1.9465 0 P 0 ;0
L 0.78548002 -1.9455 0.83943996 -1.9455 0 P 0 ;0
L 0.7842 -1.9445 0.84078996 -1.9445 0 P 0 ;0
L 0.78298002 -1.9435 0.84196998 -1.9435 0 P 0 ;0
L 0.78183996 -1.9425 0.84313996 -1.9425 0 P 0 ;0
L 0.78076998 -1.9415 0.84418996 -1.9415 0 P 0 ;0
L 0.77976004 -1.9405 0.8452 -1.9405 0 P 0 ;0
L 0.77883002 -1.9395 0.84616998 -1.9395 0 P 0 ;0
L 0.77793996 -1.9385 0.84703996 -1.9385 0 P 0 ;0
L 0.77711998 -1.9375 0.84791004 -1.9375 0 P 0 ;0
L 0.77635 -1.9365 0.84871004 -1.9365 0 P 0 ;0
L 0.77561004 -1.9355 0.84945 -1.9355 0 P 0 ;0
L 0.77493996 -1.9345 0.8502 -1.9345 0 P 0 ;0
L 0.77428002 -1.9335 0.85086998 -1.9335 0 P 0 ;0
L 0.7737 -1.9325 0.8515 -1.9325 0 P 0 ;0
L 0.77311998 -1.9315 0.8521 -1.9315 0 P 0 ;0
L 0.77258996 -1.9305 0.85263996 -1.9305 0 P 0 ;0
L 0.7721 -1.9295 0.85318002 -1.9295 0 P 0 ;0
L 0.77161004 -1.9285 0.85363002 -1.9285 0 P 0 ;0
L 0.77121004 -1.9275 0.85408002 -1.9275 0 P 0 ;0
L 0.77081004 -1.9265 0.85448002 -1.9265 0 P 0 ;0
L 0.77041004 -1.9255 0.85485 -1.9255 0 P 0 ;0
L 0.77001004 -1.9245 0.85521998 -1.9245 0 P 0 ;0
L 0.76968002 -1.9235 0.8555 -1.9235 0 P 0 ;0
L 0.76936998 -1.9225 0.85578996 -1.9225 0 P 0 ;0
L 0.76906004 -1.9215 0.85606998 -1.9215 0 P 0 ;0
L 0.76875 -1.9205 0.85633002 -1.9205 0 P 0 ;0
L 0.76848002 -1.9195 0.85653002 -1.9195 0 P 0 ;0
L 0.76826004 -1.9185 0.85673002 -1.9185 0 P 0 ;0
L 0.76803002 -1.9175 0.85693002 -1.9175 0 P 0 ;0
L 0.76783002 -1.9165 0.85708996 -1.9165 0 P 0 ;0
L 0.76768996 -1.9155 0.85721004 -1.9155 0 P 0 ;0
L 0.76755 -1.9145 0.85733002 -1.9145 0 P 0 ;0
L 0.76741998 -1.9135 0.85745 -1.9135 0 P 0 ;0
L 0.81121004 -1.9545 0.80773002 -1.95426998 0 P 0 ;0
L 0.80773002 -1.95426998 0.80426998 -1.95376998 0 P 0 ;0
L 0.80426998 -1.95376998 0.80083996 -1.95298996 0 P 0 ;0
L 0.80083996 -1.95298996 0.7975 -1.95195 0 P 0 ;0
L 0.7975 -1.95195 0.79426004 -1.95066004 0 P 0 ;0
L 0.79426004 -1.95066004 0.79111998 -1.94911998 0 P 0 ;0
L 0.79111998 -1.94911998 0.78811004 -1.94733002 0 P 0 ;0
L 0.78811004 -1.94733002 0.78573002 -1.94568996 0 P 0 ;0
L 0.78573002 -1.94568996 0.78343996 -1.9439 0 P 0 ;0
L 0.78343996 -1.9439 0.78126004 -1.94198996 0 P 0 ;0
L 0.78126004 -1.94198996 0.7793 -1.94003996 0 P 0 ;0
L 0.7793 -1.94003996 0.77746998 -1.93796004 0 P 0 ;0
L 0.77746998 -1.93796004 0.77578996 -1.93576998 0 P 0 ;0
L 0.77578996 -1.93576998 0.77423002 -1.93343002 0 P 0 ;0
L 0.77423002 -1.93343002 0.77283996 -1.931 0 P 0 ;0
L 0.77283996 -1.931 0.77161004 -1.92848996 0 P 0 ;0
L 0.77161004 -1.92848996 0.76991998 -1.92426998 0 P 0 ;0
L 0.76991998 -1.92426998 0.76858002 -1.91993996 0 P 0 ;0
L 0.76858002 -1.91993996 0.76783996 -1.91661998 0 P 0 ;0
L 0.76783996 -1.91661998 0.76738002 -1.91326998 0 P 0 ;0
L 0.76738002 -1.91326998 0.76721004 -1.90988996 0 P 0 ;0
L 0.76721004 -1.90988996 0.76731004 -1.90651004 0 P 0 ;0
L 0.76731004 -1.90651004 0.7677 -1.90315 0 P 0 ;0
L 0.7677 -1.90315 0.76838002 -1.89966998 0 P 0 ;0
L 0.76838002 -1.89966998 0.76931004 -1.89626998 0 P 0 ;0
L 0.76931004 -1.89626998 0.7705 -1.89296004 0 P 0 ;0
L 0.7705 -1.89296004 0.77193996 -1.88973996 0 P 0 ;0
L 0.77193996 -1.88973996 0.7736 -1.88663996 0 P 0 ;0
L 0.7736 -1.88663996 0.77551004 -1.88363996 0 P 0 ;0
L 0.77551004 -1.88363996 0.77763002 -1.8808 0 P 0 ;0
L 0.77763002 -1.8808 0.77996004 -1.87813002 0 P 0 ;0
L 0.77996004 -1.87813002 0.78246998 -1.87565 0 P 0 ;0
L 0.78246998 -1.87565 0.78516004 -1.87336004 0 P 0 ;0
L 0.78516004 -1.87336004 0.78795 -1.87133996 0 P 0 ;0
L 0.78795 -1.87133996 0.79088002 -1.86956004 0 P 0 ;0
L 0.79088002 -1.86956004 0.79393996 -1.86803002 0 P 0 ;0
L 0.79393996 -1.86803002 0.79711004 -1.86675 0 P 0 ;0
L 0.79711004 -1.86675 0.80038002 -1.86573002 0 P 0 ;0
L 0.80038002 -1.86573002 0.80431004 -1.86486004 0 P 0 ;0
L 0.80431004 -1.86486004 0.80828996 -1.86433996 0 P 0 ;0
L 0.80828996 -1.86433996 0.8123 -1.86416004 0 P 0 ;0
L 0.8123 -1.86416004 0.81631004 -1.86431998 0 P 0 ;0
L 0.81631004 -1.86431998 0.81946998 -1.86471004 0 P 0 ;0
L 0.81946998 -1.86471004 0.82258996 -1.86531004 0 P 0 ;0
L 0.82258996 -1.86531004 0.82566004 -1.86613996 0 P 0 ;0
L 0.82566004 -1.86613996 0.82866998 -1.86718002 0 P 0 ;0
L 0.82866998 -1.86718002 0.83158996 -1.86843002 0 P 0 ;0
L 0.83158996 -1.86843002 0.83443002 -1.86988996 0 P 0 ;0
L 0.83443002 -1.86988996 0.83716004 -1.87156004 0 P 0 ;0
L 0.83716004 -1.87156004 0.83976004 -1.87341004 0 P 0 ;0
L 0.83976004 -1.87341004 0.84223002 -1.87543996 0 P 0 ;0
L 0.84223002 -1.87543996 0.84453996 -1.87763002 0 P 0 ;0
L 0.84453996 -1.87763002 0.84726998 -1.88065 0 P 0 ;0
L 0.84726998 -1.88065 0.84971998 -1.88388002 0 P 0 ;0
L 0.84971998 -1.88388002 0.85188996 -1.88731004 0 P 0 ;0
L 0.85188996 -1.88731004 0.85376004 -1.89091004 0 P 0 ;0
L 0.85376004 -1.89091004 0.85483996 -1.89345 0 P 0 ;0
L 0.85483996 -1.89345 0.85575 -1.89605 0 P 0 ;0
L 0.85575 -1.89605 0.85646998 -1.89871004 0 P 0 ;0
L 0.85646998 -1.89871004 0.857 -1.90141004 0 P 0 ;0
L 0.857 -1.90141004 0.85748002 -1.9053 0 P 0 ;0
L 0.85748002 -1.9053 0.85763996 -1.90918996 0 P 0 ;0
L 0.85763996 -1.90918996 0.8575 -1.91308002 0 P 0 ;0
L 0.8575 -1.91308002 0.85703996 -1.91696004 0 P 0 ;0
L 0.85703996 -1.91696004 0.85628002 -1.92076004 0 P 0 ;0
L 0.85628002 -1.92076004 0.85521998 -1.92448996 0 P 0 ;0
L 0.85521998 -1.92448996 0.85428002 -1.92705 0 P 0 ;0
L 0.85428002 -1.92705 0.85316998 -1.92951998 0 P 0 ;0
L 0.85316998 -1.92951998 0.85188002 -1.93191004 0 P 0 ;0
L 0.85188002 -1.93191004 0.85041998 -1.9342 0 P 0 ;0
L 0.85041998 -1.9342 0.84826998 -1.93708002 0 P 0 ;0
L 0.84826998 -1.93708002 0.84593002 -1.93976998 0 P 0 ;0
L 0.84593002 -1.93976998 0.8434 -1.94228002 0 P 0 ;0
L 0.8434 -1.94228002 0.84068002 -1.9446 0 P 0 ;0
L 0.84068002 -1.9446 0.8378 -1.9467 0 P 0 ;0
L 0.8378 -1.9467 0.83476998 -1.94858002 0 P 0 ;0
L 0.83476998 -1.94858002 0.83163996 -1.9502 0 P 0 ;0
L 0.83163996 -1.9502 0.8284 -1.95158002 0 P 0 ;0
L 0.8284 -1.95158002 0.82506004 -1.95268996 0 P 0 ;0
L 0.82506004 -1.95268996 0.82163996 -1.95356004 0 P 0 ;0
L 0.82163996 -1.95356004 0.81818002 -1.95413996 0 P 0 ;0
L 0.81818002 -1.95413996 0.8147 -1.95446004 0 P 0 ;0
L 0.8147 -1.95446004 0.81121004 -1.9545 0 P 0 ;0
L 0.77075 -2.02925 0.84511004 -2.02925 0 P 0 ;0
L 0.77076004 -2.02825 0.8452 -2.02825 0 P 0 ;0
L 0.77076998 -2.02725 0.84528996 -2.02725 0 P 0 ;0
L 0.77078002 -2.02625 0.84536998 -2.02625 0 P 0 ;0
L 0.77078996 -2.02525 0.84548996 -2.02525 0 P 0 ;0
L 0.7708 -2.02425 0.84561998 -2.02425 0 P 0 ;0
L 0.77081004 -2.02325 0.84575 -2.02325 0 P 0 ;0
L 0.77081998 -2.02225 0.84588002 -2.02225 0 P 0 ;0
L 0.77083002 -2.02125 0.84601004 -2.02125 0 P 0 ;0
L 0.77083996 -2.02025 0.84613996 -2.02025 0 P 0 ;0
L 0.77085 -2.01925 0.84626004 -2.01925 0 P 0 ;0
L 0.77085 -2.01825 0.84638996 -2.01825 0 P 0 ;0
L 0.77085 -2.01725 0.84651998 -2.01725 0 P 0 ;0
L 0.77086004 -2.01625 0.84663996 -2.01625 0 P 0 ;0
L 0.77086004 -2.01525 0.84676998 -2.01525 0 P 0 ;0
L 0.77086004 -2.01425 0.8469 -2.01425 0 P 0 ;0
L 0.77086004 -2.01325 0.84703002 -2.01325 0 P 0 ;0
L 0.77086004 -2.01225 0.84716004 -2.01225 0 P 0 ;0
L 0.77086004 -2.01125 0.84728996 -2.01125 0 P 0 ;0
L 0.77086004 -2.01025 0.84741004 -2.01025 0 P 0 ;0
L 0.77086998 -2.00925 0.84753996 -2.00925 0 P 0 ;0
L 0.77086998 -2.00825 0.84766998 -2.00825 0 P 0 ;0
L 0.77086998 -2.00725 0.84778996 -2.00725 0 P 0 ;0
L 0.77086998 -2.00625 0.84791998 -2.00625 0 P 0 ;0
L 0.77086998 -2.00525 0.84805 -2.00525 0 P 0 ;0
L 0.77086998 -2.00425 0.84818002 -2.00425 0 P 0 ;0
L 0.77088002 -2.00325 0.84831004 -2.00325 0 P 0 ;0
L 0.77088002 -2.00225 0.84843996 -2.00225 0 P 0 ;0
L 0.77088002 -2.00125 0.84856004 -2.00125 0 P 0 ;0
L 0.77088002 -2.00025 0.84868996 -2.00025 0 P 0 ;0
L 0.77088002 -1.99925 0.84881998 -1.99925 0 P 0 ;0
L 0.77088002 -1.99825 0.84896004 -1.99825 0 P 0 ;0
L 0.77088002 -1.99725 0.84911004 -1.99725 0 P 0 ;0
L 0.77088996 -1.99625 0.84926998 -1.99625 0 P 0 ;0
L 0.77088996 -1.99525 0.84941998 -1.99525 0 P 0 ;0
L 0.77088996 -1.99425 0.84956998 -1.99425 0 P 0 ;0
L 0.77088996 -1.99325 0.84971998 -1.99325 0 P 0 ;0
L 0.77088996 -1.99225 0.84986998 -1.99225 0 P 0 ;0
L 0.77088996 -1.99125 0.85003002 -1.99125 0 P 0 ;0
L 0.7709 -1.99025 0.85018002 -1.99025 0 P 0 ;0
L 0.7709 -1.98925 0.85033002 -1.98925 0 P 0 ;0
L 0.76885 -2.01878002 0.76871998 -2.03201998 0 P 0 ;0
L 0.76871998 -2.03201998 0.7684 -2.04553996 0 P 0 ;0
L 0.7684 -2.04553996 0.76796004 -2.05751004 0 P 0 ;0
L 0.76796004 -2.05751004 0.76741004 -2.06523002 0 P 0 ;0
L 0.76741004 -2.06523002 0.76596004 -2.07933996 0 P 0 ;0
L 0.76596004 -2.07933996 0.7636 -2.09918002 0 P 0 ;0
L 0.7636 -2.09918002 0.76116004 -2.119 0 P 0 ;0
L 0.76116004 -2.119 0.76011998 -2.12526004 0 P 0 ;0
L 0.76011998 -2.12526004 0.75948996 -2.12825 0 P 0 ;0
L 0.75948996 -2.12825 0.84418002 -2.12825 0 P 0 ;0
L 0.84418002 -2.12825 0.84361998 -2.10788002 0 P 0 ;0
L 0.84361998 -2.10788002 0.8436 -2.08276004 0 P 0 ;0
L 0.8436 -2.08276004 0.8449 -2.05491998 0 P 0 ;0
L 0.8449 -2.05491998 0.84736004 -2.02641004 0 P 0 ;0
L 0.84736004 -2.02641004 0.85083996 -1.99923002 0 P 0 ;0
L 0.85083996 -1.99923002 0.85268996 -1.987 0 P 0 ;0
L 0.85268996 -1.987 0.7689 -1.987 0 P 0 ;0
L 0.7689 -1.987 0.76885 -2.01878002 0 P 0 ;0
L 0.76195 -2.12625 0.84211998 -2.12625 0 P 0 ;0
L 0.76213996 -2.12525 0.8421 -2.12525 0 P 0 ;0
L 0.76231004 -2.12425 0.84206998 -2.12425 0 P 0 ;0
L 0.76248002 -2.12325 0.84203996 -2.12325 0 P 0 ;0
L 0.76263996 -2.12225 0.84201004 -2.12225 0 P 0 ;0
L 0.76281004 -2.12125 0.84198996 -2.12125 0 P 0 ;0
L 0.76296998 -2.12025 0.84196004 -2.12025 0 P 0 ;0
L 0.76313996 -2.11925 0.84193002 -2.11925 0 P 0 ;0
L 0.76326998 -2.11825 0.8419 -2.11825 0 P 0 ;0
L 0.76338996 -2.11725 0.84188002 -2.11725 0 P 0 ;0
L 0.76351004 -2.11625 0.84185 -2.11625 0 P 0 ;0
L 0.76363996 -2.11525 0.84181998 -2.11525 0 P 0 ;0
L 0.76376004 -2.11425 0.84178996 -2.11425 0 P 0 ;0
L 0.76388002 -2.11325 0.84176998 -2.11325 0 P 0 ;0
L 0.76401004 -2.11225 0.84173996 -2.11225 0 P 0 ;0
L 0.76413002 -2.11125 0.84171004 -2.11125 0 P 0 ;0
L 0.76425 -2.11025 0.84168002 -2.11025 0 P 0 ;0
L 0.76438002 -2.10925 0.84166004 -2.10925 0 P 0 ;0
L 0.7645 -2.10825 0.84163002 -2.10825 0 P 0 ;0
L 0.76461998 -2.10725 0.84161998 -2.10725 0 P 0 ;0
L 0.76475 -2.10625 0.84161998 -2.10625 0 P 0 ;0
L 0.76486998 -2.10525 0.84161998 -2.10525 0 P 0 ;0
L 0.76498996 -2.10425 0.84161998 -2.10425 0 P 0 ;0
L 0.76511998 -2.10325 0.84161998 -2.10325 0 P 0 ;0
L 0.76523996 -2.10225 0.84161998 -2.10225 0 P 0 ;0
L 0.76536004 -2.10125 0.84161998 -2.10125 0 P 0 ;0
L 0.76548996 -2.10025 0.84161998 -2.10025 0 P 0 ;0
L 0.76561004 -2.09925 0.84161998 -2.09925 0 P 0 ;0
L 0.76573002 -2.09825 0.84161004 -2.09825 0 P 0 ;0
L 0.76583996 -2.09725 0.84161004 -2.09725 0 P 0 ;0
L 0.76596998 -2.09625 0.84161004 -2.09625 0 P 0 ;0
L 0.76608996 -2.09525 0.84161004 -2.09525 0 P 0 ;0
L 0.7662 -2.09425 0.84161004 -2.09425 0 P 0 ;0
L 0.76631998 -2.09325 0.84161004 -2.09325 0 P 0 ;0
L 0.76643996 -2.09225 0.84161004 -2.09225 0 P 0 ;0
L 0.76656004 -2.09125 0.84161004 -2.09125 0 P 0 ;0
L 0.76668002 -2.09025 0.84161004 -2.09025 0 P 0 ;0
L 0.76678996 -2.08925 0.84161004 -2.08925 0 P 0 ;0
L 0.76691998 -2.08825 0.84161004 -2.08825 0 P 0 ;0
L 0.76703002 -2.08725 0.84161004 -2.08725 0 P 0 ;0
L 0.76715 -2.08625 0.8416 -2.08625 0 P 0 ;0
L 0.76726998 -2.08525 0.8416 -2.08525 0 P 0 ;0
L 0.76738996 -2.08425 0.8416 -2.08425 0 P 0 ;0
L 0.76195 -2.12625 0.76208002 -2.12561998 0 P 0 ;0
L 0.76208002 -2.12561998 0.76313996 -2.11928996 0 P 0 ;0
L 0.76313996 -2.11928996 0.76558996 -2.09941998 0 P 0 ;0
L 0.76558996 -2.09941998 0.76558996 -2.09941004 0 P 0 ;0
L 0.76558996 -2.09941004 0.76793996 -2.07956004 0 P 0 ;0
L 0.76793996 -2.07956004 0.7694 -2.0654 0 P 0 ;0
L 0.7694 -2.0654 0.76941004 -2.06536004 0 P 0 ;0
L 0.76941004 -2.06536004 0.76996004 -2.05761998 0 P 0 ;0
L 0.76996004 -2.05761998 0.76996004 -2.05758996 0 P 0 ;0
L 0.76996004 -2.05758996 0.7704 -2.0456 0 P 0 ;0
L 0.7704 -2.0456 0.77071998 -2.03206004 0 P 0 ;0
L 0.77071998 -2.03206004 0.77085 -2.01878002 0 P 0 ;0
L 0.77085 -2.01878002 0.7709 -1.989 0 P 0 ;0
L 0.7709 -1.989 0.85036004 -1.989 0 P 0 ;0
L 0.85036004 -1.989 0.84886004 -1.99895 0 P 0 ;0
L 0.84886004 -1.99895 0.84538002 -2.02618996 0 P 0 ;0
L 0.84538002 -2.02618996 0.8429 -2.05478996 0 P 0 ;0
L 0.8429 -2.05478996 0.8416 -2.08271004 0 P 0 ;0
L 0.8416 -2.08271004 0.84161998 -2.10791004 0 P 0 ;0
L 0.84161998 -2.10791004 0.84211998 -2.12625 0 P 0 ;0
L 0.84211998 -2.12625 0.76195 -2.12625 0 P 0 ;0
L 0.71628996 -1.91261998 0.74938002 -1.91261998 0 P 0 ;0
L 0.71783002 -1.91161998 0.74933002 -1.91161998 0 P 0 ;0
L 0.71953002 -1.91061998 0.74931004 -1.91061998 0 P 0 ;0
L 0.72133002 -1.90961998 0.74928996 -1.90961998 0 P 0 ;0
L 0.72313996 -1.90861998 0.74926998 -1.90861998 0 P 0 ;0
L 0.72493996 -1.90761998 0.74928996 -1.90761998 0 P 0 ;0
L 0.72673996 -1.90661998 0.74931998 -1.90661998 0 P 0 ;0
L 0.72855 -1.90561998 0.74935 -1.90561998 0 P 0 ;0
L 0.73035 -1.90461998 0.74938996 -1.90461998 0 P 0 ;0
L 0.73215 -1.90361998 0.74946998 -1.90361998 0 P 0 ;0
L 0.73396004 -1.90261998 0.74953996 -1.90261998 0 P 0 ;0
L 0.73576004 -1.90161998 0.74961998 -1.90161998 0 P 0 ;0
L 0.73756998 -1.90061998 0.74973996 -1.90061998 0 P 0 ;0
L 0.73943002 -1.89961998 0.74986004 -1.89961998 0 P 0 ;0
L 0.74141998 -1.89861998 0.74998996 -1.89861998 0 P 0 ;0
L 0.74341004 -1.89761998 0.75015 -1.89761998 0 P 0 ;0
L 0.59843002 -2.08361998 0.6754 -2.08361998 0 P 0 ;0
L 0.59846004 -2.08261998 0.67538996 -2.08261998 0 P 0 ;0
L 0.59848002 -2.08161998 0.67538002 -2.08161998 0 P 0 ;0
L 0.59851004 -2.08061998 0.67538002 -2.08061998 0 P 0 ;0
L 0.59853002 -2.07961998 0.67546004 -2.07961998 0 P 0 ;0
L 0.59856004 -2.07861998 0.67553996 -2.07861998 0 P 0 ;0
L 0.59861998 -2.07761998 0.67561004 -2.07761998 0 P 0 ;0
L 0.5987 -2.07661998 0.67568996 -2.07661998 0 P 0 ;0
L 0.59878002 -2.07561998 0.67576004 -2.07561998 0 P 0 ;0
L 0.59885 -2.07461998 0.67583996 -2.07461998 0 P 0 ;0
L 0.59893002 -2.07361998 0.67591998 -2.07361998 0 P 0 ;0
L 0.59901004 -2.07261998 0.67598996 -2.07261998 0 P 0 ;0
L 0.59908002 -2.07161998 0.67606998 -2.07161998 0 P 0 ;0
L 0.59916004 -2.07061998 0.67613996 -2.07061998 0 P 0 ;0
L 0.59923002 -2.06961998 0.67621004 -2.06961998 0 P 0 ;0
L 0.59936004 -2.06861998 0.6763 -2.06861998 0 P 0 ;0
L 0.59948996 -2.06761998 0.67645 -2.06761998 0 P 0 ;0
L 0.59963002 -2.06661998 0.6766 -2.06661998 0 P 0 ;0
L 0.59976998 -2.06561998 0.67676004 -2.06561998 0 P 0 ;0
L 0.5999 -2.06461998 0.67691998 -2.06461998 0 P 0 ;0
L 0.60003002 -2.06361998 0.67706998 -2.06361998 0 P 0 ;0
L 0.60016998 -2.06261998 0.6773 -2.06261998 0 P 0 ;0
L 0.60031004 -2.06161998 0.67753002 -2.06161998 0 P 0 ;0
L 0.60051004 -2.06061998 0.67776004 -2.06061998 0 P 0 ;0
L 0.60071004 -2.05961998 0.67798996 -2.05961998 0 P 0 ;0
L 0.60091998 -2.05861998 0.67823002 -2.05861998 0 P 0 ;0
L 0.60111998 -2.05761998 0.67853002 -2.05761998 0 P 0 ;0
L 0.60133002 -2.05661998 0.67883996 -2.05661998 0 P 0 ;0
L 0.60153996 -2.05561998 0.67913996 -2.05561998 0 P 0 ;0
L 0.60173996 -2.05461998 0.67945 -2.05461998 0 P 0 ;0
L 0.60195 -2.05361998 0.67975 -2.05361998 0 P 0 ;0
L 0.60223002 -2.05261998 0.68006004 -2.05261998 0 P 0 ;0
L 0.60251004 -2.05161998 0.68036004 -2.05161998 0 P 0 ;0
L 0.60278996 -2.05061998 0.68066998 -2.05061998 0 P 0 ;0
L 0.60306004 -2.04961998 0.68096998 -2.04961998 0 P 0 ;0
L 0.60333996 -2.04861998 0.68135 -2.04861998 0 P 0 ;0
L 0.60361998 -2.04761998 0.68173002 -2.04761998 0 P 0 ;0
L 0.6039 -2.04661998 0.68211004 -2.04661998 0 P 0 ;0
L 0.60418002 -2.04561998 0.68248996 -2.04561998 0 P 0 ;0
L 0.60453002 -2.04461998 0.68288002 -2.04461998 0 P 0 ;0
L 0.60488002 -2.04361998 0.68326004 -2.04361998 0 P 0 ;0
L 0.60523002 -2.04261998 0.68363996 -2.04261998 0 P 0 ;0
L 0.60556998 -2.04161998 0.68401998 -2.04161998 0 P 0 ;0
L 0.60591998 -2.04061998 0.6844 -2.04061998 0 P 0 ;0
L 0.60626998 -2.03961998 0.68486004 -2.03961998 0 P 0 ;0
L 0.60661998 -2.03861998 0.68531998 -2.03861998 0 P 0 ;0
L 0.60698996 -2.03761998 0.68578002 -2.03761998 0 P 0 ;0
L 0.60743002 -2.03661998 0.68623996 -2.03661998 0 P 0 ;0
L 0.60786004 -2.03561998 0.6867 -2.03561998 0 P 0 ;0
L 0.60828996 -2.03461998 0.68716004 -2.03461998 0 P 0 ;0
L 0.60873002 -2.03361998 0.68761998 -2.03361998 0 P 0 ;0
L 0.60916004 -2.03261998 0.68808996 -2.03261998 0 P 0 ;0
L 0.60958996 -2.03161998 0.68856998 -2.03161998 0 P 0 ;0
L 0.61003002 -2.03061998 0.68911004 -2.03061998 0 P 0 ;0
L 0.61046004 -2.02961998 0.68965 -2.02961998 0 P 0 ;0
L 0.61088996 -2.02861998 0.69018996 -2.02861998 0 P 0 ;0
L 0.61133002 -2.02761998 0.69073002 -2.02761998 0 P 0 ;0
L 0.61176004 -2.02661998 0.69126998 -2.02661998 0 P 0 ;0
L 0.6122 -2.02561998 0.69181004 -2.02561998 0 P 0 ;0
L 0.61263002 -2.02461998 0.69235 -2.02461998 0 P 0 ;0
L 0.61306004 -2.02361998 0.69288002 -2.02361998 0 P 0 ;0
L 0.61348996 -2.02261998 0.69346998 -2.02261998 0 P 0 ;0
L 0.61393002 -2.02161998 0.69408996 -2.02161998 0 P 0 ;0
L 0.61436004 -2.02061998 0.6947 -2.02061998 0 P 0 ;0
L 0.61478996 -2.01961998 0.69531998 -2.01961998 0 P 0 ;0
L 0.61531004 -2.01861998 0.69593996 -2.01861998 0 P 0 ;0
L 0.61583996 -2.01761998 0.69656004 -2.01761998 0 P 0 ;0
L 0.61636004 -2.01661998 0.69718002 -2.01661998 0 P 0 ;0
L 0.61688002 -2.01561998 0.69778996 -2.01561998 0 P 0 ;0
L 0.6174 -2.01461998 0.69841998 -2.01461998 0 P 0 ;0
L 0.61791998 -2.01361998 0.69911998 -2.01361998 0 P 0 ;0
L 0.61843996 -2.01261998 0.69981998 -2.01261998 0 P 0 ;0
L 0.61896004 -2.01161998 0.70051998 -2.01161998 0 P 0 ;0
L 0.61948002 -2.01061998 0.70123002 -2.01061998 0 P 0 ;0
L 0.62 -2.00961998 0.70193002 -2.00961998 0 P 0 ;0
L 0.62051998 -2.00861998 0.70263002 -2.00861998 0 P 0 ;0
L 0.62103996 -2.00761998 0.70333002 -2.00761998 0 P 0 ;0
L 0.62163996 -2.00661998 0.70403996 -2.00661998 0 P 0 ;0
L 0.62225 -2.00561998 0.70483002 -2.00561998 0 P 0 ;0
L 0.62285 -2.00461998 0.70565 -2.00461998 0 P 0 ;0
L 0.62346004 -2.00361998 0.70646004 -2.00361998 0 P 0 ;0
L 0.62406004 -2.00261998 0.70726998 -2.00261998 0 P 0 ;0
L 0.62466004 -2.00161998 0.70808996 -2.00161998 0 P 0 ;0
L 0.62526998 -2.00061998 0.7089 -2.00061998 0 P 0 ;0
L 0.62586998 -1.99961998 0.70971004 -1.99961998 0 P 0 ;0
L 0.62648002 -1.99861998 0.71053002 -1.99861998 0 P 0 ;0
L 0.62708002 -1.99761998 0.71133996 -1.99761998 0 P 0 ;0
L 0.62768996 -1.99661998 0.71216004 -1.99661998 0 P 0 ;0
L 0.62831998 -1.99561998 0.71296998 -1.99561998 0 P 0 ;0
L 0.62901004 -1.99461998 0.71378996 -1.99461998 0 P 0 ;0
L 0.62971004 -1.99361998 0.71466004 -1.99361998 0 P 0 ;0
L 0.6304 -1.99261998 0.71561004 -1.99261998 0 P 0 ;0
L 0.6311 -1.99161998 0.71656998 -1.99161998 0 P 0 ;0
L 0.63178996 -1.99061998 0.71753002 -1.99061998 0 P 0 ;0
L 0.63248996 -1.98961998 0.71848996 -1.98961998 0 P 0 ;0
L 0.63318002 -1.98861998 0.71945 -1.98861998 0 P 0 ;0
L 0.63388002 -1.98761998 0.72041004 -1.98761998 0 P 0 ;0
L 0.63456998 -1.98661998 0.72136998 -1.98661998 0 P 0 ;0
L 0.63526998 -1.98561998 0.72233002 -1.98561998 0 P 0 ;0
L 0.63598002 -1.98461998 0.72328996 -1.98461998 0 P 0 ;0
L 0.63678996 -1.98361998 0.72425 -1.98361998 0 P 0 ;0
L 0.6376 -1.98261998 0.72521004 -1.98261998 0 P 0 ;0
L 0.63841004 -1.98161998 0.72628002 -1.98161998 0 P 0 ;0
L 0.63921998 -1.98061998 0.72738996 -1.98061998 0 P 0 ;0
L 0.64003002 -1.97961998 0.7285 -1.97961998 0 P 0 ;0
L 0.64083996 -1.97861998 0.72961004 -1.97861998 0 P 0 ;0
L 0.64165 -1.97761998 0.73071004 -1.97761998 0 P 0 ;0
L 0.64246004 -1.97661998 0.73181998 -1.97661998 0 P 0 ;0
L 0.64326998 -1.97561998 0.73293002 -1.97561998 0 P 0 ;0
L 0.64406998 -1.97461998 0.73403996 -1.97461998 0 P 0 ;0
L 0.64488002 -1.97361998 0.73515 -1.97361998 0 P 0 ;0
L 0.64568996 -1.97261998 0.73625 -1.97261998 0 P 0 ;0
L 0.6465 -1.97161998 0.73736004 -1.97161998 0 P 0 ;0
L 0.64731004 -1.97061998 0.73848002 -1.97061998 0 P 0 ;0
L 0.64811998 -1.96961998 0.73973002 -1.96961998 0 P 0 ;0
L 0.64893002 -1.96861998 0.74098996 -1.96861998 0 P 0 ;0
L 0.64981004 -1.96761998 0.74225 -1.96761998 0 P 0 ;0
L 0.65076004 -1.96661998 0.74351004 -1.96661998 0 P 0 ;0
L 0.65171004 -1.96561998 0.74476998 -1.96561998 0 P 0 ;0
L 0.65266998 -1.96461998 0.74603002 -1.96461998 0 P 0 ;0
L 0.65361998 -1.96361998 0.74728996 -1.96361998 0 P 0 ;0
L 0.65458002 -1.96261998 0.74855 -1.96261998 0 P 0 ;0
L 0.65553002 -1.96161998 0.74981004 -1.96161998 0 P 0 ;0
L 0.65648996 -1.96061998 0.75106004 -1.96061998 0 P 0 ;0
L 0.65743996 -1.95961998 0.75233996 -1.95961998 0 P 0 ;0
L 0.6584 -1.95861998 0.7537 -1.95861998 0 P 0 ;0
L 0.65935 -1.95761998 0.75506004 -1.95761998 0 P 0 ;0
L 0.66031004 -1.95661998 0.75641998 -1.95661998 0 P 0 ;0
L 0.66126004 -1.95561998 0.75778996 -1.95561998 0 P 0 ;0
L 0.66221004 -1.95461998 0.75916004 -1.95461998 0 P 0 ;0
L 0.66316998 -1.95361998 0.76053996 -1.95361998 0 P 0 ;0
L 0.66411998 -1.95261998 0.76193996 -1.95261998 0 P 0 ;0
L 0.66523002 -1.95161998 0.76333996 -1.95161998 0 P 0 ;0
L 0.66636004 -1.95061998 0.76406998 -1.95061998 0 P 0 ;0
L 0.66746998 -1.94961998 0.76355 -1.94961998 0 P 0 ;0
L 0.6686 -1.94861998 0.76291998 -1.94861998 0 P 0 ;0
L 0.66971004 -1.94761998 0.76226998 -1.94761998 0 P 0 ;0
L 0.67083996 -1.94661998 0.76161998 -1.94661998 0 P 0 ;0
L 0.67196004 -1.94561998 0.76096998 -1.94561998 0 P 0 ;0
L 0.67306998 -1.94461998 0.76033002 -1.94461998 0 P 0 ;0
L 0.6742 -1.94361998 0.75968996 -1.94361998 0 P 0 ;0
L 0.67531004 -1.94261998 0.75905 -1.94261998 0 P 0 ;0
L 0.67643996 -1.94161998 0.75846004 -1.94161998 0 P 0 ;0
L 0.67755 -1.94061998 0.75788996 -1.94061998 0 P 0 ;0
L 0.67868002 -1.93961998 0.75731998 -1.93961998 0 P 0 ;0
L 0.67978996 -1.93861998 0.75676998 -1.93861998 0 P 0 ;0
L 0.68091998 -1.93761998 0.75626998 -1.93761998 0 P 0 ;0
L 0.68221004 -1.93661998 0.75576998 -1.93661998 0 P 0 ;0
L 0.68353002 -1.93561998 0.75528002 -1.93561998 0 P 0 ;0
L 0.68483996 -1.93461998 0.75483996 -1.93461998 0 P 0 ;0
L 0.68616004 -1.93361998 0.75441004 -1.93361998 0 P 0 ;0
L 0.68746998 -1.93261998 0.75398002 -1.93261998 0 P 0 ;0
L 0.68878002 -1.93161998 0.7536 -1.93161998 0 P 0 ;0
L 0.6901 -1.93061998 0.75323996 -1.93061998 0 P 0 ;0
L 0.69141004 -1.92961998 0.75286998 -1.92961998 0 P 0 ;0
L 0.69271998 -1.92861998 0.75253996 -1.92861998 0 P 0 ;0
L 0.69403002 -1.92761998 0.75223002 -1.92761998 0 P 0 ;0
L 0.69535 -1.92661998 0.75193002 -1.92661998 0 P 0 ;0
L 0.69666004 -1.92561998 0.75163002 -1.92561998 0 P 0 ;0
L 0.69796998 -1.92461998 0.75138002 -1.92461998 0 P 0 ;0
L 0.69936998 -1.92361998 0.75113996 -1.92361998 0 P 0 ;0
L 0.70091004 -1.92261998 0.75088996 -1.92261998 0 P 0 ;0
L 0.70243996 -1.92161998 0.75066004 -1.92161998 0 P 0 ;0
L 0.70398002 -1.92061998 0.75046004 -1.92061998 0 P 0 ;0
L 0.70551998 -1.91961998 0.75026004 -1.91961998 0 P 0 ;0
L 0.70706004 -1.91861998 0.75006998 -1.91861998 0 P 0 ;0
L 0.7086 -1.91761998 0.7499 -1.91761998 0 P 0 ;0
L 0.71013996 -1.91661998 0.74976998 -1.91661998 0 P 0 ;0
L 0.71166998 -1.91561998 0.74961998 -1.91561998 0 P 0 ;0
L 0.71321004 -1.91461998 0.74951998 -1.91461998 0 P 0 ;0
L 0.71475 -1.91361998 0.74945 -1.91361998 0 P 0 ;0
L 0.61556998 -2.15661998 0.70655 -2.15661998 0 P 0 ;0
L 0.61503002 -2.15561998 0.7056 -2.15561998 0 P 0 ;0
L 0.61448996 -2.15461998 0.70465 -2.15461998 0 P 0 ;0
L 0.61395 -2.15361998 0.7037 -2.15361998 0 P 0 ;0
L 0.61341004 -2.15261998 0.70273996 -2.15261998 0 P 0 ;0
L 0.61286998 -2.15161998 0.70178996 -2.15161998 0 P 0 ;0
L 0.61233002 -2.15061998 0.70095 -2.15061998 0 P 0 ;0
L 0.61188002 -2.14961998 0.70015 -2.14961998 0 P 0 ;0
L 0.61143002 -2.14861998 0.69935 -2.14861998 0 P 0 ;0
L 0.61098002 -2.14761998 0.69855 -2.14761998 0 P 0 ;0
L 0.61053002 -2.14661998 0.69775 -2.14661998 0 P 0 ;0
L 0.61008002 -2.14561998 0.69695 -2.14561998 0 P 0 ;0
L 0.60963002 -2.14461998 0.69615 -2.14461998 0 P 0 ;0
L 0.60918002 -2.14361998 0.69535 -2.14361998 0 P 0 ;0
L 0.60873002 -2.14261998 0.69455 -2.14261998 0 P 0 ;0
L 0.60831004 -2.14161998 0.69381998 -2.14161998 0 P 0 ;0
L 0.60793996 -2.14061998 0.69315 -2.14061998 0 P 0 ;0
L 0.60756998 -2.13961998 0.69248002 -2.13961998 0 P 0 ;0
L 0.60721004 -2.13861998 0.69181004 -2.13861998 0 P 0 ;0
L 0.60683996 -2.13761998 0.69115 -2.13761998 0 P 0 ;0
L 0.60646998 -2.13661998 0.69048002 -2.13661998 0 P 0 ;0
L 0.60611004 -2.13561998 0.68981004 -2.13561998 0 P 0 ;0
L 0.60573996 -2.13461998 0.68918002 -2.13461998 0 P 0 ;0
L 0.60538002 -2.13361998 0.68863002 -2.13361998 0 P 0 ;0
L 0.60503996 -2.13261998 0.68808002 -2.13261998 0 P 0 ;0
L 0.60476004 -2.13161998 0.68753002 -2.13161998 0 P 0 ;0
L 0.60446998 -2.13061998 0.68698002 -2.13061998 0 P 0 ;0
L 0.60418002 -2.12961998 0.68643002 -2.12961998 0 P 0 ;0
L 0.6039 -2.12861998 0.68588002 -2.12861998 0 P 0 ;0
L 0.60361004 -2.12761998 0.68533002 -2.12761998 0 P 0 ;0
L 0.60331998 -2.12661998 0.68486004 -2.12661998 0 P 0 ;0
L 0.60303002 -2.12561998 0.68441998 -2.12561998 0 P 0 ;0
L 0.60275 -2.12461998 0.68396998 -2.12461998 0 P 0 ;0
L 0.60246004 -2.12361998 0.68353002 -2.12361998 0 P 0 ;0
L 0.60218002 -2.12261998 0.68308996 -2.12261998 0 P 0 ;0
L 0.60188996 -2.12161998 0.68263996 -2.12161998 0 P 0 ;0
L 0.60166998 -2.12061998 0.6822 -2.12061998 0 P 0 ;0
L 0.60145 -2.11961998 0.68176004 -2.11961998 0 P 0 ;0
L 0.60123002 -2.11861998 0.68138996 -2.11861998 0 P 0 ;0
L 0.60101004 -2.11761998 0.68105 -2.11761998 0 P 0 ;0
L 0.60078002 -2.11661998 0.68071004 -2.11661998 0 P 0 ;0
L 0.6006 -2.11561998 0.68036004 -2.11561998 0 P 0 ;0
L 0.60043002 -2.11461998 0.68001998 -2.11461998 0 P 0 ;0
L 0.60025 -2.11361998 0.67968002 -2.11361998 0 P 0 ;0
L 0.60008002 -2.11261998 0.67933002 -2.11261998 0 P 0 ;0
L 0.59991004 -2.11161998 0.67898996 -2.11161998 0 P 0 ;0
L 0.59976004 -2.11061998 0.6787 -2.11061998 0 P 0 ;0
L 0.59963996 -2.10961998 0.67845 -2.10961998 0 P 0 ;0
L 0.59951004 -2.10861998 0.6782 -2.10861998 0 P 0 ;0
L 0.59938002 -2.10761998 0.67795 -2.10761998 0 P 0 ;0
L 0.59925 -2.10661998 0.6777 -2.10661998 0 P 0 ;0
L 0.59913002 -2.10561998 0.67746004 -2.10561998 0 P 0 ;0
L 0.59905 -2.10461998 0.67721004 -2.10461998 0 P 0 ;0
L 0.59896998 -2.10361998 0.67696004 -2.10361998 0 P 0 ;0
L 0.59888002 -2.10261998 0.67671004 -2.10261998 0 P 0 ;0
L 0.5988 -2.10161998 0.67653996 -2.10161998 0 P 0 ;0
L 0.59871998 -2.10061998 0.67638002 -2.10061998 0 P 0 ;0
L 0.59866998 -2.09961998 0.67621004 -2.09961998 0 P 0 ;0
L 0.59863996 -2.09861998 0.67605 -2.09861998 0 P 0 ;0
L 0.59861004 -2.09761998 0.67588996 -2.09761998 0 P 0 ;0
L 0.59858996 -2.09661998 0.6758 -2.09661998 0 P 0 ;0
L 0.59856004 -2.09561998 0.67571004 -2.09561998 0 P 0 ;0
L 0.59853002 -2.09461998 0.67563002 -2.09461998 0 P 0 ;0
L 0.5985 -2.09361998 0.67553996 -2.09361998 0 P 0 ;0
L 0.59846998 -2.09261998 0.67546004 -2.09261998 0 P 0 ;0
L 0.59843996 -2.09161998 0.67546004 -2.09161998 0 P 0 ;0
L 0.59841998 -2.09061998 0.67545 -2.09061998 0 P 0 ;0
L 0.59838002 -2.08961998 0.67543996 -2.08961998 0 P 0 ;0
L 0.59836004 -2.08861998 0.67543002 -2.08861998 0 P 0 ;0
L 0.59833002 -2.08761998 0.67543002 -2.08761998 0 P 0 ;0
L 0.59835 -2.08661998 0.67541998 -2.08661998 0 P 0 ;0
L 0.59836998 -2.08561998 0.67541004 -2.08561998 0 P 0 ;0
L 0.5984 -2.08461998 0.67541004 -2.08461998 0 P 0 ;0
L 0.80005 -2.25161998 0.85543996 -2.25161998 0 P 0 ;0
L 0.78651998 -2.25061998 0.86596004 -2.25061998 0 P 0 ;0
L 0.77878996 -2.24961998 0.87636004 -2.24961998 0 P 0 ;0
L 0.77106004 -2.24861998 0.88285 -2.24861998 0 P 0 ;0
L 0.76398996 -2.24761998 0.88933996 -2.24761998 0 P 0 ;0
L 0.75891998 -2.24661998 0.89583996 -2.24661998 0 P 0 ;0
L 0.73781004 -1.8982 0.71738996 -1.90951998 0 P 0 ;0
L 0.71738996 -1.90951998 0.69766998 -1.92233996 0 P 0 ;0
L 0.69766998 -1.92233996 0.67971004 -1.93601998 0 P 0 ;0
L 0.67971004 -1.93601998 0.66278996 -1.95113002 0 P 0 ;0
L 0.66278996 -1.95113002 0.64786998 -1.96675 0 P 0 ;0
L 0.64786998 -1.96675 0.63423996 -1.98358996 0 P 0 ;0
L 0.63423996 -1.98358996 0.62643996 -1.99483002 0 P 0 ;0
L 0.62643996 -1.99483002 0.61933996 -2.00655 0 P 0 ;0
L 0.61933996 -2.00655 0.61298996 -2.01873996 0 P 0 ;0
L 0.61298996 -2.01873996 0.60503002 -2.03713002 0 P 0 ;0
L 0.60503002 -2.03713002 0.60225 -2.04506004 0 P 0 ;0
L 0.60225 -2.04506004 0.59998996 -2.05323002 0 P 0 ;0
L 0.59998996 -2.05323002 0.59833996 -2.0612 0 P 0 ;0
L 0.59833996 -2.0612 0.59725 -2.06928996 0 P 0 ;0
L 0.59725 -2.06928996 0.59656998 -2.07833996 0 P 0 ;0
L 0.59656998 -2.07833996 0.59633002 -2.0875 0 P 0 ;0
L 0.59633002 -2.0875 0.59668996 -2.10036998 0 P 0 ;0
L 0.59668996 -2.10036998 0.59715 -2.10596004 0 P 0 ;0
L 0.59715 -2.10596004 0.59786004 -2.11151004 0 P 0 ;0
L 0.59786004 -2.11151004 0.59878996 -2.11686998 0 P 0 ;0
L 0.59878996 -2.11686998 0.59996998 -2.1222 0 P 0 ;0
L 0.59996998 -2.1222 0.60326998 -2.13368996 0 P 0 ;0
L 0.60326998 -2.13368996 0.60656998 -2.1427 0 P 0 ;0
L 0.60656998 -2.1427 0.6105 -2.15143996 0 P 0 ;0
L 0.6105 -2.15143996 0.61505 -2.15988002 0 P 0 ;0
L 0.61505 -2.15988002 0.62023996 -2.16803996 0 P 0 ;0
L 0.62023996 -2.16803996 0.62828996 -2.17873002 0 P 0 ;0
L 0.62828996 -2.17873002 0.63718996 -2.18871004 0 P 0 ;0
L 0.63718996 -2.18871004 0.64693002 -2.19795 0 P 0 ;0
L 0.64693002 -2.19795 0.6582 -2.20701998 0 P 0 ;0
L 0.6582 -2.20701998 0.67011004 -2.21518996 0 P 0 ;0
L 0.67011004 -2.21518996 0.68261004 -2.22243002 0 P 0 ;0
L 0.68261004 -2.22243002 0.69673996 -2.22936004 0 P 0 ;0
L 0.69673996 -2.22936004 0.71123002 -2.23543996 0 P 0 ;0
L 0.71123002 -2.23543996 0.72611998 -2.24066998 0 P 0 ;0
L 0.72611998 -2.24066998 0.74536004 -2.24598996 0 P 0 ;0
L 0.74536004 -2.24598996 0.76493002 -2.24985 0 P 0 ;0
L 0.76493002 -2.24985 0.78671998 -2.25266998 0 P 0 ;0
L 0.78671998 -2.25266998 0.80863002 -2.25425 0 P 0 ;0
L 0.80863002 -2.25425 0.83146004 -2.25463002 0 P 0 ;0
L 0.83146004 -2.25463002 0.85418002 -2.25375 0 P 0 ;0
L 0.85418002 -2.25375 0.87641004 -2.25163996 0 P 0 ;0
L 0.87641004 -2.25163996 0.89853002 -2.24823002 0 P 0 ;0
L 0.89853002 -2.24823002 0.93045 -2.24101998 0 P 0 ;0
L 0.93045 -2.24101998 0.96466004 -2.23063002 0 P 0 ;0
L 0.96466004 -2.23063002 0.99911004 -2.2178 0 P 0 ;0
L 0.99911004 -2.2178 1.03183002 -2.20318002 0 P 0 ;0
L 1.03183002 -2.20318002 1.04391998 -2.19703002 0 P 0 ;0
L 1.04391998 -2.19703002 1.05581004 -2.19048996 0 P 0 ;0
L 1.05581004 -2.19048996 1.06676004 -2.18411998 0 P 0 ;0
L 1.06676004 -2.18411998 1.06681004 -2.18408996 0 P 0 ;0
L 1.06681004 -2.18408996 1.06685 -2.18405 0 P 0 ;0
L 1.06685 -2.18405 1.0669 -2.18401004 0 P 0 ;0
L 1.0669 -2.18401004 1.06693996 -2.18396998 0 P 0 ;0
L 1.06693996 -2.18396998 1.06696998 -2.18391998 0 P 0 ;0
L 1.06696998 -2.18391998 1.06701004 -2.18386998 0 P 0 ;0
L 1.06701004 -2.18386998 1.06703002 -2.18381998 0 P 0 ;0
L 1.06703002 -2.18381998 1.06706004 -2.18376004 0 P 0 ;0
L 1.06706004 -2.18376004 1.06706998 -2.18371004 0 P 0 ;0
L 1.06706998 -2.18371004 1.06708996 -2.18365 0 P 0 ;0
L 1.06708996 -2.18365 1.06708996 -2.18358996 0 P 0 ;0
L 1.06708996 -2.18358996 1.0671 -2.18353002 0 P 0 ;0
L 1.0671 -2.18353002 1.0671 -2.18346998 0 P 0 ;0
L 1.0671 -2.18346998 1.06708996 -2.18341004 0 P 0 ;0
L 1.06708996 -2.18341004 1.06706998 -2.18336004 0 P 0 ;0
L 1.06706998 -2.18336004 1.06706004 -2.1833 0 P 0 ;0
L 1.06706004 -2.1833 1.06703002 -2.18323996 0 P 0 ;0
L 1.06703002 -2.18323996 1.06701004 -2.18318996 0 P 0 ;0
L 1.06701004 -2.18318996 1.06696998 -2.18313996 0 P 0 ;0
L 1.06696998 -2.18313996 1.06693996 -2.18308996 0 P 0 ;0
L 1.06693996 -2.18308996 1.06688002 -2.18303002 0 P 0 ;0
L 1.06688002 -2.18303002 1.06678996 -2.18296998 0 P 0 ;0
L 1.06678996 -2.18296998 1.06673002 -2.18295 0 P 0 ;0
L 1.06673002 -2.18295 1.0667 -2.18295 0 P 0 ;0
L 1.0667 -2.18295 1.06666004 -2.18293996 0 P 0 ;0
L 1.06666004 -2.18293996 1.0666 -2.18293996 0 P 0 ;0
L 1.0666 -2.18293996 1.06656998 -2.18295 0 P 0 ;0
L 1.06656998 -2.18295 1.06653002 -2.18295 0 P 0 ;0
L 1.06653002 -2.18295 1.06153002 -2.1842 0 P 0 ;0
L 1.06153002 -2.1842 1.05583996 -2.18566998 0 P 0 ;0
L 1.05583996 -2.18566998 1.04916998 -2.1875 0 P 0 ;0
L 1.04916998 -2.1875 1.0153 -2.1962 0 P 0 ;0
L 1.0153 -2.1962 0.9814 -2.20333996 0 P 0 ;0
L 0.9814 -2.20333996 0.94881998 -2.2087 0 P 0 ;0
L 0.94881998 -2.2087 0.9189 -2.21198996 0 P 0 ;0
L 0.9189 -2.21198996 0.90113996 -2.21278996 0 P 0 ;0
L 0.90113996 -2.21278996 0.87738002 -2.21265 0 P 0 ;0
L 0.87738002 -2.21265 0.854 -2.21183002 0 P 0 ;0
L 0.854 -2.21183002 0.83788996 -2.21033996 0 P 0 ;0
L 0.83788996 -2.21033996 0.8174 -2.20693002 0 P 0 ;0
L 0.8174 -2.20693002 0.79708996 -2.2023 0 P 0 ;0
L 0.79708996 -2.2023 0.7769 -2.19641004 0 P 0 ;0
L 0.7769 -2.19641004 0.76433002 -2.19183996 0 P 0 ;0
L 0.76433002 -2.19183996 0.75208996 -2.18638002 0 P 0 ;0
L 0.75208996 -2.18638002 0.74026998 -2.18006998 0 P 0 ;0
L 0.74026998 -2.18006998 0.72886998 -2.17291004 0 P 0 ;0
L 0.72886998 -2.17291004 0.71961998 -2.16603002 0 P 0 ;0
L 0.71961998 -2.16603002 0.71098996 -2.15838996 0 P 0 ;0
L 0.71098996 -2.15838996 0.70303002 -2.15003002 0 P 0 ;0
L 0.70303002 -2.15003002 0.6958 -2.14098996 0 P 0 ;0
L 0.6958 -2.14098996 0.69106998 -2.1339 0 P 0 ;0
L 0.69106998 -2.1339 0.68696004 -2.12643002 0 P 0 ;0
L 0.68696004 -2.12643002 0.68351004 -2.11863002 0 P 0 ;0
L 0.68351004 -2.11863002 0.68073996 -2.11056004 0 P 0 ;0
L 0.68073996 -2.11056004 0.67866004 -2.10218996 0 P 0 ;0
L 0.67866004 -2.10218996 0.67788002 -2.09741998 0 P 0 ;0
L 0.67788002 -2.09741998 0.67746004 -2.0926 0 P 0 ;0
L 0.67746004 -2.0926 0.67738002 -2.08076004 0 P 0 ;0
L 0.67738002 -2.08076004 0.67828002 -2.06891004 0 P 0 ;0
L 0.67828002 -2.06891004 0.67903002 -2.06403996 0 P 0 ;0
L 0.67903002 -2.06403996 0.68013002 -2.05923996 0 P 0 ;0
L 0.68013002 -2.05923996 0.68288002 -2.05021998 0 P 0 ;0
L 0.68288002 -2.05021998 0.68623996 -2.04141004 0 P 0 ;0
L 0.68623996 -2.04141004 0.69018002 -2.03286004 0 P 0 ;0
L 0.69018002 -2.03286004 0.69486004 -2.02418002 0 P 0 ;0
L 0.69486004 -2.02418002 0.70003996 -2.0158 0 P 0 ;0
L 0.70003996 -2.0158 0.70573002 -2.00768996 0 P 0 ;0
L 0.70573002 -2.00768996 0.7158 -1.99531998 0 P 0 ;0
L 0.7158 -1.99531998 0.72681004 -1.98385 0 P 0 ;0
L 0.72681004 -1.98385 0.73971004 -1.9722 0 P 0 ;0
L 0.73971004 -1.9722 0.7533 -1.9614 0 P 0 ;0
L 0.7533 -1.9614 0.75753996 -1.95828002 0 P 0 ;0
L 0.75753996 -1.95828002 0.76138002 -1.95548002 0 P 0 ;0
L 0.76138002 -1.95548002 0.76463002 -1.95316004 0 P 0 ;0
L 0.76463002 -1.95316004 0.76516004 -1.95281004 0 P 0 ;0
L 0.76516004 -1.95281004 0.7657 -1.95248996 0 P 0 ;0
L 0.7657 -1.95248996 0.76578002 -1.95243996 0 P 0 ;0
L 0.76578002 -1.95243996 0.76586004 -1.95238002 0 P 0 ;0
L 0.76586004 -1.95238002 0.76593002 -1.95231998 0 P 0 ;0
L 0.76593002 -1.95231998 0.766 -1.95223996 0 P 0 ;0
L 0.766 -1.95223996 0.76606004 -1.95216998 0 P 0 ;0
L 0.76606004 -1.95216998 0.76616004 -1.95201004 0 P 0 ;0
L 0.76616004 -1.95201004 0.7662 -1.95191998 0 P 0 ;0
L 0.7662 -1.95191998 0.76626004 -1.95173996 0 P 0 ;0
L 0.76626004 -1.95173996 0.76628002 -1.95163996 0 P 0 ;0
L 0.76628002 -1.95163996 0.7663 -1.95143002 0 P 0 ;0
L 0.7663 -1.95143002 0.7663 -1.95121004 0 P 0 ;0
L 0.7663 -1.95121004 0.76628996 -1.951 0 P 0 ;0
L 0.76628996 -1.951 0.76625 -1.95078996 0 P 0 ;0
L 0.76625 -1.95078996 0.7662 -1.95058002 0 P 0 ;0
L 0.7662 -1.95058002 0.76613002 -1.95036998 0 P 0 ;0
L 0.76613002 -1.95036998 0.76583002 -1.94966998 0 P 0 ;0
L 0.76583002 -1.94966998 0.76548996 -1.94896998 0 P 0 ;0
L 0.76548996 -1.94896998 0.76508996 -1.9483 0 P 0 ;0
L 0.76508996 -1.9483 0.76253002 -1.94436004 0 P 0 ;0
L 0.76253002 -1.94436004 0.76056998 -1.94126998 0 P 0 ;0
L 0.76056998 -1.94126998 0.75871998 -1.93806004 0 P 0 ;0
L 0.75871998 -1.93806004 0.75716998 -1.93496998 0 P 0 ;0
L 0.75716998 -1.93496998 0.7558 -1.93178002 0 P 0 ;0
L 0.7558 -1.93178002 0.7546 -1.92853996 0 P 0 ;0
L 0.7546 -1.92853996 0.75358996 -1.92521004 0 P 0 ;0
L 0.75358996 -1.92521004 0.7527 -1.92161998 0 P 0 ;0
L 0.7527 -1.92161998 0.75196998 -1.91796004 0 P 0 ;0
L 0.75196998 -1.91796004 0.75155 -1.91496004 0 P 0 ;0
L 0.75155 -1.91496004 0.75133002 -1.91193002 0 P 0 ;0
L 0.75133002 -1.91193002 0.75126998 -1.9085 0 P 0 ;0
L 0.75126998 -1.9085 0.75136004 -1.90506004 0 P 0 ;0
L 0.75136004 -1.90506004 0.75161004 -1.90181998 0 P 0 ;0
L 0.75161004 -1.90181998 0.752 -1.8986 0 P 0 ;0
L 0.752 -1.8986 0.75228996 -1.89701998 0 P 0 ;0
L 0.75228996 -1.89701998 0.75268996 -1.89546998 0 P 0 ;0
L 0.75268996 -1.89546998 0.7532 -1.89395 0 P 0 ;0
L 0.7532 -1.89395 0.75358996 -1.89281998 0 P 0 ;0
L 0.75358996 -1.89281998 0.75373002 -1.89231998 0 P 0 ;0
L 0.75373002 -1.89231998 0.75383996 -1.8918 0 P 0 ;0
L 0.75383996 -1.8918 0.75391998 -1.89138996 0 P 0 ;0
L 0.75391998 -1.89138996 0.75396998 -1.89098996 0 P 0 ;0
L 0.75396998 -1.89098996 0.75396998 -1.89086004 0 P 0 ;0
L 0.75396998 -1.89086004 0.75393996 -1.89076998 0 P 0 ;0
L 0.75393996 -1.89076998 0.7539 -1.89071004 0 P 0 ;0
L 0.7539 -1.89071004 0.75386004 -1.89066998 0 P 0 ;0
L 0.75386004 -1.89066998 0.75381004 -1.89063002 0 P 0 ;0
L 0.75381004 -1.89063002 0.75378996 -1.89061004 0 P 0 ;0
L 0.75378996 -1.89061004 0.75373002 -1.89058996 0 P 0 ;0
L 0.75373002 -1.89058996 0.75368002 -1.89056998 0 P 0 ;0
L 0.75368002 -1.89056998 0.75356004 -1.89056998 0 P 0 ;0
L 0.75356004 -1.89056998 0.75346998 -1.8906 0 P 0 ;0
L 0.75346998 -1.8906 0.74898002 -1.8927 0 P 0 ;0
L 0.74898002 -1.8927 0.74383002 -1.89518002 0 P 0 ;0
L 0.74383002 -1.89518002 0.73781004 -1.8982 0 P 0 ;0
L 0.69776998 -2.22761998 0.96701004 -2.22761998 0 P 0 ;0
L 0.6957 -2.22661998 0.96968996 -2.22661998 0 P 0 ;0
L 0.69366998 -2.22561998 0.97238002 -2.22561998 0 P 0 ;0
L 0.69163002 -2.22461998 0.97506004 -2.22461998 0 P 0 ;0
L 0.68958996 -2.22361998 0.97775 -2.22361998 0 P 0 ;0
L 0.68756004 -2.22261998 0.98043002 -2.22261998 0 P 0 ;0
L 0.68551998 -2.22161998 0.98311004 -2.22161998 0 P 0 ;0
L 0.68348996 -2.22061998 0.9858 -2.22061998 0 P 0 ;0
L 0.68176998 -2.21961998 0.98848002 -2.21961998 0 P 0 ;0
L 0.68003996 -2.21861998 0.99116998 -2.21861998 0 P 0 ;0
L 0.67831004 -2.21761998 0.99385 -2.21761998 0 P 0 ;0
L 0.67658002 -2.21661998 0.99653996 -2.21661998 0 P 0 ;0
L 0.67485 -2.21561998 0.99908002 -2.21561998 0 P 0 ;0
L 0.67311998 -2.21461998 0.87665 -2.21461998 0 P 0 ;0
L 0.6714 -2.21361998 0.85166004 -2.21361998 0 P 0 ;0
L 0.6699 -2.21261998 0.84083002 -2.21261998 0 P 0 ;0
L 0.66845 -2.21161998 0.8334 -2.21161998 0 P 0 ;0
L 0.66698996 -2.21061998 0.8274 -2.21061998 0 P 0 ;0
L 0.66553002 -2.20961998 0.82138996 -2.20961998 0 P 0 ;0
L 0.66406998 -2.20861998 0.81583002 -2.20861998 0 P 0 ;0
L 0.66261998 -2.20761998 0.81143996 -2.20761998 0 P 0 ;0
L 0.66116004 -2.20661998 0.80706004 -2.20661998 0 P 0 ;0
L 0.6597 -2.20561998 0.80266998 -2.20561998 0 P 0 ;0
L 0.65841004 -2.20461998 0.79828996 -2.20461998 0 P 0 ;0
L 0.65716998 -2.20361998 0.79448996 -2.20361998 0 P 0 ;0
L 0.65593002 -2.20261998 0.79106004 -2.20261998 0 P 0 ;0
L 0.65468996 -2.20161998 0.78763996 -2.20161998 0 P 0 ;0
L 0.83143002 -2.25261998 0.80871998 -2.25225 0 P 0 ;0
L 0.80871998 -2.25225 0.78691998 -2.25066998 0 P 0 ;0
L 0.78691998 -2.25066998 0.76525 -2.24786998 0 P 0 ;0
L 0.76525 -2.24786998 0.74581998 -2.24403996 0 P 0 ;0
L 0.74581998 -2.24403996 0.72671004 -2.23876004 0 P 0 ;0
L 0.72671004 -2.23876004 0.71196004 -2.23356998 0 P 0 ;0
L 0.71196004 -2.23356998 0.69756998 -2.22753996 0 P 0 ;0
L 0.69756998 -2.22753996 0.68355 -2.22066004 0 P 0 ;0
L 0.68355 -2.22066004 0.67118002 -2.2135 0 P 0 ;0
L 0.67118002 -2.2135 0.65938996 -2.20541004 0 P 0 ;0
L 0.65938996 -2.20541004 0.64825 -2.19643996 0 P 0 ;0
L 0.64825 -2.19643996 0.63861998 -2.18731998 0 P 0 ;0
L 0.63861998 -2.18731998 0.62983002 -2.17746998 0 P 0 ;0
L 0.62983002 -2.17746998 0.62188996 -2.1669 0 P 0 ;0
L 0.62188996 -2.1669 0.61678002 -2.15886998 0 P 0 ;0
L 0.61678002 -2.15886998 0.6123 -2.15056004 0 P 0 ;0
L 0.6123 -2.15056004 0.60841998 -2.14193996 0 P 0 ;0
L 0.60841998 -2.14193996 0.60516998 -2.13306998 0 P 0 ;0
L 0.60516998 -2.13306998 0.60191004 -2.12171004 0 P 0 ;0
L 0.60191004 -2.12171004 0.60075 -2.11648002 0 P 0 ;0
L 0.60075 -2.11648002 0.59983996 -2.11121004 0 P 0 ;0
L 0.59983996 -2.11121004 0.59913996 -2.10576004 0 P 0 ;0
L 0.59913996 -2.10576004 0.59868996 -2.10026004 0 P 0 ;0
L 0.59868996 -2.10026004 0.59833002 -2.0875 0 P 0 ;0
L 0.59833002 -2.0875 0.59856998 -2.07843996 0 P 0 ;0
L 0.59856998 -2.07843996 0.59923996 -2.0695 0 P 0 ;0
L 0.59923996 -2.0695 0.60031998 -2.06153996 0 P 0 ;0
L 0.60031998 -2.06153996 0.60193002 -2.05368996 0 P 0 ;0
L 0.60193002 -2.05368996 0.60416004 -2.04566004 0 P 0 ;0
L 0.60416004 -2.04566004 0.60688996 -2.03786004 0 P 0 ;0
L 0.60688996 -2.03786004 0.6148 -2.01961004 0 P 0 ;0
L 0.6148 -2.01961004 0.62108996 -2.00753002 0 P 0 ;0
L 0.62108996 -2.00753002 0.62811998 -1.99591998 0 P 0 ;0
L 0.62811998 -1.99591998 0.63583996 -1.98478996 0 P 0 ;0
L 0.63583996 -1.98478996 0.64936998 -1.96808002 0 P 0 ;0
L 0.64936998 -1.96808002 0.66418002 -1.95256998 0 P 0 ;0
L 0.66418002 -1.95256998 0.68098002 -1.93756004 0 P 0 ;0
L 0.68098002 -1.93756004 0.69881998 -1.92398002 0 P 0 ;0
L 0.69881998 -1.92398002 0.71841998 -1.91123996 0 P 0 ;0
L 0.71841998 -1.91123996 0.73875 -1.89996998 0 P 0 ;0
L 0.73875 -1.89996998 0.74471004 -1.89696998 0 P 0 ;0
L 0.74471004 -1.89696998 0.74983002 -1.89451004 0 P 0 ;0
L 0.74983002 -1.89451004 0.7511 -1.89391004 0 P 0 ;0
L 0.7511 -1.89391004 0.75076998 -1.89488996 0 P 0 ;0
L 0.75076998 -1.89488996 0.75033996 -1.89658996 0 P 0 ;0
L 0.75033996 -1.89658996 0.75003002 -1.8983 0 P 0 ;0
L 0.75003002 -1.8983 0.74961998 -1.90161998 0 P 0 ;0
L 0.74961998 -1.90161998 0.74936004 -1.90496004 0 P 0 ;0
L 0.74936004 -1.90496004 0.74926998 -1.9085 0 P 0 ;0
L 0.74926998 -1.9085 0.74933002 -1.91201998 0 P 0 ;0
L 0.74933002 -1.91201998 0.74956004 -1.91516998 0 P 0 ;0
L 0.74956004 -1.91516998 0.75 -1.91828996 0 P 0 ;0
L 0.75 -1.91828996 0.75075 -1.92205 0 P 0 ;0
L 0.75075 -1.92205 0.75166004 -1.92573996 0 P 0 ;0
L 0.75166004 -1.92573996 0.7527 -1.92916998 0 P 0 ;0
L 0.7527 -1.92916998 0.75393996 -1.93253002 0 P 0 ;0
L 0.75393996 -1.93253002 0.75536004 -1.93581998 0 P 0 ;0
L 0.75536004 -1.93581998 0.75696004 -1.939 0 P 0 ;0
L 0.75696004 -1.939 0.75885 -1.94231004 0 P 0 ;0
L 0.75885 -1.94231004 0.76083996 -1.94543996 0 P 0 ;0
L 0.76083996 -1.94543996 0.76338996 -1.94933996 0 P 0 ;0
L 0.76338996 -1.94933996 0.76371998 -1.94991998 0 P 0 ;0
L 0.76371998 -1.94991998 0.76401004 -1.9505 0 P 0 ;0
L 0.76401004 -1.9505 0.76423996 -1.95103002 0 P 0 ;0
L 0.76423996 -1.95103002 0.76408996 -1.95111004 0 P 0 ;0
L 0.76408996 -1.95111004 0.76348996 -1.95151004 0 P 0 ;0
L 0.76348996 -1.95151004 0.76021004 -1.95386004 0 P 0 ;0
L 0.76021004 -1.95386004 0.7602 -1.95386998 0 P 0 ;0
L 0.7602 -1.95386998 0.75636998 -1.95666004 0 P 0 ;0
L 0.75636998 -1.95666004 0.75636004 -1.95666998 0 P 0 ;0
L 0.75636004 -1.95666998 0.75635 -1.95666998 0 P 0 ;0
L 0.75635 -1.95666998 0.75208996 -1.95981004 0 P 0 ;0
L 0.75208996 -1.95981004 0.73841004 -1.97066998 0 P 0 ;0
L 0.73841004 -1.97066998 0.72541004 -1.98241004 0 P 0 ;0
L 0.72541004 -1.98241004 0.7143 -1.994 0 P 0 ;0
L 0.7143 -1.994 0.71425 -1.99406004 0 P 0 ;0
L 0.71425 -1.99406004 0.70413996 -2.00648002 0 P 0 ;0
L 0.70413996 -2.00648002 0.69836998 -2.01468996 0 P 0 ;0
L 0.69836998 -2.01468996 0.69313002 -2.02318002 0 P 0 ;0
L 0.69313002 -2.02318002 0.68838996 -2.03196004 0 P 0 ;0
L 0.68838996 -2.03196004 0.68438996 -2.04063996 0 P 0 ;0
L 0.68438996 -2.04063996 0.68098996 -2.04958002 0 P 0 ;0
L 0.68098996 -2.04958002 0.6782 -2.05873002 0 P 0 ;0
L 0.6782 -2.05873002 0.67706004 -2.06366004 0 P 0 ;0
L 0.67706004 -2.06366004 0.67628996 -2.06866998 0 P 0 ;0
L 0.67628996 -2.06866998 0.67538002 -2.08068996 0 P 0 ;0
L 0.67538002 -2.08068996 0.67546004 -2.09268996 0 P 0 ;0
L 0.67546004 -2.09268996 0.67588996 -2.09766998 0 P 0 ;0
L 0.67588996 -2.09766998 0.6767 -2.10258996 0 P 0 ;0
L 0.6767 -2.10258996 0.67881998 -2.11111998 0 P 0 ;0
L 0.67881998 -2.11111998 0.68163996 -2.11936004 0 P 0 ;0
L 0.68163996 -2.11936004 0.68516004 -2.12731998 0 P 0 ;0
L 0.68516004 -2.12731998 0.68935 -2.13493996 0 P 0 ;0
L 0.68935 -2.13493996 0.69418002 -2.14216998 0 P 0 ;0
L 0.69418002 -2.14216998 0.70153002 -2.15135 0 P 0 ;0
L 0.70153002 -2.15135 0.7096 -2.15983002 0 P 0 ;0
L 0.7096 -2.15983002 0.71836004 -2.16758996 0 P 0 ;0
L 0.71836004 -2.16758996 0.71843002 -2.16763996 0 P 0 ;0
L 0.71843002 -2.16763996 0.72773996 -2.17456004 0 P 0 ;0
L 0.72773996 -2.17456004 0.73926998 -2.1818 0 P 0 ;0
L 0.73926998 -2.1818 0.75121004 -2.18818002 0 P 0 ;0
L 0.75121004 -2.18818002 0.75128002 -2.18821004 0 P 0 ;0
L 0.75128002 -2.18821004 0.76358002 -2.19368996 0 P 0 ;0
L 0.76358002 -2.19368996 0.77628002 -2.19831004 0 P 0 ;0
L 0.77628002 -2.19831004 0.79658996 -2.20423996 0 P 0 ;0
L 0.79658996 -2.20423996 0.81701004 -2.20888996 0 P 0 ;0
L 0.81701004 -2.20888996 0.83763996 -2.21233002 0 P 0 ;0
L 0.83763996 -2.21233002 0.85388002 -2.21383002 0 P 0 ;0
L 0.85388002 -2.21383002 0.87733996 -2.21465 0 P 0 ;0
L 0.87733996 -2.21465 0.90118002 -2.21478996 0 P 0 ;0
L 0.90118002 -2.21478996 0.91906004 -2.21398996 0 P 0 ;0
L 0.91906004 -2.21398996 0.94908996 -2.21068002 0 P 0 ;0
L 0.94908996 -2.21068002 0.98176998 -2.2053 0 P 0 ;0
L 0.98176998 -2.2053 1.01575 -2.19815 0 P 0 ;0
L 1.01575 -2.19815 1.04968002 -2.18943002 0 P 0 ;0
L 1.04968002 -2.18943002 1.05633996 -2.18761004 0 P 0 ;0
L 1.05633996 -2.18761004 1.05713996 -2.1874 0 P 0 ;0
L 1.05713996 -2.1874 1.05483002 -2.18875 0 P 0 ;0
L 1.05483002 -2.18875 1.04298996 -2.19526004 0 P 0 ;0
L 1.04298996 -2.19526004 1.03096998 -2.20136998 0 P 0 ;0
L 1.03096998 -2.20136998 0.99835 -2.21595 0 P 0 ;0
L 0.99835 -2.21595 0.96401998 -2.22873996 0 P 0 ;0
L 0.96401998 -2.22873996 0.92993996 -2.23908002 0 P 0 ;0
L 0.92993996 -2.23908002 0.89816004 -2.24626004 0 P 0 ;0
L 0.89816004 -2.24626004 0.87616004 -2.24965 0 P 0 ;0
L 0.87616004 -2.24965 0.85405 -2.25176004 0 P 0 ;0
L 0.85405 -2.25176004 0.83143002 -2.25261998 0 P 0 ;0
L 0.65345 -2.20061998 0.78421004 -2.20061998 0 P 0 ;0
L 0.65221004 -2.19961998 0.78078002 -2.19961998 0 P 0 ;0
L 0.65096004 -2.19861998 0.77735 -2.19861998 0 P 0 ;0
L 0.64971998 -2.19761998 0.77438996 -2.19761998 0 P 0 ;0
L 0.64848002 -2.19661998 0.77163996 -2.19661998 0 P 0 ;0
L 0.64738996 -2.19561998 0.76888996 -2.19561998 0 P 0 ;0
L 0.64633996 -2.19461998 0.76613996 -2.19461998 0 P 0 ;0
L 0.64528002 -2.19361998 0.76343002 -2.19361998 0 P 0 ;0
L 0.64421998 -2.19261998 0.76118996 -2.19261998 0 P 0 ;0
L 0.64316998 -2.19161998 0.75893996 -2.19161998 0 P 0 ;0
L 0.64211004 -2.19061998 0.7567 -2.19061998 0 P 0 ;0
L 0.64106004 -2.18961998 0.75446004 -2.18961998 0 P 0 ;0
L 0.64 -2.18861998 0.75221004 -2.18861998 0 P 0 ;0
L 0.63895 -2.18761998 0.75018002 -2.18761998 0 P 0 ;0
L 0.63801004 -2.18661998 0.74831004 -2.18661998 0 P 0 ;0
L 0.63711004 -2.18561998 0.74643002 -2.18561998 0 P 0 ;0
L 0.63621998 -2.18461998 0.74456004 -2.18461998 0 P 0 ;0
L 0.63533002 -2.18361998 0.74268002 -2.18361998 0 P 0 ;0
L 0.63443996 -2.18261998 0.74081004 -2.18261998 0 P 0 ;0
L 0.63353996 -2.18161998 0.73898996 -2.18161998 0 P 0 ;0
L 0.63265 -2.18061998 0.73738996 -2.18061998 0 P 0 ;0
L 0.63176004 -2.17961998 0.7358 -2.17961998 0 P 0 ;0
L 0.63086998 -2.17861998 0.73421004 -2.17861998 0 P 0 ;0
L 0.62996998 -2.17761998 0.73261998 -2.17761998 0 P 0 ;0
L 0.6292 -2.17661998 0.73103002 -2.17661998 0 P 0 ;0
L 0.62845 -2.17561998 0.72943996 -2.17561998 0 P 0 ;0
L 0.6277 -2.17461998 0.72783996 -2.17461998 0 P 0 ;0
L 0.62693996 -2.17361998 0.72648002 -2.17361998 0 P 0 ;0
L 0.62618996 -2.17261998 0.72513996 -2.17261998 0 P 0 ;0
L 0.62543996 -2.17161998 0.72378996 -2.17161998 0 P 0 ;0
L 0.62468996 -2.17061998 0.72245 -2.17061998 0 P 0 ;0
L 0.62393996 -2.16961998 0.7211 -2.16961998 0 P 0 ;0
L 0.62318002 -2.16861998 0.71976004 -2.16861998 0 P 0 ;0
L 0.62243996 -2.16761998 0.71841004 -2.16761998 0 P 0 ;0
L 0.62171004 -2.16661998 0.71726998 -2.16661998 0 P 0 ;0
L 0.62108002 -2.16561998 0.71613996 -2.16561998 0 P 0 ;0
L 0.62043996 -2.16461998 0.71501004 -2.16461998 0 P 0 ;0
L 0.61981004 -2.16361998 0.71388002 -2.16361998 0 P 0 ;0
L 0.61916998 -2.16261998 0.71276004 -2.16261998 0 P 0 ;0
L 0.61853002 -2.16161998 0.71163002 -2.16161998 0 P 0 ;0
L 0.6179 -2.16061998 0.7105 -2.16061998 0 P 0 ;0
L 0.61726004 -2.15961998 0.7094 -2.15961998 0 P 0 ;0
L 0.61665 -2.15861998 0.70845 -2.15861998 0 P 0 ;0
L 0.61611004 -2.15761998 0.7075 -2.15761998 0 P 0 ;0
L 0.75383996 -2.24561998 0.901 -2.24561998 0 P 0 ;0
L 0.74876998 -2.24461998 0.90541998 -2.24461998 0 P 0 ;0
L 0.74431004 -2.24361998 0.90985 -2.24361998 0 P 0 ;0
L 0.7407 -2.24261998 0.91426998 -2.24261998 0 P 0 ;0
L 0.73708002 -2.24161998 0.9187 -2.24161998 0 P 0 ;0
L 0.73346998 -2.24061998 0.92311998 -2.24061998 0 P 0 ;0
L 0.72986004 -2.23961998 0.92753996 -2.23961998 0 P 0 ;0
L 0.72633996 -2.23861998 0.93145 -2.23861998 0 P 0 ;0
L 0.72348996 -2.23761998 0.93473996 -2.23761998 0 P 0 ;0
L 0.72063996 -2.23661998 0.93803996 -2.23661998 0 P 0 ;0
L 0.7178 -2.23561998 0.94133002 -2.23561998 0 P 0 ;0
L 0.71495 -2.23461998 0.94461998 -2.23461998 0 P 0 ;0
L 0.7121 -2.23361998 0.94791998 -2.23361998 0 P 0 ;0
L 0.70968996 -2.23261998 0.95121004 -2.23261998 0 P 0 ;0
L 0.70731004 -2.23161998 0.95451004 -2.23161998 0 P 0 ;0
L 0.70491998 -2.23061998 0.9578 -2.23061998 0 P 0 ;0
L 0.70253996 -2.22961998 0.9611 -2.22961998 0 P 0 ;0
L 0.70015 -2.22861998 0.96431998 -2.22861998 0 P 0 ;0
L 0.0349 -2.3038 0.0349 -1.0038 4 P 0 ;0
L 0.0349 -1.0038 4.5349 -1.0038 4 P 0 ;0
L 4.5349 -1.0038 4.5349 -2.3038 4 P 0 ;0
L 4.5349 -2.3038 0.0349 -2.3038 4 P 0 ;0
L 0.0349 -1.6038 4.5349 -1.6038 4 P 0 ;0
L 0.0349 -1.8038 4.5349 -1.8038 4 P 0 ;0
L 2.4349 -2.1038 4.0349 -2.1038 4 P 0 ;0
L 2.4349 -2.3038 2.4349 -1.8038 4 P 0 ;0
L 3.2349 -2.1038 3.2349 -1.8038 4 P 0 ;0
L 4.0349 -2.3038 4.0349 -1.8038 4 P 0 ;0
L 0.0723999 -1.6844687 0.07906663 -1.69030079 3 P 0 ;0,3=7,5=0.000000
L 0.07906663 -1.69030079 0.08656654 -1.6938 3 P 0 ;0,3=7,5=0.000000
L 0.08656654 -1.6938 0.09323337 -1.6938 3 P 0 ;0,3=7,5=0.000000
L 0.09323337 -1.6938 0.0999001 -1.69030079 3 P 0 ;0,3=7,5=0.000000
L 0.0999001 -1.69030079 0.10490059 -1.6844687 3 P 0 ;0,3=7,5=0.000000
L 0.10490059 -1.6844687 0.1074 -1.67629951 3 P 0 ;0,3=7,5=0.000000
L 0.1074 -1.67629951 0.10573376 -1.66813455 3 P 0 ;0,3=7,5=0.000000
L 0.10573376 -1.66813455 0.10156644 -1.66113396 3 P 0 ;0,3=7,5=0.000000
L 0.10156644 -1.66113396 0.09406654 -1.65646614 3 P 0 ;0,3=7,5=0.000000
L 0.09406654 -1.65646614 0.08406713 -1.65413327 3 P 0 ;0,3=7,5=0.000000
L 0.08406713 -1.65413327 0.07823346 -1.64946762 3 P 0 ;0,3=7,5=0.000000
L 0.07823346 -1.64946762 0.07573248 -1.64130059 3 P 0 ;0,3=7,5=0.000000
L 0.07573248 -1.64130059 0.0774003 -1.63313356 3 P 0 ;0,3=7,5=0.000000
L 0.0774003 -1.63313356 0.08156614 -1.62730148 3 P 0 ;0,3=7,5=0.000000
L 0.08156614 -1.62730148 0.0873997 -1.6238 3 P 0 ;0,3=7,5=0.000000
L 0.0873997 -1.6238 0.09323337 -1.6238 3 P 0 ;0,3=7,5=0.000000
L 0.09323337 -1.6238 0.09906693 -1.62613287 3 P 0 ;0,3=7,5=0.000000
L 0.09906693 -1.62613287 0.10406742 -1.63196713 3 P 0 ;0,3=7,5=0.000000
L 0.1383999 -1.6938 0.1383999 -1.6238 3 P 0 ;0,3=7,5=0.000000
L 0.1734 -1.6238 0.1734 -1.6938 3 P 0 ;0,3=7,5=0.000000
L 0.1734 -1.65880108 0.1383999 -1.65880108 3 P 0 ;0,3=7,5=0.000000
L 0.23856683 -1.6938 0.20523307 -1.6938 3 P 0 ;0,3=7,5=0.000000
L 0.20523307 -1.6938 0.20523307 -1.6238 3 P 0 ;0,3=7,5=0.000000
L 0.20523307 -1.6238 0.23856683 -1.6238 3 P 0 ;0,3=7,5=0.000000
L 0.22523337 -1.65763258 0.20523307 -1.65763258 3 P 0 ;0,3=7,5=0.000000
L 0.30456683 -1.6938 0.27123307 -1.6938 3 P 0 ;0,3=7,5=0.000000
L 0.27123307 -1.6938 0.27123307 -1.6238 3 P 0 ;0,3=7,5=0.000000
L 0.27123307 -1.6238 0.30456683 -1.6238 3 P 0 ;0,3=7,5=0.000000
L 0.29123337 -1.65763258 0.27123307 -1.65763258 3 P 0 ;0,3=7,5=0.000000
L 0.35389921 -1.6238 0.35389921 -1.6938 3 P 0 ;0,3=7,5=0.000000
L 0.33473356 -1.6238 0.37306634 -1.6238 3 P 0 ;0,3=7,5=0.000000
L 0.09489921 -1.7188 0.09489921 -1.7888 3 P 0 ;0,3=8,5=0.000000
L 0.07573356 -1.7188 0.11406634 -1.7188 3 P 0 ;0,3=8,5=0.000000
L 0.1508998 -1.7188 0.17089862 -1.7188 3 P 0 ;0,3=8,5=0.000000
L 0.16089921 -1.7188 0.16089921 -1.7888 3 P 0 ;0,3=8,5=0.000000
L 0.1508998 -1.7888 0.17089862 -1.7888 3 P 0 ;0,3=8,5=0.000000
L 0.22689921 -1.7188 0.22689921 -1.7888 3 P 0 ;0,3=8,5=0.000000
L 0.20773356 -1.7188 0.24606634 -1.7188 3 P 0 ;0,3=8,5=0.000000
L 0.27623307 -1.7188 0.27623307 -1.7888 3 P 0 ;0,3=8,5=0.000000
L 0.27623307 -1.7888 0.30956683 -1.7888 3 P 0 ;0,3=8,5=0.000000
L 0.37556683 -1.7888 0.34223307 -1.7888 3 P 0 ;0,3=8,5=0.000000
L 0.34223307 -1.7888 0.34223307 -1.7188 3 P 0 ;0,3=8,5=0.000000
L 0.34223307 -1.7188 0.37556683 -1.7188 3 P 0 ;0,3=8,5=0.000000
L 0.36223337 -1.75263258 0.34223307 -1.75263258 3 P 0 ;0,3=8,5=0.000000
L 2.5438999 -1.96813563 2.5519 -1.97480089 3 P 0 ;0,3=9,5=0.000000
L 2.5519 -1.97480089 2.5608999 -1.9788 3 P 0 ;0,3=9,5=0.000000
L 2.5608999 -1.9788 2.5689 -1.9788 3 P 0 ;0,3=9,5=0.000000
L 2.5689 -1.9788 2.5769001 -1.97480089 3 P 0 ;0,3=9,5=0.000000
L 2.5769001 -1.97480089 2.58290069 -1.96813563 3 P 0 ;0,3=9,5=0.000000
L 2.58290069 -1.96813563 2.5859 -1.95879941 3 P 0 ;0,3=9,5=0.000000
L 2.5859 -1.95879941 2.58390049 -1.94946811 3 P 0 ;0,3=9,5=0.000000
L 2.58390049 -1.94946811 2.5788997 -1.94146732 3 P 0 ;0,3=9,5=0.000000
L 2.5788997 -1.94146732 2.5698998 -1.93613278 3 P 0 ;0,3=9,5=0.000000
L 2.5698998 -1.93613278 2.55790049 -1.93346663 3 P 0 ;0,3=9,5=0.000000
L 2.55790049 -1.93346663 2.5509002 -1.92813445 3 P 0 ;0,3=9,5=0.000000
L 2.5509002 -1.92813445 2.54789902 -1.91880069 3 P 0 ;0,3=9,5=0.000000
L 2.54789902 -1.91880069 2.54990039 -1.90946683 3 P 0 ;0,3=9,5=0.000000
L 2.54990039 -1.90946683 2.55489931 -1.90280167 3 P 0 ;0,3=9,5=0.000000
L 2.55489931 -1.90280167 2.5618997 -1.8988 3 P 0 ;0,3=9,5=0.000000
L 2.5618997 -1.8988 2.5689 -1.8988 3 P 0 ;0,3=9,5=0.000000
L 2.5689 -1.8988 2.57590039 -1.90146614 3 P 0 ;0,3=9,5=0.000000
L 2.57590039 -1.90146614 2.58190089 -1.90813386 3 P 0 ;0,3=9,5=0.000000
L 2.6648998 -1.90546772 2.65889931 -1.90146614 3 P 0 ;0,3=9,5=0.000000
L 2.65889931 -1.90146614 2.65190079 -1.8988 3 P 0 ;0,3=9,5=0.000000
L 2.65190079 -1.8988 2.64390069 -1.8988 3 P 0 ;0,3=9,5=0.000000
L 2.64390069 -1.8988 2.63489892 -1.90280167 3 P 0 ;0,3=9,5=0.000000
L 2.63489892 -1.90280167 2.62790039 -1.90946683 3 P 0 ;0,3=9,5=0.000000
L 2.62790039 -1.90946683 2.62289961 -1.91746762 3 P 0 ;0,3=9,5=0.000000
L 2.62289961 -1.91746762 2.61889862 -1.93080049 3 P 0 ;0,3=9,5=0.000000
L 2.61889862 -1.93080049 2.61789892 -1.94280039 3 P 0 ;0,3=9,5=0.000000
L 2.61789892 -1.94280039 2.6199003 -1.9548003 3 P 0 ;0,3=9,5=0.000000
L 2.6199003 -1.9548003 2.62289961 -1.96280098 3 P 0 ;0,3=9,5=0.000000
L 2.62289961 -1.96280098 2.6289002 -1.97080177 3 P 0 ;0,3=9,5=0.000000
L 2.6289002 -1.97080177 2.63590049 -1.97613396 3 P 0 ;0,3=9,5=0.000000
L 2.63590049 -1.97613396 2.64289902 -1.9788 3 P 0 ;0,3=9,5=0.000000
L 2.64289902 -1.9788 2.64989941 -1.9788 3 P 0 ;0,3=9,5=0.000000
L 2.64989941 -1.9788 2.6568997 -1.97613396 3 P 0 ;0,3=9,5=0.000000
L 2.6568997 -1.97613396 2.6629003 -1.97213484 3 P 0 ;0,3=9,5=0.000000
L 2.6629003 -1.97213484 2.66790098 -1.96680266 3 P 0 ;0,3=9,5=0.000000
L 2.69589892 -1.9788 2.72089902 -1.8988 3 P 0 ;0,3=9,5=0.000000
L 2.72089902 -1.8988 2.74590098 -1.9788 3 P 0 ;0,3=9,5=0.000000
L 2.73689931 -1.95080118 2.70489882 -1.95080118 3 P 0 ;0,3=9,5=0.000000
L 2.77889961 -1.8988 2.77889961 -1.9788 3 P 0 ;0,3=9,5=0.000000
L 2.77889961 -1.9788 2.8189003 -1.9788 3 P 0 ;0,3=9,5=0.000000
L 2.8969003 -1.9788 2.85689961 -1.9788 3 P 0 ;0,3=9,5=0.000000
L 2.85689961 -1.9788 2.85689961 -1.8988 3 P 0 ;0,3=9,5=0.000000
L 2.85689961 -1.8988 2.8969003 -1.8988 3 P 0 ;0,3=9,5=0.000000
L 2.8809 -1.93746575 2.85689961 -1.93746575 3 P 0 ;0,3=9,5=0.000000
L 3.03289902 -1.9788 3.03289902 -1.8988 3 P 0 ;0,3=9,5=0.000000
L 3.03289902 -1.8988 3.0208998 -1.91479911 3 P 0 ;0,3=9,5=0.000000
L 3.0208998 -1.9788 3.04489833 -1.9788 3 P 0 ;0,3=9,5=0.000000
L 3.11089902 -1.98146604 3.10889951 -1.98013297 3 P 0 ;0,3=9,5=0.000000
L 3.10889951 -1.98013297 3.10889951 -1.97746703 3 P 0 ;0,3=9,5=0.000000
L 3.10889951 -1.97746703 3.11089902 -1.97613396 3 P 0 ;0,3=9,5=0.000000
L 3.11089902 -1.97613396 3.11290039 -1.97746703 3 P 0 ;0,3=9,5=0.000000
L 3.11290039 -1.97746703 3.11290039 -1.98013297 3 P 0 ;0,3=9,5=0.000000
L 3.11290039 -1.98013297 3.11089902 -1.98146604 3 P 0 ;0,3=9,5=0.000000
L 3.11089902 -1.945469 3.10889951 -1.94413346 3 P 0 ;0,3=9,5=0.000000
L 3.10889951 -1.94413346 3.10889951 -1.94146732 3 P 0 ;0,3=9,5=0.000000
L 3.10889951 -1.94146732 3.11089902 -1.94013435 3 P 0 ;0,3=9,5=0.000000
L 3.11089902 -1.94013435 3.11290039 -1.94146732 3 P 0 ;0,3=9,5=0.000000
L 3.11290039 -1.94146732 3.11290039 -1.94413346 3 P 0 ;0,3=9,5=0.000000
L 3.11290039 -1.94413346 3.11089902 -1.945469 3 P 0 ;0,3=9,5=0.000000
L 3.18889902 -1.9788 3.18889902 -1.8988 3 P 0 ;0,3=9,5=0.000000
L 3.18889902 -1.8988 3.1768998 -1.91479911 3 P 0 ;0,3=9,5=0.000000
L 3.1768998 -1.9788 3.20089833 -1.9788 3 P 0 ;0,3=9,5=0.000000
L 2.5138999 -2.23313563 2.5219 -2.23980089 3 P 0 ;0,3=7,5=0.000000
L 2.5219 -2.23980089 2.5308999 -2.2438 3 P 0 ;0,3=7,5=0.000000
L 2.5308999 -2.2438 2.5389 -2.2438 3 P 0 ;0,3=7,5=0.000000
L 2.5389 -2.2438 2.5469001 -2.23980089 3 P 0 ;0,3=7,5=0.000000
L 2.5469001 -2.23980089 2.55290069 -2.23313563 3 P 0 ;0,3=7,5=0.000000
L 2.55290069 -2.23313563 2.5559 -2.22379941 3 P 0 ;0,3=7,5=0.000000
L 2.5559 -2.22379941 2.55390049 -2.21446811 3 P 0 ;0,3=7,5=0.000000
L 2.55390049 -2.21446811 2.5488997 -2.20646732 3 P 0 ;0,3=7,5=0.000000
L 2.5488997 -2.20646732 2.5398998 -2.20113278 3 P 0 ;0,3=7,5=0.000000
L 2.5398998 -2.20113278 2.52790049 -2.19846663 3 P 0 ;0,3=7,5=0.000000
L 2.52790049 -2.19846663 2.5209002 -2.19313445 3 P 0 ;0,3=7,5=0.000000
L 2.5209002 -2.19313445 2.51789902 -2.18380069 3 P 0 ;0,3=7,5=0.000000
L 2.51789902 -2.18380069 2.51990039 -2.17446683 3 P 0 ;0,3=7,5=0.000000
L 2.51990039 -2.17446683 2.52489931 -2.16780167 3 P 0 ;0,3=7,5=0.000000
L 2.52489931 -2.16780167 2.5318997 -2.1638 3 P 0 ;0,3=7,5=0.000000
L 2.5318997 -2.1638 2.5389 -2.1638 3 P 0 ;0,3=7,5=0.000000
L 2.5389 -2.1638 2.54590039 -2.16646614 3 P 0 ;0,3=7,5=0.000000
L 2.54590039 -2.16646614 2.55190089 -2.17313386 3 P 0 ;0,3=7,5=0.000000
L 2.5918999 -2.2438 2.5918999 -2.1638 3 P 0 ;0,3=7,5=0.000000
L 2.6339 -2.1638 2.6339 -2.2438 3 P 0 ;0,3=7,5=0.000000
L 2.6339 -2.20380128 2.5918999 -2.20380128 3 P 0 ;0,3=7,5=0.000000
L 2.7109003 -2.2438 2.67089961 -2.2438 3 P 0 ;0,3=7,5=0.000000
L 2.67089961 -2.2438 2.67089961 -2.1638 3 P 0 ;0,3=7,5=0.000000
L 2.67089961 -2.1638 2.7109003 -2.1638 3 P 0 ;0,3=7,5=0.000000
L 2.6949 -2.20246575 2.67089961 -2.20246575 3 P 0 ;0,3=7,5=0.000000
L 2.7889003 -2.2438 2.74889961 -2.2438 3 P 0 ;0,3=7,5=0.000000
L 2.74889961 -2.2438 2.74889961 -2.1638 3 P 0 ;0,3=7,5=0.000000
L 2.74889961 -2.1638 2.7889003 -2.1638 3 P 0 ;0,3=7,5=0.000000
L 2.7729 -2.20246575 2.74889961 -2.20246575 3 P 0 ;0,3=7,5=0.000000
L 2.84689902 -2.1638 2.84689902 -2.2438 3 P 0 ;0,3=7,5=0.000000
L 2.8239003 -2.1638 2.86989961 -2.1638 3 P 0 ;0,3=7,5=0.000000
L 3.29489961 -1.9238 3.29489961 -2.0038 3 P 0 ;0,3=10,5=0.000000
L 3.29489961 -2.0038 3.3349003 -2.0038 3 P 0 ;0,3=10,5=0.000000
L 3.36789892 -2.0038 3.39289902 -1.9238 3 P 0 ;0,3=10,5=0.000000
L 3.39289902 -1.9238 3.41790098 -2.0038 3 P 0 ;0,3=10,5=0.000000
L 3.40889931 -1.97580118 3.37689882 -1.97580118 3 P 0 ;0,3=10,5=0.000000
L 3.47089902 -2.0038 3.47089902 -1.96780039 3 P 0 ;0,3=10,5=0.000000
L 3.47089902 -1.96780039 3.45089961 -1.9238 3 P 0 ;0,3=10,5=0.000000
L 3.4909003 -1.9238 3.47089902 -1.96780039 3 P 0 ;0,3=10,5=0.000000
L 3.5689003 -2.0038 3.52889961 -2.0038 3 P 0 ;0,3=10,5=0.000000
L 3.52889961 -2.0038 3.52889961 -1.9238 3 P 0 ;0,3=10,5=0.000000
L 3.52889961 -1.9238 3.5689003 -1.9238 3 P 0 ;0,3=10,5=0.000000
L 3.5529 -1.96246575 3.52889961 -1.96246575 3 P 0 ;0,3=10,5=0.000000
L 3.60689961 -2.0038 3.60689961 -1.9238 3 P 0 ;0,3=10,5=0.000000
L 3.60689961 -1.9238 3.6318998 -1.9238 3 P 0 ;0,3=10,5=0.000000
L 3.6318998 -1.9238 3.6398999 -1.92780167 3 P 0 ;0,3=10,5=0.000000
L 3.6398999 -1.92780167 3.64490069 -1.93313386 3 P 0 ;0,3=10,5=0.000000
L 3.64490069 -1.93313386 3.6469003 -1.94380069 3 P 0 ;0,3=10,5=0.000000
L 3.6469003 -1.94380069 3.64490069 -1.95446752 3 P 0 ;0,3=10,5=0.000000
L 3.64490069 -1.95446752 3.6389001 -1.96113278 3 P 0 ;0,3=10,5=0.000000
L 3.6389001 -1.96113278 3.6318998 -1.96513435 3 P 0 ;0,3=10,5=0.000000
L 3.6318998 -1.96513435 3.60689961 -1.96513435 3 P 0 ;0,3=10,5=0.000000
L 3.6318998 -1.96513435 3.6469003 -2.0038 3 P 0 ;0,3=10,5=0.000000
L 3.33989902 -2.2538 3.33189892 -2.25246703 3 P 0 ;0,3=11,5=0.000000
L 3.33189892 -2.25246703 3.32490039 -2.24713484 3 P 0 ;0,3=11,5=0.000000
L 3.32490039 -2.24713484 3.3188999 -2.23913406 3 P 0 ;0,3=11,5=0.000000
L 3.3188999 -2.23913406 3.31489892 -2.2298003 3 P 0 ;0,3=11,5=0.000000
L 3.31489892 -2.2298003 3.31289931 -2.21913346 3 P 0 ;0,3=11,5=0.000000
L 3.31289931 -2.21913346 3.31289931 -2.20846663 3 P 0 ;0,3=11,5=0.000000
L 3.31289931 -2.20846663 3.31489892 -2.1977998 3 P 0 ;0,3=11,5=0.000000
L 3.31489892 -2.1977998 3.3188999 -2.18846604 3 P 0 ;0,3=11,5=0.000000
L 3.3188999 -2.18846604 3.32490039 -2.18046772 3 P 0 ;0,3=11,5=0.000000
L 3.32490039 -2.18046772 3.33189892 -2.17513307 3 P 0 ;0,3=11,5=0.000000
L 3.33189892 -2.17513307 3.33989902 -2.1738 3 P 0 ;0,3=11,5=0.000000
L 3.33989902 -2.1738 3.34789911 -2.17513307 3 P 0 ;0,3=11,5=0.000000
L 3.34789911 -2.17513307 3.35489951 -2.18046772 3 P 0 ;0,3=11,5=0.000000
L 3.35489951 -2.18046772 3.3609 -2.18846604 3 P 0 ;0,3=11,5=0.000000
L 3.3609 -2.18846604 3.36490098 -2.1977998 3 P 0 ;0,3=11,5=0.000000
L 3.36490098 -2.1977998 3.36690059 -2.20846663 3 P 0 ;0,3=11,5=0.000000
L 3.36690059 -2.20846663 3.36690059 -2.21913346 3 P 0 ;0,3=11,5=0.000000
L 3.36690059 -2.21913346 3.36490098 -2.2298003 3 P 0 ;0,3=11,5=0.000000
L 3.36490098 -2.2298003 3.3609 -2.23913406 3 P 0 ;0,3=11,5=0.000000
L 3.3609 -2.23913406 3.35489951 -2.24713484 3 P 0 ;0,3=11,5=0.000000
L 3.35489951 -2.24713484 3.34789911 -2.25246703 3 P 0 ;0,3=11,5=0.000000
L 3.34789911 -2.25246703 3.33989902 -2.2538 3 P 0 ;0,3=11,5=0.000000
L 3.39889941 -2.2538 3.39889941 -2.1738 3 P 0 ;0,3=11,5=0.000000
L 3.39889941 -2.1738 3.43690049 -2.1738 3 P 0 ;0,3=11,5=0.000000
L 3.4228998 -2.21246575 3.39889941 -2.21246575 3 P 0 ;0,3=11,5=0.000000
L 0.16489872 -1.0538 0.16489872 -1.1538 3 P 0 ;0,3=8,5=0.000000
L 0.13423376 -1.0538 0.19556614 -1.0538 3 P 0 ;0,3=8,5=0.000000
L 0.2588997 -1.0538 0.29089774 -1.0538 3 P 0 ;0,3=8,5=0.000000
L 0.27489872 -1.0538 0.27489872 -1.1538 3 P 0 ;0,3=8,5=0.000000
L 0.2588997 -1.1538 0.29089774 -1.1538 3 P 0 ;0,3=8,5=0.000000
L 0.38489872 -1.0538 0.38489872 -1.1538 3 P 0 ;0,3=8,5=0.000000
L 0.35423376 -1.0538 0.41556614 -1.0538 3 P 0 ;0,3=8,5=0.000000
L 0.46823287 -1.0538 0.46823287 -1.1538 3 P 0 ;0,3=8,5=0.000000
L 0.46823287 -1.1538 0.52156703 -1.1538 3 P 0 ;0,3=8,5=0.000000
L 0.63156703 -1.1538 0.57823287 -1.1538 3 P 0 ;0,3=8,5=0.000000
L 0.57823287 -1.1538 0.57823287 -1.0538 3 P 0 ;0,3=8,5=0.000000
L 0.57823287 -1.0538 0.63156703 -1.0538 3 P 0 ;0,3=8,5=0.000000
L 0.61023337 -1.10213219 0.57823287 -1.10213219 3 P 0 ;0,3=8,5=0.000000
L 4.18989892 -1.9538 4.21489902 -1.8738 3 P 0 ;0,3=12,5=0.000000
L 4.21489902 -1.8738 4.23990098 -1.9538 3 P 0 ;0,3=12,5=0.000000
L 4.23089931 -1.92580118 4.19889882 -1.92580118 3 P 0 ;0,3=12,5=0.000000
L 4.27289961 -1.9538 4.27289961 -1.8738 3 P 0 ;0,3=12,5=0.000000
L 4.27289961 -1.8738 4.2978998 -1.8738 3 P 0 ;0,3=12,5=0.000000
L 4.2978998 -1.8738 4.3058999 -1.87780167 3 P 0 ;0,3=12,5=0.000000
L 4.3058999 -1.87780167 4.31090069 -1.88313386 3 P 0 ;0,3=12,5=0.000000
L 4.31090069 -1.88313386 4.3129003 -1.89380069 3 P 0 ;0,3=12,5=0.000000
L 4.3129003 -1.89380069 4.31090069 -1.90446752 3 P 0 ;0,3=12,5=0.000000
L 4.31090069 -1.90446752 4.3049001 -1.91113278 3 P 0 ;0,3=12,5=0.000000
L 4.3049001 -1.91113278 4.2978998 -1.91513435 3 P 0 ;0,3=12,5=0.000000
L 4.2978998 -1.91513435 4.27289961 -1.91513435 3 P 0 ;0,3=12,5=0.000000
L 4.2978998 -1.91513435 4.3129003 -1.9538 3 P 0 ;0,3=12,5=0.000000
L 4.37089902 -1.8738 4.37089902 -1.9538 3 P 0 ;0,3=12,5=0.000000
L 4.3479003 -1.8738 4.39389961 -1.8738 3 P 0 ;0,3=12,5=0.000000
L 3.61989892 -2.2538 3.61989892 -2.1638 3 P 0 ;0,3=13,5=0.000000
L 3.61989892 -2.1638 3.6058997 -2.18179892 3 P 0 ;0,3=13,5=0.000000
L 3.6058997 -2.2538 3.63389803 -2.2538 3 P 0 ;0,3=13,5=0.000000
L 3.68773268 -2.17879961 3.69473337 -2.16980148 3 P 0 ;0,3=13,5=0.000000
L 3.69473337 -2.16980148 3.70290039 -2.1652997 3 P 0 ;0,3=13,5=0.000000
L 3.70290039 -2.1652997 3.71223386 -2.1638 3 P 0 ;0,3=13,5=0.000000
L 3.71223386 -2.1638 3.7239002 -2.16679941 3 P 0 ;0,3=13,5=0.000000
L 3.7239002 -2.16679941 3.73206722 -2.17430059 3 P 0 ;0,3=13,5=0.000000
L 3.73206722 -2.17430059 3.7344001 -2.18329862 3 P 0 ;0,3=13,5=0.000000
L 3.7344001 -2.18329862 3.73323366 -2.19230217 3 P 0 ;0,3=13,5=0.000000
L 3.73323366 -2.19230217 3.72856585 -2.19980059 3 P 0 ;0,3=13,5=0.000000
L 3.72856585 -2.19980059 3.70523317 -2.2148001 3 P 0 ;0,3=13,5=0.000000
L 3.70523317 -2.2148001 3.69473337 -2.22530069 3 P 0 ;0,3=13,5=0.000000
L 3.69473337 -2.22530069 3.68773268 -2.24030295 3 P 0 ;0,3=13,5=0.000000
L 3.68773268 -2.24030295 3.6853998 -2.2538 3 P 0 ;0,3=13,5=0.000000
L 3.6853998 -2.2538 3.7344001 -2.2538 3 P 0 ;0,3=13,5=0.000000
L 0.5058997 -1.6638 0.53389803 -1.6638 3 P 0 ;0,3=14,5=0.000000
L 0.51989892 -1.6638 0.51989892 -1.7538 3 P 0 ;0,3=14,5=0.000000
L 0.5058997 -1.7538 0.53389803 -1.7538 3 P 0 ;0,3=14,5=0.000000
L 0.58306703 -1.7538 0.58306703 -1.6638 3 P 0 ;0,3=14,5=0.000000
L 0.58306703 -1.6638 0.63673287 -1.7538 3 P 0 ;0,3=14,5=0.000000
L 0.63673287 -1.7538 0.63673287 -1.6638 3 P 0 ;0,3=14,5=0.000000
L 0.69989892 -1.6638 0.69989892 -1.7538 3 P 0 ;0,3=14,5=0.000000
L 0.67306703 -1.6638 0.72673287 -1.6638 3 P 0 ;0,3=14,5=0.000000
L 0.81323366 -1.7538 0.76656624 -1.7538 3 P 0 ;0,3=14,5=0.000000
L 0.76656624 -1.7538 0.76656624 -1.6638 3 P 0 ;0,3=14,5=0.000000
L 0.76656624 -1.6638 0.81323366 -1.6638 3 P 0 ;0,3=14,5=0.000000
L 0.79456673 -1.70729902 0.76656624 -1.70729902 3 P 0 ;0,3=14,5=0.000000
L 0.85656624 -1.7538 0.85656624 -1.6638 3 P 0 ;0,3=14,5=0.000000
L 0.85656624 -1.6638 0.88573307 -1.6638 3 P 0 ;0,3=14,5=0.000000
L 0.88573307 -1.6638 0.89506654 -1.66830187 3 P 0 ;0,3=14,5=0.000000
L 0.89506654 -1.66830187 0.90090079 -1.67430059 3 P 0 ;0,3=14,5=0.000000
L 0.90090079 -1.67430059 0.90323366 -1.68630069 3 P 0 ;0,3=14,5=0.000000
L 0.90323366 -1.68630069 0.90090079 -1.69830089 3 P 0 ;0,3=14,5=0.000000
L 0.90090079 -1.69830089 0.8939002 -1.70579931 3 P 0 ;0,3=14,5=0.000000
L 0.8939002 -1.70579931 0.88573307 -1.71030108 3 P 0 ;0,3=14,5=0.000000
L 0.88573307 -1.71030108 0.85656624 -1.71030108 3 P 0 ;0,3=14,5=0.000000
L 0.88573307 -1.71030108 0.90323366 -1.7538 3 P 0 ;0,3=14,5=0.000000
L 0.94306703 -1.7538 0.94306703 -1.6638 3 P 0 ;0,3=14,5=0.000000
L 0.94306703 -1.6638 0.99673287 -1.7538 3 P 0 ;0,3=14,5=0.000000
L 0.99673287 -1.7538 0.99673287 -1.6638 3 P 0 ;0,3=14,5=0.000000
L 1.03073209 -1.7538 1.05989892 -1.6638 3 P 0 ;0,3=14,5=0.000000
L 1.05989892 -1.6638 1.08906782 -1.7538 3 P 0 ;0,3=14,5=0.000000
L 1.07856585 -1.72230128 1.04123189 -1.72230128 3 P 0 ;0,3=14,5=0.000000
L 1.12656624 -1.6638 1.12656624 -1.7538 3 P 0 ;0,3=14,5=0.000000
L 1.12656624 -1.7538 1.17323366 -1.7538 3 P 0 ;0,3=14,5=0.000000
L 1.30656624 -1.6638 1.30656624 -1.7538 3 P 0 ;0,3=14,5=0.000000
L 1.30656624 -1.7538 1.35323366 -1.7538 3 P 0 ;0,3=14,5=0.000000
L 1.39073209 -1.7538 1.41989892 -1.6638 3 P 0 ;0,3=14,5=0.000000
L 1.41989892 -1.6638 1.44906782 -1.7538 3 P 0 ;0,3=14,5=0.000000
L 1.43856585 -1.72230128 1.40123189 -1.72230128 3 P 0 ;0,3=14,5=0.000000
L 1.50989892 -1.7538 1.50989892 -1.71330049 3 P 0 ;0,3=14,5=0.000000
L 1.50989892 -1.71330049 1.48656624 -1.6638 3 P 0 ;0,3=14,5=0.000000
L 1.53323366 -1.6638 1.50989892 -1.71330049 3 P 0 ;0,3=14,5=0.000000
L 1.62323366 -1.7538 1.57656624 -1.7538 3 P 0 ;0,3=14,5=0.000000
L 1.57656624 -1.7538 1.57656624 -1.6638 3 P 0 ;0,3=14,5=0.000000
L 1.57656624 -1.6638 1.62323366 -1.6638 3 P 0 ;0,3=14,5=0.000000
L 1.60456673 -1.70729902 1.57656624 -1.70729902 3 P 0 ;0,3=14,5=0.000000
L 1.66656624 -1.7538 1.66656624 -1.6638 3 P 0 ;0,3=14,5=0.000000
L 1.66656624 -1.6638 1.69573307 -1.6638 3 P 0 ;0,3=14,5=0.000000
L 1.69573307 -1.6638 1.70506654 -1.66830187 3 P 0 ;0,3=14,5=0.000000
L 1.70506654 -1.66830187 1.71090079 -1.67430059 3 P 0 ;0,3=14,5=0.000000
L 1.71090079 -1.67430059 1.71323366 -1.68630069 3 P 0 ;0,3=14,5=0.000000
L 1.71323366 -1.68630069 1.71090079 -1.69830089 3 P 0 ;0,3=14,5=0.000000
L 1.71090079 -1.69830089 1.7039002 -1.70579931 3 P 0 ;0,3=14,5=0.000000
L 1.7039002 -1.70579931 1.69573307 -1.71030108 3 P 0 ;0,3=14,5=0.000000
L 1.69573307 -1.71030108 1.66656624 -1.71030108 3 P 0 ;0,3=14,5=0.000000
L 1.69573307 -1.71030108 1.71323366 -1.7538 3 P 0 ;0,3=14,5=0.000000
L 1.84423346 -1.74030295 1.85123189 -1.74780138 3 P 0 ;0,3=14,5=0.000000
L 1.85123189 -1.74780138 1.85939902 -1.75230039 3 P 0 ;0,3=14,5=0.000000
L 1.85939902 -1.75230039 1.86989892 -1.7538 3 P 0 ;0,3=14,5=0.000000
L 1.86989892 -1.7538 1.88040089 -1.75080069 3 P 0 ;0,3=14,5=0.000000
L 1.88040089 -1.75080069 1.88856585 -1.74480197 3 P 0 ;0,3=14,5=0.000000
L 1.88856585 -1.74480197 1.8944001 -1.73430148 3 P 0 ;0,3=14,5=0.000000
L 1.8944001 -1.73430148 1.89556644 -1.72230128 3 P 0 ;0,3=14,5=0.000000
L 1.89556644 -1.72230128 1.89323366 -1.71030108 3 P 0 ;0,3=14,5=0.000000
L 1.89323366 -1.71030108 1.88739941 -1.7028 3 P 0 ;0,3=14,5=0.000000
L 1.88739941 -1.7028 1.87923238 -1.69680128 3 P 0 ;0,3=14,5=0.000000
L 1.87923238 -1.69680128 1.87106742 -1.69530157 3 P 0 ;0,3=14,5=0.000000
L 1.87106742 -1.69530157 1.86290039 -1.69680128 3 P 0 ;0,3=14,5=0.000000
L 1.86290039 -1.69680128 1.85240049 -1.7028 3 P 0 ;0,3=14,5=0.000000
L 1.85240049 -1.7028 1.8558997 -1.6638 3 P 0 ;0,3=14,5=0.000000
L 1.8558997 -1.6638 1.88739941 -1.6638 3 P 0 ;0,3=14,5=0.000000
L 3.79423346 -1.99030295 3.80123189 -1.99780138 3 P 0 ;0,3=15,5=0.000000
L 3.80123189 -1.99780138 3.80939902 -2.00230039 3 P 0 ;0,3=15,5=0.000000
L 3.80939902 -2.00230039 3.81989892 -2.0038 3 P 0 ;0,3=15,5=0.000000
L 3.81989892 -2.0038 3.83040089 -2.00080069 3 P 0 ;0,3=15,5=0.000000
L 3.83040089 -2.00080069 3.83856585 -1.99480197 3 P 0 ;0,3=15,5=0.000000
L 3.83856585 -1.99480197 3.8444001 -1.98430148 3 P 0 ;0,3=15,5=0.000000
L 3.8444001 -1.98430148 3.84556644 -1.97230128 3 P 0 ;0,3=15,5=0.000000
L 3.84556644 -1.97230128 3.84323366 -1.96030108 3 P 0 ;0,3=15,5=0.000000
L 3.84323366 -1.96030108 3.83739941 -1.9528 3 P 0 ;0,3=15,5=0.000000
L 3.83739941 -1.9528 3.82923238 -1.94680128 3 P 0 ;0,3=15,5=0.000000
L 3.82923238 -1.94680128 3.82106742 -1.94530157 3 P 0 ;0,3=15,5=0.000000
L 3.82106742 -1.94530157 3.81290039 -1.94680128 3 P 0 ;0,3=15,5=0.000000
L 3.81290039 -1.94680128 3.80240049 -1.9528 3 P 0 ;0,3=15,5=0.000000
L 3.80240049 -1.9528 3.8058997 -1.9138 3 P 0 ;0,3=15,5=0.000000
L 3.8058997 -1.9138 3.83739941 -1.9138 3 P 0 ;0,3=15,5=0.000000
L 3.04423346 -2.24030295 3.05123189 -2.24780138 3 P 0 ;0,3=15,5=0.000000
L 3.05123189 -2.24780138 3.05939902 -2.25230039 3 P 0 ;0,3=15,5=0.000000
L 3.05939902 -2.25230039 3.06989892 -2.2538 3 P 0 ;0,3=15,5=0.000000
L 3.06989892 -2.2538 3.08040089 -2.25080069 3 P 0 ;0,3=15,5=0.000000
L 3.08040089 -2.25080069 3.08856585 -2.24480197 3 P 0 ;0,3=15,5=0.000000
L 3.08856585 -2.24480197 3.0944001 -2.23430148 3 P 0 ;0,3=15,5=0.000000
L 3.0944001 -2.23430148 3.09556644 -2.22230128 3 P 0 ;0,3=15,5=0.000000
L 3.09556644 -2.22230128 3.09323366 -2.21030108 3 P 0 ;0,3=15,5=0.000000
L 3.09323366 -2.21030108 3.08739941 -2.2028 3 P 0 ;0,3=15,5=0.000000
L 3.08739941 -2.2028 3.07923238 -2.19680128 3 P 0 ;0,3=15,5=0.000000
L 3.07923238 -2.19680128 3.07106742 -2.19530157 3 P 0 ;0,3=15,5=0.000000
L 3.07106742 -2.19530157 3.06290039 -2.19680128 3 P 0 ;0,3=15,5=0.000000
L 3.06290039 -2.19680128 3.05240049 -2.2028 3 P 0 ;0,3=15,5=0.000000
L 3.05240049 -2.2028 3.0558997 -2.1638 3 P 0 ;0,3=15,5=0.000000
L 3.0558997 -2.1638 3.08739941 -2.1638 3 P 0 ;0,3=15,5=0.000000
L 0.59099833 -1.36499882 0.5990003 -1.35750039 3 P 0 ;0,3=16,5=0.000000
L 0.5990003 -1.35750039 0.60499902 -1.34500315 3 P 0 ;0,3=16,5=0.000000
L 0.60499902 -1.34500315 0.60900187 -1.32749764 3 P 0 ;0,3=16,5=0.000000
L 0.60900187 -1.32749764 0.60499902 -1.31250089 3 P 0 ;0,3=16,5=0.000000
L 0.60499902 -1.31250089 0.59700079 -1.30250305 3 P 0 ;0,3=16,5=0.000000
L 0.59700079 -1.30250305 0.5830001 -1.295 3 P 0 ;0,3=16,5=0.000000
L 0.5830001 -1.295 0.52900059 -1.295 3 P 0 ;0,3=16,5=0.000000
L 0.52900059 -1.295 0.52900059 -1.445 3 P 0 ;0,3=16,5=0.000000
L 0.52900059 -1.445 0.59500118 -1.445 3 P 0 ;0,3=16,5=0.000000
L 0.59500118 -1.445 0.60900187 -1.43500217 3 P 0 ;0,3=16,5=0.000000
L 0.60900187 -1.43500217 0.6170001 -1.42000079 3 P 0 ;0,3=16,5=0.000000
L 0.6170001 -1.42000079 0.62099931 -1.4025 3 P 0 ;0,3=16,5=0.000000
L 0.62099931 -1.4025 0.6170001 -1.38500374 3 P 0 ;0,3=16,5=0.000000
L 0.6170001 -1.38500374 0.60499902 -1.37000236 3 P 0 ;0,3=16,5=0.000000
L 0.60499902 -1.37000236 0.59099833 -1.36499882 3 P 0 ;0,3=16,5=0.000000
L 0.59099833 -1.36499882 0.52900059 -1.36499882 3 P 0 ;0,3=16,5=0.000000
L 0.77100138 -1.445 0.77100138 -1.34500315 3 P 0 ;0,3=16,5=0.000000
L 0.77100138 -1.36249941 0.76299951 -1.35250148 3 P 0 ;0,3=16,5=0.000000
L 0.76299951 -1.35250148 0.75099833 -1.34750256 3 P 0 ;0,3=16,5=0.000000
L 0.75099833 -1.34750256 0.73700138 -1.34500315 3 P 0 ;0,3=16,5=0.000000
L 0.73700138 -1.34500315 0.72300069 -1.35000207 3 P 0 ;0,3=16,5=0.000000
L 0.72300069 -1.35000207 0.71099961 -1.3599999 3 P 0 ;0,3=16,5=0.000000
L 0.71099961 -1.3599999 0.70299764 -1.37500128 3 P 0 ;0,3=16,5=0.000000
L 0.70299764 -1.37500128 0.69899852 -1.39500157 3 P 0 ;0,3=16,5=0.000000
L 0.69899852 -1.39500157 0.70299764 -1.41500187 3 P 0 ;0,3=16,5=0.000000
L 0.70299764 -1.41500187 0.71099961 -1.43000325 3 P 0 ;0,3=16,5=0.000000
L 0.71099961 -1.43000325 0.72300069 -1.44000108 3 P 0 ;0,3=16,5=0.000000
L 0.72300069 -1.44000108 0.73700138 -1.445 3 P 0 ;0,3=16,5=0.000000
L 0.73700138 -1.445 0.75099833 -1.44250059 3 P 0 ;0,3=16,5=0.000000
L 0.75099833 -1.44250059 0.76299951 -1.43500217 3 P 0 ;0,3=16,5=0.000000
L 0.76299951 -1.43500217 0.77100138 -1.42500433 3 P 0 ;0,3=16,5=0.000000
L 0.86700039 -1.445 0.86700039 -1.34500315 3 P 0 ;0,3=16,5=0.000000
L 0.86700039 -1.36499882 0.87699833 -1.35500098 3 P 0 ;0,3=16,5=0.000000
L 0.87699833 -1.35500098 0.8869998 -1.34750256 3 P 0 ;0,3=16,5=0.000000
L 0.8869998 -1.34750256 0.90100049 -1.34500315 3 P 0 ;0,3=16,5=0.000000
L 0.90100049 -1.34500315 0.91099833 -1.34750256 3 P 0 ;0,3=16,5=0.000000
L 0.91099833 -1.34750256 0.92299951 -1.35500098 3 P 0 ;0,3=16,5=0.000000
L 1.02700039 -1.445 1.02700039 -1.34500315 3 P 0 ;0,3=16,5=0.000000
L 1.02700039 -1.36499882 1.03699833 -1.35500098 3 P 0 ;0,3=16,5=0.000000
L 1.03699833 -1.35500098 1.0469998 -1.34750256 3 P 0 ;0,3=16,5=0.000000
L 1.0469998 -1.34750256 1.06100049 -1.34500315 3 P 0 ;0,3=16,5=0.000000
L 1.06100049 -1.34500315 1.07099833 -1.34750256 3 P 0 ;0,3=16,5=0.000000
L 1.07099833 -1.34750256 1.08299951 -1.35500098 3 P 0 ;0,3=16,5=0.000000
L 1.18500089 -1.37750069 1.24900187 -1.37750069 3 P 0 ;0,3=16,5=0.000000
L 1.24900187 -1.37750069 1.24299951 -1.3599999 3 P 0 ;0,3=16,5=0.000000
L 1.24299951 -1.3599999 1.23300157 -1.35000207 3 P 0 ;0,3=16,5=0.000000
L 1.23300157 -1.35000207 1.21900089 -1.34500315 3 P 0 ;0,3=16,5=0.000000
L 1.21900089 -1.34500315 1.2050003 -1.34750256 3 P 0 ;0,3=16,5=0.000000
L 1.2050003 -1.34750256 1.19299911 -1.35500098 3 P 0 ;0,3=16,5=0.000000
L 1.19299911 -1.35500098 1.18500089 -1.37250177 3 P 0 ;0,3=16,5=0.000000
L 1.18500089 -1.37250177 1.18099803 -1.38750315 3 P 0 ;0,3=16,5=0.000000
L 1.18099803 -1.38750315 1.18099803 -1.4025 3 P 0 ;0,3=16,5=0.000000
L 1.18099803 -1.4025 1.18500089 -1.41750138 3 P 0 ;0,3=16,5=0.000000
L 1.18500089 -1.41750138 1.19499872 -1.43250276 3 P 0 ;0,3=16,5=0.000000
L 1.19499872 -1.43250276 1.2069998 -1.44250059 3 P 0 ;0,3=16,5=0.000000
L 1.2069998 -1.44250059 1.22100049 -1.445 3 P 0 ;0,3=16,5=0.000000
L 1.22100049 -1.445 1.23500118 -1.44000108 3 P 0 ;0,3=16,5=0.000000
L 1.23500118 -1.44000108 1.24900187 -1.42500433 3 P 0 ;0,3=16,5=0.000000
L 1.37499813 -1.445 1.37499813 -1.295 3 P 0 ;0,3=16,5=0.000000
L 1.50500089 -1.37750069 1.56900187 -1.37750069 3 P 0 ;0,3=16,5=0.000000
L 1.56900187 -1.37750069 1.56299951 -1.3599999 3 P 0 ;0,3=16,5=0.000000
L 1.56299951 -1.3599999 1.55300157 -1.35000207 3 P 0 ;0,3=16,5=0.000000
L 1.55300157 -1.35000207 1.53900089 -1.34500315 3 P 0 ;0,3=16,5=0.000000
L 1.53900089 -1.34500315 1.5250003 -1.34750256 3 P 0 ;0,3=16,5=0.000000
L 1.5250003 -1.34750256 1.51299911 -1.35500098 3 P 0 ;0,3=16,5=0.000000
L 1.51299911 -1.35500098 1.50500089 -1.37250177 3 P 0 ;0,3=16,5=0.000000
L 1.50500089 -1.37250177 1.50099803 -1.38750315 3 P 0 ;0,3=16,5=0.000000
L 1.50099803 -1.38750315 1.50099803 -1.4025 3 P 0 ;0,3=16,5=0.000000
L 1.50099803 -1.4025 1.50500089 -1.41750138 3 P 0 ;0,3=16,5=0.000000
L 1.50500089 -1.41750138 1.51499872 -1.43250276 3 P 0 ;0,3=16,5=0.000000
L 1.51499872 -1.43250276 1.5269998 -1.44250059 3 P 0 ;0,3=16,5=0.000000
L 1.5269998 -1.44250059 1.54100049 -1.445 3 P 0 ;0,3=16,5=0.000000
L 1.54100049 -1.445 1.55500118 -1.44000108 3 P 0 ;0,3=16,5=0.000000
L 1.55500118 -1.44000108 1.56900187 -1.42500433 3 P 0 ;0,3=16,5=0.000000
L 1.6529998 -1.48999951 1.66500089 -1.49499843 3 P 0 ;0,3=16,5=0.000000
L 1.66500089 -1.49499843 1.68100108 -1.48999951 3 P 0 ;0,3=16,5=0.000000
L 1.68100108 -1.48999951 1.69099902 -1.48000167 3 P 0 ;0,3=16,5=0.000000
L 1.69099902 -1.48000167 1.69900089 -1.4674997 3 P 0 ;0,3=16,5=0.000000
L 1.69900089 -1.4674997 1.71099833 -1.42750374 3 P 0 ;0,3=16,5=0.000000
L 1.71099833 -1.42750374 1.7370001 -1.34500315 3 P 0 ;0,3=16,5=0.000000
L 1.67299911 -1.34500315 1.71099833 -1.42750374 3 P 0 ;0,3=16,5=0.000000
L 1.82500089 -1.37750069 1.88900187 -1.37750069 3 P 0 ;0,3=16,5=0.000000
L 1.88900187 -1.37750069 1.88299951 -1.3599999 3 P 0 ;0,3=16,5=0.000000
L 1.88299951 -1.3599999 1.87300157 -1.35000207 3 P 0 ;0,3=16,5=0.000000
L 1.87300157 -1.35000207 1.85900089 -1.34500315 3 P 0 ;0,3=16,5=0.000000
L 1.85900089 -1.34500315 1.8450003 -1.34750256 3 P 0 ;0,3=16,5=0.000000
L 1.8450003 -1.34750256 1.83299911 -1.35500098 3 P 0 ;0,3=16,5=0.000000
L 1.83299911 -1.35500098 1.82500089 -1.37250177 3 P 0 ;0,3=16,5=0.000000
L 1.82500089 -1.37250177 1.82099803 -1.38750315 3 P 0 ;0,3=16,5=0.000000
L 1.82099803 -1.38750315 1.82099803 -1.4025 3 P 0 ;0,3=16,5=0.000000
L 1.82099803 -1.4025 1.82500089 -1.41750138 3 P 0 ;0,3=16,5=0.000000
L 1.82500089 -1.41750138 1.83499872 -1.43250276 3 P 0 ;0,3=16,5=0.000000
L 1.83499872 -1.43250276 1.8469998 -1.44250059 3 P 0 ;0,3=16,5=0.000000
L 1.8469998 -1.44250059 1.86100049 -1.445 3 P 0 ;0,3=16,5=0.000000
L 1.86100049 -1.445 1.87500118 -1.44000108 3 P 0 ;0,3=16,5=0.000000
L 1.87500118 -1.44000108 1.88900187 -1.42500433 3 P 0 ;0,3=16,5=0.000000
L 2.18699921 -1.37000236 2.22700167 -1.37000236 3 P 0 ;0,3=16,5=0.000000
L 2.22700167 -1.37000236 2.22700167 -1.41500187 3 P 0 ;0,3=16,5=0.000000
L 2.22700167 -1.41500187 2.21500059 -1.43000325 3 P 0 ;0,3=16,5=0.000000
L 2.21500059 -1.43000325 2.2009999 -1.44000108 3 P 0 ;0,3=16,5=0.000000
L 2.2009999 -1.44000108 2.18100049 -1.445 3 P 0 ;0,3=16,5=0.000000
L 2.18100049 -1.445 2.16100108 -1.44000108 3 P 0 ;0,3=16,5=0.000000
L 2.16100108 -1.44000108 2.14700039 -1.43000325 3 P 0 ;0,3=16,5=0.000000
L 2.14700039 -1.43000325 2.13499931 -1.41500187 3 P 0 ;0,3=16,5=0.000000
L 2.13499931 -1.41500187 2.12699734 -1.39750108 3 P 0 ;0,3=16,5=0.000000
L 2.12699734 -1.39750108 2.12299823 -1.37750069 3 P 0 ;0,3=16,5=0.000000
L 2.12299823 -1.37750069 2.12299823 -1.3599999 3 P 0 ;0,3=16,5=0.000000
L 2.12299823 -1.3599999 2.12699734 -1.34500315 3 P 0 ;0,3=16,5=0.000000
L 2.12699734 -1.34500315 2.13499931 -1.32749764 3 P 0 ;0,3=16,5=0.000000
L 2.13499931 -1.32749764 2.14700039 -1.31250089 3 P 0 ;0,3=16,5=0.000000
L 2.14700039 -1.31250089 2.15899783 -1.30250305 3 P 0 ;0,3=16,5=0.000000
L 2.15899783 -1.30250305 2.17499813 -1.295 3 P 0 ;0,3=16,5=0.000000
L 2.17499813 -1.295 2.18899882 -1.295 3 P 0 ;0,3=16,5=0.000000
L 2.18899882 -1.295 2.20499902 -1.29999902 3 P 0 ;0,3=16,5=0.000000
L 2.20499902 -1.29999902 2.2170001 -1.31000138 3 P 0 ;0,3=16,5=0.000000
L 2.29699892 -1.31999931 2.309 -1.30500246 3 P 0 ;0,3=16,5=0.000000
L 2.309 -1.30500246 2.32300069 -1.29749951 3 P 0 ;0,3=16,5=0.000000
L 2.32300069 -1.29749951 2.33900089 -1.295 3 P 0 ;0,3=16,5=0.000000
L 2.33900089 -1.295 2.3590003 -1.29999902 3 P 0 ;0,3=16,5=0.000000
L 2.3590003 -1.29999902 2.37300098 -1.31250089 3 P 0 ;0,3=16,5=0.000000
L 2.37300098 -1.31250089 2.3770001 -1.32749764 3 P 0 ;0,3=16,5=0.000000
L 2.3770001 -1.32749764 2.37500059 -1.34250364 3 P 0 ;0,3=16,5=0.000000
L 2.37500059 -1.34250364 2.36699862 -1.35500098 3 P 0 ;0,3=16,5=0.000000
L 2.36699862 -1.35500098 2.3269998 -1.3800002 3 P 0 ;0,3=16,5=0.000000
L 2.3269998 -1.3800002 2.309 -1.39750108 3 P 0 ;0,3=16,5=0.000000
L 2.309 -1.39750108 2.29699892 -1.42250482 3 P 0 ;0,3=16,5=0.000000
L 2.29699892 -1.42250482 2.2929998 -1.445 3 P 0 ;0,3=16,5=0.000000
L 2.2929998 -1.445 2.3770001 -1.445 3 P 0 ;0,3=16,5=0.000000
L 2.6129998 -1.42500433 2.629 -1.43750167 3 P 0 ;0,3=16,5=0.000000
L 2.629 -1.43750167 2.6469998 -1.445 3 P 0 ;0,3=16,5=0.000000
L 2.6469998 -1.445 2.6630001 -1.445 3 P 0 ;0,3=16,5=0.000000
L 2.6630001 -1.445 2.6790003 -1.43750167 3 P 0 ;0,3=16,5=0.000000
L 2.6790003 -1.43750167 2.69100138 -1.42500433 3 P 0 ;0,3=16,5=0.000000
L 2.69100138 -1.42500433 2.6970001 -1.40749892 3 P 0 ;0,3=16,5=0.000000
L 2.6970001 -1.40749892 2.69300098 -1.39000266 3 P 0 ;0,3=16,5=0.000000
L 2.69300098 -1.39000266 2.68299951 -1.37500128 3 P 0 ;0,3=16,5=0.000000
L 2.68299951 -1.37500128 2.66499961 -1.36499882 3 P 0 ;0,3=16,5=0.000000
L 2.66499961 -1.36499882 2.64100108 -1.3599999 3 P 0 ;0,3=16,5=0.000000
L 2.64100108 -1.3599999 2.62700039 -1.35000207 3 P 0 ;0,3=16,5=0.000000
L 2.62700039 -1.35000207 2.62099803 -1.33250118 3 P 0 ;0,3=16,5=0.000000
L 2.62099803 -1.33250118 2.62500089 -1.31500039 3 P 0 ;0,3=16,5=0.000000
L 2.62500089 -1.31500039 2.63499872 -1.30250305 3 P 0 ;0,3=16,5=0.000000
L 2.63499872 -1.30250305 2.64899941 -1.295 3 P 0 ;0,3=16,5=0.000000
L 2.64899941 -1.295 2.6630001 -1.295 3 P 0 ;0,3=16,5=0.000000
L 2.6630001 -1.295 2.67700079 -1.29999902 3 P 0 ;0,3=16,5=0.000000
L 2.67700079 -1.29999902 2.68900187 -1.31250089 3 P 0 ;0,3=16,5=0.000000
L 2.7729998 -1.445 2.8570001 -1.295 3 P 0 ;0,3=16,5=0.000000
L 2.7729998 -1.295 2.8570001 -1.445 3 P 0 ;0,3=16,5=0.000000
L 2.92299823 -1.445 2.92299823 -1.295 3 P 0 ;0,3=16,5=0.000000
L 2.92299823 -1.295 2.97499813 -1.42000079 3 P 0 ;0,3=16,5=0.000000
L 2.97499813 -1.42000079 3.02700167 -1.295 3 P 0 ;0,3=16,5=0.000000
L 3.02700167 -1.295 3.02700167 -1.445 3 P 0 ;0,3=16,5=0.000000
L 3.09699892 -1.31999931 3.109 -1.30500246 3 P 0 ;0,3=16,5=0.000000
L 3.109 -1.30500246 3.12300069 -1.29749951 3 P 0 ;0,3=16,5=0.000000
L 3.12300069 -1.29749951 3.13900089 -1.295 3 P 0 ;0,3=16,5=0.000000
L 3.13900089 -1.295 3.1590003 -1.29999902 3 P 0 ;0,3=16,5=0.000000
L 3.1590003 -1.29999902 3.17300098 -1.31250089 3 P 0 ;0,3=16,5=0.000000
L 3.17300098 -1.31250089 3.1770001 -1.32749764 3 P 0 ;0,3=16,5=0.000000
L 3.1770001 -1.32749764 3.17500059 -1.34250364 3 P 0 ;0,3=16,5=0.000000
L 3.17500059 -1.34250364 3.16699862 -1.35500098 3 P 0 ;0,3=16,5=0.000000
L 3.16699862 -1.35500098 3.1269998 -1.3800002 3 P 0 ;0,3=16,5=0.000000
L 3.1269998 -1.3800002 3.109 -1.39750108 3 P 0 ;0,3=16,5=0.000000
L 3.109 -1.39750108 3.09699892 -1.42250482 3 P 0 ;0,3=16,5=0.000000
L 3.09699892 -1.42250482 3.0929998 -1.445 3 P 0 ;0,3=16,5=0.000000
L 3.0929998 -1.445 3.1770001 -1.445 3 P 0 ;0,3=16,5=0.000000
L 3.269 -1.39500157 3.3209999 -1.39500157 3 P 0 ;0,3=16,5=0.000000
L 3.41499931 -1.445 3.41499931 -1.295 3 P 0 ;0,3=16,5=0.000000
L 3.41499931 -1.295 3.46499961 -1.295 3 P 0 ;0,3=16,5=0.000000
L 3.46499961 -1.295 3.4809999 -1.30250305 3 P 0 ;0,3=16,5=0.000000
L 3.4809999 -1.30250305 3.49100138 -1.31250089 3 P 0 ;0,3=16,5=0.000000
L 3.49100138 -1.31250089 3.49500059 -1.33250118 3 P 0 ;0,3=16,5=0.000000
L 3.49500059 -1.33250118 3.49100138 -1.35250148 3 P 0 ;0,3=16,5=0.000000
L 3.49100138 -1.35250148 3.4790003 -1.36499882 3 P 0 ;0,3=16,5=0.000000
L 3.4790003 -1.36499882 3.46499961 -1.37250177 3 P 0 ;0,3=16,5=0.000000
L 3.46499961 -1.37250177 3.41499931 -1.37250177 3 P 0 ;0,3=16,5=0.000000
L 3.46499961 -1.37250177 3.49500059 -1.445 3 P 0 ;0,3=16,5=0.000000
L 3.61499813 -1.34500315 3.61499813 -1.445 3 P 0 ;0,3=16,5=0.000000
L 3.61499813 -1.30500246 3.61099902 -1.30250305 3 P 0 ;0,3=16,5=0.000000
L 3.61099902 -1.30250305 3.61099902 -1.29749951 3 P 0 ;0,3=16,5=0.000000
L 3.61099902 -1.29749951 3.61499813 -1.295 3 P 0 ;0,3=16,5=0.000000
L 3.61499813 -1.295 3.61900089 -1.29749951 3 P 0 ;0,3=16,5=0.000000
L 3.61900089 -1.29749951 3.61900089 -1.30250305 3 P 0 ;0,3=16,5=0.000000
L 3.61900089 -1.30250305 3.61499813 -1.30500246 3 P 0 ;0,3=16,5=0.000000
L 3.74500089 -1.42750374 3.75499872 -1.43750167 3 P 0 ;0,3=16,5=0.000000
L 3.75499872 -1.43750167 3.76899941 -1.445 3 P 0 ;0,3=16,5=0.000000
L 3.76899941 -1.445 3.78100049 -1.445 3 P 0 ;0,3=16,5=0.000000
L 3.78100049 -1.445 3.79300157 -1.44000108 3 P 0 ;0,3=16,5=0.000000
L 3.79300157 -1.44000108 3.8009999 -1.43250276 3 P 0 ;0,3=16,5=0.000000
L 3.8009999 -1.43250276 3.80499902 -1.42250482 3 P 0 ;0,3=16,5=0.000000
L 3.80499902 -1.42250482 3.80299951 -1.40749892 3 P 0 ;0,3=16,5=0.000000
L 3.80299951 -1.40749892 3.79500118 -1.40000049 3 P 0 ;0,3=16,5=0.000000
L 3.79500118 -1.40000049 3.75899783 -1.38500374 3 P 0 ;0,3=16,5=0.000000
L 3.75899783 -1.38500374 3.75099961 -1.36749833 3 P 0 ;0,3=16,5=0.000000
L 3.75099961 -1.36749833 3.75499872 -1.35500098 3 P 0 ;0,3=16,5=0.000000
L 3.75499872 -1.35500098 3.76300069 -1.34750256 3 P 0 ;0,3=16,5=0.000000
L 3.76300069 -1.34750256 3.77499813 -1.34500315 3 P 0 ;0,3=16,5=0.000000
L 3.77499813 -1.34500315 3.78699921 -1.34750256 3 P 0 ;0,3=16,5=0.000000
L 3.78699921 -1.34750256 3.7990003 -1.35500098 3 P 0 ;0,3=16,5=0.000000
L 3.90500089 -1.37750069 3.96900187 -1.37750069 3 P 0 ;0,3=16,5=0.000000
L 3.96900187 -1.37750069 3.96299951 -1.3599999 3 P 0 ;0,3=16,5=0.000000
L 3.96299951 -1.3599999 3.95300157 -1.35000207 3 P 0 ;0,3=16,5=0.000000
L 3.95300157 -1.35000207 3.93900089 -1.34500315 3 P 0 ;0,3=16,5=0.000000
L 3.93900089 -1.34500315 3.9250003 -1.34750256 3 P 0 ;0,3=16,5=0.000000
L 3.9250003 -1.34750256 3.91299911 -1.35500098 3 P 0 ;0,3=16,5=0.000000
L 3.91299911 -1.35500098 3.90500089 -1.37250177 3 P 0 ;0,3=16,5=0.000000
L 3.90500089 -1.37250177 3.90099803 -1.38750315 3 P 0 ;0,3=16,5=0.000000
L 3.90099803 -1.38750315 3.90099803 -1.4025 3 P 0 ;0,3=16,5=0.000000
L 3.90099803 -1.4025 3.90500089 -1.41750138 3 P 0 ;0,3=16,5=0.000000
L 3.90500089 -1.41750138 3.91499872 -1.43250276 3 P 0 ;0,3=16,5=0.000000
L 3.91499872 -1.43250276 3.9269998 -1.44250059 3 P 0 ;0,3=16,5=0.000000
L 3.9269998 -1.44250059 3.94100049 -1.445 3 P 0 ;0,3=16,5=0.000000
L 3.94100049 -1.445 3.95500118 -1.44000108 3 P 0 ;0,3=16,5=0.000000
L 3.95500118 -1.44000108 3.96900187 -1.42500433 3 P 0 ;0,3=16,5=0.000000
L 4.06700039 -1.445 4.06700039 -1.34500315 3 P 0 ;0,3=16,5=0.000000
L 4.06700039 -1.36499882 4.07699833 -1.35500098 3 P 0 ;0,3=16,5=0.000000
L 4.07699833 -1.35500098 4.0869998 -1.34750256 3 P 0 ;0,3=16,5=0.000000
L 4.0869998 -1.34750256 4.10100049 -1.34500315 3 P 0 ;0,3=16,5=0.000000
L 4.10100049 -1.34500315 4.11099833 -1.34750256 3 P 0 ;0,3=16,5=0.000000
L 4.11099833 -1.34750256 4.12299951 -1.35500098 3 P 0 ;0,3=16,5=0.000000
L 4.16964783 -2.2038 4.21839813 -2.0478 3 P 0 ;0,3=17,5=0.000000
L 4.21839813 -2.0478 4.26715207 -2.2038 3 P 0 ;0,3=17,5=0.000000
L 4.24959862 -2.14920217 4.18719774 -2.14920217 3 P 0 ;0,3=17,5=0.000000
L 4.37939813 -2.2038 4.37939813 -2.0478 3 P 0 ;0,3=17,5=0.000000
L 4.37939813 -2.0478 4.35599961 -2.07899813 3 P 0 ;0,3=17,5=0.000000
L 4.35599961 -2.2038 4.40279675 -2.2038 3 P 0 ;0,3=17,5=0.000000
L 2.0009002 -0.9538 2.0009002 -0.8038 3 P 0 ;0,3=18,5=0.000000
L 2.0009002 -0.8038 2.04089902 -0.8038 3 P 0 ;0,3=18,5=0.000000
L 2.04089902 -0.8038 2.05689921 -0.81130305 3 P 0 ;0,3=18,5=0.000000
L 2.05689921 -0.81130305 2.0689003 -0.82130089 3 P 0 ;0,3=18,5=0.000000
L 2.0689003 -0.82130089 2.07890187 -0.83629764 3 P 0 ;0,3=18,5=0.000000
L 2.07890187 -0.83629764 2.0869001 -0.85380315 3 P 0 ;0,3=18,5=0.000000
L 2.0869001 -0.85380315 2.0888997 -0.87880236 3 P 0 ;0,3=18,5=0.000000
L 2.0888997 -0.87880236 2.0869001 -0.90380157 3 P 0 ;0,3=18,5=0.000000
L 2.0869001 -0.90380157 2.07890187 -0.92130246 3 P 0 ;0,3=18,5=0.000000
L 2.07890187 -0.92130246 2.0689003 -0.93630374 3 P 0 ;0,3=18,5=0.000000
L 2.0689003 -0.93630374 2.05689921 -0.94630167 3 P 0 ;0,3=18,5=0.000000
L 2.05689921 -0.94630167 2.04089902 -0.9538 3 P 0 ;0,3=18,5=0.000000
L 2.04089902 -0.9538 2.0009002 -0.9538 3 P 0 ;0,3=18,5=0.000000
L 2.15489783 -0.9538 2.20489813 -0.8038 3 P 0 ;0,3=18,5=0.000000
L 2.20489813 -0.8038 2.25490207 -0.9538 3 P 0 ;0,3=18,5=0.000000
L 2.23689862 -0.90130207 2.17289764 -0.90130207 3 P 0 ;0,3=18,5=0.000000
L 2.36489813 -0.8038 2.36489813 -0.9538 3 P 0 ;0,3=18,5=0.000000
L 2.31890059 -0.8038 2.41089931 -0.8038 3 P 0 ;0,3=18,5=0.000000
L 2.56490059 -0.9538 2.48489931 -0.9538 3 P 0 ;0,3=18,5=0.000000
L 2.48489931 -0.9538 2.48489931 -0.8038 3 P 0 ;0,3=18,5=0.000000
L 2.48489931 -0.8038 2.56490059 -0.8038 3 P 0 ;0,3=18,5=0.000000
L 2.5329001 -0.87629833 2.48489931 -0.87629833 3 P 0 ;0,3=18,5=0.000000
L 2.84489813 -0.9538 2.82889783 -0.95130059 3 P 0 ;0,3=18,5=0.000000
L 2.82889783 -0.95130059 2.81490089 -0.94130276 3 P 0 ;0,3=18,5=0.000000
L 2.81490089 -0.94130276 2.8028998 -0.92630138 3 P 0 ;0,3=18,5=0.000000
L 2.8028998 -0.92630138 2.79489783 -0.90880049 3 P 0 ;0,3=18,5=0.000000
L 2.79489783 -0.90880049 2.79089862 -0.8888002 3 P 0 ;0,3=18,5=0.000000
L 2.79089862 -0.8888002 2.79089862 -0.8687999 3 P 0 ;0,3=18,5=0.000000
L 2.79089862 -0.8687999 2.79489783 -0.84879961 3 P 0 ;0,3=18,5=0.000000
L 2.79489783 -0.84879961 2.8028998 -0.83129872 3 P 0 ;0,3=18,5=0.000000
L 2.8028998 -0.83129872 2.81490089 -0.81630197 3 P 0 ;0,3=18,5=0.000000
L 2.81490089 -0.81630197 2.82889783 -0.80629951 3 P 0 ;0,3=18,5=0.000000
L 2.82889783 -0.80629951 2.84489813 -0.8038 3 P 0 ;0,3=18,5=0.000000
L 2.84489813 -0.8038 2.86089833 -0.80629951 3 P 0 ;0,3=18,5=0.000000
L 2.86089833 -0.80629951 2.87489902 -0.81630197 3 P 0 ;0,3=18,5=0.000000
L 2.87489902 -0.81630197 2.8869001 -0.83129872 3 P 0 ;0,3=18,5=0.000000
L 2.8869001 -0.83129872 2.89490207 -0.84879961 3 P 0 ;0,3=18,5=0.000000
L 2.89490207 -0.84879961 2.89890128 -0.8687999 3 P 0 ;0,3=18,5=0.000000
L 2.89890128 -0.8687999 2.89890128 -0.8888002 3 P 0 ;0,3=18,5=0.000000
L 2.89890128 -0.8888002 2.89490207 -0.90880049 3 P 0 ;0,3=18,5=0.000000
L 2.89490207 -0.90880049 2.8869001 -0.92630138 3 P 0 ;0,3=18,5=0.000000
L 2.8869001 -0.92630138 2.87489902 -0.94130276 3 P 0 ;0,3=18,5=0.000000
L 2.87489902 -0.94130276 2.86089833 -0.95130059 3 P 0 ;0,3=18,5=0.000000
L 2.86089833 -0.95130059 2.84489813 -0.9538 3 P 0 ;0,3=18,5=0.000000
L 3.0488997 -0.81630197 3.03689862 -0.80879902 3 P 0 ;0,3=18,5=0.000000
L 3.03689862 -0.80879902 3.02290157 -0.8038 3 P 0 ;0,3=18,5=0.000000
L 3.02290157 -0.8038 3.00690138 -0.8038 3 P 0 ;0,3=18,5=0.000000
L 3.00690138 -0.8038 2.98889783 -0.81130305 3 P 0 ;0,3=18,5=0.000000
L 2.98889783 -0.81130305 2.97490089 -0.82380039 3 P 0 ;0,3=18,5=0.000000
L 2.97490089 -0.82380039 2.96489931 -0.83880177 3 P 0 ;0,3=18,5=0.000000
L 2.96489931 -0.83880177 2.95689734 -0.86380098 3 P 0 ;0,3=18,5=0.000000
L 2.95689734 -0.86380098 2.95489783 -0.88630069 3 P 0 ;0,3=18,5=0.000000
L 2.95489783 -0.88630069 2.95890059 -0.90880049 3 P 0 ;0,3=18,5=0.000000
L 2.95890059 -0.90880049 2.96489931 -0.92380187 3 P 0 ;0,3=18,5=0.000000
L 2.96489931 -0.92380187 2.97690039 -0.93880325 3 P 0 ;0,3=18,5=0.000000
L 2.97690039 -0.93880325 2.99090108 -0.94880108 3 P 0 ;0,3=18,5=0.000000
L 2.99090108 -0.94880108 3.00489813 -0.9538 3 P 0 ;0,3=18,5=0.000000
L 3.00489813 -0.9538 3.01889882 -0.9538 3 P 0 ;0,3=18,5=0.000000
L 3.01889882 -0.9538 3.03289951 -0.94880108 3 P 0 ;0,3=18,5=0.000000
L 3.03289951 -0.94880108 3.04490059 -0.94130276 3 P 0 ;0,3=18,5=0.000000
L 3.04490059 -0.94130276 3.05490207 -0.93130482 3 P 0 ;0,3=18,5=0.000000
L 3.16489813 -0.8038 3.16489813 -0.9538 3 P 0 ;0,3=18,5=0.000000
L 3.11890059 -0.8038 3.21089931 -0.8038 3 P 0 ;0,3=18,5=0.000000
L 3.28889852 -0.95879892 3.36090138 -0.8038 3 P 0 ;0,3=18,5=0.000000
L 3.44689892 -0.82879931 3.4589 -0.81380246 3 P 0 ;0,3=18,5=0.000000
L 3.4589 -0.81380246 3.47290069 -0.80629951 3 P 0 ;0,3=18,5=0.000000
L 3.47290069 -0.80629951 3.48890089 -0.8038 3 P 0 ;0,3=18,5=0.000000
L 3.48890089 -0.8038 3.5089003 -0.80879902 3 P 0 ;0,3=18,5=0.000000
L 3.5089003 -0.80879902 3.52290098 -0.82130089 3 P 0 ;0,3=18,5=0.000000
L 3.52290098 -0.82130089 3.5269001 -0.83629764 3 P 0 ;0,3=18,5=0.000000
L 3.5269001 -0.83629764 3.52490059 -0.85130364 3 P 0 ;0,3=18,5=0.000000
L 3.52490059 -0.85130364 3.51689862 -0.86380098 3 P 0 ;0,3=18,5=0.000000
L 3.51689862 -0.86380098 3.4768998 -0.8888002 3 P 0 ;0,3=18,5=0.000000
L 3.4768998 -0.8888002 3.4589 -0.90630108 3 P 0 ;0,3=18,5=0.000000
L 3.4589 -0.90630108 3.44689892 -0.93130482 3 P 0 ;0,3=18,5=0.000000
L 3.44689892 -0.93130482 3.4428998 -0.9538 3 P 0 ;0,3=18,5=0.000000
L 3.4428998 -0.9538 3.5269001 -0.9538 3 P 0 ;0,3=18,5=0.000000
L 3.64089902 -0.9538 3.64489813 -0.92130246 3 P 0 ;0,3=18,5=0.000000
L 3.64489813 -0.92130246 3.65090049 -0.89380374 3 P 0 ;0,3=18,5=0.000000
L 3.65090049 -0.89380374 3.65889882 -0.8687999 3 P 0 ;0,3=18,5=0.000000
L 3.65889882 -0.8687999 3.6689003 -0.84130118 3 P 0 ;0,3=18,5=0.000000
L 3.6689003 -0.84130118 3.68490059 -0.8038 3 P 0 ;0,3=18,5=0.000000
L 3.68490059 -0.8038 3.60489931 -0.8038 3 P 0 ;0,3=18,5=0.000000
L 3.76889852 -0.95879892 3.84090138 -0.8038 3 P 0 ;0,3=18,5=0.000000
L 3.92689892 -0.82879931 3.9389 -0.81380246 3 P 0 ;0,3=18,5=0.000000
L 3.9389 -0.81380246 3.95290069 -0.80629951 3 P 0 ;0,3=18,5=0.000000
L 3.95290069 -0.80629951 3.96890089 -0.8038 3 P 0 ;0,3=18,5=0.000000
L 3.96890089 -0.8038 3.9889003 -0.80879902 3 P 0 ;0,3=18,5=0.000000
L 3.9889003 -0.80879902 4.00290098 -0.82130089 3 P 0 ;0,3=18,5=0.000000
L 4.00290098 -0.82130089 4.0069001 -0.83629764 3 P 0 ;0,3=18,5=0.000000
L 4.0069001 -0.83629764 4.00490059 -0.85130364 3 P 0 ;0,3=18,5=0.000000
L 4.00490059 -0.85130364 3.99689862 -0.86380098 3 P 0 ;0,3=18,5=0.000000
L 3.99689862 -0.86380098 3.9568998 -0.8888002 3 P 0 ;0,3=18,5=0.000000
L 3.9568998 -0.8888002 3.9389 -0.90630108 3 P 0 ;0,3=18,5=0.000000
L 3.9389 -0.90630108 3.92689892 -0.93130482 3 P 0 ;0,3=18,5=0.000000
L 3.92689892 -0.93130482 3.9228998 -0.9538 3 P 0 ;0,3=18,5=0.000000
L 3.9228998 -0.9538 4.0069001 -0.9538 3 P 0 ;0,3=18,5=0.000000
L 4.12489813 -0.8038 4.10889783 -0.80879902 3 P 0 ;0,3=18,5=0.000000
L 4.10889783 -0.80879902 4.09690039 -0.82130089 3 P 0 ;0,3=18,5=0.000000
L 4.09690039 -0.82130089 4.08889852 -0.83629764 3 P 0 ;0,3=18,5=0.000000
L 4.08889852 -0.83629764 4.0828998 -0.85630256 3 P 0 ;0,3=18,5=0.000000
L 4.0828998 -0.85630256 4.0809002 -0.87880236 3 P 0 ;0,3=18,5=0.000000
L 4.0809002 -0.87880236 4.0828998 -0.90130207 3 P 0 ;0,3=18,5=0.000000
L 4.0828998 -0.90130207 4.08889852 -0.92130246 3 P 0 ;0,3=18,5=0.000000
L 4.08889852 -0.92130246 4.09690039 -0.93630374 3 P 0 ;0,3=18,5=0.000000
L 4.09690039 -0.93630374 4.10889783 -0.94880108 3 P 0 ;0,3=18,5=0.000000
L 4.10889783 -0.94880108 4.12489813 -0.9538 3 P 0 ;0,3=18,5=0.000000
L 4.12489813 -0.9538 4.14089833 -0.94880108 3 P 0 ;0,3=18,5=0.000000
L 4.14089833 -0.94880108 4.15289951 -0.93630374 3 P 0 ;0,3=18,5=0.000000
L 4.15289951 -0.93630374 4.16090138 -0.92130246 3 P 0 ;0,3=18,5=0.000000
L 4.16090138 -0.92130246 4.1669001 -0.90130207 3 P 0 ;0,3=18,5=0.000000
L 4.1669001 -0.90130207 4.1688997 -0.87880236 3 P 0 ;0,3=18,5=0.000000
L 4.1688997 -0.87880236 4.1669001 -0.85630256 3 P 0 ;0,3=18,5=0.000000
L 4.1669001 -0.85630256 4.16090138 -0.83629764 3 P 0 ;0,3=18,5=0.000000
L 4.16090138 -0.83629764 4.15289951 -0.82130089 3 P 0 ;0,3=18,5=0.000000
L 4.15289951 -0.82130089 4.14089833 -0.80879902 3 P 0 ;0,3=18,5=0.000000
L 4.14089833 -0.80879902 4.12489813 -0.8038 3 P 0 ;0,3=18,5=0.000000
L 4.28489813 -0.9538 4.28489813 -0.8038 3 P 0 ;0,3=18,5=0.000000
L 4.28489813 -0.8038 4.26089961 -0.83379823 3 P 0 ;0,3=18,5=0.000000
L 4.26089961 -0.9538 4.30889665 -0.9538 3 P 0 ;0,3=18,5=0.000000
L 4.44089902 -0.9538 4.44489813 -0.92130246 3 P 0 ;0,3=18,5=0.000000
L 4.44489813 -0.92130246 4.45090049 -0.89380374 3 P 0 ;0,3=18,5=0.000000
L 4.45090049 -0.89380374 4.45889882 -0.8687999 3 P 0 ;0,3=18,5=0.000000
L 4.45889882 -0.8687999 4.4689003 -0.84130118 3 P 0 ;0,3=18,5=0.000000
L 4.4689003 -0.84130118 4.48490059 -0.8038 3 P 0 ;0,3=18,5=0.000000
L 4.48490059 -0.8038 4.40489931 -0.8038 3 P 0 ;0,3=18,5=0.000000
L 0.1075 0.8575 0.1075 0.8575 9 P 0 ;1
L 0.1075 4.8075 0.1075 4.8075 9 P 0 ;1
L 0.1575 0.1575 0.1575 0.1575 9 P 0 ;1
L 0.1575 0.2075 0.1575 0.2075 9 P 0 ;1
L 0.1575 0.2575 0.1575 0.2575 9 P 0 ;1
L 0.1575 1.0575 0.1575 1.0575 9 P 0 ;1
L 0.1575 1.1075 0.1575 1.1075 9 P 0 ;1
L 0.1575 1.1575 0.1575 1.1575 9 P 0 ;1
L 0.1575 1.2075 0.1575 1.2075 9 P 0 ;1
L 0.1575 5.5575 0.1575 5.5575 9 P 0 ;1
L 0.1575 5.6075 0.1575 5.6075 9 P 0 ;1
L 0.1575 5.6575 0.1575 5.6575 9 P 0 ;1
L 0.2075 0.1575 0.2075 0.1575 9 P 0 ;1
L 0.2075 0.2075 0.2075 0.2075 9 P 0 ;1
L 0.2075 0.2575 0.2075 0.2575 9 P 0 ;1
L 0.2075 1.0575 0.2075 1.0575 9 P 0 ;1
L 0.2075 1.1075 0.2075 1.1075 9 P 0 ;1
L 0.2075 1.1575 0.2075 1.1575 9 P 0 ;1
L 0.2075 1.2075 0.2075 1.2075 9 P 0 ;1
L 0.2075 5.5575 0.2075 5.5575 9 P 0 ;1
L 0.2075 5.6075 0.2075 5.6075 9 P 0 ;1
L 0.2075 5.6575 0.2075 5.6575 9 P 0 ;1
L 0.2575 0.1575 0.2575 0.1575 9 P 0 ;1
L 0.2575 0.2075 0.2575 0.2075 9 P 0 ;1
L 0.2575 0.2575 0.2575 0.2575 9 P 0 ;1
L 0.2575 1.0575 0.2575 1.0575 9 P 0 ;1
L 0.2575 1.1075 0.2575 1.1075 9 P 0 ;1
L 0.2575 1.1575 0.2575 1.1575 9 P 0 ;1
L 0.2575 1.2075 0.2575 1.2075 9 P 0 ;1
L 0.2575 5.5575 0.2575 5.5575 9 P 0 ;1
L 0.2575 5.6075 0.2575 5.6075 9 P 0 ;1
L 0.2575 5.6575 0.2575 5.6575 9 P 0 ;1
L 0.3075 0.1575 0.3075 0.1575 9 P 0 ;1
L 0.3075 0.2075 0.3075 0.2075 9 P 0 ;1
L 0.3075 0.2575 0.3075 0.2575 9 P 0 ;1
L 0.3075 0.3075 0.3075 0.3075 9 P 0 ;1
L 0.3075 1.0575 0.3075 1.0575 9 P 0 ;1
L 0.3075 1.1075 0.3075 1.1075 9 P 0 ;1
L 0.3075 1.1575 0.3075 1.1575 9 P 0 ;1
L 0.3075 1.2075 0.3075 1.2075 9 P 0 ;1
L 0.3075 5.5075 0.3075 5.5075 9 P 0 ;1
L 0.3075 5.5575 0.3075 5.5575 9 P 0 ;1
L 0.3075 5.6075 0.3075 5.6075 9 P 0 ;1
L 0.3075 5.6575 0.3075 5.6575 9 P 0 ;1
L 0.3075 5.7075 0.3075 5.7075 9 P 0 ;1
L 0.3575 0.1575 0.3575 0.1575 9 P 0 ;1
L 0.3575 0.2075 0.3575 0.2075 9 P 0 ;1
L 0.3575 0.2575 0.3575 0.2575 9 P 0 ;1
L 0.3575 0.3075 0.3575 0.3075 9 P 0 ;1
L 0.3575 0.3575 0.3575 0.3575 9 P 0 ;1
L 0.3575 0.4575 0.3575 0.4575 9 P 0 ;1
L 0.3575 0.5075 0.3575 0.5075 9 P 0 ;1
L 0.3575 0.8575 0.3575 0.8575 9 P 0 ;1
L 0.3575 0.9075 0.3575 0.9075 9 P 0 ;1
L 0.3575 0.9575 0.3575 0.9575 9 P 0 ;1
L 0.3575 1.0075 0.3575 1.0075 9 P 0 ;1
L 0.3575 1.0575 0.3575 1.0575 9 P 0 ;1
L 0.3575 1.1075 0.3575 1.1075 9 P 0 ;1
L 0.3575 1.1575 0.3575 1.1575 9 P 0 ;1
L 0.3575 1.2075 0.3575 1.2075 9 P 0 ;1
L 0.3575 1.2575 0.3575 1.2575 9 P 0 ;1
L 0.3575 4.7075 0.3575 4.7075 9 P 0 ;1
L 0.3575 4.7575 0.3575 4.7575 9 P 0 ;1
L 0.3575 4.8075 0.3575 4.8075 9 P 0 ;1
L 0.3575 4.8575 0.3575 4.8575 9 P 0 ;1
L 0.3575 4.9075 0.3575 4.9075 9 P 0 ;1
L 0.3575 4.9575 0.3575 4.9575 9 P 0 ;1
L 0.3575 5.3075 0.3575 5.3075 9 P 0 ;1
L 0.3575 5.4575 0.3575 5.4575 9 P 0 ;1
L 0.3575 5.5075 0.3575 5.5075 9 P 0 ;1
L 0.3575 5.5575 0.3575 5.5575 9 P 0 ;1
L 0.3575 5.6075 0.3575 5.6075 9 P 0 ;1
L 0.3575 5.6575 0.3575 5.6575 9 P 0 ;1
L 0.3575 5.7075 0.3575 5.7075 9 P 0 ;1
L 0.3575 5.7575 0.3575 5.7575 9 P 0 ;1
L 0.3575 5.8075 0.3575 5.8075 9 P 0 ;1
L 0.3575 5.8575 0.3575 5.8575 9 P 0 ;1
L 0.3575 5.9075 0.3575 5.9075 9 P 0 ;1
L 0.4075 0.1575 0.4075 0.1575 9 P 0 ;1
L 0.4075 0.2075 0.4075 0.2075 9 P 0 ;1
L 0.4075 0.2575 0.4075 0.2575 9 P 0 ;1
L 0.4075 0.3075 0.4075 0.3075 9 P 0 ;1
L 0.4075 0.3575 0.4075 0.3575 9 P 0 ;1
L 0.4075 0.4075 0.4075 0.4075 9 P 0 ;1
L 0.4075 0.4575 0.4075 0.4575 9 P 0 ;1
L 0.4075 0.5075 0.4075 0.5075 9 P 0 ;1
L 0.4075 0.5575 0.4075 0.5575 9 P 0 ;1
L 0.4075 0.6075 0.4075 0.6075 9 P 0 ;1
L 0.4075 0.7575 0.4075 0.7575 9 P 0 ;1
L 0.4075 0.8075 0.4075 0.8075 9 P 0 ;1
L 0.4075 0.8575 0.4075 0.8575 9 P 0 ;1
L 0.4075 0.9075 0.4075 0.9075 9 P 0 ;1
L 0.4075 0.9575 0.4075 0.9575 9 P 0 ;1
L 0.4075 1.0075 0.4075 1.0075 9 P 0 ;1
L 0.4075 1.0575 0.4075 1.0575 9 P 0 ;1
L 0.4075 1.1075 0.4075 1.1075 9 P 0 ;1
L 0.4075 1.1575 0.4075 1.1575 9 P 0 ;1
L 0.4075 1.2075 0.4075 1.2075 9 P 0 ;1
L 0.4075 1.2575 0.4075 1.2575 9 P 0 ;1
L 0.4075 4.7075 0.4075 4.7075 9 P 0 ;1
L 0.4075 4.7575 0.4075 4.7575 9 P 0 ;1
L 0.4075 4.8075 0.4075 4.8075 9 P 0 ;1
L 0.4075 4.8575 0.4075 4.8575 9 P 0 ;1
L 0.4075 4.9075 0.4075 4.9075 9 P 0 ;1
L 0.4075 4.9575 0.4075 4.9575 9 P 0 ;1
L 0.4075 5.0075 0.4075 5.0075 9 P 0 ;1
L 0.4075 5.0575 0.4075 5.0575 9 P 0 ;1
L 0.4075 5.2075 0.4075 5.2075 9 P 0 ;1
L 0.4075 5.2575 0.4075 5.2575 9 P 0 ;1
L 0.4075 5.3075 0.4075 5.3075 9 P 0 ;1
L 0.4075 5.3575 0.4075 5.3575 9 P 0 ;1
L 0.4075 5.4075 0.4075 5.4075 9 P 0 ;1
L 0.4075 5.4575 0.4075 5.4575 9 P 0 ;1
L 0.4075 5.5075 0.4075 5.5075 9 P 0 ;1
L 0.4075 5.5575 0.4075 5.5575 9 P 0 ;1
L 0.4075 5.6075 0.4075 5.6075 9 P 0 ;1
L 0.4075 5.6575 0.4075 5.6575 9 P 0 ;1
L 0.4075 5.7075 0.4075 5.7075 9 P 0 ;1
L 0.4075 5.7575 0.4075 5.7575 9 P 0 ;1
L 0.4075 5.8075 0.4075 5.8075 9 P 0 ;1
L 0.4075 5.8575 0.4075 5.8575 9 P 0 ;1
L 0.4575 0.1575 0.4575 0.1575 9 P 0 ;1
L 0.4575 0.2075 0.4575 0.2075 9 P 0 ;1
L 0.4575 0.2575 0.4575 0.2575 9 P 0 ;1
L 0.4575 0.3075 0.4575 0.3075 9 P 0 ;1
L 0.4575 0.3575 0.4575 0.3575 9 P 0 ;1
L 0.4575 0.4075 0.4575 0.4075 9 P 0 ;1
L 0.4575 0.4575 0.4575 0.4575 9 P 0 ;1
L 0.4575 0.5075 0.4575 0.5075 9 P 0 ;1
L 0.4575 0.5575 0.4575 0.5575 9 P 0 ;1
L 0.4575 0.6075 0.4575 0.6075 9 P 0 ;1
L 0.4575 0.6575 0.4575 0.6575 9 P 0 ;1
L 0.4575 0.7075 0.4575 0.7075 9 P 0 ;1
L 0.4575 0.7575 0.4575 0.7575 9 P 0 ;1
L 0.4575 0.8075 0.4575 0.8075 9 P 0 ;1
L 0.4575 0.8575 0.4575 0.8575 9 P 0 ;1
L 0.4575 0.9075 0.4575 0.9075 9 P 0 ;1
L 0.4575 0.9575 0.4575 0.9575 9 P 0 ;1
L 0.4575 1.0075 0.4575 1.0075 9 P 0 ;1
L 0.4575 1.0575 0.4575 1.0575 9 P 0 ;1
L 0.4575 1.1075 0.4575 1.1075 9 P 0 ;1
L 0.4575 1.1575 0.4575 1.1575 9 P 0 ;1
L 0.4575 1.2075 0.4575 1.2075 9 P 0 ;1
L 0.4575 1.2575 0.4575 1.2575 9 P 0 ;1
L 0.4575 1.3075 0.4575 1.3075 9 P 0 ;1
L 0.4575 1.3575 0.4575 1.3575 9 P 0 ;1
L 0.4575 1.4075 0.4575 1.4075 9 P 0 ;1
L 0.4575 1.4575 0.4575 1.4575 9 P 0 ;1
L 0.4575 1.5075 0.4575 1.5075 9 P 0 ;1
L 0.4575 1.5575 0.4575 1.5575 9 P 0 ;1
L 0.4575 1.6075 0.4575 1.6075 9 P 0 ;1
L 0.4575 1.6575 0.4575 1.6575 9 P 0 ;1
L 0.4575 1.7075 0.4575 1.7075 9 P 0 ;1
L 0.4575 1.7575 0.4575 1.7575 9 P 0 ;1
L 0.4575 1.8075 0.4575 1.8075 9 P 0 ;1
L 0.4575 2.0075 0.4575 2.0075 9 P 0 ;1
L 0.4575 2.0575 0.4575 2.0575 9 P 0 ;1
L 0.4575 2.1075 0.4575 2.1075 9 P 0 ;1
L 0.4575 4.4575 0.4575 4.4575 9 P 0 ;1
L 0.4575 4.5075 0.4575 4.5075 9 P 0 ;1
L 0.4575 4.5575 0.4575 4.5575 9 P 0 ;1
L 0.4575 4.6075 0.4575 4.6075 9 P 0 ;1
L 0.4575 4.6575 0.4575 4.6575 9 P 0 ;1
L 0.4575 4.7075 0.4575 4.7075 9 P 0 ;1
L 0.4575 4.7575 0.4575 4.7575 9 P 0 ;1
L 0.4575 4.8075 0.4575 4.8075 9 P 0 ;1
L 0.4575 4.8575 0.4575 4.8575 9 P 0 ;1
L 0.4575 4.9075 0.4575 4.9075 9 P 0 ;1
L 0.4575 4.9575 0.4575 4.9575 9 P 0 ;1
L 0.4575 5.0075 0.4575 5.0075 9 P 0 ;1
L 0.4575 5.0575 0.4575 5.0575 9 P 0 ;1
L 0.4575 5.1075 0.4575 5.1075 9 P 0 ;1
L 0.4575 5.1575 0.4575 5.1575 9 P 0 ;1
L 0.4575 5.2075 0.4575 5.2075 9 P 0 ;1
L 0.4575 5.2575 0.4575 5.2575 9 P 0 ;1
L 0.4575 5.3075 0.4575 5.3075 9 P 0 ;1
L 0.4575 5.3575 0.4575 5.3575 9 P 0 ;1
L 0.4575 5.4075 0.4575 5.4075 9 P 0 ;1
L 0.4575 5.4575 0.4575 5.4575 9 P 0 ;1
L 0.4575 5.5075 0.4575 5.5075 9 P 0 ;1
L 0.4575 5.5575 0.4575 5.5575 9 P 0 ;1
L 0.4575 5.6075 0.4575 5.6075 9 P 0 ;1
L 0.4575 5.6575 0.4575 5.6575 9 P 0 ;1
L 0.4575 5.7075 0.4575 5.7075 9 P 0 ;1
L 0.4575 5.7575 0.4575 5.7575 9 P 0 ;1
L 0.4575 5.8075 0.4575 5.8075 9 P 0 ;1
L 0.5075 0.1575 0.5075 0.1575 9 P 0 ;1
L 0.5075 0.2075 0.5075 0.2075 9 P 0 ;1
L 0.5075 0.2575 0.5075 0.2575 9 P 0 ;1
L 0.5075 0.3075 0.5075 0.3075 9 P 0 ;1
L 0.5075 0.3575 0.5075 0.3575 9 P 0 ;1
L 0.5075 0.4075 0.5075 0.4075 9 P 0 ;1
L 0.5075 0.4575 0.5075 0.4575 9 P 0 ;1
L 0.5075 0.5075 0.5075 0.5075 9 P 0 ;1
L 0.5075 0.5575 0.5075 0.5575 9 P 0 ;1
L 0.5075 0.6075 0.5075 0.6075 9 P 0 ;1
L 0.5075 0.6575 0.5075 0.6575 9 P 0 ;1
L 0.5075 0.7075 0.5075 0.7075 9 P 0 ;1
L 0.5075 0.7575 0.5075 0.7575 9 P 0 ;1
L 0.5075 0.8075 0.5075 0.8075 9 P 0 ;1
L 0.5075 0.8575 0.5075 0.8575 9 P 0 ;1
L 0.5075 0.9075 0.5075 0.9075 9 P 0 ;1
L 0.5075 0.9575 0.5075 0.9575 9 P 0 ;1
L 0.5075 1.0075 0.5075 1.0075 9 P 0 ;1
L 0.5075 1.0575 0.5075 1.0575 9 P 0 ;1
L 0.5075 1.1075 0.5075 1.1075 9 P 0 ;1
L 0.5075 1.1575 0.5075 1.1575 9 P 0 ;1
L 0.5075 1.2075 0.5075 1.2075 9 P 0 ;1
L 0.5075 1.2575 0.5075 1.2575 9 P 0 ;1
L 0.5075 1.3075 0.5075 1.3075 9 P 0 ;1
L 0.5075 1.3575 0.5075 1.3575 9 P 0 ;1
L 0.5075 1.4075 0.5075 1.4075 9 P 0 ;1
L 0.5075 1.4575 0.5075 1.4575 9 P 0 ;1
L 0.5075 1.5075 0.5075 1.5075 9 P 0 ;1
L 0.5075 1.5575 0.5075 1.5575 9 P 0 ;1
L 0.5075 1.6075 0.5075 1.6075 9 P 0 ;1
L 0.5075 1.6575 0.5075 1.6575 9 P 0 ;1
L 0.5075 1.7075 0.5075 1.7075 9 P 0 ;1
L 0.5075 1.7575 0.5075 1.7575 9 P 0 ;1
L 0.5075 1.8075 0.5075 1.8075 9 P 0 ;1
L 0.5075 2.0575 0.5075 2.0575 9 P 0 ;1
L 0.5075 4.4075 0.5075 4.4075 9 P 0 ;1
L 0.5075 4.4575 0.5075 4.4575 9 P 0 ;1
L 0.5075 4.5075 0.5075 4.5075 9 P 0 ;1
L 0.5075 4.5575 0.5075 4.5575 9 P 0 ;1
L 0.5075 4.6075 0.5075 4.6075 9 P 0 ;1
L 0.5075 4.6575 0.5075 4.6575 9 P 0 ;1
L 0.5075 4.7075 0.5075 4.7075 9 P 0 ;1
L 0.5075 4.7575 0.5075 4.7575 9 P 0 ;1
L 0.5075 4.8075 0.5075 4.8075 9 P 0 ;1
L 0.5075 4.8575 0.5075 4.8575 9 P 0 ;1
L 0.5575 0.1575 0.5575 0.1575 9 P 0 ;1
L 0.5575 0.4075 0.5575 0.4075 9 P 0 ;1
L 0.5575 0.4575 0.5575 0.4575 9 P 0 ;1
L 0.5575 0.5075 0.5575 0.5075 9 P 0 ;1
L 0.5575 0.5575 0.5575 0.5575 9 P 0 ;1
L 0.5575 0.6075 0.5575 0.6075 9 P 0 ;1
L 0.5575 0.6575 0.5575 0.6575 9 P 0 ;1
L 0.5575 0.7075 0.5575 0.7075 9 P 0 ;1
L 0.5575 0.7575 0.5575 0.7575 9 P 0 ;1
L 0.5575 0.8075 0.5575 0.8075 9 P 0 ;1
L 0.5575 0.8575 0.5575 0.8575 9 P 0 ;1
L 0.5575 0.9075 0.5575 0.9075 9 P 0 ;1
L 0.5575 0.9575 0.5575 0.9575 9 P 0 ;1
L 0.5575 1.0075 0.5575 1.0075 9 P 0 ;1
L 0.5575 1.0575 0.5575 1.0575 9 P 0 ;1
L 0.5575 1.1075 0.5575 1.1075 9 P 0 ;1
L 0.5575 1.1575 0.5575 1.1575 9 P 0 ;1
L 0.5575 1.2075 0.5575 1.2075 9 P 0 ;1
L 0.5575 1.2575 0.5575 1.2575 9 P 0 ;1
L 0.5575 1.3075 0.5575 1.3075 9 P 0 ;1
L 0.5575 1.3575 0.5575 1.3575 9 P 0 ;1
L 0.5575 1.4075 0.5575 1.4075 9 P 0 ;1
L 0.5575 1.4575 0.5575 1.4575 9 P 0 ;1
L 0.5575 1.5075 0.5575 1.5075 9 P 0 ;1
L 0.5575 1.5575 0.5575 1.5575 9 P 0 ;1
L 0.5575 1.6075 0.5575 1.6075 9 P 0 ;1
L 0.5575 1.6575 0.5575 1.6575 9 P 0 ;1
L 0.5575 1.7075 0.5575 1.7075 9 P 0 ;1
L 0.5575 1.7575 0.5575 1.7575 9 P 0 ;1
L 0.5575 1.8075 0.5575 1.8075 9 P 0 ;1
L 0.5575 1.8575 0.5575 1.8575 9 P 0 ;1
L 0.5575 2.0575 0.5575 2.0575 9 P 0 ;1
L 0.5575 4.3575 0.5575 4.3575 9 P 0 ;1
L 0.5575 4.4075 0.5575 4.4075 9 P 0 ;1
L 0.5575 4.4575 0.5575 4.4575 9 P 0 ;1
L 0.5575 4.5075 0.5575 4.5075 9 P 0 ;1
L 0.5575 4.5575 0.5575 4.5575 9 P 0 ;1
L 0.5575 4.6075 0.5575 4.6075 9 P 0 ;1
L 0.5575 4.6575 0.5575 4.6575 9 P 0 ;1
L 0.5575 4.7075 0.5575 4.7075 9 P 0 ;1
L 0.5575 4.7575 0.5575 4.7575 9 P 0 ;1
L 0.5575 4.8075 0.5575 4.8075 9 P 0 ;1
L 0.6075 0.1575 0.6075 0.1575 9 P 0 ;1
L 0.6075 0.4575 0.6075 0.4575 9 P 0 ;1
L 0.6075 0.5075 0.6075 0.5075 9 P 0 ;1
L 0.6075 0.5575 0.6075 0.5575 9 P 0 ;1
L 0.6075 0.6075 0.6075 0.6075 9 P 0 ;1
L 0.6075 0.6575 0.6075 0.6575 9 P 0 ;1
L 0.6075 0.7075 0.6075 0.7075 9 P 0 ;1
L 0.6075 0.7575 0.6075 0.7575 9 P 0 ;1
L 0.6075 0.8075 0.6075 0.8075 9 P 0 ;1
L 0.6075 0.8575 0.6075 0.8575 9 P 0 ;1
L 0.6075 0.9075 0.6075 0.9075 9 P 0 ;1
L 0.6075 0.9575 0.6075 0.9575 9 P 0 ;1
L 0.6075 1.0075 0.6075 1.0075 9 P 0 ;1
L 0.6075 1.0575 0.6075 1.0575 9 P 0 ;1
L 0.6075 1.1075 0.6075 1.1075 9 P 0 ;1
L 0.6075 1.1575 0.6075 1.1575 9 P 0 ;1
L 0.6075 1.2075 0.6075 1.2075 9 P 0 ;1
L 0.6075 1.2575 0.6075 1.2575 9 P 0 ;1
L 0.6075 1.3075 0.6075 1.3075 9 P 0 ;1
L 0.6075 1.3575 0.6075 1.3575 9 P 0 ;1
L 0.6075 1.4075 0.6075 1.4075 9 P 0 ;1
L 0.6075 1.4575 0.6075 1.4575 9 P 0 ;1
L 0.6075 1.5075 0.6075 1.5075 9 P 0 ;1
L 0.6075 1.5575 0.6075 1.5575 9 P 0 ;1
L 0.6075 1.7575 0.6075 1.7575 9 P 0 ;1
L 0.6075 4.3075 0.6075 4.3075 9 P 0 ;1
L 0.6075 4.3575 0.6075 4.3575 9 P 0 ;1
L 0.6075 4.4075 0.6075 4.4075 9 P 0 ;1
L 0.6075 4.4575 0.6075 4.4575 9 P 0 ;1
L 0.6075 4.5075 0.6075 4.5075 9 P 0 ;1
L 0.6075 4.5575 0.6075 4.5575 9 P 0 ;1
L 0.6075 4.6075 0.6075 4.6075 9 P 0 ;1
L 0.6075 4.6575 0.6075 4.6575 9 P 0 ;1
L 0.6075 4.7075 0.6075 4.7075 9 P 0 ;1
L 0.6075 4.7575 0.6075 4.7575 9 P 0 ;1
L 0.6075 4.8075 0.6075 4.8075 9 P 0 ;1
L 0.6575 0.4575 0.6575 0.4575 9 P 0 ;1
L 0.6575 0.5075 0.6575 0.5075 9 P 0 ;1
L 0.6575 0.5575 0.6575 0.5575 9 P 0 ;1
L 0.6575 0.6075 0.6575 0.6075 9 P 0 ;1
L 0.6575 0.6575 0.6575 0.6575 9 P 0 ;1
L 0.6575 0.7075 0.6575 0.7075 9 P 0 ;1
L 0.6575 0.7575 0.6575 0.7575 9 P 0 ;1
L 0.6575 0.8075 0.6575 0.8075 9 P 0 ;1
L 0.6575 0.8575 0.6575 0.8575 9 P 0 ;1
L 0.6575 0.9075 0.6575 0.9075 9 P 0 ;1
L 0.6575 0.9575 0.6575 0.9575 9 P 0 ;1
L 0.6575 1.0075 0.6575 1.0075 9 P 0 ;1
L 0.6575 1.0575 0.6575 1.0575 9 P 0 ;1
L 0.6575 1.1075 0.6575 1.1075 9 P 0 ;1
L 0.6575 1.1575 0.6575 1.1575 9 P 0 ;1
L 0.6575 1.2075 0.6575 1.2075 9 P 0 ;1
L 0.6575 1.2575 0.6575 1.2575 9 P 0 ;1
L 0.6575 1.3075 0.6575 1.3075 9 P 0 ;1
L 0.6575 1.3575 0.6575 1.3575 9 P 0 ;1
L 0.6575 1.4075 0.6575 1.4075 9 P 0 ;1
L 0.6575 1.4575 0.6575 1.4575 9 P 0 ;1
L 0.6575 1.5075 0.6575 1.5075 9 P 0 ;1
L 0.6575 1.5575 0.6575 1.5575 9 P 0 ;1
L 0.6575 1.7575 0.6575 1.7575 9 P 0 ;1
L 0.6575 3.3075 0.6575 3.3075 9 P 0 ;1
L 0.6575 4.2075 0.6575 4.2075 9 P 0 ;1
L 0.6575 4.2575 0.6575 4.2575 9 P 0 ;1
L 0.6575 4.3075 0.6575 4.3075 9 P 0 ;1
L 0.6575 4.3575 0.6575 4.3575 9 P 0 ;1
L 0.6575 4.4075 0.6575 4.4075 9 P 0 ;1
L 0.6575 4.4575 0.6575 4.4575 9 P 0 ;1
L 0.6575 4.5075 0.6575 4.5075 9 P 0 ;1
L 0.6575 4.5575 0.6575 4.5575 9 P 0 ;1
L 0.6575 4.6075 0.6575 4.6075 9 P 0 ;1
L 0.6575 4.6575 0.6575 4.6575 9 P 0 ;1
L 0.6575 4.7075 0.6575 4.7075 9 P 0 ;1
L 0.6575 4.7575 0.6575 4.7575 9 P 0 ;1
L 0.6575 4.8075 0.6575 4.8075 9 P 0 ;1
L 0.7075 0.1575 0.7075 0.1575 9 P 0 ;1
L 0.7075 0.4575 0.7075 0.4575 9 P 0 ;1
L 0.7075 0.5075 0.7075 0.5075 9 P 0 ;1
L 0.7075 0.5575 0.7075 0.5575 9 P 0 ;1
L 0.7075 0.6075 0.7075 0.6075 9 P 0 ;1
L 0.7075 0.6575 0.7075 0.6575 9 P 0 ;1
L 0.7075 0.7075 0.7075 0.7075 9 P 0 ;1
L 0.7075 0.7575 0.7075 0.7575 9 P 0 ;1
L 0.7075 0.8075 0.7075 0.8075 9 P 0 ;1
L 0.7075 0.8575 0.7075 0.8575 9 P 0 ;1
L 0.7075 0.9075 0.7075 0.9075 9 P 0 ;1
L 0.7075 0.9575 0.7075 0.9575 9 P 0 ;1
L 0.7075 1.0075 0.7075 1.0075 9 P 0 ;1
L 0.7075 1.0575 0.7075 1.0575 9 P 0 ;1
L 0.7075 1.1075 0.7075 1.1075 9 P 0 ;1
L 0.7075 1.1575 0.7075 1.1575 9 P 0 ;1
L 0.7075 1.2075 0.7075 1.2075 9 P 0 ;1
L 0.7075 1.2575 0.7075 1.2575 9 P 0 ;1
L 0.7075 1.3075 0.7075 1.3075 9 P 0 ;1
L 0.7075 1.3575 0.7075 1.3575 9 P 0 ;1
L 0.7075 1.4075 0.7075 1.4075 9 P 0 ;1
L 0.7075 1.4575 0.7075 1.4575 9 P 0 ;1
L 0.7075 1.5075 0.7075 1.5075 9 P 0 ;1
L 0.7075 1.5575 0.7075 1.5575 9 P 0 ;1
L 0.7075 1.7575 0.7075 1.7575 9 P 0 ;1
L 0.7075 4.1575 0.7075 4.1575 9 P 0 ;1
L 0.7075 4.2075 0.7075 4.2075 9 P 0 ;1
L 0.7075 4.2575 0.7075 4.2575 9 P 0 ;1
L 0.7075 4.3075 0.7075 4.3075 9 P 0 ;1
L 0.7075 4.3575 0.7075 4.3575 9 P 0 ;1
L 0.7075 4.4075 0.7075 4.4075 9 P 0 ;1
L 0.7075 4.4575 0.7075 4.4575 9 P 0 ;1
L 0.7075 4.5075 0.7075 4.5075 9 P 0 ;1
L 0.7075 4.5575 0.7075 4.5575 9 P 0 ;1
L 0.7075 4.6075 0.7075 4.6075 9 P 0 ;1
L 0.7075 4.6575 0.7075 4.6575 9 P 0 ;1
L 0.7075 4.7075 0.7075 4.7075 9 P 0 ;1
L 0.7075 4.7575 0.7075 4.7575 9 P 0 ;1
L 0.7075 4.8075 0.7075 4.8075 9 P 0 ;1
L 0.7575 0.1575 0.7575 0.1575 9 P 0 ;1
L 0.7575 0.4075 0.7575 0.4075 9 P 0 ;1
L 0.7575 0.4575 0.7575 0.4575 9 P 0 ;1
L 0.7575 0.5075 0.7575 0.5075 9 P 0 ;1
L 0.7575 0.5575 0.7575 0.5575 9 P 0 ;1
L 0.7575 0.6075 0.7575 0.6075 9 P 0 ;1
L 0.7575 0.6575 0.7575 0.6575 9 P 0 ;1
L 0.7575 0.7075 0.7575 0.7075 9 P 0 ;1
L 0.7575 0.7575 0.7575 0.7575 9 P 0 ;1
L 0.7575 0.8075 0.7575 0.8075 9 P 0 ;1
L 0.7575 0.8575 0.7575 0.8575 9 P 0 ;1
L 0.7575 0.9075 0.7575 0.9075 9 P 0 ;1
L 0.7575 0.9575 0.7575 0.9575 9 P 0 ;1
L 0.7575 1.0075 0.7575 1.0075 9 P 0 ;1
L 0.7575 1.0575 0.7575 1.0575 9 P 0 ;1
L 0.7575 1.1075 0.7575 1.1075 9 P 0 ;1
L 0.7575 1.1575 0.7575 1.1575 9 P 0 ;1
L 0.7575 1.2075 0.7575 1.2075 9 P 0 ;1
L 0.7575 1.2575 0.7575 1.2575 9 P 0 ;1
L 0.7575 1.3075 0.7575 1.3075 9 P 0 ;1
L 0.7575 1.3575 0.7575 1.3575 9 P 0 ;1
L 0.7575 1.4075 0.7575 1.4075 9 P 0 ;1
L 0.7575 1.4575 0.7575 1.4575 9 P 0 ;1
L 0.7575 1.6075 0.7575 1.6075 9 P 0 ;1
L 0.7575 1.6575 0.7575 1.6575 9 P 0 ;1
L 0.7575 1.7075 0.7575 1.7075 9 P 0 ;1
L 0.7575 1.7575 0.7575 1.7575 9 P 0 ;1
L 0.7575 3.1075 0.7575 3.1075 9 P 0 ;1
L 0.7575 3.1575 0.7575 3.1575 9 P 0 ;1
L 0.7575 4.0575 0.7575 4.0575 9 P 0 ;1
L 0.7575 4.1075 0.7575 4.1075 9 P 0 ;1
L 0.7575 4.1575 0.7575 4.1575 9 P 0 ;1
L 0.7575 4.2575 0.7575 4.2575 9 P 0 ;1
L 0.7575 4.3075 0.7575 4.3075 9 P 0 ;1
L 0.7575 4.3575 0.7575 4.3575 9 P 0 ;1
L 0.7575 4.4075 0.7575 4.4075 9 P 0 ;1
L 0.7575 4.4575 0.7575 4.4575 9 P 0 ;1
L 0.7575 4.5075 0.7575 4.5075 9 P 0 ;1
L 0.7575 4.5575 0.7575 4.5575 9 P 0 ;1
L 0.7575 4.6075 0.7575 4.6075 9 P 0 ;1
L 0.7575 4.6575 0.7575 4.6575 9 P 0 ;1
L 0.7575 4.7075 0.7575 4.7075 9 P 0 ;1
L 0.7575 4.7575 0.7575 4.7575 9 P 0 ;1
L 0.7575 4.8075 0.7575 4.8075 9 P 0 ;1
L 0.8075 0.1575 0.8075 0.1575 9 P 0 ;1
L 0.8075 0.2075 0.8075 0.2075 9 P 0 ;1
L 0.8075 0.2575 0.8075 0.2575 9 P 0 ;1
L 0.8075 0.3075 0.8075 0.3075 9 P 0 ;1
L 0.8075 0.3575 0.8075 0.3575 9 P 0 ;1
L 0.8075 0.4075 0.8075 0.4075 9 P 0 ;1
L 0.8075 0.4575 0.8075 0.4575 9 P 0 ;1
L 0.8075 0.5075 0.8075 0.5075 9 P 0 ;1
L 0.8075 0.5575 0.8075 0.5575 9 P 0 ;1
L 0.8075 0.6075 0.8075 0.6075 9 P 0 ;1
L 0.8075 0.6575 0.8075 0.6575 9 P 0 ;1
L 0.8075 0.7075 0.8075 0.7075 9 P 0 ;1
L 0.8075 0.7575 0.8075 0.7575 9 P 0 ;1
L 0.8075 0.8075 0.8075 0.8075 9 P 0 ;1
L 0.8075 0.8575 0.8075 0.8575 9 P 0 ;1
L 0.8075 0.9075 0.8075 0.9075 9 P 0 ;1
L 0.8075 0.9575 0.8075 0.9575 9 P 0 ;1
L 0.8075 1.0075 0.8075 1.0075 9 P 0 ;1
L 0.8075 1.0575 0.8075 1.0575 9 P 0 ;1
L 0.8075 1.1075 0.8075 1.1075 9 P 0 ;1
L 0.8075 1.1575 0.8075 1.1575 9 P 0 ;1
L 0.8075 1.2075 0.8075 1.2075 9 P 0 ;1
L 0.8075 1.2575 0.8075 1.2575 9 P 0 ;1
L 0.8075 1.3075 0.8075 1.3075 9 P 0 ;1
L 0.8075 1.3575 0.8075 1.3575 9 P 0 ;1
L 0.8075 1.7075 0.8075 1.7075 9 P 0 ;1
L 0.8075 1.7575 0.8075 1.7575 9 P 0 ;1
L 0.8075 2.8575 0.8075 2.8575 9 P 0 ;1
L 0.8075 2.9075 0.8075 2.9075 9 P 0 ;1
L 0.8075 2.9575 0.8075 2.9575 9 P 0 ;1
L 0.8075 3.0075 0.8075 3.0075 9 P 0 ;1
L 0.8075 3.0575 0.8075 3.0575 9 P 0 ;1
L 0.8075 4.0075 0.8075 4.0075 9 P 0 ;1
L 0.8075 4.0575 0.8075 4.0575 9 P 0 ;1
L 0.8075 4.3575 0.8075 4.3575 9 P 0 ;1
L 0.8075 4.4075 0.8075 4.4075 9 P 0 ;1
L 0.8075 4.4575 0.8075 4.4575 9 P 0 ;1
L 0.8075 4.5075 0.8075 4.5075 9 P 0 ;1
L 0.8075 4.5575 0.8075 4.5575 9 P 0 ;1
L 0.8075 4.6075 0.8075 4.6075 9 P 0 ;1
L 0.8075 4.6575 0.8075 4.6575 9 P 0 ;1
L 0.8075 4.7075 0.8075 4.7075 9 P 0 ;1
L 0.8075 4.7575 0.8075 4.7575 9 P 0 ;1
L 0.8075 4.8075 0.8075 4.8075 9 P 0 ;1
L 0.8575 0.1575 0.8575 0.1575 9 P 0 ;1
L 0.8575 0.2075 0.8575 0.2075 9 P 0 ;1
L 0.8575 0.2575 0.8575 0.2575 9 P 0 ;1
L 0.8575 0.3075 0.8575 0.3075 9 P 0 ;1
L 0.8575 0.3575 0.8575 0.3575 9 P 0 ;1
L 0.8575 0.4075 0.8575 0.4075 9 P 0 ;1
L 0.8575 0.4575 0.8575 0.4575 9 P 0 ;1
L 0.8575 0.5075 0.8575 0.5075 9 P 0 ;1
L 0.8575 0.5575 0.8575 0.5575 9 P 0 ;1
L 0.8575 0.6075 0.8575 0.6075 9 P 0 ;1
L 0.8575 0.6575 0.8575 0.6575 9 P 0 ;1
L 0.8575 0.7075 0.8575 0.7075 9 P 0 ;1
L 0.8575 0.7575 0.8575 0.7575 9 P 0 ;1
L 0.8575 0.8075 0.8575 0.8075 9 P 0 ;1
L 0.8575 0.8575 0.8575 0.8575 9 P 0 ;1
L 0.8575 0.9075 0.8575 0.9075 9 P 0 ;1
L 0.8575 0.9575 0.8575 0.9575 9 P 0 ;1
L 0.8575 1.0075 0.8575 1.0075 9 P 0 ;1
L 0.8575 1.0575 0.8575 1.0575 9 P 0 ;1
L 0.8575 1.1075 0.8575 1.1075 9 P 0 ;1
L 0.8575 1.1575 0.8575 1.1575 9 P 0 ;1
L 0.8575 1.2075 0.8575 1.2075 9 P 0 ;1
L 0.8575 1.2575 0.8575 1.2575 9 P 0 ;1
L 0.8575 1.3075 0.8575 1.3075 9 P 0 ;1
L 0.8575 1.3575 0.8575 1.3575 9 P 0 ;1
L 0.8575 1.7075 0.8575 1.7075 9 P 0 ;1
L 0.8575 1.7575 0.8575 1.7575 9 P 0 ;1
L 0.8575 2.7575 0.8575 2.7575 9 P 0 ;1
L 0.8575 2.8075 0.8575 2.8075 9 P 0 ;1
L 0.8575 2.8575 0.8575 2.8575 9 P 0 ;1
L 0.8575 2.9075 0.8575 2.9075 9 P 0 ;1
L 0.8575 2.9575 0.8575 2.9575 9 P 0 ;1
L 0.8575 3.0075 0.8575 3.0075 9 P 0 ;1
L 0.8575 3.9075 0.8575 3.9075 9 P 0 ;1
L 0.8575 3.9575 0.8575 3.9575 9 P 0 ;1
L 0.8575 4.0075 0.8575 4.0075 9 P 0 ;1
L 0.8575 4.4075 0.8575 4.4075 9 P 0 ;1
L 0.8575 4.4575 0.8575 4.4575 9 P 0 ;1
L 0.8575 4.5075 0.8575 4.5075 9 P 0 ;1
L 0.8575 4.5575 0.8575 4.5575 9 P 0 ;1
L 0.8575 4.6075 0.8575 4.6075 9 P 0 ;1
L 0.8575 4.6575 0.8575 4.6575 9 P 0 ;1
L 0.8575 4.7075 0.8575 4.7075 9 P 0 ;1
L 0.8575 4.7575 0.8575 4.7575 9 P 0 ;1
L 0.8575 4.8075 0.8575 4.8075 9 P 0 ;1
L 0.9075 0.1575 0.9075 0.1575 9 P 0 ;1
L 0.9075 0.2075 0.9075 0.2075 9 P 0 ;1
L 0.9075 0.2575 0.9075 0.2575 9 P 0 ;1
L 0.9075 0.3075 0.9075 0.3075 9 P 0 ;1
L 0.9075 0.3575 0.9075 0.3575 9 P 0 ;1
L 0.9075 0.4075 0.9075 0.4075 9 P 0 ;1
L 0.9075 0.4575 0.9075 0.4575 9 P 0 ;1
L 0.9075 0.5075 0.9075 0.5075 9 P 0 ;1
L 0.9075 0.5575 0.9075 0.5575 9 P 0 ;1
L 0.9075 0.6075 0.9075 0.6075 9 P 0 ;1
L 0.9075 0.6575 0.9075 0.6575 9 P 0 ;1
L 0.9075 0.7075 0.9075 0.7075 9 P 0 ;1
L 0.9075 0.7575 0.9075 0.7575 9 P 0 ;1
L 0.9075 0.8075 0.9075 0.8075 9 P 0 ;1
L 0.9075 0.8575 0.9075 0.8575 9 P 0 ;1
L 0.9075 0.9075 0.9075 0.9075 9 P 0 ;1
L 0.9075 0.9575 0.9075 0.9575 9 P 0 ;1
L 0.9075 1.0075 0.9075 1.0075 9 P 0 ;1
L 0.9075 1.0575 0.9075 1.0575 9 P 0 ;1
L 0.9075 1.1075 0.9075 1.1075 9 P 0 ;1
L 0.9075 1.1575 0.9075 1.1575 9 P 0 ;1
L 0.9075 1.2075 0.9075 1.2075 9 P 0 ;1
L 0.9075 1.2575 0.9075 1.2575 9 P 0 ;1
L 0.9075 1.3075 0.9075 1.3075 9 P 0 ;1
L 0.9075 2.7075 0.9075 2.7075 9 P 0 ;1
L 0.9075 2.7575 0.9075 2.7575 9 P 0 ;1
L 0.9075 2.8075 0.9075 2.8075 9 P 0 ;1
L 0.9075 2.8575 0.9075 2.8575 9 P 0 ;1
L 0.9075 2.9075 0.9075 2.9075 9 P 0 ;1
L 0.9075 3.8575 0.9075 3.8575 9 P 0 ;1
L 0.9075 3.9075 0.9075 3.9075 9 P 0 ;1
L 0.9075 3.9575 0.9075 3.9575 9 P 0 ;1
L 0.9075 4.0075 0.9075 4.0075 9 P 0 ;1
L 0.9075 4.4075 0.9075 4.4075 9 P 0 ;1
L 0.9075 4.4575 0.9075 4.4575 9 P 0 ;1
L 0.9075 4.5075 0.9075 4.5075 9 P 0 ;1
L 0.9075 4.5575 0.9075 4.5575 9 P 0 ;1
L 0.9075 4.6075 0.9075 4.6075 9 P 0 ;1
L 0.9075 4.6575 0.9075 4.6575 9 P 0 ;1
L 0.9075 4.7075 0.9075 4.7075 9 P 0 ;1
L 0.9075 4.7575 0.9075 4.7575 9 P 0 ;1
L 0.9075 4.8075 0.9075 4.8075 9 P 0 ;1
L 0.9575 0.1575 0.9575 0.1575 9 P 0 ;1
L 0.9575 0.2075 0.9575 0.2075 9 P 0 ;1
L 0.9575 0.2575 0.9575 0.2575 9 P 0 ;1
L 0.9575 0.3075 0.9575 0.3075 9 P 0 ;1
L 0.9575 0.3575 0.9575 0.3575 9 P 0 ;1
L 0.9575 0.4075 0.9575 0.4075 9 P 0 ;1
L 0.9575 0.4575 0.9575 0.4575 9 P 0 ;1
L 0.9575 0.5075 0.9575 0.5075 9 P 0 ;1
L 0.9575 0.5575 0.9575 0.5575 9 P 0 ;1
L 0.9575 0.6075 0.9575 0.6075 9 P 0 ;1
L 0.9575 0.6575 0.9575 0.6575 9 P 0 ;1
L 0.9575 0.7075 0.9575 0.7075 9 P 0 ;1
L 0.9575 0.7575 0.9575 0.7575 9 P 0 ;1
L 0.9575 0.8075 0.9575 0.8075 9 P 0 ;1
L 0.9575 0.8575 0.9575 0.8575 9 P 0 ;1
L 0.9575 0.9075 0.9575 0.9075 9 P 0 ;1
L 0.9575 0.9575 0.9575 0.9575 9 P 0 ;1
L 0.9575 1.0075 0.9575 1.0075 9 P 0 ;1
L 0.9575 1.0575 0.9575 1.0575 9 P 0 ;1
L 0.9575 1.1075 0.9575 1.1075 9 P 0 ;1
L 0.9575 1.1575 0.9575 1.1575 9 P 0 ;1
L 0.9575 1.2075 0.9575 1.2075 9 P 0 ;1
L 0.9575 1.2575 0.9575 1.2575 9 P 0 ;1
L 0.9575 1.3075 0.9575 1.3075 9 P 0 ;1
L 0.9575 2.7575 0.9575 2.7575 9 P 0 ;1
L 0.9575 2.8075 0.9575 2.8075 9 P 0 ;1
L 0.9575 2.8575 0.9575 2.8575 9 P 0 ;1
L 0.9575 3.8075 0.9575 3.8075 9 P 0 ;1
L 0.9575 3.8575 0.9575 3.8575 9 P 0 ;1
L 0.9575 3.9075 0.9575 3.9075 9 P 0 ;1
L 0.9575 3.9575 0.9575 3.9575 9 P 0 ;1
L 0.9575 4.4575 0.9575 4.4575 9 P 0 ;1
L 0.9575 4.5075 0.9575 4.5075 9 P 0 ;1
L 0.9575 4.5575 0.9575 4.5575 9 P 0 ;1
L 0.9575 4.6075 0.9575 4.6075 9 P 0 ;1
L 0.9575 4.6575 0.9575 4.6575 9 P 0 ;1
L 0.9575 4.7075 0.9575 4.7075 9 P 0 ;1
L 0.9575 4.7575 0.9575 4.7575 9 P 0 ;1
L 0.9575 4.8075 0.9575 4.8075 9 P 0 ;1
L 1.0075 0.1575 1.0075 0.1575 9 P 0 ;1
L 1.0075 0.2075 1.0075 0.2075 9 P 0 ;1
L 1.0075 0.2575 1.0075 0.2575 9 P 0 ;1
L 1.0075 0.3075 1.0075 0.3075 9 P 0 ;1
L 1.0075 0.3575 1.0075 0.3575 9 P 0 ;1
L 1.0075 0.4075 1.0075 0.4075 9 P 0 ;1
L 1.0075 0.4575 1.0075 0.4575 9 P 0 ;1
L 1.0075 0.5075 1.0075 0.5075 9 P 0 ;1
L 1.0075 0.5575 1.0075 0.5575 9 P 0 ;1
L 1.0075 0.6075 1.0075 0.6075 9 P 0 ;1
L 1.0075 0.6575 1.0075 0.6575 9 P 0 ;1
L 1.0075 0.7075 1.0075 0.7075 9 P 0 ;1
L 1.0075 0.7575 1.0075 0.7575 9 P 0 ;1
L 1.0075 0.8075 1.0075 0.8075 9 P 0 ;1
L 1.0075 0.8575 1.0075 0.8575 9 P 0 ;1
L 1.0075 0.9075 1.0075 0.9075 9 P 0 ;1
L 1.0075 0.9575 1.0075 0.9575 9 P 0 ;1
L 1.0075 1.0075 1.0075 1.0075 9 P 0 ;1
L 1.0075 1.0575 1.0075 1.0575 9 P 0 ;1
L 1.0075 1.1075 1.0075 1.1075 9 P 0 ;1
L 1.0075 1.1575 1.0075 1.1575 9 P 0 ;1
L 1.0075 1.2075 1.0075 1.2075 9 P 0 ;1
L 1.0075 1.2575 1.0075 1.2575 9 P 0 ;1
L 1.0075 1.3075 1.0075 1.3075 9 P 0 ;1
L 1.0075 2.7575 1.0075 2.7575 9 P 0 ;1
L 1.0075 2.8075 1.0075 2.8075 9 P 0 ;1
L 1.0075 3.7075 1.0075 3.7075 9 P 0 ;1
L 1.0075 3.7575 1.0075 3.7575 9 P 0 ;1
L 1.0075 3.8075 1.0075 3.8075 9 P 0 ;1
L 1.0075 3.8575 1.0075 3.8575 9 P 0 ;1
L 1.0075 3.9075 1.0075 3.9075 9 P 0 ;1
L 1.0075 3.9575 1.0075 3.9575 9 P 0 ;1
L 1.0075 4.0075 1.0075 4.0075 9 P 0 ;1
L 1.0075 4.4075 1.0075 4.4075 9 P 0 ;1
L 1.0075 4.4575 1.0075 4.4575 9 P 0 ;1
L 1.0075 4.5075 1.0075 4.5075 9 P 0 ;1
L 1.0075 4.5575 1.0075 4.5575 9 P 0 ;1
L 1.0075 4.6075 1.0075 4.6075 9 P 0 ;1
L 1.0075 4.6575 1.0075 4.6575 9 P 0 ;1
L 1.0075 4.7075 1.0075 4.7075 9 P 0 ;1
L 1.0075 4.7575 1.0075 4.7575 9 P 0 ;1
L 1.0075 4.8075 1.0075 4.8075 9 P 0 ;1
L 1.0575 0.1575 1.0575 0.1575 9 P 0 ;1
L 1.0575 0.2075 1.0575 0.2075 9 P 0 ;1
L 1.0575 0.2575 1.0575 0.2575 9 P 0 ;1
L 1.0575 0.3075 1.0575 0.3075 9 P 0 ;1
L 1.0575 0.3575 1.0575 0.3575 9 P 0 ;1
L 1.0575 0.4075 1.0575 0.4075 9 P 0 ;1
L 1.0575 0.4575 1.0575 0.4575 9 P 0 ;1
L 1.0575 0.5075 1.0575 0.5075 9 P 0 ;1
L 1.0575 0.5575 1.0575 0.5575 9 P 0 ;1
L 1.0575 0.6075 1.0575 0.6075 9 P 0 ;1
L 1.0575 0.6575 1.0575 0.6575 9 P 0 ;1
L 1.0575 0.7075 1.0575 0.7075 9 P 0 ;1
L 1.0575 0.7575 1.0575 0.7575 9 P 0 ;1
L 1.0575 0.8075 1.0575 0.8075 9 P 0 ;1
L 1.0575 0.8575 1.0575 0.8575 9 P 0 ;1
L 1.0575 0.9075 1.0575 0.9075 9 P 0 ;1
L 1.0575 0.9575 1.0575 0.9575 9 P 0 ;1
L 1.0575 1.0075 1.0575 1.0075 9 P 0 ;1
L 1.0575 1.0575 1.0575 1.0575 9 P 0 ;1
L 1.0575 1.1075 1.0575 1.1075 9 P 0 ;1
L 1.0575 1.1575 1.0575 1.1575 9 P 0 ;1
L 1.0575 1.2075 1.0575 1.2075 9 P 0 ;1
L 1.0575 1.2575 1.0575 1.2575 9 P 0 ;1
L 1.0575 1.3075 1.0575 1.3075 9 P 0 ;1
L 1.0575 1.3575 1.0575 1.3575 9 P 0 ;1
L 1.0575 3.6575 1.0575 3.6575 9 P 0 ;1
L 1.0575 3.7075 1.0575 3.7075 9 P 0 ;1
L 1.0575 3.7575 1.0575 3.7575 9 P 0 ;1
L 1.0575 3.8075 1.0575 3.8075 9 P 0 ;1
L 1.0575 3.8575 1.0575 3.8575 9 P 0 ;1
L 1.0575 3.9075 1.0575 3.9075 9 P 0 ;1
L 1.0575 3.9575 1.0575 3.9575 9 P 0 ;1
L 1.0575 4.0075 1.0575 4.0075 9 P 0 ;1
L 1.0575 4.4075 1.0575 4.4075 9 P 0 ;1
L 1.0575 4.4575 1.0575 4.4575 9 P 0 ;1
L 1.0575 4.5075 1.0575 4.5075 9 P 0 ;1
L 1.0575 4.5575 1.0575 4.5575 9 P 0 ;1
L 1.0575 4.6075 1.0575 4.6075 9 P 0 ;1
L 1.0575 4.6575 1.0575 4.6575 9 P 0 ;1
L 1.0575 4.7075 1.0575 4.7075 9 P 0 ;1
L 1.0575 4.7575 1.0575 4.7575 9 P 0 ;1
L 1.0575 4.8075 1.0575 4.8075 9 P 0 ;1
L 1.1075 0.1575 1.1075 0.1575 9 P 0 ;1
L 1.1075 0.2075 1.1075 0.2075 9 P 0 ;1
L 1.1075 0.2575 1.1075 0.2575 9 P 0 ;1
L 1.1075 0.3075 1.1075 0.3075 9 P 0 ;1
L 1.1075 0.3575 1.1075 0.3575 9 P 0 ;1
L 1.1075 0.4075 1.1075 0.4075 9 P 0 ;1
L 1.1075 0.4575 1.1075 0.4575 9 P 0 ;1
L 1.1075 0.5075 1.1075 0.5075 9 P 0 ;1
L 1.1075 0.5575 1.1075 0.5575 9 P 0 ;1
L 1.1075 0.6075 1.1075 0.6075 9 P 0 ;1
L 1.1075 0.6575 1.1075 0.6575 9 P 0 ;1
L 1.1075 0.7075 1.1075 0.7075 9 P 0 ;1
L 1.1075 0.7575 1.1075 0.7575 9 P 0 ;1
L 1.1075 0.8075 1.1075 0.8075 9 P 0 ;1
L 1.1075 0.8575 1.1075 0.8575 9 P 0 ;1
L 1.1075 0.9075 1.1075 0.9075 9 P 0 ;1
L 1.1075 0.9575 1.1075 0.9575 9 P 0 ;1
L 1.1075 1.0075 1.1075 1.0075 9 P 0 ;1
L 1.1075 1.0575 1.1075 1.0575 9 P 0 ;1
L 1.1075 1.1075 1.1075 1.1075 9 P 0 ;1
L 1.1075 1.1575 1.1075 1.1575 9 P 0 ;1
L 1.1075 1.2075 1.1075 1.2075 9 P 0 ;1
L 1.1075 1.2575 1.1075 1.2575 9 P 0 ;1
L 1.1075 1.3075 1.1075 1.3075 9 P 0 ;1
L 1.1075 1.3575 1.1075 1.3575 9 P 0 ;1
L 1.1075 3.5575 1.1075 3.5575 9 P 0 ;1
L 1.1075 3.6075 1.1075 3.6075 9 P 0 ;1
L 1.1075 3.6575 1.1075 3.6575 9 P 0 ;1
L 1.1075 3.7075 1.1075 3.7075 9 P 0 ;1
L 1.1075 3.7575 1.1075 3.7575 9 P 0 ;1
L 1.1075 3.8075 1.1075 3.8075 9 P 0 ;1
L 1.1075 3.8575 1.1075 3.8575 9 P 0 ;1
L 1.1075 3.9075 1.1075 3.9075 9 P 0 ;1
L 1.1075 3.9575 1.1075 3.9575 9 P 0 ;1
L 1.1075 4.0075 1.1075 4.0075 9 P 0 ;1
L 1.1075 4.3575 1.1075 4.3575 9 P 0 ;1
L 1.1075 4.4075 1.1075 4.4075 9 P 0 ;1
L 1.1075 4.4575 1.1075 4.4575 9 P 0 ;1
L 1.1075 4.5075 1.1075 4.5075 9 P 0 ;1
L 1.1075 4.5575 1.1075 4.5575 9 P 0 ;1
L 1.1075 4.6075 1.1075 4.6075 9 P 0 ;1
L 1.1075 4.6575 1.1075 4.6575 9 P 0 ;1
L 1.1075 4.7075 1.1075 4.7075 9 P 0 ;1
L 1.1075 4.7575 1.1075 4.7575 9 P 0 ;1
L 1.1075 4.8075 1.1075 4.8075 9 P 0 ;1
L 1.1575 0.1575 1.1575 0.1575 9 P 0 ;1
L 1.1575 0.2075 1.1575 0.2075 9 P 0 ;1
L 1.1575 0.2575 1.1575 0.2575 9 P 0 ;1
L 1.1575 0.3075 1.1575 0.3075 9 P 0 ;1
L 1.1575 0.3575 1.1575 0.3575 9 P 0 ;1
L 1.1575 0.4075 1.1575 0.4075 9 P 0 ;1
L 1.1575 0.4575 1.1575 0.4575 9 P 0 ;1
L 1.1575 0.5075 1.1575 0.5075 9 P 0 ;1
L 1.1575 0.5575 1.1575 0.5575 9 P 0 ;1
L 1.1575 0.6075 1.1575 0.6075 9 P 0 ;1
L 1.1575 0.6575 1.1575 0.6575 9 P 0 ;1
L 1.1575 0.7075 1.1575 0.7075 9 P 0 ;1
L 1.1575 0.7575 1.1575 0.7575 9 P 0 ;1
L 1.1575 0.8075 1.1575 0.8075 9 P 0 ;1
L 1.1575 0.8575 1.1575 0.8575 9 P 0 ;1
L 1.1575 0.9075 1.1575 0.9075 9 P 0 ;1
L 1.1575 0.9575 1.1575 0.9575 9 P 0 ;1
L 1.1575 1.0075 1.1575 1.0075 9 P 0 ;1
L 1.1575 1.0575 1.1575 1.0575 9 P 0 ;1
L 1.1575 1.1075 1.1575 1.1075 9 P 0 ;1
L 1.1575 1.1575 1.1575 1.1575 9 P 0 ;1
L 1.1575 1.2075 1.1575 1.2075 9 P 0 ;1
L 1.1575 1.2575 1.1575 1.2575 9 P 0 ;1
L 1.1575 1.3075 1.1575 1.3075 9 P 0 ;1
L 1.1575 1.3575 1.1575 1.3575 9 P 0 ;1
L 1.1575 1.4075 1.1575 1.4075 9 P 0 ;1
L 1.1575 1.4575 1.1575 1.4575 9 P 0 ;1
L 1.1575 2.4075 1.1575 2.4075 9 P 0 ;1
L 1.1575 3.5075 1.1575 3.5075 9 P 0 ;1
L 1.1575 3.5575 1.1575 3.5575 9 P 0 ;1
L 1.1575 3.6075 1.1575 3.6075 9 P 0 ;1
L 1.1575 3.6575 1.1575 3.6575 9 P 0 ;1
L 1.1575 3.7075 1.1575 3.7075 9 P 0 ;1
L 1.1575 3.7575 1.1575 3.7575 9 P 0 ;1
L 1.1575 3.8075 1.1575 3.8075 9 P 0 ;1
L 1.1575 3.8575 1.1575 3.8575 9 P 0 ;1
L 1.1575 3.9075 1.1575 3.9075 9 P 0 ;1
L 1.1575 3.9575 1.1575 3.9575 9 P 0 ;1
L 1.1575 4.0075 1.1575 4.0075 9 P 0 ;1
L 1.1575 4.0575 1.1575 4.0575 9 P 0 ;1
L 1.1575 4.1075 1.1575 4.1075 9 P 0 ;1
L 1.1575 4.1575 1.1575 4.1575 9 P 0 ;1
L 1.1575 4.2575 1.1575 4.2575 9 P 0 ;1
L 1.1575 4.3075 1.1575 4.3075 9 P 0 ;1
L 1.1575 4.3575 1.1575 4.3575 9 P 0 ;1
L 1.1575 4.4075 1.1575 4.4075 9 P 0 ;1
L 1.1575 4.4575 1.1575 4.4575 9 P 0 ;1
L 1.1575 4.5075 1.1575 4.5075 9 P 0 ;1
L 1.1575 4.5575 1.1575 4.5575 9 P 0 ;1
L 1.1575 4.6075 1.1575 4.6075 9 P 0 ;1
L 1.1575 4.6575 1.1575 4.6575 9 P 0 ;1
L 1.1575 4.7075 1.1575 4.7075 9 P 0 ;1
L 1.1575 4.7575 1.1575 4.7575 9 P 0 ;1
L 1.1575 4.8075 1.1575 4.8075 9 P 0 ;1
L 1.2075 0.1575 1.2075 0.1575 9 P 0 ;1
L 1.2075 0.2075 1.2075 0.2075 9 P 0 ;1
L 1.2075 0.2575 1.2075 0.2575 9 P 0 ;1
L 1.2075 0.3075 1.2075 0.3075 9 P 0 ;1
L 1.2075 0.3575 1.2075 0.3575 9 P 0 ;1
L 1.2075 0.4075 1.2075 0.4075 9 P 0 ;1
L 1.2075 0.4575 1.2075 0.4575 9 P 0 ;1
L 1.2075 0.5075 1.2075 0.5075 9 P 0 ;1
L 1.2075 0.5575 1.2075 0.5575 9 P 0 ;1
L 1.2075 0.6075 1.2075 0.6075 9 P 0 ;1
L 1.2075 0.6575 1.2075 0.6575 9 P 0 ;1
L 1.2075 0.7075 1.2075 0.7075 9 P 0 ;1
L 1.2075 0.7575 1.2075 0.7575 9 P 0 ;1
L 1.2075 0.8075 1.2075 0.8075 9 P 0 ;1
L 1.2075 0.8575 1.2075 0.8575 9 P 0 ;1
L 1.2075 0.9075 1.2075 0.9075 9 P 0 ;1
L 1.2075 0.9575 1.2075 0.9575 9 P 0 ;1
L 1.2075 1.0075 1.2075 1.0075 9 P 0 ;1
L 1.2075 1.0575 1.2075 1.0575 9 P 0 ;1
L 1.2075 1.1075 1.2075 1.1075 9 P 0 ;1
L 1.2075 1.1575 1.2075 1.1575 9 P 0 ;1
L 1.2075 1.2075 1.2075 1.2075 9 P 0 ;1
L 1.2075 1.2575 1.2075 1.2575 9 P 0 ;1
L 1.2075 1.3075 1.2075 1.3075 9 P 0 ;1
L 1.2075 1.3575 1.2075 1.3575 9 P 0 ;1
L 1.2075 1.4075 1.2075 1.4075 9 P 0 ;1
L 1.2075 2.3575 1.2075 2.3575 9 P 0 ;1
L 1.2075 2.4075 1.2075 2.4075 9 P 0 ;1
L 1.2075 3.4075 1.2075 3.4075 9 P 0 ;1
L 1.2075 3.4575 1.2075 3.4575 9 P 0 ;1
L 1.2075 3.5075 1.2075 3.5075 9 P 0 ;1
L 1.2075 3.5575 1.2075 3.5575 9 P 0 ;1
L 1.2075 3.6075 1.2075 3.6075 9 P 0 ;1
L 1.2075 3.6575 1.2075 3.6575 9 P 0 ;1
L 1.2075 3.7075 1.2075 3.7075 9 P 0 ;1
L 1.2075 3.7575 1.2075 3.7575 9 P 0 ;1
L 1.2075 3.8075 1.2075 3.8075 9 P 0 ;1
L 1.2075 3.8575 1.2075 3.8575 9 P 0 ;1
L 1.2075 3.9075 1.2075 3.9075 9 P 0 ;1
L 1.2075 3.9575 1.2075 3.9575 9 P 0 ;1
L 1.2075 4.0075 1.2075 4.0075 9 P 0 ;1
L 1.2075 4.0575 1.2075 4.0575 9 P 0 ;1
L 1.2075 4.1075 1.2075 4.1075 9 P 0 ;1
L 1.2075 4.1575 1.2075 4.1575 9 P 0 ;1
L 1.2075 4.2075 1.2075 4.2075 9 P 0 ;1
L 1.2075 4.2575 1.2075 4.2575 9 P 0 ;1
L 1.2075 4.5075 1.2075 4.5075 9 P 0 ;1
L 1.2075 4.8075 1.2075 4.8075 9 P 0 ;1
L 1.2575 0.1575 1.2575 0.1575 9 P 0 ;1
L 1.2575 0.2075 1.2575 0.2075 9 P 0 ;1
L 1.2575 0.2575 1.2575 0.2575 9 P 0 ;1
L 1.2575 0.3075 1.2575 0.3075 9 P 0 ;1
L 1.2575 0.3575 1.2575 0.3575 9 P 0 ;1
L 1.2575 0.4075 1.2575 0.4075 9 P 0 ;1
L 1.2575 0.4575 1.2575 0.4575 9 P 0 ;1
L 1.2575 0.5075 1.2575 0.5075 9 P 0 ;1
L 1.2575 0.5575 1.2575 0.5575 9 P 0 ;1
L 1.2575 0.6075 1.2575 0.6075 9 P 0 ;1
L 1.2575 0.6575 1.2575 0.6575 9 P 0 ;1
L 1.2575 0.7075 1.2575 0.7075 9 P 0 ;1
L 1.2575 0.7575 1.2575 0.7575 9 P 0 ;1
L 1.2575 0.8075 1.2575 0.8075 9 P 0 ;1
L 1.2575 0.8575 1.2575 0.8575 9 P 0 ;1
L 1.2575 0.9075 1.2575 0.9075 9 P 0 ;1
L 1.2575 0.9575 1.2575 0.9575 9 P 0 ;1
L 1.2575 1.0075 1.2575 1.0075 9 P 0 ;1
L 1.2575 1.0575 1.2575 1.0575 9 P 0 ;1
L 1.2575 1.1075 1.2575 1.1075 9 P 0 ;1
L 1.2575 1.1575 1.2575 1.1575 9 P 0 ;1
L 1.2575 1.2075 1.2575 1.2075 9 P 0 ;1
L 1.2575 1.2575 1.2575 1.2575 9 P 0 ;1
L 1.2575 1.3075 1.2575 1.3075 9 P 0 ;1
L 1.2575 3.3575 1.2575 3.3575 9 P 0 ;1
L 1.2575 3.4075 1.2575 3.4075 9 P 0 ;1
L 1.2575 3.4575 1.2575 3.4575 9 P 0 ;1
L 1.2575 3.5075 1.2575 3.5075 9 P 0 ;1
L 1.2575 3.5575 1.2575 3.5575 9 P 0 ;1
L 1.2575 3.6075 1.2575 3.6075 9 P 0 ;1
L 1.2575 3.6575 1.2575 3.6575 9 P 0 ;1
L 1.2575 3.7075 1.2575 3.7075 9 P 0 ;1
L 1.2575 3.7575 1.2575 3.7575 9 P 0 ;1
L 1.2575 3.8075 1.2575 3.8075 9 P 0 ;1
L 1.2575 3.8575 1.2575 3.8575 9 P 0 ;1
L 1.2575 3.9075 1.2575 3.9075 9 P 0 ;1
L 1.2575 3.9575 1.2575 3.9575 9 P 0 ;1
L 1.2575 4.8075 1.2575 4.8075 9 P 0 ;1
L 1.2575 4.8575 1.2575 4.8575 9 P 0 ;1
L 1.3075 0.1575 1.3075 0.1575 9 P 0 ;1
L 1.3075 0.2075 1.3075 0.2075 9 P 0 ;1
L 1.3075 0.2575 1.3075 0.2575 9 P 0 ;1
L 1.3075 0.3075 1.3075 0.3075 9 P 0 ;1
L 1.3075 0.3575 1.3075 0.3575 9 P 0 ;1
L 1.3075 0.4075 1.3075 0.4075 9 P 0 ;1
L 1.3075 0.4575 1.3075 0.4575 9 P 0 ;1
L 1.3075 0.5075 1.3075 0.5075 9 P 0 ;1
L 1.3075 0.5575 1.3075 0.5575 9 P 0 ;1
L 1.3075 0.6075 1.3075 0.6075 9 P 0 ;1
L 1.3075 0.6575 1.3075 0.6575 9 P 0 ;1
L 1.3075 0.7075 1.3075 0.7075 9 P 0 ;1
L 1.3075 0.7575 1.3075 0.7575 9 P 0 ;1
L 1.3075 0.8075 1.3075 0.8075 9 P 0 ;1
L 1.3075 0.8575 1.3075 0.8575 9 P 0 ;1
L 1.3075 0.9075 1.3075 0.9075 9 P 0 ;1
L 1.3075 0.9575 1.3075 0.9575 9 P 0 ;1
L 1.3075 1.0075 1.3075 1.0075 9 P 0 ;1
L 1.3075 1.0575 1.3075 1.0575 9 P 0 ;1
L 1.3075 1.1075 1.3075 1.1075 9 P 0 ;1
L 1.3075 1.1575 1.3075 1.1575 9 P 0 ;1
L 1.3075 1.2075 1.3075 1.2075 9 P 0 ;1
L 1.3075 1.2575 1.3075 1.2575 9 P 0 ;1
L 1.3075 3.3075 1.3075 3.3075 9 P 0 ;1
L 1.3075 3.3575 1.3075 3.3575 9 P 0 ;1
L 1.3075 3.4075 1.3075 3.4075 9 P 0 ;1
L 1.3075 3.4575 1.3075 3.4575 9 P 0 ;1
L 1.3075 3.5075 1.3075 3.5075 9 P 0 ;1
L 1.3075 3.5575 1.3075 3.5575 9 P 0 ;1
L 1.3075 3.6075 1.3075 3.6075 9 P 0 ;1
L 1.3075 3.6575 1.3075 3.6575 9 P 0 ;1
L 1.3575 0.1575 1.3575 0.1575 9 P 0 ;1
L 1.3575 0.2075 1.3575 0.2075 9 P 0 ;1
L 1.3575 0.2575 1.3575 0.2575 9 P 0 ;1
L 1.3575 0.3075 1.3575 0.3075 9 P 0 ;1
L 1.3575 0.3575 1.3575 0.3575 9 P 0 ;1
L 1.3575 0.4075 1.3575 0.4075 9 P 0 ;1
L 1.3575 0.4575 1.3575 0.4575 9 P 0 ;1
L 1.3575 0.5075 1.3575 0.5075 9 P 0 ;1
L 1.3575 0.5575 1.3575 0.5575 9 P 0 ;1
L 1.3575 0.6075 1.3575 0.6075 9 P 0 ;1
L 1.3575 0.6575 1.3575 0.6575 9 P 0 ;1
L 1.3575 0.7075 1.3575 0.7075 9 P 0 ;1
L 1.3575 0.7575 1.3575 0.7575 9 P 0 ;1
L 1.3575 0.8075 1.3575 0.8075 9 P 0 ;1
L 1.3575 0.8575 1.3575 0.8575 9 P 0 ;1
L 1.3575 0.9075 1.3575 0.9075 9 P 0 ;1
L 1.3575 0.9575 1.3575 0.9575 9 P 0 ;1
L 1.3575 1.0075 1.3575 1.0075 9 P 0 ;1
L 1.3575 1.0575 1.3575 1.0575 9 P 0 ;1
L 1.3575 1.1075 1.3575 1.1075 9 P 0 ;1
L 1.3575 1.1575 1.3575 1.1575 9 P 0 ;1
L 1.3575 3.2075 1.3575 3.2075 9 P 0 ;1
L 1.3575 3.2575 1.3575 3.2575 9 P 0 ;1
L 1.3575 3.3075 1.3575 3.3075 9 P 0 ;1
L 1.3575 3.3575 1.3575 3.3575 9 P 0 ;1
L 1.3575 3.4075 1.3575 3.4075 9 P 0 ;1
L 1.3575 3.4575 1.3575 3.4575 9 P 0 ;1
L 1.3575 4.9575 1.3575 4.9575 9 P 0 ;1
L 1.4075 0.1575 1.4075 0.1575 9 P 0 ;1
L 1.4075 0.2075 1.4075 0.2075 9 P 0 ;1
L 1.4075 0.2575 1.4075 0.2575 9 P 0 ;1
L 1.4075 0.3075 1.4075 0.3075 9 P 0 ;1
L 1.4075 0.3575 1.4075 0.3575 9 P 0 ;1
L 1.4075 0.4075 1.4075 0.4075 9 P 0 ;1
L 1.4075 0.4575 1.4075 0.4575 9 P 0 ;1
L 1.4075 0.5075 1.4075 0.5075 9 P 0 ;1
L 1.4075 0.5575 1.4075 0.5575 9 P 0 ;1
L 1.4075 0.6075 1.4075 0.6075 9 P 0 ;1
L 1.4075 0.6575 1.4075 0.6575 9 P 0 ;1
L 1.4075 0.7075 1.4075 0.7075 9 P 0 ;1
L 1.4075 0.7575 1.4075 0.7575 9 P 0 ;1
L 1.4075 0.8075 1.4075 0.8075 9 P 0 ;1
L 1.4075 0.8575 1.4075 0.8575 9 P 0 ;1
L 1.4075 0.9075 1.4075 0.9075 9 P 0 ;1
L 1.4075 0.9575 1.4075 0.9575 9 P 0 ;1
L 1.4075 1.0075 1.4075 1.0075 9 P 0 ;1
L 1.4075 1.0575 1.4075 1.0575 9 P 0 ;1
L 1.4075 1.1075 1.4075 1.1075 9 P 0 ;1
L 1.4075 3.1575 1.4075 3.1575 9 P 0 ;1
L 1.4075 3.2075 1.4075 3.2075 9 P 0 ;1
L 1.4075 3.2575 1.4075 3.2575 9 P 0 ;1
L 1.4075 3.3075 1.4075 3.3075 9 P 0 ;1
L 1.4075 3.3575 1.4075 3.3575 9 P 0 ;1
L 1.4075 3.4075 1.4075 3.4075 9 P 0 ;1
L 1.4075 4.7575 1.4075 4.7575 9 P 0 ;1
L 1.4075 4.8075 1.4075 4.8075 9 P 0 ;1
L 1.4075 4.9075 1.4075 4.9075 9 P 0 ;1
L 1.4075 4.9575 1.4075 4.9575 9 P 0 ;1
L 1.4075 5.0075 1.4075 5.0075 9 P 0 ;1
L 1.4575 0.1575 1.4575 0.1575 9 P 0 ;1
L 1.4575 0.2075 1.4575 0.2075 9 P 0 ;1
L 1.4575 0.2575 1.4575 0.2575 9 P 0 ;1
L 1.4575 0.3075 1.4575 0.3075 9 P 0 ;1
L 1.4575 0.3575 1.4575 0.3575 9 P 0 ;1
L 1.4575 0.4075 1.4575 0.4075 9 P 0 ;1
L 1.4575 0.4575 1.4575 0.4575 9 P 0 ;1
L 1.4575 0.5075 1.4575 0.5075 9 P 0 ;1
L 1.4575 0.5575 1.4575 0.5575 9 P 0 ;1
L 1.4575 0.6075 1.4575 0.6075 9 P 0 ;1
L 1.4575 0.6575 1.4575 0.6575 9 P 0 ;1
L 1.4575 0.7075 1.4575 0.7075 9 P 0 ;1
L 1.4575 0.7575 1.4575 0.7575 9 P 0 ;1
L 1.4575 0.8075 1.4575 0.8075 9 P 0 ;1
L 1.4575 0.8575 1.4575 0.8575 9 P 0 ;1
L 1.4575 0.9075 1.4575 0.9075 9 P 0 ;1
L 1.4575 0.9575 1.4575 0.9575 9 P 0 ;1
L 1.4575 1.0075 1.4575 1.0075 9 P 0 ;1
L 1.4575 1.0575 1.4575 1.0575 9 P 0 ;1
L 1.4575 3.0575 1.4575 3.0575 9 P 0 ;1
L 1.4575 3.1075 1.4575 3.1075 9 P 0 ;1
L 1.4575 3.1575 1.4575 3.1575 9 P 0 ;1
L 1.4575 3.2075 1.4575 3.2075 9 P 0 ;1
L 1.4575 3.2575 1.4575 3.2575 9 P 0 ;1
L 1.4575 3.3075 1.4575 3.3075 9 P 0 ;1
L 1.4575 4.6575 1.4575 4.6575 9 P 0 ;1
L 1.4575 4.7075 1.4575 4.7075 9 P 0 ;1
L 1.4575 4.8575 1.4575 4.8575 9 P 0 ;1
L 1.4575 4.9075 1.4575 4.9075 9 P 0 ;1
L 1.4575 4.9575 1.4575 4.9575 9 P 0 ;1
L 1.4575 5.0075 1.4575 5.0075 9 P 0 ;1
L 1.5075 0.1575 1.5075 0.1575 9 P 0 ;1
L 1.5075 0.2075 1.5075 0.2075 9 P 0 ;1
L 1.5075 0.2575 1.5075 0.2575 9 P 0 ;1
L 1.5075 0.3075 1.5075 0.3075 9 P 0 ;1
L 1.5075 0.3575 1.5075 0.3575 9 P 0 ;1
L 1.5075 0.4075 1.5075 0.4075 9 P 0 ;1
L 1.5075 0.4575 1.5075 0.4575 9 P 0 ;1
L 1.5075 0.5075 1.5075 0.5075 9 P 0 ;1
L 1.5075 0.5575 1.5075 0.5575 9 P 0 ;1
L 1.5075 0.6075 1.5075 0.6075 9 P 0 ;1
L 1.5075 0.6575 1.5075 0.6575 9 P 0 ;1
L 1.5075 0.7075 1.5075 0.7075 9 P 0 ;1
L 1.5075 0.7575 1.5075 0.7575 9 P 0 ;1
L 1.5075 0.8075 1.5075 0.8075 9 P 0 ;1
L 1.5075 0.8575 1.5075 0.8575 9 P 0 ;1
L 1.5075 0.9075 1.5075 0.9075 9 P 0 ;1
L 1.5075 0.9575 1.5075 0.9575 9 P 0 ;1
L 1.5075 1.0075 1.5075 1.0075 9 P 0 ;1
L 1.5075 1.0575 1.5075 1.0575 9 P 0 ;1
L 1.5075 3.0075 1.5075 3.0075 9 P 0 ;1
L 1.5075 3.0575 1.5075 3.0575 9 P 0 ;1
L 1.5075 3.1075 1.5075 3.1075 9 P 0 ;1
L 1.5075 3.1575 1.5075 3.1575 9 P 0 ;1
L 1.5075 3.2075 1.5075 3.2075 9 P 0 ;1
L 1.5075 3.2575 1.5075 3.2575 9 P 0 ;1
L 1.5575 0.1575 1.5575 0.1575 9 P 0 ;1
L 1.5575 0.2075 1.5575 0.2075 9 P 0 ;1
L 1.5575 0.2575 1.5575 0.2575 9 P 0 ;1
L 1.5575 0.3075 1.5575 0.3075 9 P 0 ;1
L 1.5575 0.3575 1.5575 0.3575 9 P 0 ;1
L 1.5575 0.4075 1.5575 0.4075 9 P 0 ;1
L 1.5575 0.4575 1.5575 0.4575 9 P 0 ;1
L 1.5575 0.5075 1.5575 0.5075 9 P 0 ;1
L 1.5575 0.5575 1.5575 0.5575 9 P 0 ;1
L 1.5575 0.6075 1.5575 0.6075 9 P 0 ;1
L 1.5575 0.6575 1.5575 0.6575 9 P 0 ;1
L 1.5575 0.7075 1.5575 0.7075 9 P 0 ;1
L 1.5575 0.7575 1.5575 0.7575 9 P 0 ;1
L 1.5575 0.8075 1.5575 0.8075 9 P 0 ;1
L 1.5575 0.8575 1.5575 0.8575 9 P 0 ;1
L 1.5575 0.9075 1.5575 0.9075 9 P 0 ;1
L 1.5575 0.9575 1.5575 0.9575 9 P 0 ;1
L 1.5575 1.0075 1.5575 1.0075 9 P 0 ;1
L 1.5575 2.9075 1.5575 2.9075 9 P 0 ;1
L 1.5575 2.9575 1.5575 2.9575 9 P 0 ;1
L 1.5575 3.0075 1.5575 3.0075 9 P 0 ;1
L 1.5575 3.0575 1.5575 3.0575 9 P 0 ;1
L 1.5575 3.1075 1.5575 3.1075 9 P 0 ;1
L 1.5575 3.1575 1.5575 3.1575 9 P 0 ;1
L 1.5575 3.2075 1.5575 3.2075 9 P 0 ;1
L 1.6075 0.1575 1.6075 0.1575 9 P 0 ;1
L 1.6075 0.2075 1.6075 0.2075 9 P 0 ;1
L 1.6075 0.2575 1.6075 0.2575 9 P 0 ;1
L 1.6075 0.3075 1.6075 0.3075 9 P 0 ;1
L 1.6075 0.3575 1.6075 0.3575 9 P 0 ;1
L 1.6075 0.4075 1.6075 0.4075 9 P 0 ;1
L 1.6075 0.4575 1.6075 0.4575 9 P 0 ;1
L 1.6075 0.5075 1.6075 0.5075 9 P 0 ;1
L 1.6075 0.5575 1.6075 0.5575 9 P 0 ;1
L 1.6075 0.6075 1.6075 0.6075 9 P 0 ;1
L 1.6075 0.6575 1.6075 0.6575 9 P 0 ;1
L 1.6075 0.7075 1.6075 0.7075 9 P 0 ;1
L 1.6075 0.7575 1.6075 0.7575 9 P 0 ;1
L 1.6075 0.8075 1.6075 0.8075 9 P 0 ;1
L 1.6075 0.8575 1.6075 0.8575 9 P 0 ;1
L 1.6075 0.9075 1.6075 0.9075 9 P 0 ;1
L 1.6075 0.9575 1.6075 0.9575 9 P 0 ;1
L 1.6075 2.7075 1.6075 2.7075 9 P 0 ;1
L 1.6075 2.7575 1.6075 2.7575 9 P 0 ;1
L 1.6075 2.8075 1.6075 2.8075 9 P 0 ;1
L 1.6075 2.8575 1.6075 2.8575 9 P 0 ;1
L 1.6075 2.9075 1.6075 2.9075 9 P 0 ;1
L 1.6075 2.9575 1.6075 2.9575 9 P 0 ;1
L 1.6075 3.0075 1.6075 3.0075 9 P 0 ;1
L 1.6075 3.0575 1.6075 3.0575 9 P 0 ;1
L 1.6075 3.1075 1.6075 3.1075 9 P 0 ;1
L 1.6075 3.1575 1.6075 3.1575 9 P 0 ;1
L 1.6575 0.1575 1.6575 0.1575 9 P 0 ;1
L 1.6575 0.2075 1.6575 0.2075 9 P 0 ;1
L 1.6575 0.2575 1.6575 0.2575 9 P 0 ;1
L 1.6575 0.3075 1.6575 0.3075 9 P 0 ;1
L 1.6575 0.3575 1.6575 0.3575 9 P 0 ;1
L 1.6575 0.4075 1.6575 0.4075 9 P 0 ;1
L 1.6575 0.4575 1.6575 0.4575 9 P 0 ;1
L 1.6575 0.5075 1.6575 0.5075 9 P 0 ;1
L 1.6575 0.5575 1.6575 0.5575 9 P 0 ;1
L 1.6575 0.6075 1.6575 0.6075 9 P 0 ;1
L 1.6575 0.6575 1.6575 0.6575 9 P 0 ;1
L 1.6575 0.7075 1.6575 0.7075 9 P 0 ;1
L 1.6575 0.7575 1.6575 0.7575 9 P 0 ;1
L 1.6575 0.8075 1.6575 0.8075 9 P 0 ;1
L 1.6575 0.8575 1.6575 0.8575 9 P 0 ;1
L 1.6575 0.9075 1.6575 0.9075 9 P 0 ;1
L 1.6575 0.9575 1.6575 0.9575 9 P 0 ;1
L 1.6575 2.4575 1.6575 2.4575 9 P 0 ;1
L 1.6575 2.5075 1.6575 2.5075 9 P 0 ;1
L 1.6575 2.5575 1.6575 2.5575 9 P 0 ;1
L 1.6575 2.6075 1.6575 2.6075 9 P 0 ;1
L 1.6575 2.6575 1.6575 2.6575 9 P 0 ;1
L 1.6575 2.7075 1.6575 2.7075 9 P 0 ;1
L 1.6575 2.7575 1.6575 2.7575 9 P 0 ;1
L 1.6575 2.8075 1.6575 2.8075 9 P 0 ;1
L 1.6575 2.8575 1.6575 2.8575 9 P 0 ;1
L 1.6575 2.9075 1.6575 2.9075 9 P 0 ;1
L 1.6575 2.9575 1.6575 2.9575 9 P 0 ;1
L 1.6575 3.0075 1.6575 3.0075 9 P 0 ;1
L 1.6575 3.0575 1.6575 3.0575 9 P 0 ;1
L 1.6575 3.1075 1.6575 3.1075 9 P 0 ;1
L 1.6575 3.1575 1.6575 3.1575 9 P 0 ;1
L 1.7075 0.1575 1.7075 0.1575 9 P 0 ;1
L 1.7075 0.2075 1.7075 0.2075 9 P 0 ;1
L 1.7075 0.2575 1.7075 0.2575 9 P 0 ;1
L 1.7075 0.3075 1.7075 0.3075 9 P 0 ;1
L 1.7075 0.3575 1.7075 0.3575 9 P 0 ;1
L 1.7075 0.4075 1.7075 0.4075 9 P 0 ;1
L 1.7075 0.4575 1.7075 0.4575 9 P 0 ;1
L 1.7075 0.5075 1.7075 0.5075 9 P 0 ;1
L 1.7075 0.5575 1.7075 0.5575 9 P 0 ;1
L 1.7075 0.6075 1.7075 0.6075 9 P 0 ;1
L 1.7075 0.6575 1.7075 0.6575 9 P 0 ;1
L 1.7075 0.7075 1.7075 0.7075 9 P 0 ;1
L 1.7075 0.7575 1.7075 0.7575 9 P 0 ;1
L 1.7075 0.8075 1.7075 0.8075 9 P 0 ;1
L 1.7075 0.8575 1.7075 0.8575 9 P 0 ;1
L 1.7075 0.9075 1.7075 0.9075 9 P 0 ;1
L 1.7075 2.4075 1.7075 2.4075 9 P 0 ;1
L 1.7075 2.4575 1.7075 2.4575 9 P 0 ;1
L 1.7075 2.5075 1.7075 2.5075 9 P 0 ;1
L 1.7075 2.5575 1.7075 2.5575 9 P 0 ;1
L 1.7075 2.6075 1.7075 2.6075 9 P 0 ;1
L 1.7075 2.6575 1.7075 2.6575 9 P 0 ;1
L 1.7075 2.7075 1.7075 2.7075 9 P 0 ;1
L 1.7075 2.7575 1.7075 2.7575 9 P 0 ;1
L 1.7075 2.8075 1.7075 2.8075 9 P 0 ;1
L 1.7075 2.8575 1.7075 2.8575 9 P 0 ;1
L 1.7075 2.9075 1.7075 2.9075 9 P 0 ;1
L 1.7075 2.9575 1.7075 2.9575 9 P 0 ;1
L 1.7075 3.0075 1.7075 3.0075 9 P 0 ;1
L 1.7075 3.0575 1.7075 3.0575 9 P 0 ;1
L 1.7075 3.1075 1.7075 3.1075 9 P 0 ;1
L 1.7075 3.1575 1.7075 3.1575 9 P 0 ;1
L 1.7075 4.1575 1.7075 4.1575 9 P 0 ;1
L 1.7075 4.2075 1.7075 4.2075 9 P 0 ;1
L 1.7075 5.2075 1.7075 5.2075 9 P 0 ;1
L 1.7575 0.1575 1.7575 0.1575 9 P 0 ;1
L 1.7575 0.2075 1.7575 0.2075 9 P 0 ;1
L 1.7575 0.2575 1.7575 0.2575 9 P 0 ;1
L 1.7575 0.3075 1.7575 0.3075 9 P 0 ;1
L 1.7575 0.3575 1.7575 0.3575 9 P 0 ;1
L 1.7575 0.4075 1.7575 0.4075 9 P 0 ;1
L 1.7575 0.4575 1.7575 0.4575 9 P 0 ;1
L 1.7575 0.5075 1.7575 0.5075 9 P 0 ;1
L 1.7575 0.5575 1.7575 0.5575 9 P 0 ;1
L 1.7575 0.6075 1.7575 0.6075 9 P 0 ;1
L 1.7575 0.6575 1.7575 0.6575 9 P 0 ;1
L 1.7575 0.7075 1.7575 0.7075 9 P 0 ;1
L 1.7575 0.7575 1.7575 0.7575 9 P 0 ;1
L 1.7575 0.8075 1.7575 0.8075 9 P 0 ;1
L 1.7575 0.8575 1.7575 0.8575 9 P 0 ;1
L 1.7575 2.3075 1.7575 2.3075 9 P 0 ;1
L 1.7575 2.3575 1.7575 2.3575 9 P 0 ;1
L 1.7575 2.5575 1.7575 2.5575 9 P 0 ;1
L 1.7575 2.6075 1.7575 2.6075 9 P 0 ;1
L 1.7575 2.6575 1.7575 2.6575 9 P 0 ;1
L 1.7575 2.7075 1.7575 2.7075 9 P 0 ;1
L 1.7575 2.7575 1.7575 2.7575 9 P 0 ;1
L 1.7575 2.8075 1.7575 2.8075 9 P 0 ;1
L 1.7575 2.8575 1.7575 2.8575 9 P 0 ;1
L 1.7575 2.9075 1.7575 2.9075 9 P 0 ;1
L 1.7575 2.9575 1.7575 2.9575 9 P 0 ;1
L 1.7575 3.0075 1.7575 3.0075 9 P 0 ;1
L 1.7575 3.0575 1.7575 3.0575 9 P 0 ;1
L 1.7575 3.1075 1.7575 3.1075 9 P 0 ;1
L 1.7575 4.1575 1.7575 4.1575 9 P 0 ;1
L 1.7575 4.3575 1.7575 4.3575 9 P 0 ;1
L 1.7575 5.1575 1.7575 5.1575 9 P 0 ;1
L 1.7575 5.2075 1.7575 5.2075 9 P 0 ;1
L 1.8075 0.1575 1.8075 0.1575 9 P 0 ;1
L 1.8075 0.2075 1.8075 0.2075 9 P 0 ;1
L 1.8075 0.2575 1.8075 0.2575 9 P 0 ;1
L 1.8075 0.3075 1.8075 0.3075 9 P 0 ;1
L 1.8075 0.3575 1.8075 0.3575 9 P 0 ;1
L 1.8075 0.4075 1.8075 0.4075 9 P 0 ;1
L 1.8075 0.4575 1.8075 0.4575 9 P 0 ;1
L 1.8075 0.5075 1.8075 0.5075 9 P 0 ;1
L 1.8075 0.5575 1.8075 0.5575 9 P 0 ;1
L 1.8075 0.6075 1.8075 0.6075 9 P 0 ;1
L 1.8075 0.6575 1.8075 0.6575 9 P 0 ;1
L 1.8075 0.7075 1.8075 0.7075 9 P 0 ;1
L 1.8075 0.7575 1.8075 0.7575 9 P 0 ;1
L 1.8075 0.8075 1.8075 0.8075 9 P 0 ;1
L 1.8075 2.2575 1.8075 2.2575 9 P 0 ;1
L 1.8075 2.3075 1.8075 2.3075 9 P 0 ;1
L 1.8075 2.3575 1.8075 2.3575 9 P 0 ;1
L 1.8075 2.5575 1.8075 2.5575 9 P 0 ;1
L 1.8075 2.6075 1.8075 2.6075 9 P 0 ;1
L 1.8075 2.6575 1.8075 2.6575 9 P 0 ;1
L 1.8075 2.7075 1.8075 2.7075 9 P 0 ;1
L 1.8075 2.7575 1.8075 2.7575 9 P 0 ;1
L 1.8075 2.8075 1.8075 2.8075 9 P 0 ;1
L 1.8075 2.8575 1.8075 2.8575 9 P 0 ;1
L 1.8075 2.9075 1.8075 2.9075 9 P 0 ;1
L 1.8075 2.9575 1.8075 2.9575 9 P 0 ;1
L 1.8075 3.0075 1.8075 3.0075 9 P 0 ;1
L 1.8075 3.0575 1.8075 3.0575 9 P 0 ;1
L 1.8075 3.1075 1.8075 3.1075 9 P 0 ;1
L 1.8575 0.1575 1.8575 0.1575 9 P 0 ;1
L 1.8575 0.2075 1.8575 0.2075 9 P 0 ;1
L 1.8575 0.2575 1.8575 0.2575 9 P 0 ;1
L 1.8575 0.3075 1.8575 0.3075 9 P 0 ;1
L 1.8575 0.3575 1.8575 0.3575 9 P 0 ;1
L 1.8575 0.4075 1.8575 0.4075 9 P 0 ;1
L 1.8575 0.4575 1.8575 0.4575 9 P 0 ;1
L 1.8575 0.5075 1.8575 0.5075 9 P 0 ;1
L 1.8575 0.5575 1.8575 0.5575 9 P 0 ;1
L 1.8575 0.6075 1.8575 0.6075 9 P 0 ;1
L 1.8575 0.6575 1.8575 0.6575 9 P 0 ;1
L 1.8575 0.7075 1.8575 0.7075 9 P 0 ;1
L 1.8575 0.7575 1.8575 0.7575 9 P 0 ;1
L 1.8575 0.8075 1.8575 0.8075 9 P 0 ;1
L 1.8575 2.2075 1.8575 2.2075 9 P 0 ;1
L 1.8575 2.2575 1.8575 2.2575 9 P 0 ;1
L 1.8575 2.3075 1.8575 2.3075 9 P 0 ;1
L 1.8575 2.3575 1.8575 2.3575 9 P 0 ;1
L 1.8575 2.4075 1.8575 2.4075 9 P 0 ;1
L 1.8575 2.5575 1.8575 2.5575 9 P 0 ;1
L 1.8575 2.6075 1.8575 2.6075 9 P 0 ;1
L 1.8575 2.6575 1.8575 2.6575 9 P 0 ;1
L 1.8575 2.7075 1.8575 2.7075 9 P 0 ;1
L 1.8575 2.7575 1.8575 2.7575 9 P 0 ;1
L 1.8575 2.8075 1.8575 2.8075 9 P 0 ;1
L 1.8575 2.8575 1.8575 2.8575 9 P 0 ;1
L 1.8575 2.9075 1.8575 2.9075 9 P 0 ;1
L 1.8575 2.9575 1.8575 2.9575 9 P 0 ;1
L 1.8575 3.0075 1.8575 3.0075 9 P 0 ;1
L 1.8575 3.0575 1.8575 3.0575 9 P 0 ;1
L 1.8575 3.1075 1.8575 3.1075 9 P 0 ;1
L 1.8575 3.7075 1.8575 3.7075 9 P 0 ;1
L 1.8575 3.8575 1.8575 3.8575 9 P 0 ;1
L 1.8575 3.9075 1.8575 3.9075 9 P 0 ;1
L 1.8575 4.1075 1.8575 4.1075 9 P 0 ;1
L 1.9075 0.1575 1.9075 0.1575 9 P 0 ;1
L 1.9075 0.2075 1.9075 0.2075 9 P 0 ;1
L 1.9075 0.2575 1.9075 0.2575 9 P 0 ;1
L 1.9075 0.3075 1.9075 0.3075 9 P 0 ;1
L 1.9075 0.3575 1.9075 0.3575 9 P 0 ;1
L 1.9075 0.4075 1.9075 0.4075 9 P 0 ;1
L 1.9075 0.4575 1.9075 0.4575 9 P 0 ;1
L 1.9075 0.5075 1.9075 0.5075 9 P 0 ;1
L 1.9075 0.5575 1.9075 0.5575 9 P 0 ;1
L 1.9075 0.6075 1.9075 0.6075 9 P 0 ;1
L 1.9075 0.6575 1.9075 0.6575 9 P 0 ;1
L 1.9075 0.7075 1.9075 0.7075 9 P 0 ;1
L 1.9075 0.7575 1.9075 0.7575 9 P 0 ;1
L 1.9075 2.1075 1.9075 2.1075 9 P 0 ;1
L 1.9075 2.1575 1.9075 2.1575 9 P 0 ;1
L 1.9075 2.2075 1.9075 2.2075 9 P 0 ;1
L 1.9075 2.2575 1.9075 2.2575 9 P 0 ;1
L 1.9075 2.3075 1.9075 2.3075 9 P 0 ;1
L 1.9075 2.3575 1.9075 2.3575 9 P 0 ;1
L 1.9075 2.4075 1.9075 2.4075 9 P 0 ;1
L 1.9075 2.4575 1.9075 2.4575 9 P 0 ;1
L 1.9075 2.5075 1.9075 2.5075 9 P 0 ;1
L 1.9075 2.5575 1.9075 2.5575 9 P 0 ;1
L 1.9075 2.6075 1.9075 2.6075 9 P 0 ;1
L 1.9075 2.6575 1.9075 2.6575 9 P 0 ;1
L 1.9075 2.7075 1.9075 2.7075 9 P 0 ;1
L 1.9075 2.7575 1.9075 2.7575 9 P 0 ;1
L 1.9075 2.8075 1.9075 2.8075 9 P 0 ;1
L 1.9075 2.8575 1.9075 2.8575 9 P 0 ;1
L 1.9075 2.9075 1.9075 2.9075 9 P 0 ;1
L 1.9075 2.9575 1.9075 2.9575 9 P 0 ;1
L 1.9075 3.0075 1.9075 3.0075 9 P 0 ;1
L 1.9075 3.0575 1.9075 3.0575 9 P 0 ;1
L 1.9075 3.1075 1.9075 3.1075 9 P 0 ;1
L 1.9075 3.6575 1.9075 3.6575 9 P 0 ;1
L 1.9075 3.7075 1.9075 3.7075 9 P 0 ;1
L 1.9075 3.7575 1.9075 3.7575 9 P 0 ;1
L 1.9075 3.8075 1.9075 3.8075 9 P 0 ;1
L 1.9075 3.8575 1.9075 3.8575 9 P 0 ;1
L 1.9075 3.9075 1.9075 3.9075 9 P 0 ;1
L 1.9075 3.9575 1.9075 3.9575 9 P 0 ;1
L 1.9075 4.0075 1.9075 4.0075 9 P 0 ;1
L 1.9575 0.1575 1.9575 0.1575 9 P 0 ;1
L 1.9575 0.2075 1.9575 0.2075 9 P 0 ;1
L 1.9575 0.2575 1.9575 0.2575 9 P 0 ;1
L 1.9575 0.3075 1.9575 0.3075 9 P 0 ;1
L 1.9575 0.3575 1.9575 0.3575 9 P 0 ;1
L 1.9575 0.4075 1.9575 0.4075 9 P 0 ;1
L 1.9575 0.4575 1.9575 0.4575 9 P 0 ;1
L 1.9575 0.5075 1.9575 0.5075 9 P 0 ;1
L 1.9575 0.5575 1.9575 0.5575 9 P 0 ;1
L 1.9575 0.6075 1.9575 0.6075 9 P 0 ;1
L 1.9575 0.6575 1.9575 0.6575 9 P 0 ;1
L 1.9575 0.7075 1.9575 0.7075 9 P 0 ;1
L 1.9575 0.7575 1.9575 0.7575 9 P 0 ;1
L 1.9575 1.6575 1.9575 1.6575 9 P 0 ;1
L 1.9575 2.0575 1.9575 2.0575 9 P 0 ;1
L 1.9575 2.1075 1.9575 2.1075 9 P 0 ;1
L 1.9575 2.1575 1.9575 2.1575 9 P 0 ;1
L 1.9575 2.2075 1.9575 2.2075 9 P 0 ;1
L 1.9575 2.2575 1.9575 2.2575 9 P 0 ;1
L 1.9575 2.3075 1.9575 2.3075 9 P 0 ;1
L 1.9575 2.3575 1.9575 2.3575 9 P 0 ;1
L 1.9575 2.4075 1.9575 2.4075 9 P 0 ;1
L 1.9575 2.4575 1.9575 2.4575 9 P 0 ;1
L 1.9575 2.5075 1.9575 2.5075 9 P 0 ;1
L 1.9575 2.5575 1.9575 2.5575 9 P 0 ;1
L 1.9575 2.6075 1.9575 2.6075 9 P 0 ;1
L 1.9575 2.9575 1.9575 2.9575 9 P 0 ;1
L 1.9575 3.0075 1.9575 3.0075 9 P 0 ;1
L 1.9575 3.0575 1.9575 3.0575 9 P 0 ;1
L 1.9575 3.1075 1.9575 3.1075 9 P 0 ;1
L 1.9575 3.6575 1.9575 3.6575 9 P 0 ;1
L 1.9575 3.7075 1.9575 3.7075 9 P 0 ;1
L 1.9575 3.7575 1.9575 3.7575 9 P 0 ;1
L 1.9575 3.8075 1.9575 3.8075 9 P 0 ;1
L 1.9575 3.8575 1.9575 3.8575 9 P 0 ;1
L 1.9575 3.9075 1.9575 3.9075 9 P 0 ;1
L 1.9575 3.9575 1.9575 3.9575 9 P 0 ;1
L 2.0075 0.1575 2.0075 0.1575 9 P 0 ;1
L 2.0075 0.2075 2.0075 0.2075 9 P 0 ;1
L 2.0075 0.2575 2.0075 0.2575 9 P 0 ;1
L 2.0075 0.3075 2.0075 0.3075 9 P 0 ;1
L 2.0075 0.3575 2.0075 0.3575 9 P 0 ;1
L 2.0075 0.4075 2.0075 0.4075 9 P 0 ;1
L 2.0075 0.4575 2.0075 0.4575 9 P 0 ;1
L 2.0075 0.5075 2.0075 0.5075 9 P 0 ;1
L 2.0075 0.5575 2.0075 0.5575 9 P 0 ;1
L 2.0075 0.6075 2.0075 0.6075 9 P 0 ;1
L 2.0075 0.6575 2.0075 0.6575 9 P 0 ;1
L 2.0075 0.7075 2.0075 0.7075 9 P 0 ;1
L 2.0075 0.7575 2.0075 0.7575 9 P 0 ;1
L 2.0075 1.6075 2.0075 1.6075 9 P 0 ;1
L 2.0075 1.6575 2.0075 1.6575 9 P 0 ;1
L 2.0575 0.1575 2.0575 0.1575 9 P 0 ;1
L 2.0575 0.2075 2.0575 0.2075 9 P 0 ;1
L 2.0575 0.2575 2.0575 0.2575 9 P 0 ;1
L 2.0575 0.3075 2.0575 0.3075 9 P 0 ;1
L 2.0575 0.3575 2.0575 0.3575 9 P 0 ;1
L 2.0575 0.4075 2.0575 0.4075 9 P 0 ;1
L 2.0575 0.4575 2.0575 0.4575 9 P 0 ;1
L 2.0575 0.5075 2.0575 0.5075 9 P 0 ;1
L 2.0575 0.5575 2.0575 0.5575 9 P 0 ;1
L 2.0575 0.6075 2.0575 0.6075 9 P 0 ;1
L 2.0575 0.6575 2.0575 0.6575 9 P 0 ;1
L 2.0575 0.7075 2.0575 0.7075 9 P 0 ;1
L 2.0575 1.6075 2.0575 1.6075 9 P 0 ;1
L 2.1075 0.1575 2.1075 0.1575 9 P 0 ;1
L 2.1075 0.2075 2.1075 0.2075 9 P 0 ;1
L 2.1075 0.2575 2.1075 0.2575 9 P 0 ;1
L 2.1075 0.3075 2.1075 0.3075 9 P 0 ;1
L 2.1075 0.3575 2.1075 0.3575 9 P 0 ;1
L 2.1075 0.4075 2.1075 0.4075 9 P 0 ;1
L 2.1075 0.4575 2.1075 0.4575 9 P 0 ;1
L 2.1075 0.5075 2.1075 0.5075 9 P 0 ;1
L 2.1075 0.5575 2.1075 0.5575 9 P 0 ;1
L 2.1075 0.6075 2.1075 0.6075 9 P 0 ;1
L 2.1075 0.6575 2.1075 0.6575 9 P 0 ;1
L 2.1075 0.7075 2.1075 0.7075 9 P 0 ;1
L 2.1575 0.1575 2.1575 0.1575 9 P 0 ;1
L 2.1575 0.2075 2.1575 0.2075 9 P 0 ;1
L 2.1575 0.2575 2.1575 0.2575 9 P 0 ;1
L 2.1575 0.3075 2.1575 0.3075 9 P 0 ;1
L 2.1575 0.3575 2.1575 0.3575 9 P 0 ;1
L 2.1575 0.4075 2.1575 0.4075 9 P 0 ;1
L 2.1575 0.4575 2.1575 0.4575 9 P 0 ;1
L 2.1575 0.5075 2.1575 0.5075 9 P 0 ;1
L 2.1575 0.5575 2.1575 0.5575 9 P 0 ;1
L 2.1575 0.6075 2.1575 0.6075 9 P 0 ;1
L 2.1575 0.6575 2.1575 0.6575 9 P 0 ;1
L 2.1575 0.7075 2.1575 0.7075 9 P 0 ;1
L 2.2075 0.1575 2.2075 0.1575 9 P 0 ;1
L 2.2075 0.2075 2.2075 0.2075 9 P 0 ;1
L 2.2075 0.2575 2.2075 0.2575 9 P 0 ;1
L 2.2075 0.3075 2.2075 0.3075 9 P 0 ;1
L 2.2075 0.3575 2.2075 0.3575 9 P 0 ;1
L 2.2075 0.4075 2.2075 0.4075 9 P 0 ;1
L 2.2075 0.4575 2.2075 0.4575 9 P 0 ;1
L 2.2075 0.5075 2.2075 0.5075 9 P 0 ;1
L 2.2075 0.5575 2.2075 0.5575 9 P 0 ;1
L 2.2075 0.6075 2.2075 0.6075 9 P 0 ;1
L 2.2075 0.6575 2.2075 0.6575 9 P 0 ;1
L 2.2075 0.7075 2.2075 0.7075 9 P 0 ;1
L 2.2075 5.2075 2.2075 5.2075 9 P 0 ;1
L 2.2575 0.1575 2.2575 0.1575 9 P 0 ;1
L 2.2575 0.2075 2.2575 0.2075 9 P 0 ;1
L 2.2575 0.2575 2.2575 0.2575 9 P 0 ;1
L 2.2575 0.3075 2.2575 0.3075 9 P 0 ;1
L 2.2575 0.3575 2.2575 0.3575 9 P 0 ;1
L 2.2575 0.4075 2.2575 0.4075 9 P 0 ;1
L 2.2575 0.4575 2.2575 0.4575 9 P 0 ;1
L 2.2575 0.5075 2.2575 0.5075 9 P 0 ;1
L 2.2575 0.5575 2.2575 0.5575 9 P 0 ;1
L 2.2575 0.6075 2.2575 0.6075 9 P 0 ;1
L 2.2575 0.6575 2.2575 0.6575 9 P 0 ;1
L 2.2575 0.7075 2.2575 0.7075 9 P 0 ;1
L 2.2575 5.1575 2.2575 5.1575 9 P 0 ;1
L 2.2575 5.2075 2.2575 5.2075 9 P 0 ;1
L 2.3075 0.1575 2.3075 0.1575 9 P 0 ;1
L 2.3075 0.2075 2.3075 0.2075 9 P 0 ;1
L 2.3075 0.2575 2.3075 0.2575 9 P 0 ;1
L 2.3075 0.3075 2.3075 0.3075 9 P 0 ;1
L 2.3075 0.3575 2.3075 0.3575 9 P 0 ;1
L 2.3075 0.4075 2.3075 0.4075 9 P 0 ;1
L 2.3075 0.4575 2.3075 0.4575 9 P 0 ;1
L 2.3075 0.5075 2.3075 0.5075 9 P 0 ;1
L 2.3075 0.5575 2.3075 0.5575 9 P 0 ;1
L 2.3075 0.6075 2.3075 0.6075 9 P 0 ;1
L 2.3075 0.6575 2.3075 0.6575 9 P 0 ;1
L 2.3075 0.7075 2.3075 0.7075 9 P 0 ;1
L 2.3575 0.1575 2.3575 0.1575 9 P 0 ;1
L 2.3575 0.2075 2.3575 0.2075 9 P 0 ;1
L 2.3575 0.2575 2.3575 0.2575 9 P 0 ;1
L 2.3575 0.3075 2.3575 0.3075 9 P 0 ;1
L 2.3575 0.3575 2.3575 0.3575 9 P 0 ;1
L 2.3575 0.4075 2.3575 0.4075 9 P 0 ;1
L 2.3575 0.4575 2.3575 0.4575 9 P 0 ;1
L 2.3575 0.5075 2.3575 0.5075 9 P 0 ;1
L 2.3575 0.5575 2.3575 0.5575 9 P 0 ;1
L 2.3575 0.6075 2.3575 0.6075 9 P 0 ;1
L 2.3575 0.6575 2.3575 0.6575 9 P 0 ;1
L 2.3575 0.7075 2.3575 0.7075 9 P 0 ;1
L 2.4075 0.1575 2.4075 0.1575 9 P 0 ;1
L 2.4075 0.2075 2.4075 0.2075 9 P 0 ;1
L 2.4075 0.2575 2.4075 0.2575 9 P 0 ;1
L 2.4075 0.3075 2.4075 0.3075 9 P 0 ;1
L 2.4075 0.3575 2.4075 0.3575 9 P 0 ;1
L 2.4075 0.4075 2.4075 0.4075 9 P 0 ;1
L 2.4075 0.4575 2.4075 0.4575 9 P 0 ;1
L 2.4075 0.5075 2.4075 0.5075 9 P 0 ;1
L 2.4075 0.5575 2.4075 0.5575 9 P 0 ;1
L 2.4075 0.6075 2.4075 0.6075 9 P 0 ;1
L 2.4075 0.6575 2.4075 0.6575 9 P 0 ;1
L 2.4075 0.7075 2.4075 0.7075 9 P 0 ;1
L 2.4575 0.1575 2.4575 0.1575 9 P 0 ;1
L 2.4575 0.2075 2.4575 0.2075 9 P 0 ;1
L 2.4575 0.2575 2.4575 0.2575 9 P 0 ;1
L 2.4575 0.3075 2.4575 0.3075 9 P 0 ;1
L 2.4575 0.3575 2.4575 0.3575 9 P 0 ;1
L 2.4575 0.4075 2.4575 0.4075 9 P 0 ;1
L 2.4575 0.4575 2.4575 0.4575 9 P 0 ;1
L 2.4575 0.5075 2.4575 0.5075 9 P 0 ;1
L 2.4575 0.5575 2.4575 0.5575 9 P 0 ;1
L 2.4575 0.6075 2.4575 0.6075 9 P 0 ;1
L 2.4575 0.6575 2.4575 0.6575 9 P 0 ;1
L 2.4575 0.7075 2.4575 0.7075 9 P 0 ;1
L 2.4575 0.7575 2.4575 0.7575 9 P 0 ;1
L 2.4575 1.4075 2.4575 1.4075 9 P 0 ;1
L 2.4575 1.4575 2.4575 1.4575 9 P 0 ;1
L 2.4575 1.5075 2.4575 1.5075 9 P 0 ;1
L 2.4575 1.5575 2.4575 1.5575 9 P 0 ;1
L 2.4575 1.6075 2.4575 1.6075 9 P 0 ;1
L 2.5075 0.1575 2.5075 0.1575 9 P 0 ;1
L 2.5075 0.2075 2.5075 0.2075 9 P 0 ;1
L 2.5075 0.2575 2.5075 0.2575 9 P 0 ;1
L 2.5075 0.3075 2.5075 0.3075 9 P 0 ;1
L 2.5075 0.3575 2.5075 0.3575 9 P 0 ;1
L 2.5075 0.4075 2.5075 0.4075 9 P 0 ;1
L 2.5075 0.4575 2.5075 0.4575 9 P 0 ;1
L 2.5075 0.5075 2.5075 0.5075 9 P 0 ;1
L 2.5075 0.5575 2.5075 0.5575 9 P 0 ;1
L 2.5075 0.6075 2.5075 0.6075 9 P 0 ;1
L 2.5075 0.6575 2.5075 0.6575 9 P 0 ;1
L 2.5075 0.7075 2.5075 0.7075 9 P 0 ;1
L 2.5075 0.7575 2.5075 0.7575 9 P 0 ;1
L 2.5075 1.4075 2.5075 1.4075 9 P 0 ;1
L 2.5075 1.4575 2.5075 1.4575 9 P 0 ;1
L 2.5075 1.5075 2.5075 1.5075 9 P 0 ;1
L 2.5075 1.5575 2.5075 1.5575 9 P 0 ;1
L 2.5075 1.6075 2.5075 1.6075 9 P 0 ;1
L 2.5075 4.8575 2.5075 4.8575 9 P 0 ;1
L 2.5075 5.1575 2.5075 5.1575 9 P 0 ;1
L 2.5075 5.2075 2.5075 5.2075 9 P 0 ;1
L 2.5575 0.1575 2.5575 0.1575 9 P 0 ;1
L 2.5575 0.2075 2.5575 0.2075 9 P 0 ;1
L 2.5575 0.2575 2.5575 0.2575 9 P 0 ;1
L 2.5575 0.3075 2.5575 0.3075 9 P 0 ;1
L 2.5575 0.3575 2.5575 0.3575 9 P 0 ;1
L 2.5575 0.4075 2.5575 0.4075 9 P 0 ;1
L 2.5575 0.4575 2.5575 0.4575 9 P 0 ;1
L 2.5575 0.5075 2.5575 0.5075 9 P 0 ;1
L 2.5575 0.5575 2.5575 0.5575 9 P 0 ;1
L 2.5575 0.6075 2.5575 0.6075 9 P 0 ;1
L 2.5575 0.6575 2.5575 0.6575 9 P 0 ;1
L 2.5575 0.7075 2.5575 0.7075 9 P 0 ;1
L 2.5575 0.7575 2.5575 0.7575 9 P 0 ;1
L 2.5575 1.4575 2.5575 1.4575 9 P 0 ;1
L 2.5575 1.5075 2.5575 1.5075 9 P 0 ;1
L 2.5575 1.5575 2.5575 1.5575 9 P 0 ;1
L 2.5575 1.6075 2.5575 1.6075 9 P 0 ;1
L 2.5575 4.8075 2.5575 4.8075 9 P 0 ;1
L 2.5575 4.8575 2.5575 4.8575 9 P 0 ;1
L 2.5575 4.9075 2.5575 4.9075 9 P 0 ;1
L 2.5575 4.9575 2.5575 4.9575 9 P 0 ;1
L 2.5575 5.0075 2.5575 5.0075 9 P 0 ;1
L 2.5575 5.0575 2.5575 5.0575 9 P 0 ;1
L 2.5575 5.1075 2.5575 5.1075 9 P 0 ;1
L 2.5575 5.1575 2.5575 5.1575 9 P 0 ;1
L 2.5575 5.2075 2.5575 5.2075 9 P 0 ;1
L 2.6075 0.1575 2.6075 0.1575 9 P 0 ;1
L 2.6075 0.2075 2.6075 0.2075 9 P 0 ;1
L 2.6075 0.2575 2.6075 0.2575 9 P 0 ;1
L 2.6075 0.3075 2.6075 0.3075 9 P 0 ;1
L 2.6075 0.3575 2.6075 0.3575 9 P 0 ;1
L 2.6075 0.4075 2.6075 0.4075 9 P 0 ;1
L 2.6075 0.4575 2.6075 0.4575 9 P 0 ;1
L 2.6075 0.5075 2.6075 0.5075 9 P 0 ;1
L 2.6075 0.5575 2.6075 0.5575 9 P 0 ;1
L 2.6075 0.6075 2.6075 0.6075 9 P 0 ;1
L 2.6075 0.6575 2.6075 0.6575 9 P 0 ;1
L 2.6075 0.7075 2.6075 0.7075 9 P 0 ;1
L 2.6075 0.7575 2.6075 0.7575 9 P 0 ;1
L 2.6075 1.4575 2.6075 1.4575 9 P 0 ;1
L 2.6075 1.5075 2.6075 1.5075 9 P 0 ;1
L 2.6075 1.5575 2.6075 1.5575 9 P 0 ;1
L 2.6075 1.6075 2.6075 1.6075 9 P 0 ;1
L 2.6075 1.9075 2.6075 1.9075 9 P 0 ;1
L 2.6075 1.9575 2.6075 1.9575 9 P 0 ;1
L 2.6075 2.0075 2.6075 2.0075 9 P 0 ;1
L 2.6075 2.0575 2.6075 2.0575 9 P 0 ;1
L 2.6075 2.1075 2.6075 2.1075 9 P 0 ;1
L 2.6075 2.1575 2.6075 2.1575 9 P 0 ;1
L 2.6075 2.2075 2.6075 2.2075 9 P 0 ;1
L 2.6075 2.2575 2.6075 2.2575 9 P 0 ;1
L 2.6075 2.3075 2.6075 2.3075 9 P 0 ;1
L 2.6075 2.3575 2.6075 2.3575 9 P 0 ;1
L 2.6075 2.4075 2.6075 2.4075 9 P 0 ;1
L 2.6075 2.4575 2.6075 2.4575 9 P 0 ;1
L 2.6075 2.5075 2.6075 2.5075 9 P 0 ;1
L 2.6075 2.5575 2.6075 2.5575 9 P 0 ;1
L 2.6075 2.6075 2.6075 2.6075 9 P 0 ;1
L 2.6075 2.6575 2.6075 2.6575 9 P 0 ;1
L 2.6075 2.7075 2.6075 2.7075 9 P 0 ;1
L 2.6075 2.7575 2.6075 2.7575 9 P 0 ;1
L 2.6075 2.8075 2.6075 2.8075 9 P 0 ;1
L 2.6075 2.8575 2.6075 2.8575 9 P 0 ;1
L 2.6075 2.9075 2.6075 2.9075 9 P 0 ;1
L 2.6075 2.9575 2.6075 2.9575 9 P 0 ;1
L 2.6075 3.0075 2.6075 3.0075 9 P 0 ;1
L 2.6075 3.0575 2.6075 3.0575 9 P 0 ;1
L 2.6075 3.1075 2.6075 3.1075 9 P 0 ;1
L 2.6075 3.1575 2.6075 3.1575 9 P 0 ;1
L 2.6075 4.8575 2.6075 4.8575 9 P 0 ;1
L 2.6075 4.9075 2.6075 4.9075 9 P 0 ;1
L 2.6075 4.9575 2.6075 4.9575 9 P 0 ;1
L 2.6075 5.0075 2.6075 5.0075 9 P 0 ;1
L 2.6075 5.0575 2.6075 5.0575 9 P 0 ;1
L 2.6075 5.1075 2.6075 5.1075 9 P 0 ;1
L 2.6075 5.1575 2.6075 5.1575 9 P 0 ;1
L 2.6075 5.2075 2.6075 5.2075 9 P 0 ;1
L 2.6575 0.1575 2.6575 0.1575 9 P 0 ;1
L 2.6575 0.2075 2.6575 0.2075 9 P 0 ;1
L 2.6575 0.2575 2.6575 0.2575 9 P 0 ;1
L 2.6575 0.3075 2.6575 0.3075 9 P 0 ;1
L 2.6575 0.3575 2.6575 0.3575 9 P 0 ;1
L 2.6575 0.4075 2.6575 0.4075 9 P 0 ;1
L 2.6575 0.4575 2.6575 0.4575 9 P 0 ;1
L 2.6575 0.5075 2.6575 0.5075 9 P 0 ;1
L 2.6575 0.5575 2.6575 0.5575 9 P 0 ;1
L 2.6575 0.6075 2.6575 0.6075 9 P 0 ;1
L 2.6575 0.6575 2.6575 0.6575 9 P 0 ;1
L 2.6575 0.7075 2.6575 0.7075 9 P 0 ;1
L 2.6575 0.7575 2.6575 0.7575 9 P 0 ;1
L 2.6575 1.4575 2.6575 1.4575 9 P 0 ;1
L 2.6575 1.5075 2.6575 1.5075 9 P 0 ;1
L 2.6575 1.5575 2.6575 1.5575 9 P 0 ;1
L 2.6575 1.6075 2.6575 1.6075 9 P 0 ;1
L 2.6575 1.6575 2.6575 1.6575 9 P 0 ;1
L 2.6575 1.9575 2.6575 1.9575 9 P 0 ;1
L 2.6575 2.0075 2.6575 2.0075 9 P 0 ;1
L 2.6575 2.0575 2.6575 2.0575 9 P 0 ;1
L 2.6575 2.1075 2.6575 2.1075 9 P 0 ;1
L 2.6575 2.1575 2.6575 2.1575 9 P 0 ;1
L 2.6575 2.2075 2.6575 2.2075 9 P 0 ;1
L 2.6575 2.2575 2.6575 2.2575 9 P 0 ;1
L 2.6575 2.3075 2.6575 2.3075 9 P 0 ;1
L 2.6575 2.3575 2.6575 2.3575 9 P 0 ;1
L 2.6575 2.4075 2.6575 2.4075 9 P 0 ;1
L 2.6575 2.4575 2.6575 2.4575 9 P 0 ;1
L 2.6575 2.5075 2.6575 2.5075 9 P 0 ;1
L 2.6575 2.5575 2.6575 2.5575 9 P 0 ;1
L 2.6575 2.6075 2.6575 2.6075 9 P 0 ;1
L 2.6575 2.6575 2.6575 2.6575 9 P 0 ;1
L 2.6575 2.7075 2.6575 2.7075 9 P 0 ;1
L 2.6575 2.7575 2.6575 2.7575 9 P 0 ;1
L 2.6575 2.8075 2.6575 2.8075 9 P 0 ;1
L 2.6575 2.8575 2.6575 2.8575 9 P 0 ;1
L 2.6575 2.9075 2.6575 2.9075 9 P 0 ;1
L 2.6575 2.9575 2.6575 2.9575 9 P 0 ;1
L 2.6575 3.0075 2.6575 3.0075 9 P 0 ;1
L 2.6575 3.0575 2.6575 3.0575 9 P 0 ;1
L 2.6575 3.1075 2.6575 3.1075 9 P 0 ;1
L 2.6575 3.1575 2.6575 3.1575 9 P 0 ;1
L 2.6575 4.5075 2.6575 4.5075 9 P 0 ;1
L 2.6575 4.5575 2.6575 4.5575 9 P 0 ;1
L 2.6575 4.6075 2.6575 4.6075 9 P 0 ;1
L 2.6575 4.6575 2.6575 4.6575 9 P 0 ;1
L 2.6575 5.2075 2.6575 5.2075 9 P 0 ;1
L 2.7075 0.1575 2.7075 0.1575 9 P 0 ;1
L 2.7075 0.2075 2.7075 0.2075 9 P 0 ;1
L 2.7075 0.2575 2.7075 0.2575 9 P 0 ;1
L 2.7075 0.3075 2.7075 0.3075 9 P 0 ;1
L 2.7075 0.3575 2.7075 0.3575 9 P 0 ;1
L 2.7075 0.4075 2.7075 0.4075 9 P 0 ;1
L 2.7075 0.4575 2.7075 0.4575 9 P 0 ;1
L 2.7075 0.5075 2.7075 0.5075 9 P 0 ;1
L 2.7075 0.5575 2.7075 0.5575 9 P 0 ;1
L 2.7075 0.6075 2.7075 0.6075 9 P 0 ;1
L 2.7075 0.6575 2.7075 0.6575 9 P 0 ;1
L 2.7075 0.7075 2.7075 0.7075 9 P 0 ;1
L 2.7075 0.7575 2.7075 0.7575 9 P 0 ;1
L 2.7075 0.8075 2.7075 0.8075 9 P 0 ;1
L 2.7075 1.4575 2.7075 1.4575 9 P 0 ;1
L 2.7075 1.5075 2.7075 1.5075 9 P 0 ;1
L 2.7075 1.5575 2.7075 1.5575 9 P 0 ;1
L 2.7075 1.6075 2.7075 1.6075 9 P 0 ;1
L 2.7075 1.6575 2.7075 1.6575 9 P 0 ;1
L 2.7075 1.9575 2.7075 1.9575 9 P 0 ;1
L 2.7075 2.0075 2.7075 2.0075 9 P 0 ;1
L 2.7075 2.0575 2.7075 2.0575 9 P 0 ;1
L 2.7075 2.1075 2.7075 2.1075 9 P 0 ;1
L 2.7075 2.1575 2.7075 2.1575 9 P 0 ;1
L 2.7075 2.2075 2.7075 2.2075 9 P 0 ;1
L 2.7075 2.2575 2.7075 2.2575 9 P 0 ;1
L 2.7075 2.3075 2.7075 2.3075 9 P 0 ;1
L 2.7075 2.3575 2.7075 2.3575 9 P 0 ;1
L 2.7075 2.4075 2.7075 2.4075 9 P 0 ;1
L 2.7075 2.4575 2.7075 2.4575 9 P 0 ;1
L 2.7075 2.5075 2.7075 2.5075 9 P 0 ;1
L 2.7075 2.5575 2.7075 2.5575 9 P 0 ;1
L 2.7075 2.6075 2.7075 2.6075 9 P 0 ;1
L 2.7075 2.6575 2.7075 2.6575 9 P 0 ;1
L 2.7075 2.7075 2.7075 2.7075 9 P 0 ;1
L 2.7075 2.7575 2.7075 2.7575 9 P 0 ;1
L 2.7075 2.8075 2.7075 2.8075 9 P 0 ;1
L 2.7075 2.8575 2.7075 2.8575 9 P 0 ;1
L 2.7075 2.9075 2.7075 2.9075 9 P 0 ;1
L 2.7075 2.9575 2.7075 2.9575 9 P 0 ;1
L 2.7075 3.0075 2.7075 3.0075 9 P 0 ;1
L 2.7075 3.0575 2.7075 3.0575 9 P 0 ;1
L 2.7075 3.1075 2.7075 3.1075 9 P 0 ;1
L 2.7075 3.1575 2.7075 3.1575 9 P 0 ;1
L 2.7075 3.2075 2.7075 3.2075 9 P 0 ;1
L 2.7075 4.4575 2.7075 4.4575 9 P 0 ;1
L 2.7075 4.5075 2.7075 4.5075 9 P 0 ;1
L 2.7075 4.5575 2.7075 4.5575 9 P 0 ;1
L 2.7575 0.1575 2.7575 0.1575 9 P 0 ;1
L 2.7575 0.2075 2.7575 0.2075 9 P 0 ;1
L 2.7575 0.2575 2.7575 0.2575 9 P 0 ;1
L 2.7575 0.3075 2.7575 0.3075 9 P 0 ;1
L 2.7575 0.3575 2.7575 0.3575 9 P 0 ;1
L 2.7575 0.4075 2.7575 0.4075 9 P 0 ;1
L 2.7575 0.4575 2.7575 0.4575 9 P 0 ;1
L 2.7575 0.5075 2.7575 0.5075 9 P 0 ;1
L 2.7575 0.5575 2.7575 0.5575 9 P 0 ;1
L 2.7575 0.6075 2.7575 0.6075 9 P 0 ;1
L 2.7575 0.6575 2.7575 0.6575 9 P 0 ;1
L 2.7575 0.7075 2.7575 0.7075 9 P 0 ;1
L 2.7575 0.7575 2.7575 0.7575 9 P 0 ;1
L 2.7575 0.8075 2.7575 0.8075 9 P 0 ;1
L 2.7575 1.4575 2.7575 1.4575 9 P 0 ;1
L 2.7575 1.5075 2.7575 1.5075 9 P 0 ;1
L 2.7575 1.5575 2.7575 1.5575 9 P 0 ;1
L 2.7575 1.6075 2.7575 1.6075 9 P 0 ;1
L 2.7575 1.6575 2.7575 1.6575 9 P 0 ;1
L 2.7575 1.9575 2.7575 1.9575 9 P 0 ;1
L 2.7575 2.0075 2.7575 2.0075 9 P 0 ;1
L 2.7575 2.0575 2.7575 2.0575 9 P 0 ;1
L 2.7575 2.1075 2.7575 2.1075 9 P 0 ;1
L 2.7575 2.1575 2.7575 2.1575 9 P 0 ;1
L 2.7575 2.2075 2.7575 2.2075 9 P 0 ;1
L 2.7575 2.2575 2.7575 2.2575 9 P 0 ;1
L 2.7575 2.3075 2.7575 2.3075 9 P 0 ;1
L 2.7575 2.3575 2.7575 2.3575 9 P 0 ;1
L 2.7575 2.4075 2.7575 2.4075 9 P 0 ;1
L 2.7575 2.4575 2.7575 2.4575 9 P 0 ;1
L 2.7575 2.5075 2.7575 2.5075 9 P 0 ;1
L 2.7575 2.5575 2.7575 2.5575 9 P 0 ;1
L 2.7575 2.6075 2.7575 2.6075 9 P 0 ;1
L 2.7575 2.6575 2.7575 2.6575 9 P 0 ;1
L 2.7575 2.7075 2.7575 2.7075 9 P 0 ;1
L 2.7575 2.7575 2.7575 2.7575 9 P 0 ;1
L 2.7575 2.8075 2.7575 2.8075 9 P 0 ;1
L 2.7575 2.8575 2.7575 2.8575 9 P 0 ;1
L 2.7575 2.9075 2.7575 2.9075 9 P 0 ;1
L 2.7575 2.9575 2.7575 2.9575 9 P 0 ;1
L 2.7575 3.0075 2.7575 3.0075 9 P 0 ;1
L 2.7575 3.0575 2.7575 3.0575 9 P 0 ;1
L 2.7575 3.1075 2.7575 3.1075 9 P 0 ;1
L 2.7575 3.1575 2.7575 3.1575 9 P 0 ;1
L 2.7575 3.2075 2.7575 3.2075 9 P 0 ;1
L 2.7575 3.2575 2.7575 3.2575 9 P 0 ;1
L 2.7575 4.3575 2.7575 4.3575 9 P 0 ;1
L 2.7575 4.4075 2.7575 4.4075 9 P 0 ;1
L 2.7575 4.4575 2.7575 4.4575 9 P 0 ;1
L 2.7575 4.5075 2.7575 4.5075 9 P 0 ;1
L 2.7575 4.5575 2.7575 4.5575 9 P 0 ;1
L 2.8075 0.1575 2.8075 0.1575 9 P 0 ;1
L 2.8075 0.2075 2.8075 0.2075 9 P 0 ;1
L 2.8075 0.2575 2.8075 0.2575 9 P 0 ;1
L 2.8075 0.3075 2.8075 0.3075 9 P 0 ;1
L 2.8075 0.3575 2.8075 0.3575 9 P 0 ;1
L 2.8075 0.4075 2.8075 0.4075 9 P 0 ;1
L 2.8075 0.4575 2.8075 0.4575 9 P 0 ;1
L 2.8075 0.5075 2.8075 0.5075 9 P 0 ;1
L 2.8075 0.5575 2.8075 0.5575 9 P 0 ;1
L 2.8075 0.6075 2.8075 0.6075 9 P 0 ;1
L 2.8075 0.6575 2.8075 0.6575 9 P 0 ;1
L 2.8075 0.7075 2.8075 0.7075 9 P 0 ;1
L 2.8075 0.7575 2.8075 0.7575 9 P 0 ;1
L 2.8075 0.8075 2.8075 0.8075 9 P 0 ;1
L 2.8075 1.5075 2.8075 1.5075 9 P 0 ;1
L 2.8075 1.5575 2.8075 1.5575 9 P 0 ;1
L 2.8075 1.6075 2.8075 1.6075 9 P 0 ;1
L 2.8075 1.6575 2.8075 1.6575 9 P 0 ;1
L 2.8075 1.9575 2.8075 1.9575 9 P 0 ;1
L 2.8075 2.0075 2.8075 2.0075 9 P 0 ;1
L 2.8075 2.0575 2.8075 2.0575 9 P 0 ;1
L 2.8075 2.1075 2.8075 2.1075 9 P 0 ;1
L 2.8075 2.1575 2.8075 2.1575 9 P 0 ;1
L 2.8075 2.2075 2.8075 2.2075 9 P 0 ;1
L 2.8075 2.2575 2.8075 2.2575 9 P 0 ;1
L 2.8075 2.3075 2.8075 2.3075 9 P 0 ;1
L 2.8075 2.3575 2.8075 2.3575 9 P 0 ;1
L 2.8075 2.4075 2.8075 2.4075 9 P 0 ;1
L 2.8075 2.4575 2.8075 2.4575 9 P 0 ;1
L 2.8075 2.5075 2.8075 2.5075 9 P 0 ;1
L 2.8075 2.5575 2.8075 2.5575 9 P 0 ;1
L 2.8075 2.6075 2.8075 2.6075 9 P 0 ;1
L 2.8075 2.6575 2.8075 2.6575 9 P 0 ;1
L 2.8075 2.7075 2.8075 2.7075 9 P 0 ;1
L 2.8075 2.7575 2.8075 2.7575 9 P 0 ;1
L 2.8075 2.8075 2.8075 2.8075 9 P 0 ;1
L 2.8075 2.8575 2.8075 2.8575 9 P 0 ;1
L 2.8075 2.9075 2.8075 2.9075 9 P 0 ;1
L 2.8075 2.9575 2.8075 2.9575 9 P 0 ;1
L 2.8075 3.0075 2.8075 3.0075 9 P 0 ;1
L 2.8075 3.0575 2.8075 3.0575 9 P 0 ;1
L 2.8075 3.1075 2.8075 3.1075 9 P 0 ;1
L 2.8075 3.1575 2.8075 3.1575 9 P 0 ;1
L 2.8075 3.2075 2.8075 3.2075 9 P 0 ;1
L 2.8075 3.2575 2.8075 3.2575 9 P 0 ;1
L 2.8075 3.3075 2.8075 3.3075 9 P 0 ;1
L 2.8075 3.3575 2.8075 3.3575 9 P 0 ;1
L 2.8075 3.4075 2.8075 3.4075 9 P 0 ;1
L 2.8075 4.0075 2.8075 4.0075 9 P 0 ;1
L 2.8075 4.0575 2.8075 4.0575 9 P 0 ;1
L 2.8075 4.1075 2.8075 4.1075 9 P 0 ;1
L 2.8075 4.1575 2.8075 4.1575 9 P 0 ;1
L 2.8075 4.2075 2.8075 4.2075 9 P 0 ;1
L 2.8075 4.2575 2.8075 4.2575 9 P 0 ;1
L 2.8075 4.3075 2.8075 4.3075 9 P 0 ;1
L 2.8075 4.3575 2.8075 4.3575 9 P 0 ;1
L 2.8075 4.4075 2.8075 4.4075 9 P 0 ;1
L 2.8075 4.4575 2.8075 4.4575 9 P 0 ;1
L 2.8075 4.5075 2.8075 4.5075 9 P 0 ;1
L 2.8075 4.5575 2.8075 4.5575 9 P 0 ;1
L 2.8575 0.1575 2.8575 0.1575 9 P 0 ;1
L 2.8575 0.2075 2.8575 0.2075 9 P 0 ;1
L 2.8575 0.2575 2.8575 0.2575 9 P 0 ;1
L 2.8575 0.3075 2.8575 0.3075 9 P 0 ;1
L 2.8575 0.3575 2.8575 0.3575 9 P 0 ;1
L 2.8575 0.4075 2.8575 0.4075 9 P 0 ;1
L 2.8575 0.4575 2.8575 0.4575 9 P 0 ;1
L 2.8575 0.5075 2.8575 0.5075 9 P 0 ;1
L 2.8575 0.5575 2.8575 0.5575 9 P 0 ;1
L 2.8575 0.6075 2.8575 0.6075 9 P 0 ;1
L 2.8575 0.6575 2.8575 0.6575 9 P 0 ;1
L 2.8575 0.7075 2.8575 0.7075 9 P 0 ;1
L 2.8575 0.7575 2.8575 0.7575 9 P 0 ;1
L 2.8575 0.8075 2.8575 0.8075 9 P 0 ;1
L 2.8575 1.5075 2.8575 1.5075 9 P 0 ;1
L 2.8575 1.5575 2.8575 1.5575 9 P 0 ;1
L 2.8575 1.6075 2.8575 1.6075 9 P 0 ;1
L 2.8575 1.6575 2.8575 1.6575 9 P 0 ;1
L 2.8575 1.9575 2.8575 1.9575 9 P 0 ;1
L 2.8575 2.0075 2.8575 2.0075 9 P 0 ;1
L 2.8575 2.0575 2.8575 2.0575 9 P 0 ;1
L 2.8575 2.1075 2.8575 2.1075 9 P 0 ;1
L 2.8575 2.1575 2.8575 2.1575 9 P 0 ;1
L 2.8575 2.2075 2.8575 2.2075 9 P 0 ;1
L 2.8575 2.2575 2.8575 2.2575 9 P 0 ;1
L 2.8575 2.3075 2.8575 2.3075 9 P 0 ;1
L 2.8575 2.3575 2.8575 2.3575 9 P 0 ;1
L 2.8575 2.4075 2.8575 2.4075 9 P 0 ;1
L 2.8575 2.4575 2.8575 2.4575 9 P 0 ;1
L 2.8575 2.5075 2.8575 2.5075 9 P 0 ;1
L 2.8575 2.5575 2.8575 2.5575 9 P 0 ;1
L 2.8575 2.6075 2.8575 2.6075 9 P 0 ;1
L 2.8575 2.6575 2.8575 2.6575 9 P 0 ;1
L 2.8575 2.7075 2.8575 2.7075 9 P 0 ;1
L 2.8575 2.7575 2.8575 2.7575 9 P 0 ;1
L 2.8575 2.8075 2.8575 2.8075 9 P 0 ;1
L 2.8575 2.8575 2.8575 2.8575 9 P 0 ;1
L 2.8575 2.9075 2.8575 2.9075 9 P 0 ;1
L 2.8575 2.9575 2.8575 2.9575 9 P 0 ;1
L 2.8575 3.0075 2.8575 3.0075 9 P 0 ;1
L 2.8575 3.0575 2.8575 3.0575 9 P 0 ;1
L 2.8575 3.1075 2.8575 3.1075 9 P 0 ;1
L 2.8575 3.1575 2.8575 3.1575 9 P 0 ;1
L 2.8575 3.2075 2.8575 3.2075 9 P 0 ;1
L 2.8575 3.2575 2.8575 3.2575 9 P 0 ;1
L 2.8575 3.3075 2.8575 3.3075 9 P 0 ;1
L 2.8575 3.3575 2.8575 3.3575 9 P 0 ;1
L 2.8575 3.4075 2.8575 3.4075 9 P 0 ;1
L 2.8575 3.4575 2.8575 3.4575 9 P 0 ;1
L 2.8575 3.5075 2.8575 3.5075 9 P 0 ;1
L 2.8575 3.5575 2.8575 3.5575 9 P 0 ;1
L 2.8575 3.6075 2.8575 3.6075 9 P 0 ;1
L 2.8575 3.6575 2.8575 3.6575 9 P 0 ;1
L 2.8575 3.7075 2.8575 3.7075 9 P 0 ;1
L 2.8575 3.7575 2.8575 3.7575 9 P 0 ;1
L 2.8575 3.8075 2.8575 3.8075 9 P 0 ;1
L 2.8575 3.8575 2.8575 3.8575 9 P 0 ;1
L 2.8575 3.9075 2.8575 3.9075 9 P 0 ;1
L 2.8575 3.9575 2.8575 3.9575 9 P 0 ;1
L 2.8575 4.0075 2.8575 4.0075 9 P 0 ;1
L 2.8575 4.0575 2.8575 4.0575 9 P 0 ;1
L 2.8575 4.1075 2.8575 4.1075 9 P 0 ;1
L 2.8575 4.1575 2.8575 4.1575 9 P 0 ;1
L 2.8575 4.2075 2.8575 4.2075 9 P 0 ;1
L 2.8575 4.2575 2.8575 4.2575 9 P 0 ;1
L 2.8575 4.3075 2.8575 4.3075 9 P 0 ;1
L 2.8575 4.3575 2.8575 4.3575 9 P 0 ;1
L 2.8575 4.4075 2.8575 4.4075 9 P 0 ;1
L 2.8575 4.4575 2.8575 4.4575 9 P 0 ;1
L 2.8575 4.5075 2.8575 4.5075 9 P 0 ;1
L 2.8575 4.5575 2.8575 4.5575 9 P 0 ;1
L 2.9075 0.1575 2.9075 0.1575 9 P 0 ;1
L 2.9075 0.2075 2.9075 0.2075 9 P 0 ;1
L 2.9075 0.2575 2.9075 0.2575 9 P 0 ;1
L 2.9075 0.3075 2.9075 0.3075 9 P 0 ;1
L 2.9075 0.3575 2.9075 0.3575 9 P 0 ;1
L 2.9075 0.4075 2.9075 0.4075 9 P 0 ;1
L 2.9075 0.4575 2.9075 0.4575 9 P 0 ;1
L 2.9075 0.5075 2.9075 0.5075 9 P 0 ;1
L 2.9075 0.5575 2.9075 0.5575 9 P 0 ;1
L 2.9075 0.6075 2.9075 0.6075 9 P 0 ;1
L 2.9075 0.6575 2.9075 0.6575 9 P 0 ;1
L 2.9075 0.7075 2.9075 0.7075 9 P 0 ;1
L 2.9075 0.7575 2.9075 0.7575 9 P 0 ;1
L 2.9075 0.8075 2.9075 0.8075 9 P 0 ;1
L 2.9075 1.5075 2.9075 1.5075 9 P 0 ;1
L 2.9075 1.5575 2.9075 1.5575 9 P 0 ;1
L 2.9075 1.6075 2.9075 1.6075 9 P 0 ;1
L 2.9075 1.6575 2.9075 1.6575 9 P 0 ;1
L 2.9075 2.0075 2.9075 2.0075 9 P 0 ;1
L 2.9075 2.0575 2.9075 2.0575 9 P 0 ;1
L 2.9075 2.1075 2.9075 2.1075 9 P 0 ;1
L 2.9075 2.1575 2.9075 2.1575 9 P 0 ;1
L 2.9075 2.2075 2.9075 2.2075 9 P 0 ;1
L 2.9075 2.2575 2.9075 2.2575 9 P 0 ;1
L 2.9075 2.3075 2.9075 2.3075 9 P 0 ;1
L 2.9075 2.3575 2.9075 2.3575 9 P 0 ;1
L 2.9075 2.4075 2.9075 2.4075 9 P 0 ;1
L 2.9075 2.4575 2.9075 2.4575 9 P 0 ;1
L 2.9075 2.5075 2.9075 2.5075 9 P 0 ;1
L 2.9075 2.5575 2.9075 2.5575 9 P 0 ;1
L 2.9075 2.6075 2.9075 2.6075 9 P 0 ;1
L 2.9075 2.6575 2.9075 2.6575 9 P 0 ;1
L 2.9075 2.7075 2.9075 2.7075 9 P 0 ;1
L 2.9075 3.0075 2.9075 3.0075 9 P 0 ;1
L 2.9075 3.0575 2.9075 3.0575 9 P 0 ;1
L 2.9075 3.1075 2.9075 3.1075 9 P 0 ;1
L 2.9075 3.1575 2.9075 3.1575 9 P 0 ;1
L 2.9075 3.2075 2.9075 3.2075 9 P 0 ;1
L 2.9075 3.2575 2.9075 3.2575 9 P 0 ;1
L 2.9075 3.3075 2.9075 3.3075 9 P 0 ;1
L 2.9075 3.3575 2.9075 3.3575 9 P 0 ;1
L 2.9075 3.4075 2.9075 3.4075 9 P 0 ;1
L 2.9075 3.4575 2.9075 3.4575 9 P 0 ;1
L 2.9075 3.5075 2.9075 3.5075 9 P 0 ;1
L 2.9075 3.5575 2.9075 3.5575 9 P 0 ;1
L 2.9075 3.6075 2.9075 3.6075 9 P 0 ;1
L 2.9075 3.6575 2.9075 3.6575 9 P 0 ;1
L 2.9075 3.7075 2.9075 3.7075 9 P 0 ;1
L 2.9075 3.7575 2.9075 3.7575 9 P 0 ;1
L 2.9075 3.8075 2.9075 3.8075 9 P 0 ;1
L 2.9075 3.8575 2.9075 3.8575 9 P 0 ;1
L 2.9075 3.9075 2.9075 3.9075 9 P 0 ;1
L 2.9075 3.9575 2.9075 3.9575 9 P 0 ;1
L 2.9075 4.0075 2.9075 4.0075 9 P 0 ;1
L 2.9075 4.0575 2.9075 4.0575 9 P 0 ;1
L 2.9075 4.1075 2.9075 4.1075 9 P 0 ;1
L 2.9075 4.1575 2.9075 4.1575 9 P 0 ;1
L 2.9075 4.2075 2.9075 4.2075 9 P 0 ;1
L 2.9075 4.2575 2.9075 4.2575 9 P 0 ;1
L 2.9075 4.3075 2.9075 4.3075 9 P 0 ;1
L 2.9075 4.3575 2.9075 4.3575 9 P 0 ;1
L 2.9075 4.4075 2.9075 4.4075 9 P 0 ;1
L 2.9075 4.4575 2.9075 4.4575 9 P 0 ;1
L 2.9075 4.5075 2.9075 4.5075 9 P 0 ;1
L 2.9075 4.5575 2.9075 4.5575 9 P 0 ;1
L 2.9575 0.1575 2.9575 0.1575 9 P 0 ;1
L 2.9575 0.2075 2.9575 0.2075 9 P 0 ;1
L 2.9575 0.2575 2.9575 0.2575 9 P 0 ;1
L 2.9575 0.3075 2.9575 0.3075 9 P 0 ;1
L 2.9575 0.3575 2.9575 0.3575 9 P 0 ;1
L 2.9575 0.4075 2.9575 0.4075 9 P 0 ;1
L 2.9575 0.4575 2.9575 0.4575 9 P 0 ;1
L 2.9575 0.5075 2.9575 0.5075 9 P 0 ;1
L 2.9575 0.5575 2.9575 0.5575 9 P 0 ;1
L 2.9575 0.6075 2.9575 0.6075 9 P 0 ;1
L 2.9575 0.6575 2.9575 0.6575 9 P 0 ;1
L 2.9575 0.7075 2.9575 0.7075 9 P 0 ;1
L 2.9575 0.7575 2.9575 0.7575 9 P 0 ;1
L 2.9575 0.8075 2.9575 0.8075 9 P 0 ;1
L 2.9575 1.5075 2.9575 1.5075 9 P 0 ;1
L 2.9575 1.5575 2.9575 1.5575 9 P 0 ;1
L 2.9575 1.6075 2.9575 1.6075 9 P 0 ;1
L 2.9575 1.6575 2.9575 1.6575 9 P 0 ;1
L 2.9575 1.7075 2.9575 1.7075 9 P 0 ;1
L 2.9575 2.0075 2.9575 2.0075 9 P 0 ;1
L 2.9575 2.0575 2.9575 2.0575 9 P 0 ;1
L 2.9575 2.1075 2.9575 2.1075 9 P 0 ;1
L 2.9575 2.1575 2.9575 2.1575 9 P 0 ;1
L 2.9575 2.2075 2.9575 2.2075 9 P 0 ;1
L 2.9575 2.2575 2.9575 2.2575 9 P 0 ;1
L 2.9575 2.3075 2.9575 2.3075 9 P 0 ;1
L 2.9575 2.3575 2.9575 2.3575 9 P 0 ;1
L 2.9575 2.4075 2.9575 2.4075 9 P 0 ;1
L 2.9575 2.4575 2.9575 2.4575 9 P 0 ;1
L 2.9575 2.5075 2.9575 2.5075 9 P 0 ;1
L 2.9575 2.5575 2.9575 2.5575 9 P 0 ;1
L 2.9575 2.6075 2.9575 2.6075 9 P 0 ;1
L 2.9575 2.6575 2.9575 2.6575 9 P 0 ;1
L 2.9575 2.7075 2.9575 2.7075 9 P 0 ;1
L 2.9575 3.0075 2.9575 3.0075 9 P 0 ;1
L 2.9575 3.0575 2.9575 3.0575 9 P 0 ;1
L 2.9575 3.1075 2.9575 3.1075 9 P 0 ;1
L 2.9575 3.1575 2.9575 3.1575 9 P 0 ;1
L 2.9575 3.2075 2.9575 3.2075 9 P 0 ;1
L 2.9575 3.2575 2.9575 3.2575 9 P 0 ;1
L 2.9575 3.3075 2.9575 3.3075 9 P 0 ;1
L 2.9575 3.3575 2.9575 3.3575 9 P 0 ;1
L 2.9575 3.4075 2.9575 3.4075 9 P 0 ;1
L 2.9575 3.4575 2.9575 3.4575 9 P 0 ;1
L 2.9575 3.5075 2.9575 3.5075 9 P 0 ;1
L 2.9575 3.5575 2.9575 3.5575 9 P 0 ;1
L 2.9575 3.6075 2.9575 3.6075 9 P 0 ;1
L 2.9575 3.6575 2.9575 3.6575 9 P 0 ;1
L 2.9575 3.7075 2.9575 3.7075 9 P 0 ;1
L 2.9575 3.7575 2.9575 3.7575 9 P 0 ;1
L 2.9575 3.8075 2.9575 3.8075 9 P 0 ;1
L 2.9575 3.8575 2.9575 3.8575 9 P 0 ;1
L 2.9575 3.9075 2.9575 3.9075 9 P 0 ;1
L 2.9575 3.9575 2.9575 3.9575 9 P 0 ;1
L 2.9575 4.0075 2.9575 4.0075 9 P 0 ;1
L 2.9575 4.0575 2.9575 4.0575 9 P 0 ;1
L 2.9575 4.1075 2.9575 4.1075 9 P 0 ;1
L 2.9575 4.1575 2.9575 4.1575 9 P 0 ;1
L 2.9575 4.2075 2.9575 4.2075 9 P 0 ;1
L 2.9575 4.2575 2.9575 4.2575 9 P 0 ;1
L 2.9575 4.3075 2.9575 4.3075 9 P 0 ;1
L 2.9575 4.3575 2.9575 4.3575 9 P 0 ;1
L 2.9575 4.4075 2.9575 4.4075 9 P 0 ;1
L 2.9575 4.4575 2.9575 4.4575 9 P 0 ;1
L 2.9575 4.5075 2.9575 4.5075 9 P 0 ;1
L 2.9575 4.5575 2.9575 4.5575 9 P 0 ;1
L 3.0075 0.1575 3.0075 0.1575 9 P 0 ;1
L 3.0075 0.2075 3.0075 0.2075 9 P 0 ;1
L 3.0075 0.2575 3.0075 0.2575 9 P 0 ;1
L 3.0075 0.3075 3.0075 0.3075 9 P 0 ;1
L 3.0075 0.3575 3.0075 0.3575 9 P 0 ;1
L 3.0075 0.4075 3.0075 0.4075 9 P 0 ;1
L 3.0075 0.4575 3.0075 0.4575 9 P 0 ;1
L 3.0075 0.5075 3.0075 0.5075 9 P 0 ;1
L 3.0075 0.5575 3.0075 0.5575 9 P 0 ;1
L 3.0075 0.6075 3.0075 0.6075 9 P 0 ;1
L 3.0075 0.6575 3.0075 0.6575 9 P 0 ;1
L 3.0075 0.7075 3.0075 0.7075 9 P 0 ;1
L 3.0075 0.7575 3.0075 0.7575 9 P 0 ;1
L 3.0075 0.8075 3.0075 0.8075 9 P 0 ;1
L 3.0075 0.8575 3.0075 0.8575 9 P 0 ;1
L 3.0075 1.5075 3.0075 1.5075 9 P 0 ;1
L 3.0075 1.5575 3.0075 1.5575 9 P 0 ;1
L 3.0075 1.6075 3.0075 1.6075 9 P 0 ;1
L 3.0075 1.6575 3.0075 1.6575 9 P 0 ;1
L 3.0075 1.7075 3.0075 1.7075 9 P 0 ;1
L 3.0075 2.0075 3.0075 2.0075 9 P 0 ;1
L 3.0075 2.0575 3.0075 2.0575 9 P 0 ;1
L 3.0075 2.1075 3.0075 2.1075 9 P 0 ;1
L 3.0075 2.1575 3.0075 2.1575 9 P 0 ;1
L 3.0075 2.2075 3.0075 2.2075 9 P 0 ;1
L 3.0075 2.2575 3.0075 2.2575 9 P 0 ;1
L 3.0075 2.3075 3.0075 2.3075 9 P 0 ;1
L 3.0075 2.3575 3.0075 2.3575 9 P 0 ;1
L 3.0075 2.4075 3.0075 2.4075 9 P 0 ;1
L 3.0075 2.4575 3.0075 2.4575 9 P 0 ;1
L 3.0075 2.5075 3.0075 2.5075 9 P 0 ;1
L 3.0075 2.5575 3.0075 2.5575 9 P 0 ;1
L 3.0075 2.6075 3.0075 2.6075 9 P 0 ;1
L 3.0075 2.6575 3.0075 2.6575 9 P 0 ;1
L 3.0075 2.7075 3.0075 2.7075 9 P 0 ;1
L 3.0075 3.0075 3.0075 3.0075 9 P 0 ;1
L 3.0075 3.0575 3.0075 3.0575 9 P 0 ;1
L 3.0075 3.1075 3.0075 3.1075 9 P 0 ;1
L 3.0075 3.1575 3.0075 3.1575 9 P 0 ;1
L 3.0075 3.2075 3.0075 3.2075 9 P 0 ;1
L 3.0075 3.2575 3.0075 3.2575 9 P 0 ;1
L 3.0075 3.3075 3.0075 3.3075 9 P 0 ;1
L 3.0075 3.3575 3.0075 3.3575 9 P 0 ;1
L 3.0075 3.4075 3.0075 3.4075 9 P 0 ;1
L 3.0075 3.4575 3.0075 3.4575 9 P 0 ;1
L 3.0075 3.5075 3.0075 3.5075 9 P 0 ;1
L 3.0075 3.5575 3.0075 3.5575 9 P 0 ;1
L 3.0075 3.6075 3.0075 3.6075 9 P 0 ;1
L 3.0075 3.6575 3.0075 3.6575 9 P 0 ;1
L 3.0075 3.7075 3.0075 3.7075 9 P 0 ;1
L 3.0075 3.7575 3.0075 3.7575 9 P 0 ;1
L 3.0075 3.8075 3.0075 3.8075 9 P 0 ;1
L 3.0075 3.8575 3.0075 3.8575 9 P 0 ;1
L 3.0075 3.9075 3.0075 3.9075 9 P 0 ;1
L 3.0075 3.9575 3.0075 3.9575 9 P 0 ;1
L 3.0075 4.0075 3.0075 4.0075 9 P 0 ;1
L 3.0075 4.0575 3.0075 4.0575 9 P 0 ;1
L 3.0075 4.1075 3.0075 4.1075 9 P 0 ;1
L 3.0075 4.1575 3.0075 4.1575 9 P 0 ;1
L 3.0075 4.2075 3.0075 4.2075 9 P 0 ;1
L 3.0075 4.2575 3.0075 4.2575 9 P 0 ;1
L 3.0075 4.3075 3.0075 4.3075 9 P 0 ;1
L 3.0075 4.3575 3.0075 4.3575 9 P 0 ;1
L 3.0075 4.5075 3.0075 4.5075 9 P 0 ;1
L 3.0075 4.5575 3.0075 4.5575 9 P 0 ;1
L 3.0575 0.1575 3.0575 0.1575 9 P 0 ;1
L 3.0575 0.2075 3.0575 0.2075 9 P 0 ;1
L 3.0575 0.2575 3.0575 0.2575 9 P 0 ;1
L 3.0575 0.3075 3.0575 0.3075 9 P 0 ;1
L 3.0575 0.3575 3.0575 0.3575 9 P 0 ;1
L 3.0575 0.4075 3.0575 0.4075 9 P 0 ;1
L 3.0575 0.4575 3.0575 0.4575 9 P 0 ;1
L 3.0575 0.5075 3.0575 0.5075 9 P 0 ;1
L 3.0575 0.5575 3.0575 0.5575 9 P 0 ;1
L 3.0575 0.6075 3.0575 0.6075 9 P 0 ;1
L 3.0575 0.6575 3.0575 0.6575 9 P 0 ;1
L 3.0575 0.7075 3.0575 0.7075 9 P 0 ;1
L 3.0575 0.7575 3.0575 0.7575 9 P 0 ;1
L 3.0575 0.8075 3.0575 0.8075 9 P 0 ;1
L 3.0575 0.8575 3.0575 0.8575 9 P 0 ;1
L 3.0575 1.5075 3.0575 1.5075 9 P 0 ;1
L 3.0575 1.5575 3.0575 1.5575 9 P 0 ;1
L 3.0575 1.6075 3.0575 1.6075 9 P 0 ;1
L 3.0575 1.6575 3.0575 1.6575 9 P 0 ;1
L 3.0575 1.7075 3.0575 1.7075 9 P 0 ;1
L 3.0575 2.0075 3.0575 2.0075 9 P 0 ;1
L 3.0575 2.0575 3.0575 2.0575 9 P 0 ;1
L 3.0575 2.1075 3.0575 2.1075 9 P 0 ;1
L 3.0575 2.1575 3.0575 2.1575 9 P 0 ;1
L 3.0575 2.2075 3.0575 2.2075 9 P 0 ;1
L 3.0575 2.2575 3.0575 2.2575 9 P 0 ;1
L 3.0575 2.3075 3.0575 2.3075 9 P 0 ;1
L 3.0575 2.3575 3.0575 2.3575 9 P 0 ;1
L 3.0575 2.4075 3.0575 2.4075 9 P 0 ;1
L 3.0575 2.4575 3.0575 2.4575 9 P 0 ;1
L 3.0575 2.5075 3.0575 2.5075 9 P 0 ;1
L 3.0575 2.5575 3.0575 2.5575 9 P 0 ;1
L 3.0575 2.6075 3.0575 2.6075 9 P 0 ;1
L 3.0575 2.6575 3.0575 2.6575 9 P 0 ;1
L 3.0575 2.7075 3.0575 2.7075 9 P 0 ;1
L 3.0575 2.7575 3.0575 2.7575 9 P 0 ;1
L 3.0575 3.0075 3.0575 3.0075 9 P 0 ;1
L 3.0575 3.0575 3.0575 3.0575 9 P 0 ;1
L 3.0575 3.1075 3.0575 3.1075 9 P 0 ;1
L 3.0575 3.1575 3.0575 3.1575 9 P 0 ;1
L 3.0575 3.2075 3.0575 3.2075 9 P 0 ;1
L 3.0575 3.2575 3.0575 3.2575 9 P 0 ;1
L 3.0575 3.3075 3.0575 3.3075 9 P 0 ;1
L 3.0575 3.3575 3.0575 3.3575 9 P 0 ;1
L 3.0575 3.4075 3.0575 3.4075 9 P 0 ;1
L 3.0575 3.4575 3.0575 3.4575 9 P 0 ;1
L 3.0575 3.5075 3.0575 3.5075 9 P 0 ;1
L 3.0575 3.5575 3.0575 3.5575 9 P 0 ;1
L 3.0575 3.6075 3.0575 3.6075 9 P 0 ;1
L 3.0575 3.6575 3.0575 3.6575 9 P 0 ;1
L 3.0575 3.7075 3.0575 3.7075 9 P 0 ;1
L 3.0575 3.7575 3.0575 3.7575 9 P 0 ;1
L 3.0575 3.8075 3.0575 3.8075 9 P 0 ;1
L 3.0575 3.8575 3.0575 3.8575 9 P 0 ;1
L 3.0575 3.9075 3.0575 3.9075 9 P 0 ;1
L 3.0575 3.9575 3.0575 3.9575 9 P 0 ;1
L 3.0575 4.0075 3.0575 4.0075 9 P 0 ;1
L 3.0575 4.0575 3.0575 4.0575 9 P 0 ;1
L 3.0575 4.1075 3.0575 4.1075 9 P 0 ;1
L 3.0575 4.1575 3.0575 4.1575 9 P 0 ;1
L 3.0575 4.2075 3.0575 4.2075 9 P 0 ;1
L 3.0575 4.2575 3.0575 4.2575 9 P 0 ;1
L 3.0575 4.3075 3.0575 4.3075 9 P 0 ;1
L 3.0575 4.5575 3.0575 4.5575 9 P 0 ;1
L 3.1075 0.1575 3.1075 0.1575 9 P 0 ;1
L 3.1075 0.2075 3.1075 0.2075 9 P 0 ;1
L 3.1075 0.2575 3.1075 0.2575 9 P 0 ;1
L 3.1075 0.3075 3.1075 0.3075 9 P 0 ;1
L 3.1075 0.3575 3.1075 0.3575 9 P 0 ;1
L 3.1075 0.4075 3.1075 0.4075 9 P 0 ;1
L 3.1075 0.4575 3.1075 0.4575 9 P 0 ;1
L 3.1075 0.5075 3.1075 0.5075 9 P 0 ;1
L 3.1075 0.5575 3.1075 0.5575 9 P 0 ;1
L 3.1075 0.6075 3.1075 0.6075 9 P 0 ;1
L 3.1075 0.6575 3.1075 0.6575 9 P 0 ;1
L 3.1075 0.7075 3.1075 0.7075 9 P 0 ;1
L 3.1075 0.7575 3.1075 0.7575 9 P 0 ;1
L 3.1075 0.8075 3.1075 0.8075 9 P 0 ;1
L 3.1075 0.8575 3.1075 0.8575 9 P 0 ;1
L 3.1075 1.5575 3.1075 1.5575 9 P 0 ;1
L 3.1075 1.6075 3.1075 1.6075 9 P 0 ;1
L 3.1075 1.6575 3.1075 1.6575 9 P 0 ;1
L 3.1075 1.7075 3.1075 1.7075 9 P 0 ;1
L 3.1075 2.0075 3.1075 2.0075 9 P 0 ;1
L 3.1075 2.0575 3.1075 2.0575 9 P 0 ;1
L 3.1075 2.1075 3.1075 2.1075 9 P 0 ;1
L 3.1075 2.1575 3.1075 2.1575 9 P 0 ;1
L 3.1075 2.2075 3.1075 2.2075 9 P 0 ;1
L 3.1075 2.2575 3.1075 2.2575 9 P 0 ;1
L 3.1075 2.3075 3.1075 2.3075 9 P 0 ;1
L 3.1075 2.3575 3.1075 2.3575 9 P 0 ;1
L 3.1075 2.4075 3.1075 2.4075 9 P 0 ;1
L 3.1075 2.4575 3.1075 2.4575 9 P 0 ;1
L 3.1075 2.5075 3.1075 2.5075 9 P 0 ;1
L 3.1075 2.5575 3.1075 2.5575 9 P 0 ;1
L 3.1075 2.6075 3.1075 2.6075 9 P 0 ;1
L 3.1075 2.6575 3.1075 2.6575 9 P 0 ;1
L 3.1075 2.7075 3.1075 2.7075 9 P 0 ;1
L 3.1075 2.7575 3.1075 2.7575 9 P 0 ;1
L 3.1075 3.2575 3.1075 3.2575 9 P 0 ;1
L 3.1075 3.3075 3.1075 3.3075 9 P 0 ;1
L 3.1075 3.3575 3.1075 3.3575 9 P 0 ;1
L 3.1075 3.4075 3.1075 3.4075 9 P 0 ;1
L 3.1075 3.4575 3.1075 3.4575 9 P 0 ;1
L 3.1075 3.5075 3.1075 3.5075 9 P 0 ;1
L 3.1075 3.5575 3.1075 3.5575 9 P 0 ;1
L 3.1075 3.6075 3.1075 3.6075 9 P 0 ;1
L 3.1075 3.6575 3.1075 3.6575 9 P 0 ;1
L 3.1075 3.7075 3.1075 3.7075 9 P 0 ;1
L 3.1075 3.7575 3.1075 3.7575 9 P 0 ;1
L 3.1075 3.8075 3.1075 3.8075 9 P 0 ;1
L 3.1075 3.8575 3.1075 3.8575 9 P 0 ;1
L 3.1075 3.9075 3.1075 3.9075 9 P 0 ;1
L 3.1075 3.9575 3.1075 3.9575 9 P 0 ;1
L 3.1075 4.0075 3.1075 4.0075 9 P 0 ;1
L 3.1075 4.0575 3.1075 4.0575 9 P 0 ;1
L 3.1075 4.1075 3.1075 4.1075 9 P 0 ;1
L 3.1075 4.1575 3.1075 4.1575 9 P 0 ;1
L 3.1075 4.2075 3.1075 4.2075 9 P 0 ;1
L 3.1075 4.2575 3.1075 4.2575 9 P 0 ;1
L 3.1075 4.3075 3.1075 4.3075 9 P 0 ;1
L 3.1075 4.5575 3.1075 4.5575 9 P 0 ;1
L 3.1575 0.1575 3.1575 0.1575 9 P 0 ;1
L 3.1575 0.2075 3.1575 0.2075 9 P 0 ;1
L 3.1575 0.2575 3.1575 0.2575 9 P 0 ;1
L 3.1575 0.3075 3.1575 0.3075 9 P 0 ;1
L 3.1575 0.3575 3.1575 0.3575 9 P 0 ;1
L 3.1575 0.4075 3.1575 0.4075 9 P 0 ;1
L 3.1575 0.4575 3.1575 0.4575 9 P 0 ;1
L 3.1575 0.5075 3.1575 0.5075 9 P 0 ;1
L 3.1575 0.5575 3.1575 0.5575 9 P 0 ;1
L 3.1575 0.6075 3.1575 0.6075 9 P 0 ;1
L 3.1575 0.6575 3.1575 0.6575 9 P 0 ;1
L 3.1575 0.7075 3.1575 0.7075 9 P 0 ;1
L 3.1575 0.7575 3.1575 0.7575 9 P 0 ;1
L 3.1575 0.8075 3.1575 0.8075 9 P 0 ;1
L 3.1575 0.8575 3.1575 0.8575 9 P 0 ;1
L 3.1575 1.5575 3.1575 1.5575 9 P 0 ;1
L 3.1575 1.6075 3.1575 1.6075 9 P 0 ;1
L 3.1575 1.6575 3.1575 1.6575 9 P 0 ;1
L 3.1575 1.7075 3.1575 1.7075 9 P 0 ;1
L 3.1575 2.0075 3.1575 2.0075 9 P 0 ;1
L 3.1575 2.0575 3.1575 2.0575 9 P 0 ;1
L 3.1575 2.1075 3.1575 2.1075 9 P 0 ;1
L 3.1575 2.1575 3.1575 2.1575 9 P 0 ;1
L 3.1575 2.2075 3.1575 2.2075 9 P 0 ;1
L 3.1575 2.2575 3.1575 2.2575 9 P 0 ;1
L 3.1575 2.3075 3.1575 2.3075 9 P 0 ;1
L 3.1575 2.3575 3.1575 2.3575 9 P 0 ;1
L 3.1575 2.4075 3.1575 2.4075 9 P 0 ;1
L 3.1575 2.4575 3.1575 2.4575 9 P 0 ;1
L 3.1575 2.5075 3.1575 2.5075 9 P 0 ;1
L 3.1575 2.5575 3.1575 2.5575 9 P 0 ;1
L 3.1575 2.6075 3.1575 2.6075 9 P 0 ;1
L 3.1575 2.6575 3.1575 2.6575 9 P 0 ;1
L 3.1575 2.7075 3.1575 2.7075 9 P 0 ;1
L 3.1575 2.7575 3.1575 2.7575 9 P 0 ;1
L 3.1575 2.8075 3.1575 2.8075 9 P 0 ;1
L 3.1575 3.5575 3.1575 3.5575 9 P 0 ;1
L 3.1575 3.6075 3.1575 3.6075 9 P 0 ;1
L 3.1575 3.6575 3.1575 3.6575 9 P 0 ;1
L 3.1575 3.7075 3.1575 3.7075 9 P 0 ;1
L 3.1575 3.7575 3.1575 3.7575 9 P 0 ;1
L 3.1575 3.8075 3.1575 3.8075 9 P 0 ;1
L 3.1575 3.8575 3.1575 3.8575 9 P 0 ;1
L 3.1575 3.9075 3.1575 3.9075 9 P 0 ;1
L 3.1575 3.9575 3.1575 3.9575 9 P 0 ;1
L 3.1575 4.0075 3.1575 4.0075 9 P 0 ;1
L 3.1575 4.0575 3.1575 4.0575 9 P 0 ;1
L 3.1575 4.1075 3.1575 4.1075 9 P 0 ;1
L 3.1575 4.1575 3.1575 4.1575 9 P 0 ;1
L 3.1575 4.2075 3.1575 4.2075 9 P 0 ;1
L 3.1575 4.2575 3.1575 4.2575 9 P 0 ;1
L 3.1575 4.3075 3.1575 4.3075 9 P 0 ;1
L 3.1575 4.3575 3.1575 4.3575 9 P 0 ;1
L 3.1575 4.4075 3.1575 4.4075 9 P 0 ;1
L 3.1575 4.5575 3.1575 4.5575 9 P 0 ;1
L 3.1575 4.6075 3.1575 4.6075 9 P 0 ;1
L 3.2075 0.1575 3.2075 0.1575 9 P 0 ;1
L 3.2075 0.2075 3.2075 0.2075 9 P 0 ;1
L 3.2075 0.2575 3.2075 0.2575 9 P 0 ;1
L 3.2075 0.3075 3.2075 0.3075 9 P 0 ;1
L 3.2075 0.3575 3.2075 0.3575 9 P 0 ;1
L 3.2075 0.4075 3.2075 0.4075 9 P 0 ;1
L 3.2075 0.4575 3.2075 0.4575 9 P 0 ;1
L 3.2075 0.5075 3.2075 0.5075 9 P 0 ;1
L 3.2075 0.5575 3.2075 0.5575 9 P 0 ;1
L 3.2075 0.6075 3.2075 0.6075 9 P 0 ;1
L 3.2075 0.6575 3.2075 0.6575 9 P 0 ;1
L 3.2075 0.7075 3.2075 0.7075 9 P 0 ;1
L 3.2075 0.7575 3.2075 0.7575 9 P 0 ;1
L 3.2075 0.8075 3.2075 0.8075 9 P 0 ;1
L 3.2075 0.8575 3.2075 0.8575 9 P 0 ;1
L 3.2075 1.6075 3.2075 1.6075 9 P 0 ;1
L 3.2075 1.6575 3.2075 1.6575 9 P 0 ;1
L 3.2075 1.7075 3.2075 1.7075 9 P 0 ;1
L 3.2075 2.0575 3.2075 2.0575 9 P 0 ;1
L 3.2075 2.1075 3.2075 2.1075 9 P 0 ;1
L 3.2075 2.1575 3.2075 2.1575 9 P 0 ;1
L 3.2075 2.2075 3.2075 2.2075 9 P 0 ;1
L 3.2075 2.2575 3.2075 2.2575 9 P 0 ;1
L 3.2075 2.3075 3.2075 2.3075 9 P 0 ;1
L 3.2075 2.3575 3.2075 2.3575 9 P 0 ;1
L 3.2075 2.4075 3.2075 2.4075 9 P 0 ;1
L 3.2075 2.4575 3.2075 2.4575 9 P 0 ;1
L 3.2075 2.5075 3.2075 2.5075 9 P 0 ;1
L 3.2075 2.5575 3.2075 2.5575 9 P 0 ;1
L 3.2075 2.6075 3.2075 2.6075 9 P 0 ;1
L 3.2075 2.6575 3.2075 2.6575 9 P 0 ;1
L 3.2075 2.7075 3.2075 2.7075 9 P 0 ;1
L 3.2075 2.7575 3.2075 2.7575 9 P 0 ;1
L 3.2075 2.8075 3.2075 2.8075 9 P 0 ;1
L 3.2075 2.8575 3.2075 2.8575 9 P 0 ;1
L 3.2075 2.9075 3.2075 2.9075 9 P 0 ;1
L 3.2075 4.2575 3.2075 4.2575 9 P 0 ;1
L 3.2075 4.3075 3.2075 4.3075 9 P 0 ;1
L 3.2075 4.3575 3.2075 4.3575 9 P 0 ;1
L 3.2075 4.4075 3.2075 4.4075 9 P 0 ;1
L 3.2075 4.4575 3.2075 4.4575 9 P 0 ;1
L 3.2075 4.5075 3.2075 4.5075 9 P 0 ;1
L 3.2075 4.5575 3.2075 4.5575 9 P 0 ;1
L 3.2575 0.1575 3.2575 0.1575 9 P 0 ;1
L 3.2575 0.2075 3.2575 0.2075 9 P 0 ;1
L 3.2575 0.2575 3.2575 0.2575 9 P 0 ;1
L 3.2575 0.3075 3.2575 0.3075 9 P 0 ;1
L 3.2575 0.3575 3.2575 0.3575 9 P 0 ;1
L 3.2575 0.4075 3.2575 0.4075 9 P 0 ;1
L 3.2575 0.4575 3.2575 0.4575 9 P 0 ;1
L 3.2575 0.5075 3.2575 0.5075 9 P 0 ;1
L 3.2575 0.5575 3.2575 0.5575 9 P 0 ;1
L 3.2575 0.6075 3.2575 0.6075 9 P 0 ;1
L 3.2575 0.6575 3.2575 0.6575 9 P 0 ;1
L 3.2575 0.7075 3.2575 0.7075 9 P 0 ;1
L 3.2575 0.7575 3.2575 0.7575 9 P 0 ;1
L 3.2575 0.8075 3.2575 0.8075 9 P 0 ;1
L 3.2575 0.8575 3.2575 0.8575 9 P 0 ;1
L 3.2575 1.6575 3.2575 1.6575 9 P 0 ;1
L 3.2575 1.7075 3.2575 1.7075 9 P 0 ;1
L 3.2575 1.7575 3.2575 1.7575 9 P 0 ;1
L 3.2575 2.0575 3.2575 2.0575 9 P 0 ;1
L 3.2575 2.1075 3.2575 2.1075 9 P 0 ;1
L 3.2575 2.1575 3.2575 2.1575 9 P 0 ;1
L 3.2575 2.2075 3.2575 2.2075 9 P 0 ;1
L 3.2575 2.2575 3.2575 2.2575 9 P 0 ;1
L 3.2575 2.3075 3.2575 2.3075 9 P 0 ;1
L 3.2575 2.3575 3.2575 2.3575 9 P 0 ;1
L 3.2575 2.4075 3.2575 2.4075 9 P 0 ;1
L 3.2575 2.4575 3.2575 2.4575 9 P 0 ;1
L 3.2575 2.5075 3.2575 2.5075 9 P 0 ;1
L 3.2575 2.5575 3.2575 2.5575 9 P 0 ;1
L 3.2575 2.6075 3.2575 2.6075 9 P 0 ;1
L 3.2575 2.6575 3.2575 2.6575 9 P 0 ;1
L 3.2575 2.7075 3.2575 2.7075 9 P 0 ;1
L 3.2575 2.7575 3.2575 2.7575 9 P 0 ;1
L 3.2575 2.8075 3.2575 2.8075 9 P 0 ;1
L 3.2575 2.8575 3.2575 2.8575 9 P 0 ;1
L 3.2575 2.9075 3.2575 2.9075 9 P 0 ;1
L 3.2575 2.9575 3.2575 2.9575 9 P 0 ;1
L 3.2575 3.0075 3.2575 3.0075 9 P 0 ;1
L 3.2575 3.0575 3.2575 3.0575 9 P 0 ;1
L 3.2575 3.1075 3.2575 3.1075 9 P 0 ;1
L 3.2575 3.1575 3.2575 3.1575 9 P 0 ;1
L 3.2575 4.5075 3.2575 4.5075 9 P 0 ;1
L 3.2575 4.5575 3.2575 4.5575 9 P 0 ;1
L 3.3075 0.1575 3.3075 0.1575 9 P 0 ;1
L 3.3075 0.2075 3.3075 0.2075 9 P 0 ;1
L 3.3075 0.2575 3.3075 0.2575 9 P 0 ;1
L 3.3075 0.3075 3.3075 0.3075 9 P 0 ;1
L 3.3075 0.3575 3.3075 0.3575 9 P 0 ;1
L 3.3075 0.4075 3.3075 0.4075 9 P 0 ;1
L 3.3075 0.4575 3.3075 0.4575 9 P 0 ;1
L 3.3075 0.5075 3.3075 0.5075 9 P 0 ;1
L 3.3075 0.5575 3.3075 0.5575 9 P 0 ;1
L 3.3075 0.6075 3.3075 0.6075 9 P 0 ;1
L 3.3075 0.6575 3.3075 0.6575 9 P 0 ;1
L 3.3075 0.7075 3.3075 0.7075 9 P 0 ;1
L 3.3075 0.7575 3.3075 0.7575 9 P 0 ;1
L 3.3075 0.8075 3.3075 0.8075 9 P 0 ;1
L 3.3075 0.8575 3.3075 0.8575 9 P 0 ;1
L 3.3075 0.9075 3.3075 0.9075 9 P 0 ;1
L 3.3075 1.6575 3.3075 1.6575 9 P 0 ;1
L 3.3075 1.7075 3.3075 1.7075 9 P 0 ;1
L 3.3075 1.7575 3.3075 1.7575 9 P 0 ;1
L 3.3075 2.0575 3.3075 2.0575 9 P 0 ;1
L 3.3075 2.1075 3.3075 2.1075 9 P 0 ;1
L 3.3075 2.1575 3.3075 2.1575 9 P 0 ;1
L 3.3075 2.2075 3.3075 2.2075 9 P 0 ;1
L 3.3075 2.2575 3.3075 2.2575 9 P 0 ;1
L 3.3075 2.3075 3.3075 2.3075 9 P 0 ;1
L 3.3075 2.3575 3.3075 2.3575 9 P 0 ;1
L 3.3075 2.4075 3.3075 2.4075 9 P 0 ;1
L 3.3075 2.4575 3.3075 2.4575 9 P 0 ;1
L 3.3075 2.5075 3.3075 2.5075 9 P 0 ;1
L 3.3075 2.5575 3.3075 2.5575 9 P 0 ;1
L 3.3075 2.6075 3.3075 2.6075 9 P 0 ;1
L 3.3075 2.6575 3.3075 2.6575 9 P 0 ;1
L 3.3075 2.7075 3.3075 2.7075 9 P 0 ;1
L 3.3075 2.7575 3.3075 2.7575 9 P 0 ;1
L 3.3075 2.8075 3.3075 2.8075 9 P 0 ;1
L 3.3075 2.8575 3.3075 2.8575 9 P 0 ;1
L 3.3075 2.9075 3.3075 2.9075 9 P 0 ;1
L 3.3075 2.9575 3.3075 2.9575 9 P 0 ;1
L 3.3075 3.0075 3.3075 3.0075 9 P 0 ;1
L 3.3075 3.0575 3.3075 3.0575 9 P 0 ;1
L 3.3075 3.1075 3.3075 3.1075 9 P 0 ;1
L 3.3075 3.1575 3.3075 3.1575 9 P 0 ;1
L 3.3075 3.2075 3.3075 3.2075 9 P 0 ;1
L 3.3075 3.2575 3.3075 3.2575 9 P 0 ;1
L 3.3075 3.3075 3.3075 3.3075 9 P 0 ;1
L 3.3075 3.3575 3.3075 3.3575 9 P 0 ;1
L 3.3075 3.4075 3.3075 3.4075 9 P 0 ;1
L 3.3075 3.4575 3.3075 3.4575 9 P 0 ;1
L 3.3575 0.1575 3.3575 0.1575 9 P 0 ;1
L 3.3575 0.2075 3.3575 0.2075 9 P 0 ;1
L 3.3575 0.2575 3.3575 0.2575 9 P 0 ;1
L 3.3575 0.3075 3.3575 0.3075 9 P 0 ;1
L 3.3575 0.3575 3.3575 0.3575 9 P 0 ;1
L 3.3575 0.4075 3.3575 0.4075 9 P 0 ;1
L 3.3575 0.4575 3.3575 0.4575 9 P 0 ;1
L 3.3575 0.5075 3.3575 0.5075 9 P 0 ;1
L 3.3575 0.5575 3.3575 0.5575 9 P 0 ;1
L 3.3575 0.6075 3.3575 0.6075 9 P 0 ;1
L 3.3575 0.6575 3.3575 0.6575 9 P 0 ;1
L 3.3575 0.7075 3.3575 0.7075 9 P 0 ;1
L 3.3575 0.7575 3.3575 0.7575 9 P 0 ;1
L 3.3575 0.8075 3.3575 0.8075 9 P 0 ;1
L 3.3575 0.8575 3.3575 0.8575 9 P 0 ;1
L 3.3575 0.9075 3.3575 0.9075 9 P 0 ;1
L 3.3575 1.7075 3.3575 1.7075 9 P 0 ;1
L 3.3575 1.7575 3.3575 1.7575 9 P 0 ;1
L 3.3575 2.0575 3.3575 2.0575 9 P 0 ;1
L 3.3575 2.1075 3.3575 2.1075 9 P 0 ;1
L 3.3575 2.1575 3.3575 2.1575 9 P 0 ;1
L 3.3575 2.2075 3.3575 2.2075 9 P 0 ;1
L 3.3575 2.2575 3.3575 2.2575 9 P 0 ;1
L 3.3575 2.3075 3.3575 2.3075 9 P 0 ;1
L 3.3575 2.3575 3.3575 2.3575 9 P 0 ;1
L 3.3575 2.4075 3.3575 2.4075 9 P 0 ;1
L 3.3575 2.4575 3.3575 2.4575 9 P 0 ;1
L 3.3575 2.5075 3.3575 2.5075 9 P 0 ;1
L 3.3575 2.5575 3.3575 2.5575 9 P 0 ;1
L 3.3575 2.6075 3.3575 2.6075 9 P 0 ;1
L 3.3575 2.6575 3.3575 2.6575 9 P 0 ;1
L 3.3575 2.7075 3.3575 2.7075 9 P 0 ;1
L 3.3575 2.7575 3.3575 2.7575 9 P 0 ;1
L 3.3575 2.8075 3.3575 2.8075 9 P 0 ;1
L 3.3575 2.8575 3.3575 2.8575 9 P 0 ;1
L 3.3575 2.9075 3.3575 2.9075 9 P 0 ;1
L 3.3575 2.9575 3.3575 2.9575 9 P 0 ;1
L 3.3575 3.0075 3.3575 3.0075 9 P 0 ;1
L 3.3575 3.0575 3.3575 3.0575 9 P 0 ;1
L 3.3575 3.1075 3.3575 3.1075 9 P 0 ;1
L 3.3575 3.1575 3.3575 3.1575 9 P 0 ;1
L 3.3575 3.2075 3.3575 3.2075 9 P 0 ;1
L 3.3575 3.2575 3.3575 3.2575 9 P 0 ;1
L 3.3575 3.3075 3.3575 3.3075 9 P 0 ;1
L 3.3575 3.3575 3.3575 3.3575 9 P 0 ;1
L 3.3575 3.4075 3.3575 3.4075 9 P 0 ;1
L 3.3575 3.4575 3.3575 3.4575 9 P 0 ;1
L 3.3575 3.5075 3.3575 3.5075 9 P 0 ;1
L 3.3575 3.5575 3.3575 3.5575 9 P 0 ;1
L 3.3575 3.6075 3.3575 3.6075 9 P 0 ;1
L 3.3575 3.6575 3.3575 3.6575 9 P 0 ;1
L 3.3575 3.7075 3.3575 3.7075 9 P 0 ;1
L 3.3575 3.7575 3.3575 3.7575 9 P 0 ;1
L 3.3575 3.8075 3.3575 3.8075 9 P 0 ;1
L 3.3575 3.8575 3.3575 3.8575 9 P 0 ;1
L 3.3575 3.9075 3.3575 3.9075 9 P 0 ;1
L 3.3575 3.9575 3.3575 3.9575 9 P 0 ;1
L 3.3575 4.0075 3.3575 4.0075 9 P 0 ;1
L 3.3575 4.0575 3.3575 4.0575 9 P 0 ;1
L 3.3575 4.1075 3.3575 4.1075 9 P 0 ;1
L 3.4075 0.1575 3.4075 0.1575 9 P 0 ;1
L 3.4075 0.2075 3.4075 0.2075 9 P 0 ;1
L 3.4075 0.2575 3.4075 0.2575 9 P 0 ;1
L 3.4075 0.3075 3.4075 0.3075 9 P 0 ;1
L 3.4075 0.3575 3.4075 0.3575 9 P 0 ;1
L 3.4075 0.4075 3.4075 0.4075 9 P 0 ;1
L 3.4075 0.4575 3.4075 0.4575 9 P 0 ;1
L 3.4075 0.5075 3.4075 0.5075 9 P 0 ;1
L 3.4075 0.5575 3.4075 0.5575 9 P 0 ;1
L 3.4075 0.6075 3.4075 0.6075 9 P 0 ;1
L 3.4075 0.6575 3.4075 0.6575 9 P 0 ;1
L 3.4075 0.7075 3.4075 0.7075 9 P 0 ;1
L 3.4075 0.7575 3.4075 0.7575 9 P 0 ;1
L 3.4075 0.8075 3.4075 0.8075 9 P 0 ;1
L 3.4075 0.8575 3.4075 0.8575 9 P 0 ;1
L 3.4075 0.9075 3.4075 0.9075 9 P 0 ;1
L 3.4075 1.7575 3.4075 1.7575 9 P 0 ;1
L 3.4075 2.0575 3.4075 2.0575 9 P 0 ;1
L 3.4075 2.1075 3.4075 2.1075 9 P 0 ;1
L 3.4075 2.1575 3.4075 2.1575 9 P 0 ;1
L 3.4075 2.2075 3.4075 2.2075 9 P 0 ;1
L 3.4075 2.2575 3.4075 2.2575 9 P 0 ;1
L 3.4075 2.3075 3.4075 2.3075 9 P 0 ;1
L 3.4075 2.3575 3.4075 2.3575 9 P 0 ;1
L 3.4075 2.4075 3.4075 2.4075 9 P 0 ;1
L 3.4075 2.4575 3.4075 2.4575 9 P 0 ;1
L 3.4075 2.5075 3.4075 2.5075 9 P 0 ;1
L 3.4075 2.5575 3.4075 2.5575 9 P 0 ;1
L 3.4075 2.6075 3.4075 2.6075 9 P 0 ;1
L 3.4075 2.6575 3.4075 2.6575 9 P 0 ;1
L 3.4075 2.7075 3.4075 2.7075 9 P 0 ;1
L 3.4075 2.7575 3.4075 2.7575 9 P 0 ;1
L 3.4075 2.8075 3.4075 2.8075 9 P 0 ;1
L 3.4075 2.8575 3.4075 2.8575 9 P 0 ;1
L 3.4075 2.9075 3.4075 2.9075 9 P 0 ;1
L 3.4075 2.9575 3.4075 2.9575 9 P 0 ;1
L 3.4075 3.0075 3.4075 3.0075 9 P 0 ;1
L 3.4075 3.0575 3.4075 3.0575 9 P 0 ;1
L 3.4075 3.1075 3.4075 3.1075 9 P 0 ;1
L 3.4075 3.1575 3.4075 3.1575 9 P 0 ;1
L 3.4075 3.2075 3.4075 3.2075 9 P 0 ;1
L 3.4075 3.2575 3.4075 3.2575 9 P 0 ;1
L 3.4075 3.3075 3.4075 3.3075 9 P 0 ;1
L 3.4075 3.3575 3.4075 3.3575 9 P 0 ;1
L 3.4075 3.4075 3.4075 3.4075 9 P 0 ;1
L 3.4075 3.4575 3.4075 3.4575 9 P 0 ;1
L 3.4075 3.5075 3.4075 3.5075 9 P 0 ;1
L 3.4075 3.5575 3.4075 3.5575 9 P 0 ;1
L 3.4075 3.6075 3.4075 3.6075 9 P 0 ;1
L 3.4075 3.6575 3.4075 3.6575 9 P 0 ;1
L 3.4075 3.7075 3.4075 3.7075 9 P 0 ;1
L 3.4075 3.7575 3.4075 3.7575 9 P 0 ;1
L 3.4075 3.8075 3.4075 3.8075 9 P 0 ;1
L 3.4075 3.8575 3.4075 3.8575 9 P 0 ;1
L 3.4075 3.9075 3.4075 3.9075 9 P 0 ;1
L 3.4075 3.9575 3.4075 3.9575 9 P 0 ;1
L 3.4075 4.0075 3.4075 4.0075 9 P 0 ;1
L 3.4075 4.0575 3.4075 4.0575 9 P 0 ;1
L 3.4075 4.1075 3.4075 4.1075 9 P 0 ;1
L 3.4075 4.1575 3.4075 4.1575 9 P 0 ;1
L 3.4075 4.2075 3.4075 4.2075 9 P 0 ;1
L 3.4075 4.2575 3.4075 4.2575 9 P 0 ;1
L 3.4075 4.3075 3.4075 4.3075 9 P 0 ;1
L 3.4075 4.3575 3.4075 4.3575 9 P 0 ;1
L 3.4075 4.4075 3.4075 4.4075 9 P 0 ;1
L 3.4575 0.1575 3.4575 0.1575 9 P 0 ;1
L 3.4575 0.2075 3.4575 0.2075 9 P 0 ;1
L 3.4575 0.2575 3.4575 0.2575 9 P 0 ;1
L 3.4575 0.3075 3.4575 0.3075 9 P 0 ;1
L 3.4575 0.3575 3.4575 0.3575 9 P 0 ;1
L 3.4575 0.4075 3.4575 0.4075 9 P 0 ;1
L 3.4575 0.4575 3.4575 0.4575 9 P 0 ;1
L 3.4575 0.5075 3.4575 0.5075 9 P 0 ;1
L 3.4575 0.5575 3.4575 0.5575 9 P 0 ;1
L 3.4575 0.6075 3.4575 0.6075 9 P 0 ;1
L 3.4575 0.6575 3.4575 0.6575 9 P 0 ;1
L 3.4575 0.7075 3.4575 0.7075 9 P 0 ;1
L 3.4575 0.7575 3.4575 0.7575 9 P 0 ;1
L 3.4575 0.8075 3.4575 0.8075 9 P 0 ;1
L 3.4575 0.8575 3.4575 0.8575 9 P 0 ;1
L 3.4575 0.9075 3.4575 0.9075 9 P 0 ;1
L 3.4575 0.9575 3.4575 0.9575 9 P 0 ;1
L 3.4575 2.0575 3.4575 2.0575 9 P 0 ;1
L 3.4575 2.1075 3.4575 2.1075 9 P 0 ;1
L 3.4575 2.1575 3.4575 2.1575 9 P 0 ;1
L 3.4575 2.2075 3.4575 2.2075 9 P 0 ;1
L 3.4575 2.2575 3.4575 2.2575 9 P 0 ;1
L 3.4575 2.3075 3.4575 2.3075 9 P 0 ;1
L 3.4575 2.3575 3.4575 2.3575 9 P 0 ;1
L 3.4575 2.4075 3.4575 2.4075 9 P 0 ;1
L 3.4575 2.4575 3.4575 2.4575 9 P 0 ;1
L 3.4575 2.5075 3.4575 2.5075 9 P 0 ;1
L 3.4575 2.5575 3.4575 2.5575 9 P 0 ;1
L 3.4575 2.6075 3.4575 2.6075 9 P 0 ;1
L 3.4575 2.6575 3.4575 2.6575 9 P 0 ;1
L 3.4575 2.7075 3.4575 2.7075 9 P 0 ;1
L 3.4575 2.7575 3.4575 2.7575 9 P 0 ;1
L 3.4575 2.8075 3.4575 2.8075 9 P 0 ;1
L 3.4575 2.8575 3.4575 2.8575 9 P 0 ;1
L 3.4575 2.9075 3.4575 2.9075 9 P 0 ;1
L 3.4575 2.9575 3.4575 2.9575 9 P 0 ;1
L 3.4575 3.0075 3.4575 3.0075 9 P 0 ;1
L 3.4575 3.0575 3.4575 3.0575 9 P 0 ;1
L 3.4575 3.1075 3.4575 3.1075 9 P 0 ;1
L 3.4575 3.1575 3.4575 3.1575 9 P 0 ;1
L 3.4575 3.2075 3.4575 3.2075 9 P 0 ;1
L 3.4575 3.2575 3.4575 3.2575 9 P 0 ;1
L 3.4575 3.3075 3.4575 3.3075 9 P 0 ;1
L 3.4575 3.3575 3.4575 3.3575 9 P 0 ;1
L 3.4575 3.4075 3.4575 3.4075 9 P 0 ;1
L 3.4575 3.4575 3.4575 3.4575 9 P 0 ;1
L 3.4575 3.5075 3.4575 3.5075 9 P 0 ;1
L 3.4575 3.5575 3.4575 3.5575 9 P 0 ;1
L 3.4575 3.6075 3.4575 3.6075 9 P 0 ;1
L 3.4575 3.6575 3.4575 3.6575 9 P 0 ;1
L 3.4575 3.7075 3.4575 3.7075 9 P 0 ;1
L 3.4575 3.7575 3.4575 3.7575 9 P 0 ;1
L 3.4575 3.8075 3.4575 3.8075 9 P 0 ;1
L 3.4575 3.8575 3.4575 3.8575 9 P 0 ;1
L 3.4575 3.9075 3.4575 3.9075 9 P 0 ;1
L 3.4575 3.9575 3.4575 3.9575 9 P 0 ;1
L 3.4575 4.0075 3.4575 4.0075 9 P 0 ;1
L 3.4575 4.0575 3.4575 4.0575 9 P 0 ;1
L 3.4575 4.1075 3.4575 4.1075 9 P 0 ;1
L 3.4575 4.1575 3.4575 4.1575 9 P 0 ;1
L 3.4575 4.2075 3.4575 4.2075 9 P 0 ;1
L 3.4575 4.2575 3.4575 4.2575 9 P 0 ;1
L 3.4575 4.3075 3.4575 4.3075 9 P 0 ;1
L 3.4575 4.3575 3.4575 4.3575 9 P 0 ;1
L 3.4575 4.4075 3.4575 4.4075 9 P 0 ;1
L 3.4575 4.4575 3.4575 4.4575 9 P 0 ;1
L 3.4575 4.5075 3.4575 4.5075 9 P 0 ;1
L 3.5075 0.1575 3.5075 0.1575 9 P 0 ;1
L 3.5075 0.2075 3.5075 0.2075 9 P 0 ;1
L 3.5075 0.2575 3.5075 0.2575 9 P 0 ;1
L 3.5075 0.3075 3.5075 0.3075 9 P 0 ;1
L 3.5075 0.3575 3.5075 0.3575 9 P 0 ;1
L 3.5075 0.4075 3.5075 0.4075 9 P 0 ;1
L 3.5075 0.5575 3.5075 0.5575 9 P 0 ;1
L 3.5075 0.6075 3.5075 0.6075 9 P 0 ;1
L 3.5075 0.6575 3.5075 0.6575 9 P 0 ;1
L 3.5075 0.7075 3.5075 0.7075 9 P 0 ;1
L 3.5075 0.7575 3.5075 0.7575 9 P 0 ;1
L 3.5075 0.8075 3.5075 0.8075 9 P 0 ;1
L 3.5075 0.8575 3.5075 0.8575 9 P 0 ;1
L 3.5075 0.9075 3.5075 0.9075 9 P 0 ;1
L 3.5075 0.9575 3.5075 0.9575 9 P 0 ;1
L 3.5075 1.0075 3.5075 1.0075 9 P 0 ;1
L 3.5075 1.8075 3.5075 1.8075 9 P 0 ;1
L 3.5075 2.1075 3.5075 2.1075 9 P 0 ;1
L 3.5075 2.1575 3.5075 2.1575 9 P 0 ;1
L 3.5075 2.2075 3.5075 2.2075 9 P 0 ;1
L 3.5075 2.2575 3.5075 2.2575 9 P 0 ;1
L 3.5075 2.3075 3.5075 2.3075 9 P 0 ;1
L 3.5075 2.3575 3.5075 2.3575 9 P 0 ;1
L 3.5075 2.4075 3.5075 2.4075 9 P 0 ;1
L 3.5075 2.4575 3.5075 2.4575 9 P 0 ;1
L 3.5075 2.5075 3.5075 2.5075 9 P 0 ;1
L 3.5075 2.5575 3.5075 2.5575 9 P 0 ;1
L 3.5075 2.6075 3.5075 2.6075 9 P 0 ;1
L 3.5075 2.6575 3.5075 2.6575 9 P 0 ;1
L 3.5075 2.7075 3.5075 2.7075 9 P 0 ;1
L 3.5075 2.7575 3.5075 2.7575 9 P 0 ;1
L 3.5075 2.8075 3.5075 2.8075 9 P 0 ;1
L 3.5075 2.8575 3.5075 2.8575 9 P 0 ;1
L 3.5075 2.9075 3.5075 2.9075 9 P 0 ;1
L 3.5075 2.9575 3.5075 2.9575 9 P 0 ;1
L 3.5075 3.0075 3.5075 3.0075 9 P 0 ;1
L 3.5075 3.0575 3.5075 3.0575 9 P 0 ;1
L 3.5075 3.1075 3.5075 3.1075 9 P 0 ;1
L 3.5075 3.1575 3.5075 3.1575 9 P 0 ;1
L 3.5075 3.2075 3.5075 3.2075 9 P 0 ;1
L 3.5075 3.2575 3.5075 3.2575 9 P 0 ;1
L 3.5075 3.3075 3.5075 3.3075 9 P 0 ;1
L 3.5075 3.3575 3.5075 3.3575 9 P 0 ;1
L 3.5075 3.4075 3.5075 3.4075 9 P 0 ;1
L 3.5075 3.4575 3.5075 3.4575 9 P 0 ;1
L 3.5075 3.5075 3.5075 3.5075 9 P 0 ;1
L 3.5075 3.5575 3.5075 3.5575 9 P 0 ;1
L 3.5075 3.6075 3.5075 3.6075 9 P 0 ;1
L 3.5075 3.6575 3.5075 3.6575 9 P 0 ;1
L 3.5075 3.7075 3.5075 3.7075 9 P 0 ;1
L 3.5075 3.7575 3.5075 3.7575 9 P 0 ;1
L 3.5075 3.8075 3.5075 3.8075 9 P 0 ;1
L 3.5075 3.8575 3.5075 3.8575 9 P 0 ;1
L 3.5075 3.9075 3.5075 3.9075 9 P 0 ;1
L 3.5075 3.9575 3.5075 3.9575 9 P 0 ;1
L 3.5075 4.0075 3.5075 4.0075 9 P 0 ;1
L 3.5075 4.0575 3.5075 4.0575 9 P 0 ;1
L 3.5075 4.1075 3.5075 4.1075 9 P 0 ;1
L 3.5075 4.1575 3.5075 4.1575 9 P 0 ;1
L 3.5075 4.2075 3.5075 4.2075 9 P 0 ;1
L 3.5075 4.2575 3.5075 4.2575 9 P 0 ;1
L 3.5075 4.3075 3.5075 4.3075 9 P 0 ;1
L 3.5075 4.3575 3.5075 4.3575 9 P 0 ;1
L 3.5075 4.5075 3.5075 4.5075 9 P 0 ;1
L 3.5575 0.1575 3.5575 0.1575 9 P 0 ;1
L 3.5575 0.3075 3.5575 0.3075 9 P 0 ;1
L 3.5575 0.3575 3.5575 0.3575 9 P 0 ;1
L 3.5575 0.4075 3.5575 0.4075 9 P 0 ;1
L 3.5575 0.6075 3.5575 0.6075 9 P 0 ;1
L 3.5575 0.6575 3.5575 0.6575 9 P 0 ;1
L 3.5575 0.7575 3.5575 0.7575 9 P 0 ;1
L 3.5575 0.8075 3.5575 0.8075 9 P 0 ;1
L 3.5575 0.8575 3.5575 0.8575 9 P 0 ;1
L 3.5575 0.9075 3.5575 0.9075 9 P 0 ;1
L 3.5575 0.9575 3.5575 0.9575 9 P 0 ;1
L 3.5575 1.0075 3.5575 1.0075 9 P 0 ;1
L 3.5575 1.0575 3.5575 1.0575 9 P 0 ;1
L 3.5575 2.1075 3.5575 2.1075 9 P 0 ;1
L 3.5575 2.1575 3.5575 2.1575 9 P 0 ;1
L 3.5575 2.2075 3.5575 2.2075 9 P 0 ;1
L 3.5575 2.2575 3.5575 2.2575 9 P 0 ;1
L 3.5575 2.3075 3.5575 2.3075 9 P 0 ;1
L 3.5575 2.3575 3.5575 2.3575 9 P 0 ;1
L 3.5575 2.4075 3.5575 2.4075 9 P 0 ;1
L 3.5575 2.4575 3.5575 2.4575 9 P 0 ;1
L 3.5575 2.5075 3.5575 2.5075 9 P 0 ;1
L 3.5575 2.5575 3.5575 2.5575 9 P 0 ;1
L 3.5575 2.6075 3.5575 2.6075 9 P 0 ;1
L 3.5575 2.6575 3.5575 2.6575 9 P 0 ;1
L 3.5575 2.7075 3.5575 2.7075 9 P 0 ;1
L 3.5575 2.7575 3.5575 2.7575 9 P 0 ;1
L 3.5575 2.8075 3.5575 2.8075 9 P 0 ;1
L 3.5575 2.8575 3.5575 2.8575 9 P 0 ;1
L 3.5575 2.9075 3.5575 2.9075 9 P 0 ;1
L 3.5575 2.9575 3.5575 2.9575 9 P 0 ;1
L 3.5575 3.0075 3.5575 3.0075 9 P 0 ;1
L 3.5575 3.0575 3.5575 3.0575 9 P 0 ;1
L 3.5575 3.1075 3.5575 3.1075 9 P 0 ;1
L 3.5575 3.1575 3.5575 3.1575 9 P 0 ;1
L 3.5575 3.2075 3.5575 3.2075 9 P 0 ;1
L 3.5575 3.2575 3.5575 3.2575 9 P 0 ;1
L 3.5575 3.3075 3.5575 3.3075 9 P 0 ;1
L 3.5575 3.3575 3.5575 3.3575 9 P 0 ;1
L 3.5575 3.4075 3.5575 3.4075 9 P 0 ;1
L 3.5575 3.4575 3.5575 3.4575 9 P 0 ;1
L 3.5575 3.5075 3.5575 3.5075 9 P 0 ;1
L 3.5575 3.5575 3.5575 3.5575 9 P 0 ;1
L 3.5575 3.6075 3.5575 3.6075 9 P 0 ;1
L 3.5575 3.6575 3.5575 3.6575 9 P 0 ;1
L 3.5575 3.7075 3.5575 3.7075 9 P 0 ;1
L 3.5575 3.7575 3.5575 3.7575 9 P 0 ;1
L 3.5575 3.8075 3.5575 3.8075 9 P 0 ;1
L 3.5575 3.8575 3.5575 3.8575 9 P 0 ;1
L 3.5575 3.9075 3.5575 3.9075 9 P 0 ;1
L 3.5575 3.9575 3.5575 3.9575 9 P 0 ;1
L 3.5575 4.0075 3.5575 4.0075 9 P 0 ;1
L 3.5575 4.0575 3.5575 4.0575 9 P 0 ;1
L 3.5575 4.1075 3.5575 4.1075 9 P 0 ;1
L 3.5575 4.1575 3.5575 4.1575 9 P 0 ;1
L 3.5575 4.2075 3.5575 4.2075 9 P 0 ;1
L 3.5575 4.2575 3.5575 4.2575 9 P 0 ;1
L 3.5575 4.3075 3.5575 4.3075 9 P 0 ;1
L 3.5575 4.3575 3.5575 4.3575 9 P 0 ;1
L 3.6075 0.1575 3.6075 0.1575 9 P 0 ;1
L 3.6075 0.4075 3.6075 0.4075 9 P 0 ;1
L 3.6075 0.6075 3.6075 0.6075 9 P 0 ;1
L 3.6075 0.8075 3.6075 0.8075 9 P 0 ;1
L 3.6075 0.8575 3.6075 0.8575 9 P 0 ;1
L 3.6075 0.9075 3.6075 0.9075 9 P 0 ;1
L 3.6075 0.9575 3.6075 0.9575 9 P 0 ;1
L 3.6075 1.0075 3.6075 1.0075 9 P 0 ;1
L 3.6075 1.0575 3.6075 1.0575 9 P 0 ;1
L 3.6075 2.1075 3.6075 2.1075 9 P 0 ;1
L 3.6075 2.1575 3.6075 2.1575 9 P 0 ;1
L 3.6075 2.2075 3.6075 2.2075 9 P 0 ;1
L 3.6075 2.2575 3.6075 2.2575 9 P 0 ;1
L 3.6075 2.3075 3.6075 2.3075 9 P 0 ;1
L 3.6075 2.3575 3.6075 2.3575 9 P 0 ;1
L 3.6075 2.4075 3.6075 2.4075 9 P 0 ;1
L 3.6075 2.4575 3.6075 2.4575 9 P 0 ;1
L 3.6075 2.5075 3.6075 2.5075 9 P 0 ;1
L 3.6075 2.5575 3.6075 2.5575 9 P 0 ;1
L 3.6075 2.6075 3.6075 2.6075 9 P 0 ;1
L 3.6075 2.6575 3.6075 2.6575 9 P 0 ;1
L 3.6075 2.7075 3.6075 2.7075 9 P 0 ;1
L 3.6075 2.7575 3.6075 2.7575 9 P 0 ;1
L 3.6075 2.8075 3.6075 2.8075 9 P 0 ;1
L 3.6075 2.8575 3.6075 2.8575 9 P 0 ;1
L 3.6075 2.9075 3.6075 2.9075 9 P 0 ;1
L 3.6075 2.9575 3.6075 2.9575 9 P 0 ;1
L 3.6075 3.0075 3.6075 3.0075 9 P 0 ;1
L 3.6075 3.0575 3.6075 3.0575 9 P 0 ;1
L 3.6075 3.1075 3.6075 3.1075 9 P 0 ;1
L 3.6075 3.1575 3.6075 3.1575 9 P 0 ;1
L 3.6075 3.2075 3.6075 3.2075 9 P 0 ;1
L 3.6075 3.2575 3.6075 3.2575 9 P 0 ;1
L 3.6075 3.3075 3.6075 3.3075 9 P 0 ;1
L 3.6075 3.3575 3.6075 3.3575 9 P 0 ;1
L 3.6075 3.4075 3.6075 3.4075 9 P 0 ;1
L 3.6075 3.4575 3.6075 3.4575 9 P 0 ;1
L 3.6075 3.5075 3.6075 3.5075 9 P 0 ;1
L 3.6075 3.5575 3.6075 3.5575 9 P 0 ;1
L 3.6075 3.6075 3.6075 3.6075 9 P 0 ;1
L 3.6075 3.6575 3.6075 3.6575 9 P 0 ;1
L 3.6075 3.7075 3.6075 3.7075 9 P 0 ;1
L 3.6075 3.7575 3.6075 3.7575 9 P 0 ;1
L 3.6075 3.8075 3.6075 3.8075 9 P 0 ;1
L 3.6075 3.8575 3.6075 3.8575 9 P 0 ;1
L 3.6075 3.9075 3.6075 3.9075 9 P 0 ;1
L 3.6075 3.9575 3.6075 3.9575 9 P 0 ;1
L 3.6075 4.0075 3.6075 4.0075 9 P 0 ;1
L 3.6075 4.0575 3.6075 4.0575 9 P 0 ;1
L 3.6075 4.1075 3.6075 4.1075 9 P 0 ;1
L 3.6075 4.1575 3.6075 4.1575 9 P 0 ;1
L 3.6075 4.2075 3.6075 4.2075 9 P 0 ;1
L 3.6075 4.2575 3.6075 4.2575 9 P 0 ;1
L 3.6075 4.3075 3.6075 4.3075 9 P 0 ;1
L 3.6075 4.3575 3.6075 4.3575 9 P 0 ;1
L 3.6075 4.5575 3.6075 4.5575 9 P 0 ;1
L 3.6575 0.1575 3.6575 0.1575 9 P 0 ;1
L 3.6575 0.6075 3.6575 0.6075 9 P 0 ;1
L 3.6575 0.8575 3.6575 0.8575 9 P 0 ;1
L 3.6575 0.9075 3.6575 0.9075 9 P 0 ;1
L 3.6575 0.9575 3.6575 0.9575 9 P 0 ;1
L 3.6575 1.0075 3.6575 1.0075 9 P 0 ;1
L 3.6575 1.0575 3.6575 1.0575 9 P 0 ;1
L 3.6575 1.1075 3.6575 1.1075 9 P 0 ;1
L 3.6575 2.1075 3.6575 2.1075 9 P 0 ;1
L 3.6575 2.1575 3.6575 2.1575 9 P 0 ;1
L 3.6575 2.2075 3.6575 2.2075 9 P 0 ;1
L 3.6575 2.2575 3.6575 2.2575 9 P 0 ;1
L 3.6575 2.3075 3.6575 2.3075 9 P 0 ;1
L 3.6575 2.3575 3.6575 2.3575 9 P 0 ;1
L 3.6575 2.4075 3.6575 2.4075 9 P 0 ;1
L 3.6575 2.4575 3.6575 2.4575 9 P 0 ;1
L 3.6575 2.5075 3.6575 2.5075 9 P 0 ;1
L 3.6575 2.5575 3.6575 2.5575 9 P 0 ;1
L 3.6575 2.6075 3.6575 2.6075 9 P 0 ;1
L 3.6575 2.6575 3.6575 2.6575 9 P 0 ;1
L 3.6575 2.7075 3.6575 2.7075 9 P 0 ;1
L 3.6575 2.7575 3.6575 2.7575 9 P 0 ;1
L 3.6575 2.8075 3.6575 2.8075 9 P 0 ;1
L 3.6575 2.8575 3.6575 2.8575 9 P 0 ;1
L 3.6575 2.9075 3.6575 2.9075 9 P 0 ;1
L 3.6575 2.9575 3.6575 2.9575 9 P 0 ;1
L 3.6575 3.0075 3.6575 3.0075 9 P 0 ;1
L 3.6575 3.0575 3.6575 3.0575 9 P 0 ;1
L 3.6575 3.1075 3.6575 3.1075 9 P 0 ;1
L 3.6575 3.1575 3.6575 3.1575 9 P 0 ;1
L 3.6575 3.2075 3.6575 3.2075 9 P 0 ;1
L 3.6575 3.2575 3.6575 3.2575 9 P 0 ;1
L 3.6575 3.3075 3.6575 3.3075 9 P 0 ;1
L 3.6575 3.3575 3.6575 3.3575 9 P 0 ;1
L 3.6575 3.4075 3.6575 3.4075 9 P 0 ;1
L 3.6575 3.4575 3.6575 3.4575 9 P 0 ;1
L 3.6575 3.5075 3.6575 3.5075 9 P 0 ;1
L 3.6575 3.5575 3.6575 3.5575 9 P 0 ;1
L 3.6575 3.6075 3.6575 3.6075 9 P 0 ;1
L 3.6575 3.6575 3.6575 3.6575 9 P 0 ;1
L 3.6575 3.7075 3.6575 3.7075 9 P 0 ;1
L 3.6575 3.7575 3.6575 3.7575 9 P 0 ;1
L 3.6575 3.8075 3.6575 3.8075 9 P 0 ;1
L 3.6575 3.8575 3.6575 3.8575 9 P 0 ;1
L 3.6575 3.9075 3.6575 3.9075 9 P 0 ;1
L 3.6575 3.9575 3.6575 3.9575 9 P 0 ;1
L 3.6575 4.0075 3.6575 4.0075 9 P 0 ;1
L 3.6575 4.0575 3.6575 4.0575 9 P 0 ;1
L 3.6575 4.1075 3.6575 4.1075 9 P 0 ;1
L 3.6575 4.1575 3.6575 4.1575 9 P 0 ;1
L 3.6575 4.2075 3.6575 4.2075 9 P 0 ;1
L 3.6575 4.2575 3.6575 4.2575 9 P 0 ;1
L 3.6575 4.3075 3.6575 4.3075 9 P 0 ;1
L 3.6575 4.3575 3.6575 4.3575 9 P 0 ;1
L 3.7075 0.1575 3.7075 0.1575 9 P 0 ;1
L 3.7075 0.5575 3.7075 0.5575 9 P 0 ;1
L 3.7075 0.6075 3.7075 0.6075 9 P 0 ;1
L 3.7075 0.8575 3.7075 0.8575 9 P 0 ;1
L 3.7075 0.9075 3.7075 0.9075 9 P 0 ;1
L 3.7075 0.9575 3.7075 0.9575 9 P 0 ;1
L 3.7075 1.0075 3.7075 1.0075 9 P 0 ;1
L 3.7075 1.0575 3.7075 1.0575 9 P 0 ;1
L 3.7075 1.1075 3.7075 1.1075 9 P 0 ;1
L 3.7075 1.1575 3.7075 1.1575 9 P 0 ;1
L 3.7075 2.1575 3.7075 2.1575 9 P 0 ;1
L 3.7075 2.2075 3.7075 2.2075 9 P 0 ;1
L 3.7075 2.2575 3.7075 2.2575 9 P 0 ;1
L 3.7075 2.3075 3.7075 2.3075 9 P 0 ;1
L 3.7075 2.3575 3.7075 2.3575 9 P 0 ;1
L 3.7075 2.4075 3.7075 2.4075 9 P 0 ;1
L 3.7075 2.4575 3.7075 2.4575 9 P 0 ;1
L 3.7075 2.5075 3.7075 2.5075 9 P 0 ;1
L 3.7075 2.5575 3.7075 2.5575 9 P 0 ;1
L 3.7075 2.6075 3.7075 2.6075 9 P 0 ;1
L 3.7075 2.6575 3.7075 2.6575 9 P 0 ;1
L 3.7075 2.7075 3.7075 2.7075 9 P 0 ;1
L 3.7075 2.7575 3.7075 2.7575 9 P 0 ;1
L 3.7075 2.8075 3.7075 2.8075 9 P 0 ;1
L 3.7075 2.8575 3.7075 2.8575 9 P 0 ;1
L 3.7075 2.9075 3.7075 2.9075 9 P 0 ;1
L 3.7075 2.9575 3.7075 2.9575 9 P 0 ;1
L 3.7075 3.0075 3.7075 3.0075 9 P 0 ;1
L 3.7075 3.0575 3.7075 3.0575 9 P 0 ;1
L 3.7075 3.1075 3.7075 3.1075 9 P 0 ;1
L 3.7075 3.1575 3.7075 3.1575 9 P 0 ;1
L 3.7075 3.2075 3.7075 3.2075 9 P 0 ;1
L 3.7075 3.2575 3.7075 3.2575 9 P 0 ;1
L 3.7075 3.3075 3.7075 3.3075 9 P 0 ;1
L 3.7075 3.3575 3.7075 3.3575 9 P 0 ;1
L 3.7075 3.4075 3.7075 3.4075 9 P 0 ;1
L 3.7075 3.4575 3.7075 3.4575 9 P 0 ;1
L 3.7075 3.5075 3.7075 3.5075 9 P 0 ;1
L 3.7075 3.5575 3.7075 3.5575 9 P 0 ;1
L 3.7075 3.6075 3.7075 3.6075 9 P 0 ;1
L 3.7075 3.6575 3.7075 3.6575 9 P 0 ;1
L 3.7075 3.7075 3.7075 3.7075 9 P 0 ;1
L 3.7075 3.7575 3.7075 3.7575 9 P 0 ;1
L 3.7075 3.8075 3.7075 3.8075 9 P 0 ;1
L 3.7075 3.8575 3.7075 3.8575 9 P 0 ;1
L 3.7075 3.9075 3.7075 3.9075 9 P 0 ;1
L 3.7075 3.9575 3.7075 3.9575 9 P 0 ;1
L 3.7075 4.0075 3.7075 4.0075 9 P 0 ;1
L 3.7075 4.0575 3.7075 4.0575 9 P 0 ;1
L 3.7075 4.1075 3.7075 4.1075 9 P 0 ;1
L 3.7075 4.1575 3.7075 4.1575 9 P 0 ;1
L 3.7075 4.2075 3.7075 4.2075 9 P 0 ;1
L 3.7075 4.2575 3.7075 4.2575 9 P 0 ;1
L 3.7075 4.3075 3.7075 4.3075 9 P 0 ;1
L 3.7075 4.3575 3.7075 4.3575 9 P 0 ;1
L 3.7575 0.1575 3.7575 0.1575 9 P 0 ;1
L 3.7575 0.4575 3.7575 0.4575 9 P 0 ;1
L 3.7575 0.5075 3.7575 0.5075 9 P 0 ;1
L 3.7575 0.5575 3.7575 0.5575 9 P 0 ;1
L 3.7575 0.6075 3.7575 0.6075 9 P 0 ;1
L 3.7575 0.8575 3.7575 0.8575 9 P 0 ;1
L 3.7575 0.9075 3.7575 0.9075 9 P 0 ;1
L 3.7575 0.9575 3.7575 0.9575 9 P 0 ;1
L 3.7575 1.0075 3.7575 1.0075 9 P 0 ;1
L 3.7575 1.0575 3.7575 1.0575 9 P 0 ;1
L 3.7575 1.1075 3.7575 1.1075 9 P 0 ;1
L 3.7575 1.1575 3.7575 1.1575 9 P 0 ;1
L 3.7575 2.2075 3.7575 2.2075 9 P 0 ;1
L 3.7575 2.2575 3.7575 2.2575 9 P 0 ;1
L 3.7575 2.3075 3.7575 2.3075 9 P 0 ;1
L 3.7575 2.3575 3.7575 2.3575 9 P 0 ;1
L 3.7575 2.4075 3.7575 2.4075 9 P 0 ;1
L 3.7575 2.4575 3.7575 2.4575 9 P 0 ;1
L 3.7575 2.5075 3.7575 2.5075 9 P 0 ;1
L 3.7575 2.5575 3.7575 2.5575 9 P 0 ;1
L 3.7575 2.6075 3.7575 2.6075 9 P 0 ;1
L 3.7575 2.6575 3.7575 2.6575 9 P 0 ;1
L 3.7575 2.7075 3.7575 2.7075 9 P 0 ;1
L 3.7575 2.7575 3.7575 2.7575 9 P 0 ;1
L 3.7575 2.8075 3.7575 2.8075 9 P 0 ;1
L 3.7575 2.8575 3.7575 2.8575 9 P 0 ;1
L 3.7575 2.9075 3.7575 2.9075 9 P 0 ;1
L 3.7575 2.9575 3.7575 2.9575 9 P 0 ;1
L 3.7575 3.0075 3.7575 3.0075 9 P 0 ;1
L 3.7575 3.0575 3.7575 3.0575 9 P 0 ;1
L 3.7575 3.1075 3.7575 3.1075 9 P 0 ;1
L 3.7575 3.1575 3.7575 3.1575 9 P 0 ;1
L 3.7575 3.2075 3.7575 3.2075 9 P 0 ;1
L 3.7575 3.2575 3.7575 3.2575 9 P 0 ;1
L 3.7575 3.3075 3.7575 3.3075 9 P 0 ;1
L 3.7575 3.3575 3.7575 3.3575 9 P 0 ;1
L 3.7575 3.4075 3.7575 3.4075 9 P 0 ;1
L 3.7575 3.4575 3.7575 3.4575 9 P 0 ;1
L 3.7575 3.5075 3.7575 3.5075 9 P 0 ;1
L 3.7575 3.5575 3.7575 3.5575 9 P 0 ;1
L 3.7575 3.6075 3.7575 3.6075 9 P 0 ;1
L 3.7575 3.6575 3.7575 3.6575 9 P 0 ;1
L 3.7575 3.7075 3.7575 3.7075 9 P 0 ;1
L 3.7575 3.7575 3.7575 3.7575 9 P 0 ;1
L 3.7575 3.8075 3.7575 3.8075 9 P 0 ;1
L 3.7575 3.8575 3.7575 3.8575 9 P 0 ;1
L 3.7575 3.9075 3.7575 3.9075 9 P 0 ;1
L 3.7575 3.9575 3.7575 3.9575 9 P 0 ;1
L 3.7575 4.0075 3.7575 4.0075 9 P 0 ;1
L 3.7575 4.0575 3.7575 4.0575 9 P 0 ;1
L 3.7575 4.1075 3.7575 4.1075 9 P 0 ;1
L 3.7575 4.1575 3.7575 4.1575 9 P 0 ;1
L 3.7575 4.2075 3.7575 4.2075 9 P 0 ;1
L 3.7575 4.2575 3.7575 4.2575 9 P 0 ;1
L 3.7575 4.3075 3.7575 4.3075 9 P 0 ;1
L 3.7575 4.3575 3.7575 4.3575 9 P 0 ;1
L 3.8075 0.1575 3.8075 0.1575 9 P 0 ;1
L 3.8075 0.4575 3.8075 0.4575 9 P 0 ;1
L 3.8075 0.5075 3.8075 0.5075 9 P 0 ;1
L 3.8075 0.5575 3.8075 0.5575 9 P 0 ;1
L 3.8075 0.6075 3.8075 0.6075 9 P 0 ;1
L 3.8075 0.8575 3.8075 0.8575 9 P 0 ;1
L 3.8075 0.9075 3.8075 0.9075 9 P 0 ;1
L 3.8075 0.9575 3.8075 0.9575 9 P 0 ;1
L 3.8075 1.0075 3.8075 1.0075 9 P 0 ;1
L 3.8075 1.0575 3.8075 1.0575 9 P 0 ;1
L 3.8075 1.1075 3.8075 1.1075 9 P 0 ;1
L 3.8075 1.1575 3.8075 1.1575 9 P 0 ;1
L 3.8075 1.2075 3.8075 1.2075 9 P 0 ;1
L 3.8075 2.2075 3.8075 2.2075 9 P 0 ;1
L 3.8075 2.2575 3.8075 2.2575 9 P 0 ;1
L 3.8075 2.3075 3.8075 2.3075 9 P 0 ;1
L 3.8075 2.3575 3.8075 2.3575 9 P 0 ;1
L 3.8075 2.4075 3.8075 2.4075 9 P 0 ;1
L 3.8075 2.4575 3.8075 2.4575 9 P 0 ;1
L 3.8075 2.5075 3.8075 2.5075 9 P 0 ;1
L 3.8075 2.5575 3.8075 2.5575 9 P 0 ;1
L 3.8075 2.7075 3.8075 2.7075 9 P 0 ;1
L 3.8075 2.7575 3.8075 2.7575 9 P 0 ;1
L 3.8075 2.8075 3.8075 2.8075 9 P 0 ;1
L 3.8075 2.8575 3.8075 2.8575 9 P 0 ;1
L 3.8075 2.9075 3.8075 2.9075 9 P 0 ;1
L 3.8075 2.9575 3.8075 2.9575 9 P 0 ;1
L 3.8075 3.0075 3.8075 3.0075 9 P 0 ;1
L 3.8075 3.0575 3.8075 3.0575 9 P 0 ;1
L 3.8075 3.1075 3.8075 3.1075 9 P 0 ;1
L 3.8075 3.1575 3.8075 3.1575 9 P 0 ;1
L 3.8075 3.2075 3.8075 3.2075 9 P 0 ;1
L 3.8075 3.2575 3.8075 3.2575 9 P 0 ;1
L 3.8075 3.3075 3.8075 3.3075 9 P 0 ;1
L 3.8075 3.3575 3.8075 3.3575 9 P 0 ;1
L 3.8075 3.4075 3.8075 3.4075 9 P 0 ;1
L 3.8075 3.4575 3.8075 3.4575 9 P 0 ;1
L 3.8075 3.5075 3.8075 3.5075 9 P 0 ;1
L 3.8075 3.5575 3.8075 3.5575 9 P 0 ;1
L 3.8075 3.6075 3.8075 3.6075 9 P 0 ;1
L 3.8075 3.6575 3.8075 3.6575 9 P 0 ;1
L 3.8075 3.7075 3.8075 3.7075 9 P 0 ;1
L 3.8075 3.7575 3.8075 3.7575 9 P 0 ;1
L 3.8075 3.8075 3.8075 3.8075 9 P 0 ;1
L 3.8075 3.8575 3.8075 3.8575 9 P 0 ;1
L 3.8075 3.9075 3.8075 3.9075 9 P 0 ;1
L 3.8075 3.9575 3.8075 3.9575 9 P 0 ;1
L 3.8075 4.0075 3.8075 4.0075 9 P 0 ;1
L 3.8075 4.0575 3.8075 4.0575 9 P 0 ;1
L 3.8075 4.1075 3.8075 4.1075 9 P 0 ;1
L 3.8075 4.1575 3.8075 4.1575 9 P 0 ;1
L 3.8075 4.2075 3.8075 4.2075 9 P 0 ;1
L 3.8075 4.2575 3.8075 4.2575 9 P 0 ;1
L 3.8075 4.3075 3.8075 4.3075 9 P 0 ;1
L 3.8075 4.3575 3.8075 4.3575 9 P 0 ;1
L 3.8075 4.4075 3.8075 4.4075 9 P 0 ;1
L 3.8075 4.4575 3.8075 4.4575 9 P 0 ;1
L 3.8075 4.5075 3.8075 4.5075 9 P 0 ;1
L 3.8575 0.1575 3.8575 0.1575 9 P 0 ;1
L 3.8575 0.2075 3.8575 0.2075 9 P 0 ;1
L 3.8575 0.2575 3.8575 0.2575 9 P 0 ;1
L 3.8575 0.3075 3.8575 0.3075 9 P 0 ;1
L 3.8575 0.3575 3.8575 0.3575 9 P 0 ;1
L 3.8575 0.4075 3.8575 0.4075 9 P 0 ;1
L 3.8575 0.4575 3.8575 0.4575 9 P 0 ;1
L 3.8575 0.5075 3.8575 0.5075 9 P 0 ;1
L 3.8575 0.5575 3.8575 0.5575 9 P 0 ;1
L 3.8575 0.6075 3.8575 0.6075 9 P 0 ;1
L 3.8575 0.8575 3.8575 0.8575 9 P 0 ;1
L 3.8575 0.9075 3.8575 0.9075 9 P 0 ;1
L 3.8575 0.9575 3.8575 0.9575 9 P 0 ;1
L 3.8575 1.0075 3.8575 1.0075 9 P 0 ;1
L 3.8575 1.0575 3.8575 1.0575 9 P 0 ;1
L 3.8575 1.1075 3.8575 1.1075 9 P 0 ;1
L 3.8575 1.1575 3.8575 1.1575 9 P 0 ;1
L 3.8575 1.2075 3.8575 1.2075 9 P 0 ;1
L 3.8575 1.2575 3.8575 1.2575 9 P 0 ;1
L 3.8575 2.2575 3.8575 2.2575 9 P 0 ;1
L 3.8575 2.3075 3.8575 2.3075 9 P 0 ;1
L 3.8575 2.3575 3.8575 2.3575 9 P 0 ;1
L 3.8575 2.4075 3.8575 2.4075 9 P 0 ;1
L 3.8575 2.4575 3.8575 2.4575 9 P 0 ;1
L 3.8575 2.5075 3.8575 2.5075 9 P 0 ;1
L 3.8575 2.5575 3.8575 2.5575 9 P 0 ;1
L 3.8575 2.7575 3.8575 2.7575 9 P 0 ;1
L 3.8575 2.8075 3.8575 2.8075 9 P 0 ;1
L 3.8575 2.8575 3.8575 2.8575 9 P 0 ;1
L 3.8575 2.9075 3.8575 2.9075 9 P 0 ;1
L 3.8575 2.9575 3.8575 2.9575 9 P 0 ;1
L 3.8575 3.0075 3.8575 3.0075 9 P 0 ;1
L 3.8575 3.0575 3.8575 3.0575 9 P 0 ;1
L 3.8575 3.1075 3.8575 3.1075 9 P 0 ;1
L 3.8575 3.1575 3.8575 3.1575 9 P 0 ;1
L 3.8575 3.2075 3.8575 3.2075 9 P 0 ;1
L 3.8575 3.2575 3.8575 3.2575 9 P 0 ;1
L 3.8575 3.3075 3.8575 3.3075 9 P 0 ;1
L 3.8575 3.3575 3.8575 3.3575 9 P 0 ;1
L 3.8575 3.4075 3.8575 3.4075 9 P 0 ;1
L 3.8575 3.4575 3.8575 3.4575 9 P 0 ;1
L 3.8575 3.5075 3.8575 3.5075 9 P 0 ;1
L 3.8575 3.5575 3.8575 3.5575 9 P 0 ;1
L 3.8575 3.6075 3.8575 3.6075 9 P 0 ;1
L 3.8575 3.6575 3.8575 3.6575 9 P 0 ;1
L 3.8575 3.7075 3.8575 3.7075 9 P 0 ;1
L 3.8575 3.7575 3.8575 3.7575 9 P 0 ;1
L 3.8575 3.8075 3.8575 3.8075 9 P 0 ;1
L 3.8575 3.8575 3.8575 3.8575 9 P 0 ;1
L 3.8575 3.9075 3.8575 3.9075 9 P 0 ;1
L 3.8575 3.9575 3.8575 3.9575 9 P 0 ;1
L 3.8575 4.0075 3.8575 4.0075 9 P 0 ;1
L 3.8575 4.0575 3.8575 4.0575 9 P 0 ;1
L 3.8575 4.1075 3.8575 4.1075 9 P 0 ;1
L 3.8575 4.1575 3.8575 4.1575 9 P 0 ;1
L 3.8575 4.2075 3.8575 4.2075 9 P 0 ;1
L 3.8575 4.2575 3.8575 4.2575 9 P 0 ;1
L 3.8575 4.3075 3.8575 4.3075 9 P 0 ;1
L 3.8575 4.3575 3.8575 4.3575 9 P 0 ;1
L 3.8575 4.4075 3.8575 4.4075 9 P 0 ;1
L 3.8575 4.4575 3.8575 4.4575 9 P 0 ;1
L 3.9075 0.1575 3.9075 0.1575 9 P 0 ;1
L 3.9075 0.2075 3.9075 0.2075 9 P 0 ;1
L 3.9075 0.2575 3.9075 0.2575 9 P 0 ;1
L 3.9075 0.3075 3.9075 0.3075 9 P 0 ;1
L 3.9075 0.3575 3.9075 0.3575 9 P 0 ;1
L 3.9075 0.4075 3.9075 0.4075 9 P 0 ;1
L 3.9075 0.4575 3.9075 0.4575 9 P 0 ;1
L 3.9075 0.5075 3.9075 0.5075 9 P 0 ;1
L 3.9075 0.5575 3.9075 0.5575 9 P 0 ;1
L 3.9075 0.6075 3.9075 0.6075 9 P 0 ;1
L 3.9075 0.8575 3.9075 0.8575 9 P 0 ;1
L 3.9075 0.9075 3.9075 0.9075 9 P 0 ;1
L 3.9075 0.9575 3.9075 0.9575 9 P 0 ;1
L 3.9075 1.0075 3.9075 1.0075 9 P 0 ;1
L 3.9075 1.0575 3.9075 1.0575 9 P 0 ;1
L 3.9075 1.1075 3.9075 1.1075 9 P 0 ;1
L 3.9075 1.1575 3.9075 1.1575 9 P 0 ;1
L 3.9075 1.2075 3.9075 1.2075 9 P 0 ;1
L 3.9075 1.2575 3.9075 1.2575 9 P 0 ;1
L 3.9075 1.3075 3.9075 1.3075 9 P 0 ;1
L 3.9075 2.3075 3.9075 2.3075 9 P 0 ;1
L 3.9075 2.3575 3.9075 2.3575 9 P 0 ;1
L 3.9075 2.4075 3.9075 2.4075 9 P 0 ;1
L 3.9075 2.4575 3.9075 2.4575 9 P 0 ;1
L 3.9075 2.5075 3.9075 2.5075 9 P 0 ;1
L 3.9075 2.5575 3.9075 2.5575 9 P 0 ;1
L 3.9075 2.7575 3.9075 2.7575 9 P 0 ;1
L 3.9075 2.8075 3.9075 2.8075 9 P 0 ;1
L 3.9075 2.8575 3.9075 2.8575 9 P 0 ;1
L 3.9075 2.9075 3.9075 2.9075 9 P 0 ;1
L 3.9075 2.9575 3.9075 2.9575 9 P 0 ;1
L 3.9075 3.0075 3.9075 3.0075 9 P 0 ;1
L 3.9075 3.0575 3.9075 3.0575 9 P 0 ;1
L 3.9075 3.1075 3.9075 3.1075 9 P 0 ;1
L 3.9075 3.1575 3.9075 3.1575 9 P 0 ;1
L 3.9075 3.2075 3.9075 3.2075 9 P 0 ;1
L 3.9075 3.2575 3.9075 3.2575 9 P 0 ;1
L 3.9075 3.3075 3.9075 3.3075 9 P 0 ;1
L 3.9075 3.3575 3.9075 3.3575 9 P 0 ;1
L 3.9075 3.4075 3.9075 3.4075 9 P 0 ;1
L 3.9075 3.4575 3.9075 3.4575 9 P 0 ;1
L 3.9075 3.5075 3.9075 3.5075 9 P 0 ;1
L 3.9075 3.5575 3.9075 3.5575 9 P 0 ;1
L 3.9075 3.6075 3.9075 3.6075 9 P 0 ;1
L 3.9075 3.6575 3.9075 3.6575 9 P 0 ;1
L 3.9075 3.7075 3.9075 3.7075 9 P 0 ;1
L 3.9075 3.7575 3.9075 3.7575 9 P 0 ;1
L 3.9075 3.8075 3.9075 3.8075 9 P 0 ;1
L 3.9075 3.8575 3.9075 3.8575 9 P 0 ;1
L 3.9075 3.9075 3.9075 3.9075 9 P 0 ;1
L 3.9075 3.9575 3.9075 3.9575 9 P 0 ;1
L 3.9075 4.0075 3.9075 4.0075 9 P 0 ;1
L 3.9075 4.0575 3.9075 4.0575 9 P 0 ;1
L 3.9075 4.1075 3.9075 4.1075 9 P 0 ;1
L 3.9075 4.1575 3.9075 4.1575 9 P 0 ;1
L 3.9075 4.2075 3.9075 4.2075 9 P 0 ;1
L 3.9075 4.2575 3.9075 4.2575 9 P 0 ;1
L 3.9575 0.1575 3.9575 0.1575 9 P 0 ;1
L 3.9575 0.2075 3.9575 0.2075 9 P 0 ;1
L 3.9575 0.2575 3.9575 0.2575 9 P 0 ;1
L 3.9575 0.3075 3.9575 0.3075 9 P 0 ;1
L 3.9575 0.3575 3.9575 0.3575 9 P 0 ;1
L 3.9575 0.4075 3.9575 0.4075 9 P 0 ;1
L 3.9575 0.4575 3.9575 0.4575 9 P 0 ;1
L 3.9575 0.5075 3.9575 0.5075 9 P 0 ;1
L 3.9575 0.5575 3.9575 0.5575 9 P 0 ;1
L 3.9575 0.6075 3.9575 0.6075 9 P 0 ;1
L 3.9575 0.6575 3.9575 0.6575 9 P 0 ;1
L 3.9575 0.7075 3.9575 0.7075 9 P 0 ;1
L 3.9575 0.7575 3.9575 0.7575 9 P 0 ;1
L 3.9575 0.8075 3.9575 0.8075 9 P 0 ;1
L 3.9575 0.8575 3.9575 0.8575 9 P 0 ;1
L 3.9575 0.9075 3.9575 0.9075 9 P 0 ;1
L 3.9575 0.9575 3.9575 0.9575 9 P 0 ;1
L 3.9575 1.0075 3.9575 1.0075 9 P 0 ;1
L 3.9575 1.0575 3.9575 1.0575 9 P 0 ;1
L 3.9575 1.1075 3.9575 1.1075 9 P 0 ;1
L 3.9575 1.1575 3.9575 1.1575 9 P 0 ;1
L 3.9575 1.2075 3.9575 1.2075 9 P 0 ;1
L 3.9575 1.2575 3.9575 1.2575 9 P 0 ;1
L 3.9575 1.3075 3.9575 1.3075 9 P 0 ;1
L 3.9575 2.3075 3.9575 2.3075 9 P 0 ;1
L 3.9575 2.3575 3.9575 2.3575 9 P 0 ;1
L 3.9575 2.4075 3.9575 2.4075 9 P 0 ;1
L 3.9575 2.4575 3.9575 2.4575 9 P 0 ;1
L 3.9575 2.5075 3.9575 2.5075 9 P 0 ;1
L 3.9575 2.6575 3.9575 2.6575 9 P 0 ;1
L 3.9575 2.7075 3.9575 2.7075 9 P 0 ;1
L 4.0075 0.1575 4.0075 0.1575 9 P 0 ;1
L 4.0075 0.2075 4.0075 0.2075 9 P 0 ;1
L 4.0075 0.2575 4.0075 0.2575 9 P 0 ;1
L 4.0075 0.3075 4.0075 0.3075 9 P 0 ;1
L 4.0075 0.3575 4.0075 0.3575 9 P 0 ;1
L 4.0075 0.4075 4.0075 0.4075 9 P 0 ;1
L 4.0075 0.4575 4.0075 0.4575 9 P 0 ;1
L 4.0075 0.5075 4.0075 0.5075 9 P 0 ;1
L 4.0075 0.5575 4.0075 0.5575 9 P 0 ;1
L 4.0075 0.6075 4.0075 0.6075 9 P 0 ;1
L 4.0075 0.6575 4.0075 0.6575 9 P 0 ;1
L 4.0075 0.7075 4.0075 0.7075 9 P 0 ;1
L 4.0075 0.7575 4.0075 0.7575 9 P 0 ;1
L 4.0075 0.8075 4.0075 0.8075 9 P 0 ;1
L 4.0075 0.8575 4.0075 0.8575 9 P 0 ;1
L 4.0075 0.9075 4.0075 0.9075 9 P 0 ;1
L 4.0075 0.9575 4.0075 0.9575 9 P 0 ;1
L 4.0075 1.0075 4.0075 1.0075 9 P 0 ;1
L 4.0075 1.0575 4.0075 1.0575 9 P 0 ;1
L 4.0075 1.1075 4.0075 1.1075 9 P 0 ;1
L 4.0075 1.1575 4.0075 1.1575 9 P 0 ;1
L 4.0075 1.2075 4.0075 1.2075 9 P 0 ;1
L 4.0075 1.2575 4.0075 1.2575 9 P 0 ;1
L 4.0075 1.3075 4.0075 1.3075 9 P 0 ;1
L 4.0075 1.3575 4.0075 1.3575 9 P 0 ;1
L 4.0075 2.3575 4.0075 2.3575 9 P 0 ;1
L 4.0075 2.4075 4.0075 2.4075 9 P 0 ;1
L 4.0075 2.4575 4.0075 2.4575 9 P 0 ;1
L 4.0575 0.1575 4.0575 0.1575 9 P 0 ;1
L 4.0575 0.2075 4.0575 0.2075 9 P 0 ;1
L 4.0575 0.2575 4.0575 0.2575 9 P 0 ;1
L 4.0575 0.3075 4.0575 0.3075 9 P 0 ;1
L 4.0575 0.3575 4.0575 0.3575 9 P 0 ;1
L 4.0575 0.4075 4.0575 0.4075 9 P 0 ;1
L 4.0575 0.4575 4.0575 0.4575 9 P 0 ;1
L 4.0575 0.5075 4.0575 0.5075 9 P 0 ;1
L 4.0575 0.5575 4.0575 0.5575 9 P 0 ;1
L 4.0575 0.6075 4.0575 0.6075 9 P 0 ;1
L 4.0575 0.6575 4.0575 0.6575 9 P 0 ;1
L 4.0575 0.7075 4.0575 0.7075 9 P 0 ;1
L 4.0575 0.7575 4.0575 0.7575 9 P 0 ;1
L 4.0575 0.8075 4.0575 0.8075 9 P 0 ;1
L 4.0575 0.8575 4.0575 0.8575 9 P 0 ;1
L 4.0575 0.9075 4.0575 0.9075 9 P 0 ;1
L 4.0575 0.9575 4.0575 0.9575 9 P 0 ;1
L 4.0575 1.0075 4.0575 1.0075 9 P 0 ;1
L 4.0575 1.0575 4.0575 1.0575 9 P 0 ;1
L 4.0575 1.1075 4.0575 1.1075 9 P 0 ;1
L 4.0575 1.1575 4.0575 1.1575 9 P 0 ;1
L 4.0575 1.2075 4.0575 1.2075 9 P 0 ;1
L 4.0575 1.2575 4.0575 1.2575 9 P 0 ;1
L 4.0575 1.3075 4.0575 1.3075 9 P 0 ;1
L 4.0575 1.3575 4.0575 1.3575 9 P 0 ;1
L 4.0575 1.4075 4.0575 1.4075 9 P 0 ;1
L 4.0575 2.4075 4.0575 2.4075 9 P 0 ;1
L 4.0575 2.4575 4.0575 2.4575 9 P 0 ;1
L 4.0575 4.5075 4.0575 4.5075 9 P 0 ;1
L 4.1075 0.1575 4.1075 0.1575 9 P 0 ;1
L 4.1075 0.2075 4.1075 0.2075 9 P 0 ;1
L 4.1075 0.2575 4.1075 0.2575 9 P 0 ;1
L 4.1075 0.3075 4.1075 0.3075 9 P 0 ;1
L 4.1075 0.3575 4.1075 0.3575 9 P 0 ;1
L 4.1075 0.4075 4.1075 0.4075 9 P 0 ;1
L 4.1075 0.4575 4.1075 0.4575 9 P 0 ;1
L 4.1075 0.5075 4.1075 0.5075 9 P 0 ;1
L 4.1075 0.5575 4.1075 0.5575 9 P 0 ;1
L 4.1075 0.6075 4.1075 0.6075 9 P 0 ;1
L 4.1075 0.6575 4.1075 0.6575 9 P 0 ;1
L 4.1075 0.7075 4.1075 0.7075 9 P 0 ;1
L 4.1075 0.7575 4.1075 0.7575 9 P 0 ;1
L 4.1075 0.8075 4.1075 0.8075 9 P 0 ;1
L 4.1075 0.8575 4.1075 0.8575 9 P 0 ;1
L 4.1075 0.9075 4.1075 0.9075 9 P 0 ;1
L 4.1075 0.9575 4.1075 0.9575 9 P 0 ;1
L 4.1075 1.0075 4.1075 1.0075 9 P 0 ;1
L 4.1075 1.0575 4.1075 1.0575 9 P 0 ;1
L 4.1075 1.1075 4.1075 1.1075 9 P 0 ;1
L 4.1075 1.1575 4.1075 1.1575 9 P 0 ;1
L 4.1075 1.2075 4.1075 1.2075 9 P 0 ;1
L 4.1075 1.2575 4.1075 1.2575 9 P 0 ;1
L 4.1075 1.3075 4.1075 1.3075 9 P 0 ;1
L 4.1075 1.3575 4.1075 1.3575 9 P 0 ;1
L 4.1075 1.4075 4.1075 1.4075 9 P 0 ;1
L 4.1075 2.4575 4.1075 2.4575 9 P 0 ;1
L 4.1075 4.4575 4.1075 4.4575 9 P 0 ;1
L 4.1075 4.5075 4.1075 4.5075 9 P 0 ;1
L 4.1575 0.1575 4.1575 0.1575 9 P 0 ;1
L 4.1575 0.2075 4.1575 0.2075 9 P 0 ;1
L 4.1575 0.2575 4.1575 0.2575 9 P 0 ;1
L 4.1575 0.3075 4.1575 0.3075 9 P 0 ;1
L 4.1575 0.3575 4.1575 0.3575 9 P 0 ;1
L 4.1575 0.4075 4.1575 0.4075 9 P 0 ;1
L 4.1575 0.4575 4.1575 0.4575 9 P 0 ;1
L 4.1575 0.5075 4.1575 0.5075 9 P 0 ;1
L 4.1575 0.5575 4.1575 0.5575 9 P 0 ;1
L 4.1575 0.6075 4.1575 0.6075 9 P 0 ;1
L 4.1575 0.6575 4.1575 0.6575 9 P 0 ;1
L 4.1575 0.7075 4.1575 0.7075 9 P 0 ;1
L 4.1575 0.7575 4.1575 0.7575 9 P 0 ;1
L 4.1575 0.8075 4.1575 0.8075 9 P 0 ;1
L 4.1575 0.8575 4.1575 0.8575 9 P 0 ;1
L 4.1575 0.9075 4.1575 0.9075 9 P 0 ;1
L 4.1575 0.9575 4.1575 0.9575 9 P 0 ;1
L 4.1575 1.0075 4.1575 1.0075 9 P 0 ;1
L 4.1575 1.0575 4.1575 1.0575 9 P 0 ;1
L 4.1575 1.1075 4.1575 1.1075 9 P 0 ;1
L 4.1575 1.1575 4.1575 1.1575 9 P 0 ;1
L 4.1575 1.2075 4.1575 1.2075 9 P 0 ;1
L 4.1575 1.2575 4.1575 1.2575 9 P 0 ;1
L 4.1575 1.3075 4.1575 1.3075 9 P 0 ;1
L 4.1575 1.3575 4.1575 1.3575 9 P 0 ;1
L 4.1575 1.4075 4.1575 1.4075 9 P 0 ;1
L 4.1575 1.4575 4.1575 1.4575 9 P 0 ;1
L 4.1575 2.4575 4.1575 2.4575 9 P 0 ;1
L 4.1575 2.5075 4.1575 2.5075 9 P 0 ;1
L 4.1575 2.5575 4.1575 2.5575 9 P 0 ;1
L 4.1575 3.0075 4.1575 3.0075 9 P 0 ;1
L 4.1575 3.0575 4.1575 3.0575 9 P 0 ;1
L 4.1575 3.1075 4.1575 3.1075 9 P 0 ;1
L 4.1575 3.1575 4.1575 3.1575 9 P 0 ;1
L 4.1575 3.2075 4.1575 3.2075 9 P 0 ;1
L 4.1575 3.2575 4.1575 3.2575 9 P 0 ;1
L 4.1575 3.3075 4.1575 3.3075 9 P 0 ;1
L 4.1575 3.3575 4.1575 3.3575 9 P 0 ;1
L 4.1575 3.4075 4.1575 3.4075 9 P 0 ;1
L 4.1575 3.4575 4.1575 3.4575 9 P 0 ;1
L 4.1575 3.5075 4.1575 3.5075 9 P 0 ;1
L 4.1575 3.5575 4.1575 3.5575 9 P 0 ;1
L 4.1575 3.6075 4.1575 3.6075 9 P 0 ;1
L 4.1575 3.6575 4.1575 3.6575 9 P 0 ;1
L 4.1575 3.7075 4.1575 3.7075 9 P 0 ;1
L 4.1575 3.7575 4.1575 3.7575 9 P 0 ;1
L 4.1575 3.8075 4.1575 3.8075 9 P 0 ;1
L 4.1575 3.8575 4.1575 3.8575 9 P 0 ;1
L 4.1575 3.9075 4.1575 3.9075 9 P 0 ;1
L 4.1575 3.9575 4.1575 3.9575 9 P 0 ;1
L 4.1575 4.0075 4.1575 4.0075 9 P 0 ;1
L 4.1575 4.0575 4.1575 4.0575 9 P 0 ;1
L 4.1575 4.1075 4.1575 4.1075 9 P 0 ;1
L 4.1575 4.1575 4.1575 4.1575 9 P 0 ;1
L 4.1575 4.2075 4.1575 4.2075 9 P 0 ;1
L 4.1575 4.2575 4.1575 4.2575 9 P 0 ;1
L 4.1575 4.3075 4.1575 4.3075 9 P 0 ;1
L 4.1575 4.3575 4.1575 4.3575 9 P 0 ;1
L 4.1575 4.4075 4.1575 4.4075 9 P 0 ;1
L 4.1575 4.4575 4.1575 4.4575 9 P 0 ;1
L 4.1575 4.5075 4.1575 4.5075 9 P 0 ;1
L 4.1575 4.5575 4.1575 4.5575 9 P 0 ;1
L 4.2075 0.1575 4.2075 0.1575 9 P 0 ;1
L 4.2075 0.2075 4.2075 0.2075 9 P 0 ;1
L 4.2075 0.2575 4.2075 0.2575 9 P 0 ;1
L 4.2075 0.3075 4.2075 0.3075 9 P 0 ;1
L 4.2075 0.3575 4.2075 0.3575 9 P 0 ;1
L 4.2075 0.4075 4.2075 0.4075 9 P 0 ;1
L 4.2075 0.4575 4.2075 0.4575 9 P 0 ;1
L 4.2075 0.5075 4.2075 0.5075 9 P 0 ;1
L 4.2075 0.5575 4.2075 0.5575 9 P 0 ;1
L 4.2075 0.6075 4.2075 0.6075 9 P 0 ;1
L 4.2075 0.6575 4.2075 0.6575 9 P 0 ;1
L 4.2075 0.7075 4.2075 0.7075 9 P 0 ;1
L 4.2075 0.7575 4.2075 0.7575 9 P 0 ;1
L 4.2075 0.8075 4.2075 0.8075 9 P 0 ;1
L 4.2075 0.8575 4.2075 0.8575 9 P 0 ;1
L 4.2075 0.9075 4.2075 0.9075 9 P 0 ;1
L 4.2075 0.9575 4.2075 0.9575 9 P 0 ;1
L 4.2075 1.0075 4.2075 1.0075 9 P 0 ;1
L 4.2075 1.0575 4.2075 1.0575 9 P 0 ;1
L 4.2075 1.1075 4.2075 1.1075 9 P 0 ;1
L 4.2075 1.1575 4.2075 1.1575 9 P 0 ;1
L 4.2075 1.2075 4.2075 1.2075 9 P 0 ;1
L 4.2075 1.2575 4.2075 1.2575 9 P 0 ;1
L 4.2075 1.3075 4.2075 1.3075 9 P 0 ;1
L 4.2075 1.3575 4.2075 1.3575 9 P 0 ;1
L 4.2075 1.4075 4.2075 1.4075 9 P 0 ;1
L 4.2075 1.4575 4.2075 1.4575 9 P 0 ;1
L 4.2075 1.5075 4.2075 1.5075 9 P 0 ;1
L 4.2075 2.5075 4.2075 2.5075 9 P 0 ;1
L 4.2075 2.5575 4.2075 2.5575 9 P 0 ;1
L 4.2075 2.6075 4.2075 2.6075 9 P 0 ;1
L 4.2075 2.6575 4.2075 2.6575 9 P 0 ;1
L 4.2075 2.8575 4.2075 2.8575 9 P 0 ;1
L 4.2575 0.1575 4.2575 0.1575 9 P 0 ;1
L 4.2575 0.2075 4.2575 0.2075 9 P 0 ;1
L 4.2575 0.2575 4.2575 0.2575 9 P 0 ;1
L 4.2575 0.3075 4.2575 0.3075 9 P 0 ;1
L 4.2575 0.3575 4.2575 0.3575 9 P 0 ;1
L 4.2575 0.4075 4.2575 0.4075 9 P 0 ;1
L 4.2575 0.4575 4.2575 0.4575 9 P 0 ;1
L 4.2575 0.5075 4.2575 0.5075 9 P 0 ;1
L 4.2575 0.5575 4.2575 0.5575 9 P 0 ;1
L 4.2575 0.6075 4.2575 0.6075 9 P 0 ;1
L 4.2575 0.6575 4.2575 0.6575 9 P 0 ;1
L 4.2575 0.7075 4.2575 0.7075 9 P 0 ;1
L 4.2575 0.7575 4.2575 0.7575 9 P 0 ;1
L 4.2575 0.8075 4.2575 0.8075 9 P 0 ;1
L 4.2575 0.8575 4.2575 0.8575 9 P 0 ;1
L 4.2575 0.9075 4.2575 0.9075 9 P 0 ;1
L 4.2575 0.9575 4.2575 0.9575 9 P 0 ;1
L 4.2575 1.0075 4.2575 1.0075 9 P 0 ;1
L 4.2575 1.0575 4.2575 1.0575 9 P 0 ;1
L 4.2575 1.1075 4.2575 1.1075 9 P 0 ;1
L 4.2575 1.1575 4.2575 1.1575 9 P 0 ;1
L 4.2575 1.2075 4.2575 1.2075 9 P 0 ;1
L 4.2575 1.2575 4.2575 1.2575 9 P 0 ;1
L 4.2575 1.3075 4.2575 1.3075 9 P 0 ;1
L 4.2575 1.3575 4.2575 1.3575 9 P 0 ;1
L 4.2575 1.4075 4.2575 1.4075 9 P 0 ;1
L 4.2575 1.4575 4.2575 1.4575 9 P 0 ;1
L 4.2575 1.5075 4.2575 1.5075 9 P 0 ;1
L 4.2575 2.5575 4.2575 2.5575 9 P 0 ;1
L 4.2575 2.6075 4.2575 2.6075 9 P 0 ;1
L 4.2575 2.6575 4.2575 2.6575 9 P 0 ;1
L 4.2575 2.8575 4.2575 2.8575 9 P 0 ;1
L 4.3075 0.1575 4.3075 0.1575 9 P 0 ;1
L 4.3075 0.2075 4.3075 0.2075 9 P 0 ;1
L 4.3075 0.2575 4.3075 0.2575 9 P 0 ;1
L 4.3075 0.3075 4.3075 0.3075 9 P 0 ;1
L 4.3075 0.3575 4.3075 0.3575 9 P 0 ;1
L 4.3075 0.4075 4.3075 0.4075 9 P 0 ;1
L 4.3075 0.4575 4.3075 0.4575 9 P 0 ;1
L 4.3075 0.5075 4.3075 0.5075 9 P 0 ;1
L 4.3075 0.5575 4.3075 0.5575 9 P 0 ;1
L 4.3075 0.6075 4.3075 0.6075 9 P 0 ;1
L 4.3075 0.6575 4.3075 0.6575 9 P 0 ;1
L 4.3075 0.7075 4.3075 0.7075 9 P 0 ;1
L 4.3075 0.7575 4.3075 0.7575 9 P 0 ;1
L 4.3075 0.8075 4.3075 0.8075 9 P 0 ;1
L 4.3075 0.8575 4.3075 0.8575 9 P 0 ;1
L 4.3075 0.9075 4.3075 0.9075 9 P 0 ;1
L 4.3075 0.9575 4.3075 0.9575 9 P 0 ;1
L 4.3075 1.0075 4.3075 1.0075 9 P 0 ;1
L 4.3075 1.0575 4.3075 1.0575 9 P 0 ;1
L 4.3075 1.1075 4.3075 1.1075 9 P 0 ;1
L 4.3075 1.1575 4.3075 1.1575 9 P 0 ;1
L 4.3075 1.2075 4.3075 1.2075 9 P 0 ;1
L 4.3075 1.2575 4.3075 1.2575 9 P 0 ;1
L 4.3075 1.3075 4.3075 1.3075 9 P 0 ;1
L 4.3075 1.3575 4.3075 1.3575 9 P 0 ;1
L 4.3075 1.4075 4.3075 1.4075 9 P 0 ;1
L 4.3075 1.4575 4.3075 1.4575 9 P 0 ;1
L 4.3075 1.5075 4.3075 1.5075 9 P 0 ;1
L 4.3075 2.5575 4.3075 2.5575 9 P 0 ;1
L 4.3075 2.6075 4.3075 2.6075 9 P 0 ;1
L 4.3075 2.6575 4.3075 2.6575 9 P 0 ;1
L 4.3075 2.8575 4.3075 2.8575 9 P 0 ;1
L 4.3575 0.1575 4.3575 0.1575 9 P 0 ;1
L 4.3575 0.2075 4.3575 0.2075 9 P 0 ;1
L 4.3575 0.2575 4.3575 0.2575 9 P 0 ;1
L 4.3575 0.3075 4.3575 0.3075 9 P 0 ;1
L 4.3575 0.3575 4.3575 0.3575 9 P 0 ;1
L 4.3575 0.4075 4.3575 0.4075 9 P 0 ;1
L 4.3575 0.4575 4.3575 0.4575 9 P 0 ;1
L 4.3575 0.5075 4.3575 0.5075 9 P 0 ;1
L 4.3575 0.5575 4.3575 0.5575 9 P 0 ;1
L 4.3575 0.6075 4.3575 0.6075 9 P 0 ;1
L 4.3575 0.6575 4.3575 0.6575 9 P 0 ;1
L 4.3575 0.7075 4.3575 0.7075 9 P 0 ;1
L 4.3575 0.7575 4.3575 0.7575 9 P 0 ;1
L 4.3575 0.8075 4.3575 0.8075 9 P 0 ;1
L 4.3575 0.8575 4.3575 0.8575 9 P 0 ;1
L 4.3575 0.9075 4.3575 0.9075 9 P 0 ;1
L 4.3575 0.9575 4.3575 0.9575 9 P 0 ;1
L 4.3575 1.0075 4.3575 1.0075 9 P 0 ;1
L 4.3575 1.0575 4.3575 1.0575 9 P 0 ;1
L 4.3575 1.1075 4.3575 1.1075 9 P 0 ;1
L 4.3575 1.1575 4.3575 1.1575 9 P 0 ;1
L 4.3575 1.2075 4.3575 1.2075 9 P 0 ;1
L 4.3575 1.2575 4.3575 1.2575 9 P 0 ;1
L 4.3575 1.3075 4.3575 1.3075 9 P 0 ;1
L 4.3575 1.3575 4.3575 1.3575 9 P 0 ;1
L 4.3575 1.4075 4.3575 1.4075 9 P 0 ;1
L 4.3575 1.4575 4.3575 1.4575 9 P 0 ;1
L 4.3575 1.5075 4.3575 1.5075 9 P 0 ;1
L 4.3575 1.5575 4.3575 1.5575 9 P 0 ;1
L 4.3575 2.5575 4.3575 2.5575 9 P 0 ;1
L 4.3575 2.6075 4.3575 2.6075 9 P 0 ;1
L 4.3575 2.6575 4.3575 2.6575 9 P 0 ;1
L 4.3575 2.8575 4.3575 2.8575 9 P 0 ;1
L 4.4075 0.1575 4.4075 0.1575 9 P 0 ;1
L 4.4075 0.2075 4.4075 0.2075 9 P 0 ;1
L 4.4075 0.2575 4.4075 0.2575 9 P 0 ;1
L 4.4075 0.3075 4.4075 0.3075 9 P 0 ;1
L 4.4075 0.3575 4.4075 0.3575 9 P 0 ;1
L 4.4075 0.4075 4.4075 0.4075 9 P 0 ;1
L 4.4075 0.4575 4.4075 0.4575 9 P 0 ;1
L 4.4075 0.5075 4.4075 0.5075 9 P 0 ;1
L 4.4075 0.5575 4.4075 0.5575 9 P 0 ;1
L 4.4075 0.6075 4.4075 0.6075 9 P 0 ;1
L 4.4075 0.6575 4.4075 0.6575 9 P 0 ;1
L 4.4075 0.7075 4.4075 0.7075 9 P 0 ;1
L 4.4075 0.7575 4.4075 0.7575 9 P 0 ;1
L 4.4075 0.8075 4.4075 0.8075 9 P 0 ;1
L 4.4075 0.8575 4.4075 0.8575 9 P 0 ;1
L 4.4075 0.9075 4.4075 0.9075 9 P 0 ;1
L 4.4075 0.9575 4.4075 0.9575 9 P 0 ;1
L 4.4075 1.0075 4.4075 1.0075 9 P 0 ;1
L 4.4075 1.0575 4.4075 1.0575 9 P 0 ;1
L 4.4075 1.1075 4.4075 1.1075 9 P 0 ;1
L 4.4075 1.1575 4.4075 1.1575 9 P 0 ;1
L 4.4075 1.2075 4.4075 1.2075 9 P 0 ;1
L 4.4075 1.2575 4.4075 1.2575 9 P 0 ;1
L 4.4075 1.3075 4.4075 1.3075 9 P 0 ;1
L 4.4075 1.3575 4.4075 1.3575 9 P 0 ;1
L 4.4075 1.4075 4.4075 1.4075 9 P 0 ;1
L 4.4075 1.4575 4.4075 1.4575 9 P 0 ;1
L 4.4075 1.5075 4.4075 1.5075 9 P 0 ;1
L 4.4075 1.5575 4.4075 1.5575 9 P 0 ;1
L 4.4075 2.5575 4.4075 2.5575 9 P 0 ;1
L 4.4075 2.6075 4.4075 2.6075 9 P 0 ;1
L 4.4075 2.6575 4.4075 2.6575 9 P 0 ;1
L 4.4075 2.8575 4.4075 2.8575 9 P 0 ;1
L 4.4575 0.1575 4.4575 0.1575 9 P 0 ;1
L 4.4575 0.2075 4.4575 0.2075 9 P 0 ;1
L 4.4575 0.2575 4.4575 0.2575 9 P 0 ;1
L 4.4575 0.3075 4.4575 0.3075 9 P 0 ;1
L 4.4575 0.3575 4.4575 0.3575 9 P 0 ;1
L 4.4575 0.4075 4.4575 0.4075 9 P 0 ;1
L 4.4575 0.4575 4.4575 0.4575 9 P 0 ;1
L 4.4575 0.5075 4.4575 0.5075 9 P 0 ;1
L 4.4575 0.5575 4.4575 0.5575 9 P 0 ;1
L 4.4575 0.6075 4.4575 0.6075 9 P 0 ;1
L 4.4575 0.6575 4.4575 0.6575 9 P 0 ;1
L 4.4575 0.7075 4.4575 0.7075 9 P 0 ;1
L 4.4575 0.7575 4.4575 0.7575 9 P 0 ;1
L 4.4575 0.8075 4.4575 0.8075 9 P 0 ;1
L 4.4575 0.8575 4.4575 0.8575 9 P 0 ;1
L 4.4575 0.9075 4.4575 0.9075 9 P 0 ;1
L 4.4575 0.9575 4.4575 0.9575 9 P 0 ;1
L 4.4575 1.0075 4.4575 1.0075 9 P 0 ;1
L 4.4575 1.0575 4.4575 1.0575 9 P 0 ;1
L 4.4575 1.1075 4.4575 1.1075 9 P 0 ;1
L 4.4575 1.1575 4.4575 1.1575 9 P 0 ;1
L 4.4575 1.2075 4.4575 1.2075 9 P 0 ;1
L 4.4575 1.2575 4.4575 1.2575 9 P 0 ;1
L 4.4575 1.3075 4.4575 1.3075 9 P 0 ;1
L 4.4575 1.3575 4.4575 1.3575 9 P 0 ;1
L 4.4575 1.4075 4.4575 1.4075 9 P 0 ;1
L 4.4575 1.4575 4.4575 1.4575 9 P 0 ;1
L 4.4575 1.5075 4.4575 1.5075 9 P 0 ;1
L 4.4575 1.5575 4.4575 1.5575 9 P 0 ;1
L 4.4575 2.5575 4.4575 2.5575 9 P 0 ;1
L 4.4575 2.6075 4.4575 2.6075 9 P 0 ;1
L 4.4575 2.6575 4.4575 2.6575 9 P 0 ;1
L 4.4575 2.8575 4.4575 2.8575 9 P 0 ;1
L 4.5075 0.1575 4.5075 0.1575 9 P 0 ;1
L 4.5075 0.2075 4.5075 0.2075 9 P 0 ;1
L 4.5075 0.2575 4.5075 0.2575 9 P 0 ;1
L 4.5075 0.3075 4.5075 0.3075 9 P 0 ;1
L 4.5075 0.3575 4.5075 0.3575 9 P 0 ;1
L 4.5075 0.4075 4.5075 0.4075 9 P 0 ;1
L 4.5075 0.4575 4.5075 0.4575 9 P 0 ;1
L 4.5075 0.5075 4.5075 0.5075 9 P 0 ;1
L 4.5075 0.5575 4.5075 0.5575 9 P 0 ;1
L 4.5075 0.6075 4.5075 0.6075 9 P 0 ;1
L 4.5075 0.6575 4.5075 0.6575 9 P 0 ;1
L 4.5075 0.7075 4.5075 0.7075 9 P 0 ;1
L 4.5075 0.7575 4.5075 0.7575 9 P 0 ;1
L 4.5075 0.8075 4.5075 0.8075 9 P 0 ;1
L 4.5075 0.8575 4.5075 0.8575 9 P 0 ;1
L 4.5075 0.9075 4.5075 0.9075 9 P 0 ;1
L 4.5075 0.9575 4.5075 0.9575 9 P 0 ;1
L 4.5075 1.0075 4.5075 1.0075 9 P 0 ;1
L 4.5075 1.0575 4.5075 1.0575 9 P 0 ;1
L 4.5075 1.1075 4.5075 1.1075 9 P 0 ;1
L 4.5075 1.1575 4.5075 1.1575 9 P 0 ;1
L 4.5075 1.2075 4.5075 1.2075 9 P 0 ;1
L 4.5075 1.2575 4.5075 1.2575 9 P 0 ;1
L 4.5075 1.3075 4.5075 1.3075 9 P 0 ;1
L 4.5075 1.3575 4.5075 1.3575 9 P 0 ;1
L 4.5075 1.4075 4.5075 1.4075 9 P 0 ;1
L 4.5075 1.4575 4.5075 1.4575 9 P 0 ;1
L 4.5075 1.5075 4.5075 1.5075 9 P 0 ;1
L 4.5075 1.5575 4.5075 1.5575 9 P 0 ;1
L 4.5075 2.8575 4.5075 2.8575 9 P 0 ;1
L 4.5575 0.1575 4.5575 0.1575 9 P 0 ;1
L 4.5575 0.2075 4.5575 0.2075 9 P 0 ;1
L 4.5575 0.2575 4.5575 0.2575 9 P 0 ;1
L 4.5575 0.3075 4.5575 0.3075 9 P 0 ;1
L 4.5575 0.3575 4.5575 0.3575 9 P 0 ;1
L 4.5575 0.4075 4.5575 0.4075 9 P 0 ;1
L 4.5575 0.4575 4.5575 0.4575 9 P 0 ;1
L 4.5575 0.5075 4.5575 0.5075 9 P 0 ;1
L 4.5575 0.5575 4.5575 0.5575 9 P 0 ;1
L 4.5575 0.6075 4.5575 0.6075 9 P 0 ;1
L 4.5575 0.6575 4.5575 0.6575 9 P 0 ;1
L 4.5575 0.7075 4.5575 0.7075 9 P 0 ;1
L 4.5575 0.7575 4.5575 0.7575 9 P 0 ;1
L 4.5575 0.8075 4.5575 0.8075 9 P 0 ;1
L 4.5575 0.8575 4.5575 0.8575 9 P 0 ;1
L 4.5575 0.9075 4.5575 0.9075 9 P 0 ;1
L 4.5575 0.9575 4.5575 0.9575 9 P 0 ;1
L 4.5575 1.0075 4.5575 1.0075 9 P 0 ;1
L 4.5575 1.0575 4.5575 1.0575 9 P 0 ;1
L 4.5575 1.1075 4.5575 1.1075 9 P 0 ;1
L 4.5575 1.1575 4.5575 1.1575 9 P 0 ;1
L 4.5575 1.2075 4.5575 1.2075 9 P 0 ;1
L 4.5575 1.2575 4.5575 1.2575 9 P 0 ;1
L 4.5575 1.3075 4.5575 1.3075 9 P 0 ;1
L 4.5575 1.3575 4.5575 1.3575 9 P 0 ;1
L 4.5575 1.4075 4.5575 1.4075 9 P 0 ;1
L 4.5575 1.4575 4.5575 1.4575 9 P 0 ;1
L 4.5575 1.5075 4.5575 1.5075 9 P 0 ;1
L 4.5575 1.5575 4.5575 1.5575 9 P 0 ;1
L 4.5575 4.9575 4.5575 4.9575 9 P 0 ;1
L 4.5575 5.0075 4.5575 5.0075 9 P 0 ;1
L 4.5575 5.0575 4.5575 5.0575 9 P 0 ;1
L 4.5575 5.1075 4.5575 5.1075 9 P 0 ;1
L 4.6075 0.1575 4.6075 0.1575 9 P 0 ;1
L 4.6075 0.2075 4.6075 0.2075 9 P 0 ;1
L 4.6075 0.2575 4.6075 0.2575 9 P 0 ;1
L 4.6075 0.3075 4.6075 0.3075 9 P 0 ;1
L 4.6075 0.3575 4.6075 0.3575 9 P 0 ;1
L 4.6075 0.4075 4.6075 0.4075 9 P 0 ;1
L 4.6075 0.4575 4.6075 0.4575 9 P 0 ;1
L 4.6075 0.5075 4.6075 0.5075 9 P 0 ;1
L 4.6075 0.5575 4.6075 0.5575 9 P 0 ;1
L 4.6075 0.6075 4.6075 0.6075 9 P 0 ;1
L 4.6075 0.6575 4.6075 0.6575 9 P 0 ;1
L 4.6075 0.7075 4.6075 0.7075 9 P 0 ;1
L 4.6075 0.7575 4.6075 0.7575 9 P 0 ;1
L 4.6075 0.8075 4.6075 0.8075 9 P 0 ;1
L 4.6075 0.8575 4.6075 0.8575 9 P 0 ;1
L 4.6075 0.9075 4.6075 0.9075 9 P 0 ;1
L 4.6075 0.9575 4.6075 0.9575 9 P 0 ;1
L 4.6075 1.0075 4.6075 1.0075 9 P 0 ;1
L 4.6075 1.0575 4.6075 1.0575 9 P 0 ;1
L 4.6075 1.1075 4.6075 1.1075 9 P 0 ;1
L 4.6075 1.1575 4.6075 1.1575 9 P 0 ;1
L 4.6075 1.2075 4.6075 1.2075 9 P 0 ;1
L 4.6075 1.2575 4.6075 1.2575 9 P 0 ;1
L 4.6075 1.3075 4.6075 1.3075 9 P 0 ;1
L 4.6075 1.3575 4.6075 1.3575 9 P 0 ;1
L 4.6075 1.4075 4.6075 1.4075 9 P 0 ;1
L 4.6075 1.4575 4.6075 1.4575 9 P 0 ;1
L 4.6075 1.5075 4.6075 1.5075 9 P 0 ;1
L 4.6075 1.5575 4.6075 1.5575 9 P 0 ;1
L 4.6575 0.1575 4.6575 0.1575 9 P 0 ;1
L 4.6575 0.2075 4.6575 0.2075 9 P 0 ;1
L 4.6575 0.2575 4.6575 0.2575 9 P 0 ;1
L 4.6575 0.3075 4.6575 0.3075 9 P 0 ;1
L 4.6575 0.3575 4.6575 0.3575 9 P 0 ;1
L 4.6575 0.4075 4.6575 0.4075 9 P 0 ;1
L 4.6575 0.4575 4.6575 0.4575 9 P 0 ;1
L 4.6575 0.5075 4.6575 0.5075 9 P 0 ;1
L 4.6575 0.5575 4.6575 0.5575 9 P 0 ;1
L 4.6575 0.6075 4.6575 0.6075 9 P 0 ;1
L 4.6575 0.6575 4.6575 0.6575 9 P 0 ;1
L 4.6575 0.7075 4.6575 0.7075 9 P 0 ;1
L 4.6575 0.7575 4.6575 0.7575 9 P 0 ;1
L 4.6575 0.8075 4.6575 0.8075 9 P 0 ;1
L 4.6575 0.8575 4.6575 0.8575 9 P 0 ;1
L 4.6575 0.9075 4.6575 0.9075 9 P 0 ;1
L 4.6575 0.9575 4.6575 0.9575 9 P 0 ;1
L 4.6575 1.0075 4.6575 1.0075 9 P 0 ;1
L 4.6575 1.0575 4.6575 1.0575 9 P 0 ;1
L 4.6575 1.1075 4.6575 1.1075 9 P 0 ;1
L 4.6575 1.1575 4.6575 1.1575 9 P 0 ;1
L 4.6575 1.2075 4.6575 1.2075 9 P 0 ;1
L 4.6575 1.2575 4.6575 1.2575 9 P 0 ;1
L 4.6575 1.3075 4.6575 1.3075 9 P 0 ;1
L 4.6575 1.3575 4.6575 1.3575 9 P 0 ;1
L 4.6575 1.4075 4.6575 1.4075 9 P 0 ;1
L 4.6575 1.6075 4.6575 1.6075 9 P 0 ;1
L 4.7075 0.1575 4.7075 0.1575 9 P 0 ;1
L 4.7075 0.2075 4.7075 0.2075 9 P 0 ;1
L 4.7075 0.2575 4.7075 0.2575 9 P 0 ;1
L 4.7075 0.3075 4.7075 0.3075 9 P 0 ;1
L 4.7075 0.3575 4.7075 0.3575 9 P 0 ;1
L 4.7075 0.4075 4.7075 0.4075 9 P 0 ;1
L 4.7075 0.4575 4.7075 0.4575 9 P 0 ;1
L 4.7075 0.5075 4.7075 0.5075 9 P 0 ;1
L 4.7075 0.5575 4.7075 0.5575 9 P 0 ;1
L 4.7075 0.6075 4.7075 0.6075 9 P 0 ;1
L 4.7075 0.6575 4.7075 0.6575 9 P 0 ;1
L 4.7075 0.7075 4.7075 0.7075 9 P 0 ;1
L 4.7075 0.7575 4.7075 0.7575 9 P 0 ;1
L 4.7075 0.8075 4.7075 0.8075 9 P 0 ;1
L 4.7075 0.8575 4.7075 0.8575 9 P 0 ;1
L 4.7075 0.9075 4.7075 0.9075 9 P 0 ;1
L 4.7075 0.9575 4.7075 0.9575 9 P 0 ;1
L 4.7075 1.0075 4.7075 1.0075 9 P 0 ;1
L 4.7075 1.0575 4.7075 1.0575 9 P 0 ;1
L 4.7075 1.1075 4.7075 1.1075 9 P 0 ;1
L 4.7075 1.1575 4.7075 1.1575 9 P 0 ;1
L 4.7075 1.2075 4.7075 1.2075 9 P 0 ;1
L 4.7075 1.2575 4.7075 1.2575 9 P 0 ;1
L 4.7075 1.3075 4.7075 1.3075 9 P 0 ;1
L 4.7575 0.4575 4.7575 0.4575 9 P 0 ;1
L 4.7575 0.5075 4.7575 0.5075 9 P 0 ;1
L 4.7575 0.5575 4.7575 0.5575 9 P 0 ;1
L 4.7575 0.6075 4.7575 0.6075 9 P 0 ;1
L 4.7575 0.6575 4.7575 0.6575 9 P 0 ;1
L 4.7575 0.7075 4.7575 0.7075 9 P 0 ;1
L 4.7575 0.7575 4.7575 0.7575 9 P 0 ;1
L 4.7575 0.8075 4.7575 0.8075 9 P 0 ;1
L 4.7575 0.8575 4.7575 0.8575 9 P 0 ;1
L 4.7575 0.9075 4.7575 0.9075 9 P 0 ;1
L 4.7575 0.9575 4.7575 0.9575 9 P 0 ;1
L 4.7575 1.0075 4.7575 1.0075 9 P 0 ;1
L 4.7575 1.0575 4.7575 1.0575 9 P 0 ;1
L 4.7575 1.1075 4.7575 1.1075 9 P 0 ;1
L 4.7575 1.1575 4.7575 1.1575 9 P 0 ;1
L 4.7575 1.2075 4.7575 1.2075 9 P 0 ;1
L 4.7575 1.2575 4.7575 1.2575 9 P 0 ;1
L 4.7575 1.3075 4.7575 1.3075 9 P 0 ;1
L 4.8075 0.5075 4.8075 0.5075 9 P 0 ;1
L 4.8075 0.5575 4.8075 0.5575 9 P 0 ;1
L 4.8075 0.6075 4.8075 0.6075 9 P 0 ;1
L 4.8075 0.6575 4.8075 0.6575 9 P 0 ;1
L 4.8075 0.7075 4.8075 0.7075 9 P 0 ;1
L 4.8075 0.7575 4.8075 0.7575 9 P 0 ;1
L 4.8075 0.8075 4.8075 0.8075 9 P 0 ;1
L 4.8075 0.8575 4.8075 0.8575 9 P 0 ;1
L 4.8075 0.9075 4.8075 0.9075 9 P 0 ;1
L 4.8075 0.9575 4.8075 0.9575 9 P 0 ;1
L 4.8075 1.0075 4.8075 1.0075 9 P 0 ;1
L 4.8075 1.0575 4.8075 1.0575 9 P 0 ;1
L 4.8075 1.1075 4.8075 1.1075 9 P 0 ;1
L 4.8075 1.1575 4.8075 1.1575 9 P 0 ;1
L 4.8075 1.2075 4.8075 1.2075 9 P 0 ;1
L 4.8075 1.2575 4.8075 1.2575 9 P 0 ;1
L 4.8575 0.5575 4.8575 0.5575 9 P 0 ;1
L 4.8575 0.6075 4.8575 0.6075 9 P 0 ;1
L 4.8575 0.6575 4.8575 0.6575 9 P 0 ;1
L 4.8575 0.7075 4.8575 0.7075 9 P 0 ;1
L 4.8575 0.7575 4.8575 0.7575 9 P 0 ;1
L 4.8575 0.8075 4.8575 0.8075 9 P 0 ;1
L 4.8575 0.8575 4.8575 0.8575 9 P 0 ;1
L 4.8575 0.9075 4.8575 0.9075 9 P 0 ;1
L 4.8575 0.9575 4.8575 0.9575 9 P 0 ;1
L 4.8575 1.0075 4.8575 1.0075 9 P 0 ;1
L 4.8575 1.0575 4.8575 1.0575 9 P 0 ;1
L 4.8575 1.1075 4.8575 1.1075 9 P 0 ;1
L 4.8575 1.1575 4.8575 1.1575 9 P 0 ;1
L 4.8575 1.2075 4.8575 1.2075 9 P 0 ;1
L 4.8575 1.2575 4.8575 1.2575 9 P 0 ;1
L 4.8575 1.7575 4.8575 1.7575 9 P 0 ;1
L 4.9075 0.5575 4.9075 0.5575 9 P 0 ;1
L 4.9075 0.6075 4.9075 0.6075 9 P 0 ;1
L 4.9075 0.6575 4.9075 0.6575 9 P 0 ;1
L 4.9075 0.7075 4.9075 0.7075 9 P 0 ;1
L 4.9075 0.7575 4.9075 0.7575 9 P 0 ;1
L 4.9075 0.8075 4.9075 0.8075 9 P 0 ;1
L 4.9075 0.8575 4.9075 0.8575 9 P 0 ;1
L 4.9075 0.9075 4.9075 0.9075 9 P 0 ;1
L 4.9075 0.9575 4.9075 0.9575 9 P 0 ;1
L 4.9075 1.0075 4.9075 1.0075 9 P 0 ;1
L 4.9075 1.0575 4.9075 1.0575 9 P 0 ;1
L 4.9075 1.1075 4.9075 1.1075 9 P 0 ;1
L 4.9075 1.1575 4.9075 1.1575 9 P 0 ;1
L 4.9075 1.2075 4.9075 1.2075 9 P 0 ;1
L 4.9075 1.2575 4.9075 1.2575 9 P 0 ;1
L 4.9075 1.3075 4.9075 1.3075 9 P 0 ;1
L 4.9075 1.7075 4.9075 1.7075 9 P 0 ;1
L 4.9075 1.7575 4.9075 1.7575 9 P 0 ;1
L 4.9575 0.5575 4.9575 0.5575 9 P 0 ;1
L 4.9575 0.6075 4.9575 0.6075 9 P 0 ;1
L 4.9575 0.6575 4.9575 0.6575 9 P 0 ;1
L 4.9575 0.7075 4.9575 0.7075 9 P 0 ;1
L 4.9575 0.7575 4.9575 0.7575 9 P 0 ;1
L 4.9575 0.8075 4.9575 0.8075 9 P 0 ;1
L 4.9575 0.8575 4.9575 0.8575 9 P 0 ;1
L 4.9575 0.9075 4.9575 0.9075 9 P 0 ;1
L 4.9575 0.9575 4.9575 0.9575 9 P 0 ;1
L 4.9575 1.0075 4.9575 1.0075 9 P 0 ;1
L 4.9575 1.0575 4.9575 1.0575 9 P 0 ;1
L 4.9575 1.1075 4.9575 1.1075 9 P 0 ;1
L 4.9575 1.1575 4.9575 1.1575 9 P 0 ;1
L 4.9575 1.2075 4.9575 1.2075 9 P 0 ;1
L 4.9575 1.2575 4.9575 1.2575 9 P 0 ;1
L 4.9575 1.3075 4.9575 1.3075 9 P 0 ;1
L 4.9575 1.7075 4.9575 1.7075 9 P 0 ;1
L 4.9575 1.7575 4.9575 1.7575 9 P 0 ;1
L 5.0075 0.5575 5.0075 0.5575 9 P 0 ;1
L 5.0075 0.6075 5.0075 0.6075 9 P 0 ;1
L 5.0075 0.6575 5.0075 0.6575 9 P 0 ;1
L 5.0075 0.7075 5.0075 0.7075 9 P 0 ;1
L 5.0075 0.7575 5.0075 0.7575 9 P 0 ;1
L 5.0075 0.8075 5.0075 0.8075 9 P 0 ;1
L 5.0075 0.8575 5.0075 0.8575 9 P 0 ;1
L 5.0075 0.9075 5.0075 0.9075 9 P 0 ;1
L 5.0075 0.9575 5.0075 0.9575 9 P 0 ;1
L 5.0075 1.0075 5.0075 1.0075 9 P 0 ;1
L 5.0075 1.0575 5.0075 1.0575 9 P 0 ;1
L 5.0075 1.1075 5.0075 1.1075 9 P 0 ;1
L 5.0075 1.1575 5.0075 1.1575 9 P 0 ;1
L 5.0075 1.2075 5.0075 1.2075 9 P 0 ;1
L 5.0075 1.2575 5.0075 1.2575 9 P 0 ;1
L 5.0075 1.3075 5.0075 1.3075 9 P 0 ;1
L 5.0075 1.3575 5.0075 1.3575 9 P 0 ;1
L 5.0075 1.4075 5.0075 1.4075 9 P 0 ;1
L 5.0075 1.6075 5.0075 1.6075 9 P 0 ;1
L 5.0075 1.6575 5.0075 1.6575 9 P 0 ;1
L 5.0075 1.7075 5.0075 1.7075 9 P 0 ;1
L 5.0075 1.7575 5.0075 1.7575 9 P 0 ;1
L 5.0575 0.5575 5.0575 0.5575 9 P 0 ;1
L 5.0575 0.6075 5.0575 0.6075 9 P 0 ;1
L 5.0575 0.6575 5.0575 0.6575 9 P 0 ;1
L 5.0575 0.7075 5.0575 0.7075 9 P 0 ;1
L 5.0575 0.7575 5.0575 0.7575 9 P 0 ;1
L 5.0575 0.8075 5.0575 0.8075 9 P 0 ;1
L 5.0575 0.8575 5.0575 0.8575 9 P 0 ;1
L 5.0575 0.9075 5.0575 0.9075 9 P 0 ;1
L 5.0575 0.9575 5.0575 0.9575 9 P 0 ;1
L 5.0575 1.0075 5.0575 1.0075 9 P 0 ;1
L 5.0575 1.0575 5.0575 1.0575 9 P 0 ;1
L 5.0575 1.1075 5.0575 1.1075 9 P 0 ;1
L 5.0575 1.1575 5.0575 1.1575 9 P 0 ;1
L 5.0575 1.2075 5.0575 1.2075 9 P 0 ;1
L 5.0575 1.2575 5.0575 1.2575 9 P 0 ;1
L 5.0575 1.3075 5.0575 1.3075 9 P 0 ;1
L 5.0575 1.3575 5.0575 1.3575 9 P 0 ;1
L 5.0575 1.4075 5.0575 1.4075 9 P 0 ;1
L 5.0575 1.4575 5.0575 1.4575 9 P 0 ;1
L 5.0575 1.5075 5.0575 1.5075 9 P 0 ;1
L 5.0575 1.5575 5.0575 1.5575 9 P 0 ;1
L 5.0575 1.6075 5.0575 1.6075 9 P 0 ;1
L 5.0575 1.6575 5.0575 1.6575 9 P 0 ;1
L 5.0575 1.7075 5.0575 1.7075 9 P 0 ;1
L 5.0575 1.7575 5.0575 1.7575 9 P 0 ;1
L 5.1075 0.5575 5.1075 0.5575 9 P 0 ;1
L 5.1075 0.6075 5.1075 0.6075 9 P 0 ;1
L 5.1075 0.6575 5.1075 0.6575 9 P 0 ;1
L 5.1075 0.7075 5.1075 0.7075 9 P 0 ;1
L 5.1075 0.7575 5.1075 0.7575 9 P 0 ;1
L 5.1075 0.8075 5.1075 0.8075 9 P 0 ;1
L 5.1075 0.8575 5.1075 0.8575 9 P 0 ;1
L 5.1075 0.9075 5.1075 0.9075 9 P 0 ;1
L 5.1075 0.9575 5.1075 0.9575 9 P 0 ;1
L 5.1075 1.0075 5.1075 1.0075 9 P 0 ;1
L 5.1075 1.0575 5.1075 1.0575 9 P 0 ;1
L 5.1075 1.1075 5.1075 1.1075 9 P 0 ;1
L 5.1075 1.1575 5.1075 1.1575 9 P 0 ;1
L 5.1075 1.2075 5.1075 1.2075 9 P 0 ;1
L 5.1075 1.2575 5.1075 1.2575 9 P 0 ;1
L 5.1075 1.3075 5.1075 1.3075 9 P 0 ;1
L 5.1075 1.3575 5.1075 1.3575 9 P 0 ;1
L 5.1075 1.4075 5.1075 1.4075 9 P 0 ;1
L 5.1075 1.4575 5.1075 1.4575 9 P 0 ;1
L 5.1075 1.5075 5.1075 1.5075 9 P 0 ;1
L 5.1075 1.5575 5.1075 1.5575 9 P 0 ;1
L 5.1075 1.6075 5.1075 1.6075 9 P 0 ;1
L 5.1075 1.6575 5.1075 1.6575 9 P 0 ;1
L 5.1075 1.7075 5.1075 1.7075 9 P 0 ;1
L 5.1075 1.7575 5.1075 1.7575 9 P 0 ;1
L 5.1575 0.5575 5.1575 0.5575 9 P 0 ;1
L 5.1575 0.6075 5.1575 0.6075 9 P 0 ;1
L 5.1575 0.6575 5.1575 0.6575 9 P 0 ;1
L 5.1575 0.7075 5.1575 0.7075 9 P 0 ;1
L 5.1575 0.7575 5.1575 0.7575 9 P 0 ;1
L 5.1575 0.8075 5.1575 0.8075 9 P 0 ;1
L 5.1575 0.8575 5.1575 0.8575 9 P 0 ;1
L 5.1575 0.9075 5.1575 0.9075 9 P 0 ;1
L 5.1575 0.9575 5.1575 0.9575 9 P 0 ;1
L 5.1575 1.0075 5.1575 1.0075 9 P 0 ;1
L 5.1575 1.0575 5.1575 1.0575 9 P 0 ;1
L 5.1575 1.1075 5.1575 1.1075 9 P 0 ;1
L 5.1575 1.1575 5.1575 1.1575 9 P 0 ;1
L 5.1575 1.2075 5.1575 1.2075 9 P 0 ;1
L 5.1575 1.2575 5.1575 1.2575 9 P 0 ;1
L 5.1575 1.3075 5.1575 1.3075 9 P 0 ;1
L 5.1575 1.3575 5.1575 1.3575 9 P 0 ;1
L 5.1575 1.4075 5.1575 1.4075 9 P 0 ;1
L 5.1575 1.4575 5.1575 1.4575 9 P 0 ;1
L 5.1575 1.5075 5.1575 1.5075 9 P 0 ;1
L 5.1575 1.5575 5.1575 1.5575 9 P 0 ;1
L 5.1575 1.6075 5.1575 1.6075 9 P 0 ;1
L 5.1575 1.6575 5.1575 1.6575 9 P 0 ;1
L 5.1575 1.7075 5.1575 1.7075 9 P 0 ;1
L 5.1575 1.7575 5.1575 1.7575 9 P 0 ;1
L 5.1575 1.8075 5.1575 1.8075 9 P 0 ;1
L 5.1575 2.8575 5.1575 2.8575 9 P 0 ;1
L 5.2075 0.5575 5.2075 0.5575 9 P 0 ;1
L 5.2075 0.6075 5.2075 0.6075 9 P 0 ;1
L 5.2075 0.6575 5.2075 0.6575 9 P 0 ;1
L 5.2075 0.7075 5.2075 0.7075 9 P 0 ;1
L 5.2075 0.7575 5.2075 0.7575 9 P 0 ;1
L 5.2075 0.8075 5.2075 0.8075 9 P 0 ;1
L 5.2075 0.8575 5.2075 0.8575 9 P 0 ;1
L 5.2075 0.9075 5.2075 0.9075 9 P 0 ;1
L 5.2075 0.9575 5.2075 0.9575 9 P 0 ;1
L 5.2075 1.0075 5.2075 1.0075 9 P 0 ;1
L 5.2075 1.0575 5.2075 1.0575 9 P 0 ;1
L 5.2075 1.1075 5.2075 1.1075 9 P 0 ;1
L 5.2075 1.1575 5.2075 1.1575 9 P 0 ;1
L 5.2075 1.2075 5.2075 1.2075 9 P 0 ;1
L 5.2075 1.2575 5.2075 1.2575 9 P 0 ;1
L 5.2075 1.3075 5.2075 1.3075 9 P 0 ;1
L 5.2075 1.3575 5.2075 1.3575 9 P 0 ;1
L 5.2075 1.4075 5.2075 1.4075 9 P 0 ;1
L 5.2075 1.4575 5.2075 1.4575 9 P 0 ;1
L 5.2075 1.5075 5.2075 1.5075 9 P 0 ;1
L 5.2075 1.5575 5.2075 1.5575 9 P 0 ;1
L 5.2075 1.6075 5.2075 1.6075 9 P 0 ;1
L 5.2075 1.6575 5.2075 1.6575 9 P 0 ;1
L 5.2075 1.7075 5.2075 1.7075 9 P 0 ;1
L 5.2075 1.7575 5.2075 1.7575 9 P 0 ;1
L 5.2075 1.8075 5.2075 1.8075 9 P 0 ;1
L 5.2075 1.8575 5.2075 1.8575 9 P 0 ;1
L 5.2075 1.9075 5.2075 1.9075 9 P 0 ;1
L 5.2075 1.9575 5.2075 1.9575 9 P 0 ;1
L 5.2075 2.0075 5.2075 2.0075 9 P 0 ;1
L 5.2075 2.0575 5.2075 2.0575 9 P 0 ;1
L 5.2075 2.1075 5.2075 2.1075 9 P 0 ;1
L 5.2075 2.1575 5.2075 2.1575 9 P 0 ;1
L 5.2075 2.2075 5.2075 2.2075 9 P 0 ;1
L 5.2075 2.2575 5.2075 2.2575 9 P 0 ;1
L 5.2075 2.3075 5.2075 2.3075 9 P 0 ;1
L 5.2075 2.3575 5.2075 2.3575 9 P 0 ;1
L 5.2075 2.4075 5.2075 2.4075 9 P 0 ;1
L 5.2075 2.4575 5.2075 2.4575 9 P 0 ;1
L 5.2075 2.5075 5.2075 2.5075 9 P 0 ;1
L 5.2075 2.5575 5.2075 2.5575 9 P 0 ;1
L 5.2075 2.6075 5.2075 2.6075 9 P 0 ;1
L 5.2075 2.6575 5.2075 2.6575 9 P 0 ;1
L 5.2075 2.7075 5.2075 2.7075 9 P 0 ;1
L 5.2075 2.7575 5.2075 2.7575 9 P 0 ;1
L 5.2075 2.8075 5.2075 2.8075 9 P 0 ;1
L 5.2075 2.8575 5.2075 2.8575 9 P 0 ;1
L 5.2575 0.5575 5.2575 0.5575 9 P 0 ;1
L 5.2575 0.6075 5.2575 0.6075 9 P 0 ;1
L 5.2575 0.6575 5.2575 0.6575 9 P 0 ;1
L 5.2575 0.7075 5.2575 0.7075 9 P 0 ;1
L 5.2575 0.7575 5.2575 0.7575 9 P 0 ;1
L 5.2575 0.8075 5.2575 0.8075 9 P 0 ;1
L 5.2575 0.8575 5.2575 0.8575 9 P 0 ;1
L 5.2575 0.9075 5.2575 0.9075 9 P 0 ;1
L 5.2575 0.9575 5.2575 0.9575 9 P 0 ;1
L 5.2575 1.0075 5.2575 1.0075 9 P 0 ;1
L 5.2575 1.0575 5.2575 1.0575 9 P 0 ;1
L 5.2575 1.1075 5.2575 1.1075 9 P 0 ;1
L 5.2575 1.1575 5.2575 1.1575 9 P 0 ;1
L 5.2575 1.2075 5.2575 1.2075 9 P 0 ;1
L 5.2575 1.2575 5.2575 1.2575 9 P 0 ;1
L 5.2575 1.3075 5.2575 1.3075 9 P 0 ;1
L 5.2575 1.3575 5.2575 1.3575 9 P 0 ;1
L 5.2575 1.4075 5.2575 1.4075 9 P 0 ;1
L 5.2575 1.4575 5.2575 1.4575 9 P 0 ;1
L 5.2575 1.5075 5.2575 1.5075 9 P 0 ;1
L 5.2575 1.5575 5.2575 1.5575 9 P 0 ;1
L 5.2575 1.6075 5.2575 1.6075 9 P 0 ;1
L 5.2575 1.6575 5.2575 1.6575 9 P 0 ;1
L 5.2575 1.7075 5.2575 1.7075 9 P 0 ;1
L 5.2575 1.7575 5.2575 1.7575 9 P 0 ;1
L 5.2575 1.8075 5.2575 1.8075 9 P 0 ;1
L 5.2575 1.8575 5.2575 1.8575 9 P 0 ;1
L 5.2575 1.9075 5.2575 1.9075 9 P 0 ;1
L 5.2575 1.9575 5.2575 1.9575 9 P 0 ;1
L 5.2575 2.0075 5.2575 2.0075 9 P 0 ;1
L 5.2575 2.0575 5.2575 2.0575 9 P 0 ;1
L 5.2575 2.1075 5.2575 2.1075 9 P 0 ;1
L 5.2575 2.1575 5.2575 2.1575 9 P 0 ;1
L 5.2575 2.2075 5.2575 2.2075 9 P 0 ;1
L 5.2575 2.2575 5.2575 2.2575 9 P 0 ;1
L 5.2575 2.3075 5.2575 2.3075 9 P 0 ;1
L 5.2575 2.3575 5.2575 2.3575 9 P 0 ;1
L 5.2575 2.4075 5.2575 2.4075 9 P 0 ;1
L 5.2575 2.4575 5.2575 2.4575 9 P 0 ;1
L 5.2575 2.5075 5.2575 2.5075 9 P 0 ;1
L 5.2575 2.5575 5.2575 2.5575 9 P 0 ;1
L 5.2575 2.6075 5.2575 2.6075 9 P 0 ;1
L 5.2575 2.6575 5.2575 2.6575 9 P 0 ;1
L 5.2575 2.7075 5.2575 2.7075 9 P 0 ;1
L 5.2575 2.7575 5.2575 2.7575 9 P 0 ;1
L 5.2575 2.8075 5.2575 2.8075 9 P 0 ;1
L 5.2575 2.8575 5.2575 2.8575 9 P 0 ;1
L 5.3075 0.5575 5.3075 0.5575 9 P 0 ;1
L 5.3075 0.6075 5.3075 0.6075 9 P 0 ;1
L 5.3075 0.6575 5.3075 0.6575 9 P 0 ;1
L 5.3075 0.7075 5.3075 0.7075 9 P 0 ;1
L 5.3075 0.7575 5.3075 0.7575 9 P 0 ;1
L 5.3075 0.8075 5.3075 0.8075 9 P 0 ;1
L 5.3075 0.8575 5.3075 0.8575 9 P 0 ;1
L 5.3075 0.9075 5.3075 0.9075 9 P 0 ;1
L 5.3075 0.9575 5.3075 0.9575 9 P 0 ;1
L 5.3075 1.0075 5.3075 1.0075 9 P 0 ;1
L 5.3075 1.0575 5.3075 1.0575 9 P 0 ;1
L 5.3075 1.1075 5.3075 1.1075 9 P 0 ;1
L 5.3075 1.1575 5.3075 1.1575 9 P 0 ;1
L 5.3075 1.2075 5.3075 1.2075 9 P 0 ;1
L 5.3075 1.2575 5.3075 1.2575 9 P 0 ;1
L 5.3075 1.3075 5.3075 1.3075 9 P 0 ;1
L 5.3075 1.3575 5.3075 1.3575 9 P 0 ;1
L 5.3075 1.4075 5.3075 1.4075 9 P 0 ;1
L 5.3075 1.4575 5.3075 1.4575 9 P 0 ;1
L 5.3075 1.5075 5.3075 1.5075 9 P 0 ;1
L 5.3075 1.5575 5.3075 1.5575 9 P 0 ;1
L 5.3075 2.1075 5.3075 2.1075 9 P 0 ;1
L 5.3075 3.4075 5.3075 3.4075 9 P 0 ;1
L 5.3075 3.4575 5.3075 3.4575 9 P 0 ;1
L 5.3075 3.5075 5.3075 3.5075 9 P 0 ;1
L 5.3075 3.5575 5.3075 3.5575 9 P 0 ;1
L 5.3075 3.6075 5.3075 3.6075 9 P 0 ;1
L 5.3075 3.6575 5.3075 3.6575 9 P 0 ;1
L 5.3075 3.7075 5.3075 3.7075 9 P 0 ;1
L 5.3075 3.7575 5.3075 3.7575 9 P 0 ;1
L 5.3075 3.8075 5.3075 3.8075 9 P 0 ;1
L 5.3575 0.5575 5.3575 0.5575 9 P 0 ;1
L 5.3575 0.6075 5.3575 0.6075 9 P 0 ;1
L 5.3575 0.6575 5.3575 0.6575 9 P 0 ;1
L 5.3575 0.7075 5.3575 0.7075 9 P 0 ;1
L 5.3575 0.7575 5.3575 0.7575 9 P 0 ;1
L 5.3575 0.8075 5.3575 0.8075 9 P 0 ;1
L 5.3575 0.8575 5.3575 0.8575 9 P 0 ;1
L 5.3575 0.9075 5.3575 0.9075 9 P 0 ;1
L 5.3575 0.9575 5.3575 0.9575 9 P 0 ;1
L 5.3575 1.0075 5.3575 1.0075 9 P 0 ;1
L 5.3575 1.0575 5.3575 1.0575 9 P 0 ;1
L 5.3575 1.1075 5.3575 1.1075 9 P 0 ;1
L 5.3575 1.1575 5.3575 1.1575 9 P 0 ;1
L 5.3575 1.2075 5.3575 1.2075 9 P 0 ;1
L 5.3575 1.2575 5.3575 1.2575 9 P 0 ;1
L 5.3575 1.3075 5.3575 1.3075 9 P 0 ;1
L 5.3575 1.3575 5.3575 1.3575 9 P 0 ;1
L 5.3575 1.4075 5.3575 1.4075 9 P 0 ;1
L 5.3575 1.4575 5.3575 1.4575 9 P 0 ;1
L 5.3575 1.5075 5.3575 1.5075 9 P 0 ;1
L 5.3575 3.0075 5.3575 3.0075 9 P 0 ;1
L 5.3575 3.0575 5.3575 3.0575 9 P 0 ;1
L 5.3575 3.1075 5.3575 3.1075 9 P 0 ;1
L 5.3575 3.1575 5.3575 3.1575 9 P 0 ;1
L 5.3575 3.2075 5.3575 3.2075 9 P 0 ;1
L 5.3575 3.2575 5.3575 3.2575 9 P 0 ;1
L 5.3575 3.3075 5.3575 3.3075 9 P 0 ;1
L 5.3575 3.3575 5.3575 3.3575 9 P 0 ;1
L 5.3575 3.4075 5.3575 3.4075 9 P 0 ;1
L 5.3575 3.4575 5.3575 3.4575 9 P 0 ;1
L 5.3575 3.5075 5.3575 3.5075 9 P 0 ;1
L 5.3575 3.5575 5.3575 3.5575 9 P 0 ;1
L 5.3575 3.6075 5.3575 3.6075 9 P 0 ;1
L 5.3575 3.6575 5.3575 3.6575 9 P 0 ;1
L 5.3575 3.7075 5.3575 3.7075 9 P 0 ;1
L 5.3575 3.7575 5.3575 3.7575 9 P 0 ;1
L 5.4075 0.5575 5.4075 0.5575 9 P 0 ;1
L 5.4075 0.6075 5.4075 0.6075 9 P 0 ;1
L 5.4075 0.6575 5.4075 0.6575 9 P 0 ;1
L 5.4075 0.7075 5.4075 0.7075 9 P 0 ;1
L 5.4075 0.7575 5.4075 0.7575 9 P 0 ;1
L 5.4075 0.8075 5.4075 0.8075 9 P 0 ;1
L 5.4075 0.8575 5.4075 0.8575 9 P 0 ;1
L 5.4075 0.9075 5.4075 0.9075 9 P 0 ;1
L 5.4075 0.9575 5.4075 0.9575 9 P 0 ;1
L 5.4075 1.0075 5.4075 1.0075 9 P 0 ;1
L 5.4075 1.0575 5.4075 1.0575 9 P 0 ;1
L 5.4075 1.1075 5.4075 1.1075 9 P 0 ;1
L 5.4075 1.1575 5.4075 1.1575 9 P 0 ;1
L 5.4075 1.2075 5.4075 1.2075 9 P 0 ;1
L 5.4075 1.2575 5.4075 1.2575 9 P 0 ;1
L 5.4075 1.3075 5.4075 1.3075 9 P 0 ;1
L 5.4075 1.3575 5.4075 1.3575 9 P 0 ;1
L 5.4075 1.4075 5.4075 1.4075 9 P 0 ;1
L 5.4075 1.4575 5.4075 1.4575 9 P 0 ;1
L 5.4075 1.5075 5.4075 1.5075 9 P 0 ;1
L 5.4075 3.4075 5.4075 3.4075 9 P 0 ;1
L 5.4075 3.4575 5.4075 3.4575 9 P 0 ;1
L 5.4075 3.5075 5.4075 3.5075 9 P 0 ;1
L 5.4075 3.5575 5.4075 3.5575 9 P 0 ;1
L 5.4075 3.6075 5.4075 3.6075 9 P 0 ;1
L 5.4075 3.6575 5.4075 3.6575 9 P 0 ;1
L 5.4075 3.7075 5.4075 3.7075 9 P 0 ;1
L 5.4575 0.5575 5.4575 0.5575 9 P 0 ;1
L 5.4575 0.6075 5.4575 0.6075 9 P 0 ;1
L 5.4575 0.6575 5.4575 0.6575 9 P 0 ;1
L 5.4575 0.7075 5.4575 0.7075 9 P 0 ;1
L 5.4575 0.7575 5.4575 0.7575 9 P 0 ;1
L 5.4575 0.8075 5.4575 0.8075 9 P 0 ;1
L 5.4575 0.8575 5.4575 0.8575 9 P 0 ;1
L 5.4575 0.9075 5.4575 0.9075 9 P 0 ;1
L 5.4575 0.9575 5.4575 0.9575 9 P 0 ;1
L 5.4575 1.0075 5.4575 1.0075 9 P 0 ;1
L 5.4575 1.0575 5.4575 1.0575 9 P 0 ;1
L 5.4575 1.1075 5.4575 1.1075 9 P 0 ;1
L 5.4575 1.1575 5.4575 1.1575 9 P 0 ;1
L 5.4575 1.2075 5.4575 1.2075 9 P 0 ;1
L 5.4575 1.2575 5.4575 1.2575 9 P 0 ;1
L 5.4575 1.3075 5.4575 1.3075 9 P 0 ;1
L 5.4575 1.3575 5.4575 1.3575 9 P 0 ;1
L 5.4575 1.4075 5.4575 1.4075 9 P 0 ;1
L 5.4575 1.4575 5.4575 1.4575 9 P 0 ;1
L 5.4575 1.5075 5.4575 1.5075 9 P 0 ;1
L 5.4575 3.4075 5.4575 3.4075 9 P 0 ;1
L 5.4575 3.4575 5.4575 3.4575 9 P 0 ;1
L 5.4575 3.5075 5.4575 3.5075 9 P 0 ;1
L 5.4575 3.5575 5.4575 3.5575 9 P 0 ;1
L 5.4575 3.6075 5.4575 3.6075 9 P 0 ;1
L 5.4575 3.6575 5.4575 3.6575 9 P 0 ;1
L 5.5075 0.5575 5.5075 0.5575 9 P 0 ;1
L 5.5075 0.6075 5.5075 0.6075 9 P 0 ;1
L 5.5075 0.6575 5.5075 0.6575 9 P 0 ;1
L 5.5075 0.7075 5.5075 0.7075 9 P 0 ;1
L 5.5075 0.7575 5.5075 0.7575 9 P 0 ;1
L 5.5075 0.8075 5.5075 0.8075 9 P 0 ;1
L 5.5075 0.8575 5.5075 0.8575 9 P 0 ;1
L 5.5075 0.9075 5.5075 0.9075 9 P 0 ;1
L 5.5075 0.9575 5.5075 0.9575 9 P 0 ;1
L 5.5075 1.0075 5.5075 1.0075 9 P 0 ;1
L 5.5075 1.0575 5.5075 1.0575 9 P 0 ;1
L 5.5075 1.1075 5.5075 1.1075 9 P 0 ;1
L 5.5075 1.1575 5.5075 1.1575 9 P 0 ;1
L 5.5075 1.2075 5.5075 1.2075 9 P 0 ;1
L 5.5075 1.2575 5.5075 1.2575 9 P 0 ;1
L 5.5075 1.3075 5.5075 1.3075 9 P 0 ;1
L 5.5075 1.3575 5.5075 1.3575 9 P 0 ;1
L 5.5075 1.4075 5.5075 1.4075 9 P 0 ;1
L 5.5075 1.4575 5.5075 1.4575 9 P 0 ;1
L 5.5075 1.5075 5.5075 1.5075 9 P 0 ;1
L 5.5075 1.5575 5.5075 1.5575 9 P 0 ;1
L 5.5075 3.3575 5.5075 3.3575 9 P 0 ;1
L 5.5075 3.4075 5.5075 3.4075 9 P 0 ;1
L 5.5075 3.4575 5.5075 3.4575 9 P 0 ;1
L 5.5075 3.5075 5.5075 3.5075 9 P 0 ;1
L 5.5075 3.5575 5.5075 3.5575 9 P 0 ;1
L 5.5075 3.6075 5.5075 3.6075 9 P 0 ;1
L 5.5575 0.5575 5.5575 0.5575 9 P 0 ;1
L 5.5575 0.6075 5.5575 0.6075 9 P 0 ;1
L 5.5575 0.6575 5.5575 0.6575 9 P 0 ;1
L 5.5575 0.7075 5.5575 0.7075 9 P 0 ;1
L 5.5575 0.7575 5.5575 0.7575 9 P 0 ;1
L 5.5575 0.8075 5.5575 0.8075 9 P 0 ;1
L 5.5575 0.8575 5.5575 0.8575 9 P 0 ;1
L 5.5575 0.9075 5.5575 0.9075 9 P 0 ;1
L 5.5575 0.9575 5.5575 0.9575 9 P 0 ;1
L 5.5575 1.0075 5.5575 1.0075 9 P 0 ;1
L 5.5575 1.0575 5.5575 1.0575 9 P 0 ;1
L 5.5575 1.1075 5.5575 1.1075 9 P 0 ;1
L 5.5575 1.1575 5.5575 1.1575 9 P 0 ;1
L 5.5575 1.2075 5.5575 1.2075 9 P 0 ;1
L 5.5575 1.2575 5.5575 1.2575 9 P 0 ;1
L 5.5575 1.3075 5.5575 1.3075 9 P 0 ;1
L 5.5575 1.3575 5.5575 1.3575 9 P 0 ;1
L 5.5575 1.4075 5.5575 1.4075 9 P 0 ;1
L 5.5575 1.4575 5.5575 1.4575 9 P 0 ;1
L 5.5575 1.5075 5.5575 1.5075 9 P 0 ;1
L 5.5575 1.5575 5.5575 1.5575 9 P 0 ;1
L 5.5575 3.1075 5.5575 3.1075 9 P 0 ;1
L 5.5575 3.1575 5.5575 3.1575 9 P 0 ;1
L 5.5575 3.2075 5.5575 3.2075 9 P 0 ;1
L 5.5575 3.2575 5.5575 3.2575 9 P 0 ;1
L 5.5575 3.3075 5.5575 3.3075 9 P 0 ;1
L 5.5575 3.3575 5.5575 3.3575 9 P 0 ;1
L 5.5575 3.4075 5.5575 3.4075 9 P 0 ;1
L 5.5575 3.4575 5.5575 3.4575 9 P 0 ;1
L 5.5575 3.5075 5.5575 3.5075 9 P 0 ;1
L 5.5575 3.5575 5.5575 3.5575 9 P 0 ;1
L 5.6075 0.5575 5.6075 0.5575 9 P 0 ;1
L 5.6075 0.6075 5.6075 0.6075 9 P 0 ;1
L 5.6075 0.6575 5.6075 0.6575 9 P 0 ;1
L 5.6075 0.7075 5.6075 0.7075 9 P 0 ;1
L 5.6075 0.7575 5.6075 0.7575 9 P 0 ;1
L 5.6075 0.8075 5.6075 0.8075 9 P 0 ;1
L 5.6075 0.8575 5.6075 0.8575 9 P 0 ;1
L 5.6075 0.9075 5.6075 0.9075 9 P 0 ;1
L 5.6075 0.9575 5.6075 0.9575 9 P 0 ;1
L 5.6075 1.0075 5.6075 1.0075 9 P 0 ;1
L 5.6075 1.0575 5.6075 1.0575 9 P 0 ;1
L 5.6075 1.1075 5.6075 1.1075 9 P 0 ;1
L 5.6075 1.1575 5.6075 1.1575 9 P 0 ;1
L 5.6075 1.2075 5.6075 1.2075 9 P 0 ;1
L 5.6075 1.2575 5.6075 1.2575 9 P 0 ;1
L 5.6075 1.3075 5.6075 1.3075 9 P 0 ;1
L 5.6075 1.3575 5.6075 1.3575 9 P 0 ;1
L 5.6075 1.4075 5.6075 1.4075 9 P 0 ;1
L 5.6075 1.4575 5.6075 1.4575 9 P 0 ;1
L 5.6075 1.5075 5.6075 1.5075 9 P 0 ;1
L 5.6075 1.5575 5.6075 1.5575 9 P 0 ;1
L 5.6575 0.5575 5.6575 0.5575 9 P 0 ;1
L 5.6575 0.6075 5.6575 0.6075 9 P 0 ;1
L 5.6575 0.6575 5.6575 0.6575 9 P 0 ;1
L 5.6575 0.7075 5.6575 0.7075 9 P 0 ;1
L 5.6575 0.7575 5.6575 0.7575 9 P 0 ;1
L 5.6575 0.8075 5.6575 0.8075 9 P 0 ;1
L 5.6575 0.8575 5.6575 0.8575 9 P 0 ;1
L 5.6575 0.9075 5.6575 0.9075 9 P 0 ;1
L 5.6575 0.9575 5.6575 0.9575 9 P 0 ;1
L 5.6575 1.0075 5.6575 1.0075 9 P 0 ;1
L 5.6575 1.0575 5.6575 1.0575 9 P 0 ;1
L 5.6575 1.1075 5.6575 1.1075 9 P 0 ;1
L 5.6575 1.1575 5.6575 1.1575 9 P 0 ;1
L 5.6575 1.2075 5.6575 1.2075 9 P 0 ;1
L 5.6575 1.2575 5.6575 1.2575 9 P 0 ;1
L 5.6575 1.3075 5.6575 1.3075 9 P 0 ;1
L 5.6575 1.3575 5.6575 1.3575 9 P 0 ;1
L 5.6575 1.4075 5.6575 1.4075 9 P 0 ;1
L 5.6575 1.4575 5.6575 1.4575 9 P 0 ;1
L 5.6575 1.5075 5.6575 1.5075 9 P 0 ;1
L 5.6575 1.5575 5.6575 1.5575 9 P 0 ;1
L 5.6575 1.6075 5.6575 1.6075 9 P 0 ;1
L 5.6575 1.6575 5.6575 1.6575 9 P 0 ;1
L 5.6575 1.7075 5.6575 1.7075 9 P 0 ;1
L 5.6575 1.7575 5.6575 1.7575 9 P 0 ;1
L 5.6575 1.8075 5.6575 1.8075 9 P 0 ;1
L 5.6575 1.8575 5.6575 1.8575 9 P 0 ;1
L 5.6575 1.9075 5.6575 1.9075 9 P 0 ;1
L 5.6575 1.9575 5.6575 1.9575 9 P 0 ;1
L 5.6575 2.0075 5.6575 2.0075 9 P 0 ;1
L 5.6575 2.0575 5.6575 2.0575 9 P 0 ;1
L 5.6575 2.1075 5.6575 2.1075 9 P 0 ;1
L 5.6575 2.1575 5.6575 2.1575 9 P 0 ;1
L 5.6575 2.2075 5.6575 2.2075 9 P 0 ;1
L 5.6575 2.2575 5.6575 2.2575 9 P 0 ;1
L 5.6575 2.3075 5.6575 2.3075 9 P 0 ;1
L 5.6575 2.3575 5.6575 2.3575 9 P 0 ;1
L 5.6575 2.4075 5.6575 2.4075 9 P 0 ;1
L 5.6575 2.4575 5.6575 2.4575 9 P 0 ;1
L 5.6575 2.5075 5.6575 2.5075 9 P 0 ;1
L 5.6575 2.5575 5.6575 2.5575 9 P 0 ;1
L 5.6575 2.6075 5.6575 2.6075 9 P 0 ;1
L 5.6575 4.4075 5.6575 4.4075 9 P 0 ;1
L 5.7075 0.5575 5.7075 0.5575 9 P 0 ;1
L 5.7075 0.6075 5.7075 0.6075 9 P 0 ;1
L 5.7075 0.6575 5.7075 0.6575 9 P 0 ;1
L 5.7075 0.7075 5.7075 0.7075 9 P 0 ;1
L 5.7075 0.7575 5.7075 0.7575 9 P 0 ;1
L 5.7075 0.8075 5.7075 0.8075 9 P 0 ;1
L 5.7075 0.8575 5.7075 0.8575 9 P 0 ;1
L 5.7075 0.9075 5.7075 0.9075 9 P 0 ;1
L 5.7075 0.9575 5.7075 0.9575 9 P 0 ;1
L 5.7075 1.0075 5.7075 1.0075 9 P 0 ;1
L 5.7075 1.0575 5.7075 1.0575 9 P 0 ;1
L 5.7075 1.1075 5.7075 1.1075 9 P 0 ;1
L 5.7075 1.1575 5.7075 1.1575 9 P 0 ;1
L 5.7075 1.2075 5.7075 1.2075 9 P 0 ;1
L 5.7075 1.2575 5.7075 1.2575 9 P 0 ;1
L 5.7075 1.3075 5.7075 1.3075 9 P 0 ;1
L 5.7075 1.3575 5.7075 1.3575 9 P 0 ;1
L 5.7075 1.4075 5.7075 1.4075 9 P 0 ;1
L 5.7075 1.4575 5.7075 1.4575 9 P 0 ;1
L 5.7075 1.5075 5.7075 1.5075 9 P 0 ;1
L 5.7075 1.5575 5.7075 1.5575 9 P 0 ;1
L 5.7075 1.6075 5.7075 1.6075 9 P 0 ;1
L 5.7075 1.6575 5.7075 1.6575 9 P 0 ;1
L 5.7075 1.7075 5.7075 1.7075 9 P 0 ;1
L 5.7075 1.7575 5.7075 1.7575 9 P 0 ;1
L 5.7075 1.8075 5.7075 1.8075 9 P 0 ;1
L 5.7075 1.8575 5.7075 1.8575 9 P 0 ;1
L 5.7075 1.9075 5.7075 1.9075 9 P 0 ;1
L 5.7075 1.9575 5.7075 1.9575 9 P 0 ;1
L 5.7075 2.0075 5.7075 2.0075 9 P 0 ;1
L 5.7075 2.0575 5.7075 2.0575 9 P 0 ;1
L 5.7075 2.1075 5.7075 2.1075 9 P 0 ;1
L 5.7075 2.1575 5.7075 2.1575 9 P 0 ;1
L 5.7075 2.2075 5.7075 2.2075 9 P 0 ;1
L 5.7075 2.2575 5.7075 2.2575 9 P 0 ;1
L 5.7075 2.3075 5.7075 2.3075 9 P 0 ;1
L 5.7075 2.3575 5.7075 2.3575 9 P 0 ;1
L 5.7075 2.4075 5.7075 2.4075 9 P 0 ;1
L 5.7075 2.4575 5.7075 2.4575 9 P 0 ;1
L 5.7075 2.5075 5.7075 2.5075 9 P 0 ;1
L 5.7075 2.5575 5.7075 2.5575 9 P 0 ;1
L 5.7075 4.3575 5.7075 4.3575 9 P 0 ;1
L 5.7075 4.4075 5.7075 4.4075 9 P 0 ;1
L 5.7075 4.9075 5.7075 4.9075 9 P 0 ;1
L 5.7575 0.5575 5.7575 0.5575 9 P 0 ;1
L 5.7575 0.6075 5.7575 0.6075 9 P 0 ;1
L 5.7575 0.6575 5.7575 0.6575 9 P 0 ;1
L 5.7575 0.7075 5.7575 0.7075 9 P 0 ;1
L 5.7575 0.7575 5.7575 0.7575 9 P 0 ;1
L 5.7575 0.8075 5.7575 0.8075 9 P 0 ;1
L 5.7575 0.8575 5.7575 0.8575 9 P 0 ;1
L 5.7575 1.0075 5.7575 1.0075 9 P 0 ;1
L 5.7575 1.0575 5.7575 1.0575 9 P 0 ;1
L 5.7575 1.1075 5.7575 1.1075 9 P 0 ;1
L 5.7575 1.1575 5.7575 1.1575 9 P 0 ;1
L 5.7575 1.2075 5.7575 1.2075 9 P 0 ;1
L 5.7575 1.2575 5.7575 1.2575 9 P 0 ;1
L 5.7575 1.3075 5.7575 1.3075 9 P 0 ;1
L 5.7575 1.3575 5.7575 1.3575 9 P 0 ;1
L 5.7575 1.4075 5.7575 1.4075 9 P 0 ;1
L 5.7575 1.4575 5.7575 1.4575 9 P 0 ;1
L 5.7575 1.5075 5.7575 1.5075 9 P 0 ;1
L 5.7575 1.5575 5.7575 1.5575 9 P 0 ;1
L 5.7575 1.6075 5.7575 1.6075 9 P 0 ;1
L 5.7575 1.6575 5.7575 1.6575 9 P 0 ;1
L 5.7575 1.7075 5.7575 1.7075 9 P 0 ;1
L 5.7575 1.7575 5.7575 1.7575 9 P 0 ;1
L 5.7575 1.8075 5.7575 1.8075 9 P 0 ;1
L 5.7575 1.8575 5.7575 1.8575 9 P 0 ;1
L 5.7575 1.9075 5.7575 1.9075 9 P 0 ;1
L 5.7575 1.9575 5.7575 1.9575 9 P 0 ;1
L 5.7575 2.0075 5.7575 2.0075 9 P 0 ;1
L 5.7575 2.0575 5.7575 2.0575 9 P 0 ;1
L 5.7575 2.1075 5.7575 2.1075 9 P 0 ;1
L 5.7575 2.1575 5.7575 2.1575 9 P 0 ;1
L 5.7575 2.2075 5.7575 2.2075 9 P 0 ;1
L 5.7575 2.2575 5.7575 2.2575 9 P 0 ;1
L 5.7575 2.3075 5.7575 2.3075 9 P 0 ;1
L 5.7575 2.3575 5.7575 2.3575 9 P 0 ;1
L 5.7575 2.4075 5.7575 2.4075 9 P 0 ;1
L 5.7575 2.4575 5.7575 2.4575 9 P 0 ;1
L 5.7575 2.5075 5.7575 2.5075 9 P 0 ;1
L 5.7575 2.5575 5.7575 2.5575 9 P 0 ;1
L 5.7575 4.3075 5.7575 4.3075 9 P 0 ;1
L 5.7575 4.3575 5.7575 4.3575 9 P 0 ;1
L 5.7575 4.4075 5.7575 4.4075 9 P 0 ;1
L 5.7575 4.9075 5.7575 4.9075 9 P 0 ;1
L 5.8075 0.5575 5.8075 0.5575 9 P 0 ;1
L 5.8075 0.6075 5.8075 0.6075 9 P 0 ;1
L 5.8075 0.6575 5.8075 0.6575 9 P 0 ;1
L 5.8075 0.7075 5.8075 0.7075 9 P 0 ;1
L 5.8075 0.7575 5.8075 0.7575 9 P 0 ;1
L 5.8075 0.8075 5.8075 0.8075 9 P 0 ;1
L 5.8075 1.0075 5.8075 1.0075 9 P 0 ;1
L 5.8075 1.0575 5.8075 1.0575 9 P 0 ;1
L 5.8075 1.1075 5.8075 1.1075 9 P 0 ;1
L 5.8075 1.1575 5.8075 1.1575 9 P 0 ;1
L 5.8075 1.2075 5.8075 1.2075 9 P 0 ;1
L 5.8075 1.2575 5.8075 1.2575 9 P 0 ;1
L 5.8075 1.3075 5.8075 1.3075 9 P 0 ;1
L 5.8075 1.3575 5.8075 1.3575 9 P 0 ;1
L 5.8075 1.4075 5.8075 1.4075 9 P 0 ;1
L 5.8075 1.4575 5.8075 1.4575 9 P 0 ;1
L 5.8075 1.5075 5.8075 1.5075 9 P 0 ;1
L 5.8075 1.5575 5.8075 1.5575 9 P 0 ;1
L 5.8075 1.6075 5.8075 1.6075 9 P 0 ;1
L 5.8075 1.6575 5.8075 1.6575 9 P 0 ;1
L 5.8075 1.7075 5.8075 1.7075 9 P 0 ;1
L 5.8075 1.7575 5.8075 1.7575 9 P 0 ;1
L 5.8075 1.8075 5.8075 1.8075 9 P 0 ;1
L 5.8075 1.8575 5.8075 1.8575 9 P 0 ;1
L 5.8075 1.9075 5.8075 1.9075 9 P 0 ;1
L 5.8075 1.9575 5.8075 1.9575 9 P 0 ;1
L 5.8075 2.0075 5.8075 2.0075 9 P 0 ;1
L 5.8075 2.0575 5.8075 2.0575 9 P 0 ;1
L 5.8075 2.1075 5.8075 2.1075 9 P 0 ;1
L 5.8075 2.1575 5.8075 2.1575 9 P 0 ;1
L 5.8075 2.2075 5.8075 2.2075 9 P 0 ;1
L 5.8075 2.2575 5.8075 2.2575 9 P 0 ;1
L 5.8075 2.3075 5.8075 2.3075 9 P 0 ;1
L 5.8075 2.3575 5.8075 2.3575 9 P 0 ;1
L 5.8075 2.4075 5.8075 2.4075 9 P 0 ;1
L 5.8075 2.4575 5.8075 2.4575 9 P 0 ;1
L 5.8075 2.5075 5.8075 2.5075 9 P 0 ;1
L 5.8075 2.5575 5.8075 2.5575 9 P 0 ;1
L 5.8075 4.2575 5.8075 4.2575 9 P 0 ;1
L 5.8075 4.3075 5.8075 4.3075 9 P 0 ;1
L 5.8075 4.3575 5.8075 4.3575 9 P 0 ;1
L 5.8075 4.4075 5.8075 4.4075 9 P 0 ;1
L 5.8075 4.9075 5.8075 4.9075 9 P 0 ;1
L 5.8575 0.5575 5.8575 0.5575 9 P 0 ;1
L 5.8575 0.6075 5.8575 0.6075 9 P 0 ;1
L 5.8575 0.6575 5.8575 0.6575 9 P 0 ;1
L 5.8575 0.7075 5.8575 0.7075 9 P 0 ;1
L 5.8575 0.7575 5.8575 0.7575 9 P 0 ;1
L 5.8575 0.8075 5.8575 0.8075 9 P 0 ;1
L 5.8575 1.0075 5.8575 1.0075 9 P 0 ;1
L 5.8575 1.0575 5.8575 1.0575 9 P 0 ;1
L 5.8575 1.1075 5.8575 1.1075 9 P 0 ;1
L 5.8575 1.1575 5.8575 1.1575 9 P 0 ;1
L 5.8575 1.2075 5.8575 1.2075 9 P 0 ;1
L 5.8575 1.2575 5.8575 1.2575 9 P 0 ;1
L 5.8575 1.3075 5.8575 1.3075 9 P 0 ;1
L 5.8575 1.3575 5.8575 1.3575 9 P 0 ;1
L 5.8575 1.4075 5.8575 1.4075 9 P 0 ;1
L 5.8575 1.4575 5.8575 1.4575 9 P 0 ;1
L 5.8575 1.5075 5.8575 1.5075 9 P 0 ;1
L 5.8575 1.5575 5.8575 1.5575 9 P 0 ;1
L 5.8575 1.6075 5.8575 1.6075 9 P 0 ;1
L 5.8575 1.6575 5.8575 1.6575 9 P 0 ;1
L 5.8575 1.7075 5.8575 1.7075 9 P 0 ;1
L 5.8575 1.7575 5.8575 1.7575 9 P 0 ;1
L 5.8575 1.8075 5.8575 1.8075 9 P 0 ;1
L 5.8575 1.8575 5.8575 1.8575 9 P 0 ;1
L 5.8575 1.9075 5.8575 1.9075 9 P 0 ;1
L 5.8575 1.9575 5.8575 1.9575 9 P 0 ;1
L 5.8575 2.0075 5.8575 2.0075 9 P 0 ;1
L 5.8575 2.0575 5.8575 2.0575 9 P 0 ;1
L 5.8575 2.1075 5.8575 2.1075 9 P 0 ;1
L 5.8575 2.1575 5.8575 2.1575 9 P 0 ;1
L 5.8575 2.2075 5.8575 2.2075 9 P 0 ;1
L 5.8575 2.2575 5.8575 2.2575 9 P 0 ;1
L 5.8575 2.3075 5.8575 2.3075 9 P 0 ;1
L 5.8575 2.3575 5.8575 2.3575 9 P 0 ;1
L 5.8575 2.4075 5.8575 2.4075 9 P 0 ;1
L 5.8575 2.4575 5.8575 2.4575 9 P 0 ;1
L 5.8575 2.5075 5.8575 2.5075 9 P 0 ;1
L 5.8575 2.5575 5.8575 2.5575 9 P 0 ;1
L 5.8575 2.6075 5.8575 2.6075 9 P 0 ;1
L 5.8575 4.2075 5.8575 4.2075 9 P 0 ;1
L 5.8575 4.2575 5.8575 4.2575 9 P 0 ;1
L 5.8575 4.3075 5.8575 4.3075 9 P 0 ;1
L 5.8575 4.3575 5.8575 4.3575 9 P 0 ;1
L 5.8575 4.4075 5.8575 4.4075 9 P 0 ;1
L 5.8575 4.9075 5.8575 4.9075 9 P 0 ;1
L 5.9075 0.5575 5.9075 0.5575 9 P 0 ;1
L 5.9075 0.6075 5.9075 0.6075 9 P 0 ;1
L 5.9075 0.6575 5.9075 0.6575 9 P 0 ;1
L 5.9075 0.7075 5.9075 0.7075 9 P 0 ;1
L 5.9075 0.7575 5.9075 0.7575 9 P 0 ;1
L 5.9075 0.8075 5.9075 0.8075 9 P 0 ;1
L 5.9075 0.8575 5.9075 0.8575 9 P 0 ;1
L 5.9075 1.0075 5.9075 1.0075 9 P 0 ;1
L 5.9075 1.0575 5.9075 1.0575 9 P 0 ;1
L 5.9075 1.1075 5.9075 1.1075 9 P 0 ;1
L 5.9075 1.1575 5.9075 1.1575 9 P 0 ;1
L 5.9075 1.2075 5.9075 1.2075 9 P 0 ;1
L 5.9075 1.2575 5.9075 1.2575 9 P 0 ;1
L 5.9075 1.3075 5.9075 1.3075 9 P 0 ;1
L 5.9075 1.3575 5.9075 1.3575 9 P 0 ;1
L 5.9075 1.4075 5.9075 1.4075 9 P 0 ;1
L 5.9075 1.4575 5.9075 1.4575 9 P 0 ;1
L 5.9075 1.5075 5.9075 1.5075 9 P 0 ;1
L 5.9075 1.5575 5.9075 1.5575 9 P 0 ;1
L 5.9075 1.6075 5.9075 1.6075 9 P 0 ;1
L 5.9075 1.6575 5.9075 1.6575 9 P 0 ;1
L 5.9075 1.7075 5.9075 1.7075 9 P 0 ;1
L 5.9075 1.7575 5.9075 1.7575 9 P 0 ;1
L 5.9075 1.8075 5.9075 1.8075 9 P 0 ;1
L 5.9075 1.8575 5.9075 1.8575 9 P 0 ;1
L 5.9075 1.9075 5.9075 1.9075 9 P 0 ;1
L 5.9075 1.9575 5.9075 1.9575 9 P 0 ;1
L 5.9075 2.0075 5.9075 2.0075 9 P 0 ;1
L 5.9075 2.0575 5.9075 2.0575 9 P 0 ;1
L 5.9075 2.1075 5.9075 2.1075 9 P 0 ;1
L 5.9075 2.1575 5.9075 2.1575 9 P 0 ;1
L 5.9075 2.2075 5.9075 2.2075 9 P 0 ;1
L 5.9075 2.2575 5.9075 2.2575 9 P 0 ;1
L 5.9075 2.3075 5.9075 2.3075 9 P 0 ;1
L 5.9075 2.3575 5.9075 2.3575 9 P 0 ;1
L 5.9075 2.4075 5.9075 2.4075 9 P 0 ;1
L 5.9075 2.4575 5.9075 2.4575 9 P 0 ;1
L 5.9075 2.5075 5.9075 2.5075 9 P 0 ;1
L 5.9075 2.5575 5.9075 2.5575 9 P 0 ;1
L 5.9075 2.6075 5.9075 2.6075 9 P 0 ;1
L 5.9075 4.1575 5.9075 4.1575 9 P 0 ;1
L 5.9075 4.2075 5.9075 4.2075 9 P 0 ;1
L 5.9075 4.2575 5.9075 4.2575 9 P 0 ;1
L 5.9075 4.3075 5.9075 4.3075 9 P 0 ;1
L 5.9075 4.3575 5.9075 4.3575 9 P 0 ;1
L 5.9075 4.4075 5.9075 4.4075 9 P 0 ;1
L 5.9075 4.9075 5.9075 4.9075 9 P 0 ;1
L 5.9575 0.5575 5.9575 0.5575 9 P 0 ;1
L 5.9575 0.6075 5.9575 0.6075 9 P 0 ;1
L 5.9575 0.6575 5.9575 0.6575 9 P 0 ;1
L 5.9575 0.7075 5.9575 0.7075 9 P 0 ;1
L 5.9575 0.7575 5.9575 0.7575 9 P 0 ;1
L 5.9575 0.8075 5.9575 0.8075 9 P 0 ;1
L 5.9575 0.8575 5.9575 0.8575 9 P 0 ;1
L 5.9575 0.9075 5.9575 0.9075 9 P 0 ;1
L 5.9575 0.9575 5.9575 0.9575 9 P 0 ;1
L 5.9575 1.0075 5.9575 1.0075 9 P 0 ;1
L 5.9575 1.0575 5.9575 1.0575 9 P 0 ;1
L 5.9575 1.1075 5.9575 1.1075 9 P 0 ;1
L 5.9575 1.1575 5.9575 1.1575 9 P 0 ;1
L 5.9575 1.2075 5.9575 1.2075 9 P 0 ;1
L 5.9575 1.2575 5.9575 1.2575 9 P 0 ;1
L 5.9575 1.3075 5.9575 1.3075 9 P 0 ;1
L 5.9575 1.3575 5.9575 1.3575 9 P 0 ;1
L 5.9575 1.6575 5.9575 1.6575 9 P 0 ;1
L 5.9575 1.7075 5.9575 1.7075 9 P 0 ;1
L 5.9575 1.7575 5.9575 1.7575 9 P 0 ;1
L 5.9575 1.8075 5.9575 1.8075 9 P 0 ;1
L 5.9575 1.8575 5.9575 1.8575 9 P 0 ;1
L 5.9575 1.9075 5.9575 1.9075 9 P 0 ;1
L 5.9575 1.9575 5.9575 1.9575 9 P 0 ;1
L 5.9575 2.0075 5.9575 2.0075 9 P 0 ;1
L 5.9575 2.0575 5.9575 2.0575 9 P 0 ;1
L 5.9575 2.1075 5.9575 2.1075 9 P 0 ;1
L 5.9575 2.1575 5.9575 2.1575 9 P 0 ;1
L 5.9575 2.2075 5.9575 2.2075 9 P 0 ;1
L 5.9575 2.2575 5.9575 2.2575 9 P 0 ;1
L 5.9575 2.3075 5.9575 2.3075 9 P 0 ;1
L 5.9575 2.3575 5.9575 2.3575 9 P 0 ;1
L 5.9575 2.4075 5.9575 2.4075 9 P 0 ;1
L 5.9575 2.4575 5.9575 2.4575 9 P 0 ;1
L 5.9575 4.3575 5.9575 4.3575 9 P 0 ;1
L 5.9575 4.4075 5.9575 4.4075 9 P 0 ;1
L 5.9575 4.9075 5.9575 4.9075 9 P 0 ;1
L 6.0075 0.5575 6.0075 0.5575 9 P 0 ;1
L 6.0075 0.6075 6.0075 0.6075 9 P 0 ;1
L 6.0075 0.6575 6.0075 0.6575 9 P 0 ;1
L 6.0075 0.7075 6.0075 0.7075 9 P 0 ;1
L 6.0075 0.7575 6.0075 0.7575 9 P 0 ;1
L 6.0075 0.8075 6.0075 0.8075 9 P 0 ;1
L 6.0075 0.8575 6.0075 0.8575 9 P 0 ;1
L 6.0075 0.9075 6.0075 0.9075 9 P 0 ;1
L 6.0075 0.9575 6.0075 0.9575 9 P 0 ;1
L 6.0075 1.0075 6.0075 1.0075 9 P 0 ;1
L 6.0075 1.0575 6.0075 1.0575 9 P 0 ;1
L 6.0075 1.1075 6.0075 1.1075 9 P 0 ;1
L 6.0075 1.1575 6.0075 1.1575 9 P 0 ;1
L 6.0075 1.2075 6.0075 1.2075 9 P 0 ;1
L 6.0075 1.2575 6.0075 1.2575 9 P 0 ;1
L 6.0075 1.3075 6.0075 1.3075 9 P 0 ;1
L 6.0075 1.3575 6.0075 1.3575 9 P 0 ;1
L 6.0075 1.7075 6.0075 1.7075 9 P 0 ;1
L 6.0075 1.7575 6.0075 1.7575 9 P 0 ;1
L 6.0075 1.8075 6.0075 1.8075 9 P 0 ;1
L 6.0075 1.8575 6.0075 1.8575 9 P 0 ;1
L 6.0075 1.9075 6.0075 1.9075 9 P 0 ;1
L 6.0075 1.9575 6.0075 1.9575 9 P 0 ;1
L 6.0075 2.0075 6.0075 2.0075 9 P 0 ;1
L 6.0075 2.0575 6.0075 2.0575 9 P 0 ;1
L 6.0075 2.1075 6.0075 2.1075 9 P 0 ;1
L 6.0075 2.1575 6.0075 2.1575 9 P 0 ;1
L 6.0075 2.2075 6.0075 2.2075 9 P 0 ;1
L 6.0075 2.2575 6.0075 2.2575 9 P 0 ;1
L 6.0075 2.3075 6.0075 2.3075 9 P 0 ;1
L 6.0075 2.3575 6.0075 2.3575 9 P 0 ;1
L 6.0075 2.4075 6.0075 2.4075 9 P 0 ;1
L 6.0075 4.4075 6.0075 4.4075 9 P 0 ;1
L 6.0075 4.9075 6.0075 4.9075 9 P 0 ;1
L 6.0575 0.5575 6.0575 0.5575 9 P 0 ;1
L 6.0575 0.6075 6.0575 0.6075 9 P 0 ;1
L 6.0575 0.6575 6.0575 0.6575 9 P 0 ;1
L 6.0575 0.7075 6.0575 0.7075 9 P 0 ;1
L 6.0575 0.7575 6.0575 0.7575 9 P 0 ;1
L 6.0575 0.8075 6.0575 0.8075 9 P 0 ;1
L 6.0575 0.8575 6.0575 0.8575 9 P 0 ;1
L 6.0575 0.9075 6.0575 0.9075 9 P 0 ;1
L 6.0575 0.9575 6.0575 0.9575 9 P 0 ;1
L 6.0575 1.0075 6.0575 1.0075 9 P 0 ;1
L 6.0575 1.0575 6.0575 1.0575 9 P 0 ;1
L 6.0575 1.1075 6.0575 1.1075 9 P 0 ;1
L 6.0575 1.1575 6.0575 1.1575 9 P 0 ;1
L 6.0575 1.2075 6.0575 1.2075 9 P 0 ;1
L 6.0575 1.2575 6.0575 1.2575 9 P 0 ;1
L 6.0575 1.3075 6.0575 1.3075 9 P 0 ;1
L 6.0575 1.7575 6.0575 1.7575 9 P 0 ;1
L 6.0575 1.8075 6.0575 1.8075 9 P 0 ;1
L 6.0575 1.8575 6.0575 1.8575 9 P 0 ;1
L 6.0575 1.9075 6.0575 1.9075 9 P 0 ;1
L 6.0575 1.9575 6.0575 1.9575 9 P 0 ;1
L 6.0575 2.0075 6.0575 2.0075 9 P 0 ;1
L 6.0575 2.0575 6.0575 2.0575 9 P 0 ;1
L 6.0575 2.1075 6.0575 2.1075 9 P 0 ;1
L 6.0575 2.1575 6.0575 2.1575 9 P 0 ;1
L 6.0575 2.2075 6.0575 2.2075 9 P 0 ;1
L 6.0575 2.2575 6.0575 2.2575 9 P 0 ;1
L 6.0575 2.3075 6.0575 2.3075 9 P 0 ;1
L 6.0575 2.3575 6.0575 2.3575 9 P 0 ;1
L 6.0575 2.4075 6.0575 2.4075 9 P 0 ;1
L 6.0575 3.9575 6.0575 3.9575 9 P 0 ;1
L 6.0575 4.0075 6.0575 4.0075 9 P 0 ;1
L 6.0575 4.4075 6.0575 4.4075 9 P 0 ;1
L 6.0575 4.9075 6.0575 4.9075 9 P 0 ;1
L 6.1075 0.5575 6.1075 0.5575 9 P 0 ;1
L 6.1075 0.6075 6.1075 0.6075 9 P 0 ;1
L 6.1075 0.6575 6.1075 0.6575 9 P 0 ;1
L 6.1075 0.7075 6.1075 0.7075 9 P 0 ;1
L 6.1075 0.7575 6.1075 0.7575 9 P 0 ;1
L 6.1075 0.8075 6.1075 0.8075 9 P 0 ;1
L 6.1075 0.8575 6.1075 0.8575 9 P 0 ;1
L 6.1075 0.9075 6.1075 0.9075 9 P 0 ;1
L 6.1075 0.9575 6.1075 0.9575 9 P 0 ;1
L 6.1075 1.0075 6.1075 1.0075 9 P 0 ;1
L 6.1075 1.0575 6.1075 1.0575 9 P 0 ;1
L 6.1075 1.1075 6.1075 1.1075 9 P 0 ;1
L 6.1075 1.1575 6.1075 1.1575 9 P 0 ;1
L 6.1075 1.2075 6.1075 1.2075 9 P 0 ;1
L 6.1075 1.2575 6.1075 1.2575 9 P 0 ;1
L 6.1075 1.3075 6.1075 1.3075 9 P 0 ;1
L 6.1075 1.7575 6.1075 1.7575 9 P 0 ;1
L 6.1075 1.8075 6.1075 1.8075 9 P 0 ;1
L 6.1075 1.8575 6.1075 1.8575 9 P 0 ;1
L 6.1075 1.9075 6.1075 1.9075 9 P 0 ;1
L 6.1075 1.9575 6.1075 1.9575 9 P 0 ;1
L 6.1075 2.0075 6.1075 2.0075 9 P 0 ;1
L 6.1075 2.0575 6.1075 2.0575 9 P 0 ;1
L 6.1075 2.1075 6.1075 2.1075 9 P 0 ;1
L 6.1075 2.1575 6.1075 2.1575 9 P 0 ;1
L 6.1075 2.2075 6.1075 2.2075 9 P 0 ;1
L 6.1075 2.2575 6.1075 2.2575 9 P 0 ;1
L 6.1075 2.3075 6.1075 2.3075 9 P 0 ;1
L 6.1075 2.3575 6.1075 2.3575 9 P 0 ;1
L 6.1075 2.4075 6.1075 2.4075 9 P 0 ;1
L 6.1075 3.1575 6.1075 3.1575 9 P 0 ;1
L 6.1075 3.2075 6.1075 3.2075 9 P 0 ;1
L 6.1075 3.2575 6.1075 3.2575 9 P 0 ;1
L 6.1075 3.3075 6.1075 3.3075 9 P 0 ;1
L 6.1075 3.3575 6.1075 3.3575 9 P 0 ;1
L 6.1075 3.4075 6.1075 3.4075 9 P 0 ;1
L 6.1075 3.4575 6.1075 3.4575 9 P 0 ;1
L 6.1075 3.5075 6.1075 3.5075 9 P 0 ;1
L 6.1075 3.5575 6.1075 3.5575 9 P 0 ;1
L 6.1075 3.6075 6.1075 3.6075 9 P 0 ;1
L 6.1075 3.6575 6.1075 3.6575 9 P 0 ;1
L 6.1075 3.7075 6.1075 3.7075 9 P 0 ;1
L 6.1075 3.7575 6.1075 3.7575 9 P 0 ;1
L 6.1075 3.8075 6.1075 3.8075 9 P 0 ;1
L 6.1075 3.8575 6.1075 3.8575 9 P 0 ;1
L 6.1075 3.9075 6.1075 3.9075 9 P 0 ;1
L 6.1075 3.9575 6.1075 3.9575 9 P 0 ;1
L 6.1575 0.5575 6.1575 0.5575 9 P 0 ;1
L 6.1575 0.6075 6.1575 0.6075 9 P 0 ;1
L 6.1575 0.6575 6.1575 0.6575 9 P 0 ;1
L 6.1575 0.7075 6.1575 0.7075 9 P 0 ;1
L 6.1575 0.7575 6.1575 0.7575 9 P 0 ;1
L 6.1575 0.8075 6.1575 0.8075 9 P 0 ;1
L 6.1575 0.8575 6.1575 0.8575 9 P 0 ;1
L 6.1575 0.9075 6.1575 0.9075 9 P 0 ;1
L 6.1575 0.9575 6.1575 0.9575 9 P 0 ;1
L 6.1575 1.0075 6.1575 1.0075 9 P 0 ;1
L 6.1575 1.0575 6.1575 1.0575 9 P 0 ;1
L 6.1575 1.1075 6.1575 1.1075 9 P 0 ;1
L 6.1575 1.1575 6.1575 1.1575 9 P 0 ;1
L 6.1575 1.2075 6.1575 1.2075 9 P 0 ;1
L 6.1575 1.2575 6.1575 1.2575 9 P 0 ;1
L 6.1575 1.3075 6.1575 1.3075 9 P 0 ;1
L 6.1575 1.7575 6.1575 1.7575 9 P 0 ;1
L 6.1575 1.8075 6.1575 1.8075 9 P 0 ;1
L 6.1575 1.8575 6.1575 1.8575 9 P 0 ;1
L 6.1575 1.9075 6.1575 1.9075 9 P 0 ;1
L 6.1575 1.9575 6.1575 1.9575 9 P 0 ;1
L 6.1575 2.0075 6.1575 2.0075 9 P 0 ;1
L 6.1575 2.0575 6.1575 2.0575 9 P 0 ;1
L 6.1575 2.1075 6.1575 2.1075 9 P 0 ;1
L 6.1575 2.1575 6.1575 2.1575 9 P 0 ;1
L 6.1575 2.2075 6.1575 2.2075 9 P 0 ;1
L 6.1575 2.2575 6.1575 2.2575 9 P 0 ;1
L 6.1575 2.3075 6.1575 2.3075 9 P 0 ;1
L 6.1575 2.3575 6.1575 2.3575 9 P 0 ;1
L 6.1575 2.4075 6.1575 2.4075 9 P 0 ;1
L 6.1575 2.4575 6.1575 2.4575 9 P 0 ;1
L 6.1575 3.2075 6.1575 3.2075 9 P 0 ;1
L 6.1575 3.2575 6.1575 3.2575 9 P 0 ;1
L 6.1575 3.3075 6.1575 3.3075 9 P 0 ;1
L 6.1575 3.3575 6.1575 3.3575 9 P 0 ;1
L 6.1575 3.4075 6.1575 3.4075 9 P 0 ;1
L 6.1575 3.4575 6.1575 3.4575 9 P 0 ;1
L 6.1575 3.5075 6.1575 3.5075 9 P 0 ;1
L 6.1575 3.5575 6.1575 3.5575 9 P 0 ;1
L 6.1575 3.6075 6.1575 3.6075 9 P 0 ;1
L 6.1575 3.6575 6.1575 3.6575 9 P 0 ;1
L 6.1575 3.7075 6.1575 3.7075 9 P 0 ;1
L 6.1575 3.7575 6.1575 3.7575 9 P 0 ;1
L 6.1575 3.8075 6.1575 3.8075 9 P 0 ;1
L 6.1575 3.8575 6.1575 3.8575 9 P 0 ;1
L 6.1575 3.9075 6.1575 3.9075 9 P 0 ;1
L 6.1575 3.9575 6.1575 3.9575 9 P 0 ;1
L 6.1575 4.4075 6.1575 4.4075 9 P 0 ;1
L 6.1575 5.0075 6.1575 5.0075 9 P 0 ;1
L 6.2075 0.5575 6.2075 0.5575 9 P 0 ;1
L 6.2075 0.6075 6.2075 0.6075 9 P 0 ;1
L 6.2075 0.6575 6.2075 0.6575 9 P 0 ;1
L 6.2075 0.7075 6.2075 0.7075 9 P 0 ;1
L 6.2075 0.7575 6.2075 0.7575 9 P 0 ;1
L 6.2075 0.8075 6.2075 0.8075 9 P 0 ;1
L 6.2075 0.8575 6.2075 0.8575 9 P 0 ;1
L 6.2075 0.9075 6.2075 0.9075 9 P 0 ;1
L 6.2075 0.9575 6.2075 0.9575 9 P 0 ;1
L 6.2075 1.0075 6.2075 1.0075 9 P 0 ;1
L 6.2075 1.0575 6.2075 1.0575 9 P 0 ;1
L 6.2075 1.1075 6.2075 1.1075 9 P 0 ;1
L 6.2075 1.1575 6.2075 1.1575 9 P 0 ;1
L 6.2075 1.2075 6.2075 1.2075 9 P 0 ;1
L 6.2075 1.2575 6.2075 1.2575 9 P 0 ;1
L 6.2075 1.3075 6.2075 1.3075 9 P 0 ;1
L 6.2075 1.3575 6.2075 1.3575 9 P 0 ;1
L 6.2075 1.7075 6.2075 1.7075 9 P 0 ;1
L 6.2075 1.7575 6.2075 1.7575 9 P 0 ;1
L 6.2075 1.8075 6.2075 1.8075 9 P 0 ;1
L 6.2075 1.8575 6.2075 1.8575 9 P 0 ;1
L 6.2075 1.9075 6.2075 1.9075 9 P 0 ;1
L 6.2075 1.9575 6.2075 1.9575 9 P 0 ;1
L 6.2075 2.0075 6.2075 2.0075 9 P 0 ;1
L 6.2075 2.0575 6.2075 2.0575 9 P 0 ;1
L 6.2075 2.1075 6.2075 2.1075 9 P 0 ;1
L 6.2075 2.1575 6.2075 2.1575 9 P 0 ;1
L 6.2075 2.2075 6.2075 2.2075 9 P 0 ;1
L 6.2075 2.2575 6.2075 2.2575 9 P 0 ;1
L 6.2075 2.3075 6.2075 2.3075 9 P 0 ;1
L 6.2075 2.3575 6.2075 2.3575 9 P 0 ;1
L 6.2075 2.4075 6.2075 2.4075 9 P 0 ;1
L 6.2075 2.4575 6.2075 2.4575 9 P 0 ;1
L 6.2075 2.5075 6.2075 2.5075 9 P 0 ;1
L 6.2075 2.5575 6.2075 2.5575 9 P 0 ;1
L 6.2075 2.6075 6.2075 2.6075 9 P 0 ;1
L 6.2075 3.2575 6.2075 3.2575 9 P 0 ;1
L 6.2075 3.3075 6.2075 3.3075 9 P 0 ;1
L 6.2075 3.3575 6.2075 3.3575 9 P 0 ;1
L 6.2075 3.4075 6.2075 3.4075 9 P 0 ;1
L 6.2075 3.4575 6.2075 3.4575 9 P 0 ;1
L 6.2075 3.5075 6.2075 3.5075 9 P 0 ;1
L 6.2075 3.5575 6.2075 3.5575 9 P 0 ;1
L 6.2075 3.6075 6.2075 3.6075 9 P 0 ;1
L 6.2075 3.6575 6.2075 3.6575 9 P 0 ;1
L 6.2075 3.7075 6.2075 3.7075 9 P 0 ;1
L 6.2075 3.7575 6.2075 3.7575 9 P 0 ;1
L 6.2075 3.8075 6.2075 3.8075 9 P 0 ;1
L 6.2075 3.8575 6.2075 3.8575 9 P 0 ;1
L 6.2075 3.9075 6.2075 3.9075 9 P 0 ;1
L 6.2075 3.9575 6.2075 3.9575 9 P 0 ;1
L 6.2075 4.0075 6.2075 4.0075 9 P 0 ;1
L 6.2075 4.4075 6.2075 4.4075 9 P 0 ;1
L 6.2075 4.4575 6.2075 4.4575 9 P 0 ;1
L 6.2075 4.5075 6.2075 4.5075 9 P 0 ;1
L 6.2075 4.5575 6.2075 4.5575 9 P 0 ;1
L 6.2075 5.0075 6.2075 5.0075 9 P 0 ;1
L 6.2075 5.0575 6.2075 5.0575 9 P 0 ;1
L 6.2575 0.5575 6.2575 0.5575 9 P 0 ;1
L 6.2575 0.6075 6.2575 0.6075 9 P 0 ;1
L 6.2575 0.6575 6.2575 0.6575 9 P 0 ;1
L 6.2575 0.7075 6.2575 0.7075 9 P 0 ;1
L 6.2575 0.7575 6.2575 0.7575 9 P 0 ;1
L 6.2575 0.8075 6.2575 0.8075 9 P 0 ;1
L 6.2575 0.8575 6.2575 0.8575 9 P 0 ;1
L 6.2575 0.9075 6.2575 0.9075 9 P 0 ;1
L 6.2575 0.9575 6.2575 0.9575 9 P 0 ;1
L 6.2575 1.0075 6.2575 1.0075 9 P 0 ;1
L 6.2575 1.0575 6.2575 1.0575 9 P 0 ;1
L 6.2575 1.1075 6.2575 1.1075 9 P 0 ;1
L 6.2575 1.1575 6.2575 1.1575 9 P 0 ;1
L 6.2575 1.2075 6.2575 1.2075 9 P 0 ;1
L 6.2575 1.2575 6.2575 1.2575 9 P 0 ;1
L 6.2575 1.3075 6.2575 1.3075 9 P 0 ;1
L 6.2575 1.3575 6.2575 1.3575 9 P 0 ;1
L 6.2575 1.7075 6.2575 1.7075 9 P 0 ;1
L 6.2575 1.7575 6.2575 1.7575 9 P 0 ;1
L 6.2575 1.8075 6.2575 1.8075 9 P 0 ;1
L 6.2575 1.8575 6.2575 1.8575 9 P 0 ;1
L 6.2575 1.9075 6.2575 1.9075 9 P 0 ;1
L 6.2575 1.9575 6.2575 1.9575 9 P 0 ;1
L 6.2575 2.0075 6.2575 2.0075 9 P 0 ;1
L 6.2575 2.0575 6.2575 2.0575 9 P 0 ;1
L 6.2575 2.1075 6.2575 2.1075 9 P 0 ;1
L 6.2575 2.1575 6.2575 2.1575 9 P 0 ;1
L 6.2575 2.2075 6.2575 2.2075 9 P 0 ;1
L 6.2575 2.2575 6.2575 2.2575 9 P 0 ;1
L 6.2575 2.3075 6.2575 2.3075 9 P 0 ;1
L 6.2575 2.3575 6.2575 2.3575 9 P 0 ;1
L 6.2575 2.4075 6.2575 2.4075 9 P 0 ;1
L 6.2575 2.4575 6.2575 2.4575 9 P 0 ;1
L 6.2575 2.5075 6.2575 2.5075 9 P 0 ;1
L 6.2575 2.5575 6.2575 2.5575 9 P 0 ;1
L 6.2575 2.6075 6.2575 2.6075 9 P 0 ;1
L 6.2575 2.6575 6.2575 2.6575 9 P 0 ;1
L 6.2575 3.3075 6.2575 3.3075 9 P 0 ;1
L 6.2575 3.3575 6.2575 3.3575 9 P 0 ;1
L 6.2575 3.4075 6.2575 3.4075 9 P 0 ;1
L 6.2575 3.4575 6.2575 3.4575 9 P 0 ;1
L 6.2575 3.5075 6.2575 3.5075 9 P 0 ;1
L 6.2575 3.5575 6.2575 3.5575 9 P 0 ;1
L 6.2575 3.6075 6.2575 3.6075 9 P 0 ;1
L 6.2575 3.6575 6.2575 3.6575 9 P 0 ;1
L 6.2575 3.7075 6.2575 3.7075 9 P 0 ;1
L 6.2575 3.7575 6.2575 3.7575 9 P 0 ;1
L 6.2575 3.8075 6.2575 3.8075 9 P 0 ;1
L 6.2575 3.8575 6.2575 3.8575 9 P 0 ;1
L 6.2575 3.9075 6.2575 3.9075 9 P 0 ;1
L 6.2575 3.9575 6.2575 3.9575 9 P 0 ;1
L 6.2575 4.0075 6.2575 4.0075 9 P 0 ;1
L 6.2575 4.4075 6.2575 4.4075 9 P 0 ;1
L 6.2575 4.4575 6.2575 4.4575 9 P 0 ;1
L 6.2575 4.5075 6.2575 4.5075 9 P 0 ;1
L 6.2575 4.5575 6.2575 4.5575 9 P 0 ;1
L 6.2575 5.0575 6.2575 5.0575 9 P 0 ;1
L 6.3075 0.5575 6.3075 0.5575 9 P 0 ;1
L 6.3075 0.6075 6.3075 0.6075 9 P 0 ;1
L 6.3075 0.6575 6.3075 0.6575 9 P 0 ;1
L 6.3075 0.7075 6.3075 0.7075 9 P 0 ;1
L 6.3075 0.7575 6.3075 0.7575 9 P 0 ;1
L 6.3075 0.8075 6.3075 0.8075 9 P 0 ;1
L 6.3075 0.8575 6.3075 0.8575 9 P 0 ;1
L 6.3075 0.9075 6.3075 0.9075 9 P 0 ;1
L 6.3075 0.9575 6.3075 0.9575 9 P 0 ;1
L 6.3075 1.0075 6.3075 1.0075 9 P 0 ;1
L 6.3075 1.0575 6.3075 1.0575 9 P 0 ;1
L 6.3075 1.1075 6.3075 1.1075 9 P 0 ;1
L 6.3075 1.1575 6.3075 1.1575 9 P 0 ;1
L 6.3075 1.2075 6.3075 1.2075 9 P 0 ;1
L 6.3075 1.2575 6.3075 1.2575 9 P 0 ;1
L 6.3075 1.3075 6.3075 1.3075 9 P 0 ;1
L 6.3075 1.3575 6.3075 1.3575 9 P 0 ;1
L 6.3075 1.4075 6.3075 1.4075 9 P 0 ;1
L 6.3075 1.4575 6.3075 1.4575 9 P 0 ;1
L 6.3075 1.6075 6.3075 1.6075 9 P 0 ;1
L 6.3075 1.6575 6.3075 1.6575 9 P 0 ;1
L 6.3075 1.7075 6.3075 1.7075 9 P 0 ;1
L 6.3075 1.7575 6.3075 1.7575 9 P 0 ;1
L 6.3075 1.8075 6.3075 1.8075 9 P 0 ;1
L 6.3075 1.8575 6.3075 1.8575 9 P 0 ;1
L 6.3075 1.9075 6.3075 1.9075 9 P 0 ;1
L 6.3075 1.9575 6.3075 1.9575 9 P 0 ;1
L 6.3075 2.0075 6.3075 2.0075 9 P 0 ;1
L 6.3075 2.0575 6.3075 2.0575 9 P 0 ;1
L 6.3075 2.1075 6.3075 2.1075 9 P 0 ;1
L 6.3075 2.1575 6.3075 2.1575 9 P 0 ;1
L 6.3075 2.2075 6.3075 2.2075 9 P 0 ;1
L 6.3075 2.2575 6.3075 2.2575 9 P 0 ;1
L 6.3075 2.3075 6.3075 2.3075 9 P 0 ;1
L 6.3075 2.3575 6.3075 2.3575 9 P 0 ;1
L 6.3075 2.4075 6.3075 2.4075 9 P 0 ;1
L 6.3075 2.4575 6.3075 2.4575 9 P 0 ;1
L 6.3075 2.5075 6.3075 2.5075 9 P 0 ;1
L 6.3075 2.5575 6.3075 2.5575 9 P 0 ;1
L 6.3075 2.6075 6.3075 2.6075 9 P 0 ;1
L 6.3075 2.6575 6.3075 2.6575 9 P 0 ;1
L 6.3075 2.7075 6.3075 2.7075 9 P 0 ;1
L 6.3075 3.3575 6.3075 3.3575 9 P 0 ;1
L 6.3075 3.4075 6.3075 3.4075 9 P 0 ;1
L 6.3075 3.4575 6.3075 3.4575 9 P 0 ;1
L 6.3075 3.5075 6.3075 3.5075 9 P 0 ;1
L 6.3075 3.5575 6.3075 3.5575 9 P 0 ;1
L 6.3075 3.6075 6.3075 3.6075 9 P 0 ;1
L 6.3075 3.6575 6.3075 3.6575 9 P 0 ;1
L 6.3075 3.7075 6.3075 3.7075 9 P 0 ;1
L 6.3075 3.7575 6.3075 3.7575 9 P 0 ;1
L 6.3075 3.8075 6.3075 3.8075 9 P 0 ;1
L 6.3075 3.8575 6.3075 3.8575 9 P 0 ;1
L 6.3075 3.9075 6.3075 3.9075 9 P 0 ;1
L 6.3075 3.9575 6.3075 3.9575 9 P 0 ;1
L 6.3075 4.0075 6.3075 4.0075 9 P 0 ;1
L 6.3075 4.0575 6.3075 4.0575 9 P 0 ;1
L 6.3075 4.1075 6.3075 4.1075 9 P 0 ;1
L 6.3075 4.3075 6.3075 4.3075 9 P 0 ;1
L 6.3075 4.3575 6.3075 4.3575 9 P 0 ;1
L 6.3075 4.4075 6.3075 4.4075 9 P 0 ;1
L 6.3075 4.4575 6.3075 4.4575 9 P 0 ;1
L 6.3075 4.5075 6.3075 4.5075 9 P 0 ;1
L 6.3575 0.5575 6.3575 0.5575 9 P 0 ;1
L 6.3575 0.6075 6.3575 0.6075 9 P 0 ;1
L 6.3575 0.6575 6.3575 0.6575 9 P 0 ;1
L 6.3575 0.7075 6.3575 0.7075 9 P 0 ;1
L 6.3575 0.7575 6.3575 0.7575 9 P 0 ;1
L 6.3575 0.8075 6.3575 0.8075 9 P 0 ;1
L 6.3575 0.8575 6.3575 0.8575 9 P 0 ;1
L 6.3575 0.9075 6.3575 0.9075 9 P 0 ;1
L 6.3575 0.9575 6.3575 0.9575 9 P 0 ;1
L 6.3575 1.0075 6.3575 1.0075 9 P 0 ;1
L 6.3575 1.0575 6.3575 1.0575 9 P 0 ;1
L 6.3575 1.1075 6.3575 1.1075 9 P 0 ;1
L 6.3575 1.1575 6.3575 1.1575 9 P 0 ;1
L 6.3575 1.2075 6.3575 1.2075 9 P 0 ;1
L 6.3575 1.2575 6.3575 1.2575 9 P 0 ;1
L 6.3575 1.3075 6.3575 1.3075 9 P 0 ;1
L 6.3575 1.3575 6.3575 1.3575 9 P 0 ;1
L 6.3575 1.4075 6.3575 1.4075 9 P 0 ;1
L 6.3575 1.4575 6.3575 1.4575 9 P 0 ;1
L 6.3575 1.5075 6.3575 1.5075 9 P 0 ;1
L 6.3575 1.5575 6.3575 1.5575 9 P 0 ;1
L 6.3575 1.6075 6.3575 1.6075 9 P 0 ;1
L 6.3575 1.6575 6.3575 1.6575 9 P 0 ;1
L 6.3575 1.7075 6.3575 1.7075 9 P 0 ;1
L 6.3575 1.7575 6.3575 1.7575 9 P 0 ;1
L 6.3575 1.8075 6.3575 1.8075 9 P 0 ;1
L 6.3575 1.8575 6.3575 1.8575 9 P 0 ;1
L 6.3575 1.9075 6.3575 1.9075 9 P 0 ;1
L 6.3575 1.9575 6.3575 1.9575 9 P 0 ;1
L 6.3575 2.0075 6.3575 2.0075 9 P 0 ;1
L 6.3575 2.0575 6.3575 2.0575 9 P 0 ;1
L 6.3575 2.1075 6.3575 2.1075 9 P 0 ;1
L 6.3575 2.1575 6.3575 2.1575 9 P 0 ;1
L 6.3575 2.2075 6.3575 2.2075 9 P 0 ;1
L 6.3575 2.2575 6.3575 2.2575 9 P 0 ;1
L 6.3575 2.3075 6.3575 2.3075 9 P 0 ;1
L 6.3575 2.3575 6.3575 2.3575 9 P 0 ;1
L 6.3575 2.4075 6.3575 2.4075 9 P 0 ;1
L 6.3575 2.4575 6.3575 2.4575 9 P 0 ;1
L 6.3575 2.5075 6.3575 2.5075 9 P 0 ;1
L 6.3575 2.5575 6.3575 2.5575 9 P 0 ;1
L 6.3575 2.6075 6.3575 2.6075 9 P 0 ;1
L 6.3575 2.6575 6.3575 2.6575 9 P 0 ;1
L 6.3575 2.7075 6.3575 2.7075 9 P 0 ;1
L 6.3575 2.7575 6.3575 2.7575 9 P 0 ;1
L 6.3575 3.4075 6.3575 3.4075 9 P 0 ;1
L 6.3575 3.4575 6.3575 3.4575 9 P 0 ;1
L 6.3575 3.5075 6.3575 3.5075 9 P 0 ;1
L 6.3575 3.5575 6.3575 3.5575 9 P 0 ;1
L 6.3575 3.6075 6.3575 3.6075 9 P 0 ;1
L 6.3575 3.6575 6.3575 3.6575 9 P 0 ;1
L 6.3575 3.7075 6.3575 3.7075 9 P 0 ;1
L 6.3575 3.7575 6.3575 3.7575 9 P 0 ;1
L 6.3575 3.8075 6.3575 3.8075 9 P 0 ;1
L 6.3575 3.8575 6.3575 3.8575 9 P 0 ;1
L 6.3575 3.9075 6.3575 3.9075 9 P 0 ;1
L 6.3575 3.9575 6.3575 3.9575 9 P 0 ;1
L 6.3575 4.0075 6.3575 4.0075 9 P 0 ;1
L 6.3575 4.0575 6.3575 4.0575 9 P 0 ;1
L 6.3575 4.1075 6.3575 4.1075 9 P 0 ;1
L 6.3575 4.1575 6.3575 4.1575 9 P 0 ;1
L 6.3575 4.2075 6.3575 4.2075 9 P 0 ;1
L 6.3575 4.2575 6.3575 4.2575 9 P 0 ;1
L 6.3575 4.3075 6.3575 4.3075 9 P 0 ;1
L 6.3575 4.3575 6.3575 4.3575 9 P 0 ;1
L 6.3575 4.4075 6.3575 4.4075 9 P 0 ;1
L 6.3575 4.4575 6.3575 4.4575 9 P 0 ;1
L 6.3575 4.5075 6.3575 4.5075 9 P 0 ;1
L 6.4075 0.5575 6.4075 0.5575 9 P 0 ;1
L 6.4075 0.6075 6.4075 0.6075 9 P 0 ;1
L 6.4075 0.6575 6.4075 0.6575 9 P 0 ;1
L 6.4075 0.7075 6.4075 0.7075 9 P 0 ;1
L 6.4075 0.7575 6.4075 0.7575 9 P 0 ;1
L 6.4075 0.8075 6.4075 0.8075 9 P 0 ;1
L 6.4075 0.8575 6.4075 0.8575 9 P 0 ;1
L 6.4075 0.9075 6.4075 0.9075 9 P 0 ;1
L 6.4075 0.9575 6.4075 0.9575 9 P 0 ;1
L 6.4075 1.0075 6.4075 1.0075 9 P 0 ;1
L 6.4075 1.0575 6.4075 1.0575 9 P 0 ;1
L 6.4075 1.1075 6.4075 1.1075 9 P 0 ;1
L 6.4075 1.1575 6.4075 1.1575 9 P 0 ;1
L 6.4075 1.2075 6.4075 1.2075 9 P 0 ;1
L 6.4075 1.2575 6.4075 1.2575 9 P 0 ;1
L 6.4075 1.3075 6.4075 1.3075 9 P 0 ;1
L 6.4075 1.3575 6.4075 1.3575 9 P 0 ;1
L 6.4075 1.4075 6.4075 1.4075 9 P 0 ;1
L 6.4075 1.4575 6.4075 1.4575 9 P 0 ;1
L 6.4075 1.5075 6.4075 1.5075 9 P 0 ;1
L 6.4075 1.5575 6.4075 1.5575 9 P 0 ;1
L 6.4075 1.6075 6.4075 1.6075 9 P 0 ;1
L 6.4075 1.6575 6.4075 1.6575 9 P 0 ;1
L 6.4075 1.7075 6.4075 1.7075 9 P 0 ;1
L 6.4075 1.7575 6.4075 1.7575 9 P 0 ;1
L 6.4075 1.8075 6.4075 1.8075 9 P 0 ;1
L 6.4075 1.8575 6.4075 1.8575 9 P 0 ;1
L 6.4075 1.9075 6.4075 1.9075 9 P 0 ;1
L 6.4075 1.9575 6.4075 1.9575 9 P 0 ;1
L 6.4075 2.0075 6.4075 2.0075 9 P 0 ;1
L 6.4075 2.0575 6.4075 2.0575 9 P 0 ;1
L 6.4075 2.1075 6.4075 2.1075 9 P 0 ;1
L 6.4075 2.1575 6.4075 2.1575 9 P 0 ;1
L 6.4075 2.2075 6.4075 2.2075 9 P 0 ;1
L 6.4075 2.2575 6.4075 2.2575 9 P 0 ;1
L 6.4075 2.3075 6.4075 2.3075 9 P 0 ;1
L 6.4075 2.3575 6.4075 2.3575 9 P 0 ;1
L 6.4075 2.4075 6.4075 2.4075 9 P 0 ;1
L 6.4075 2.4575 6.4075 2.4575 9 P 0 ;1
L 6.4075 2.5075 6.4075 2.5075 9 P 0 ;1
L 6.4075 2.5575 6.4075 2.5575 9 P 0 ;1
L 6.4075 2.6075 6.4075 2.6075 9 P 0 ;1
L 6.4075 2.6575 6.4075 2.6575 9 P 0 ;1
L 6.4075 2.7075 6.4075 2.7075 9 P 0 ;1
L 6.4075 2.7575 6.4075 2.7575 9 P 0 ;1
L 6.4075 2.8075 6.4075 2.8075 9 P 0 ;1
L 6.4075 3.4575 6.4075 3.4575 9 P 0 ;1
L 6.4075 3.5075 6.4075 3.5075 9 P 0 ;1
L 6.4075 3.5575 6.4075 3.5575 9 P 0 ;1
L 6.4075 3.6075 6.4075 3.6075 9 P 0 ;1
L 6.4075 3.6575 6.4075 3.6575 9 P 0 ;1
L 6.4075 3.7075 6.4075 3.7075 9 P 0 ;1
L 6.4075 3.7575 6.4075 3.7575 9 P 0 ;1
L 6.4075 3.8075 6.4075 3.8075 9 P 0 ;1
L 6.4075 3.8575 6.4075 3.8575 9 P 0 ;1
L 6.4075 3.9075 6.4075 3.9075 9 P 0 ;1
L 6.4075 3.9575 6.4075 3.9575 9 P 0 ;1
L 6.4075 4.0075 6.4075 4.0075 9 P 0 ;1
L 6.4075 4.0575 6.4075 4.0575 9 P 0 ;1
L 6.4075 4.1075 6.4075 4.1075 9 P 0 ;1
L 6.4075 4.1575 6.4075 4.1575 9 P 0 ;1
L 6.4075 4.2075 6.4075 4.2075 9 P 0 ;1
L 6.4075 4.2575 6.4075 4.2575 9 P 0 ;1
L 6.4075 4.3075 6.4075 4.3075 9 P 0 ;1
L 6.4075 4.3575 6.4075 4.3575 9 P 0 ;1
L 6.4075 4.4075 6.4075 4.4075 9 P 0 ;1
L 6.4075 4.4575 6.4075 4.4575 9 P 0 ;1
L 6.4075 4.5075 6.4075 4.5075 9 P 0 ;1
L 6.4075 4.5575 6.4075 4.5575 9 P 0 ;1
L 6.4075 4.6075 6.4075 4.6075 9 P 0 ;1
L 6.4075 4.6575 6.4075 4.6575 9 P 0 ;1
L 6.4075 4.7075 6.4075 4.7075 9 P 0 ;1
L 6.4075 4.7575 6.4075 4.7575 9 P 0 ;1
L 6.4075 4.8075 6.4075 4.8075 9 P 0 ;1
L 6.4075 4.8575 6.4075 4.8575 9 P 0 ;1
L 6.4075 4.9075 6.4075 4.9075 9 P 0 ;1
L 6.4575 0.5575 6.4575 0.5575 9 P 0 ;1
L 6.4575 0.6075 6.4575 0.6075 9 P 0 ;1
L 6.4575 0.6575 6.4575 0.6575 9 P 0 ;1
L 6.4575 0.7075 6.4575 0.7075 9 P 0 ;1
L 6.4575 0.7575 6.4575 0.7575 9 P 0 ;1
L 6.4575 0.8075 6.4575 0.8075 9 P 0 ;1
L 6.4575 0.8575 6.4575 0.8575 9 P 0 ;1
L 6.4575 0.9075 6.4575 0.9075 9 P 0 ;1
L 6.4575 0.9575 6.4575 0.9575 9 P 0 ;1
L 6.4575 1.0075 6.4575 1.0075 9 P 0 ;1
L 6.4575 1.0575 6.4575 1.0575 9 P 0 ;1
L 6.4575 1.1075 6.4575 1.1075 9 P 0 ;1
L 6.4575 1.1575 6.4575 1.1575 9 P 0 ;1
L 6.4575 1.2075 6.4575 1.2075 9 P 0 ;1
L 6.4575 1.2575 6.4575 1.2575 9 P 0 ;1
L 6.4575 1.3075 6.4575 1.3075 9 P 0 ;1
L 6.4575 1.3575 6.4575 1.3575 9 P 0 ;1
L 6.4575 1.4075 6.4575 1.4075 9 P 0 ;1
L 6.4575 1.4575 6.4575 1.4575 9 P 0 ;1
L 6.4575 1.5075 6.4575 1.5075 9 P 0 ;1
L 6.4575 1.5575 6.4575 1.5575 9 P 0 ;1
L 6.4575 1.6075 6.4575 1.6075 9 P 0 ;1
L 6.4575 1.6575 6.4575 1.6575 9 P 0 ;1
L 6.4575 1.7075 6.4575 1.7075 9 P 0 ;1
L 6.4575 1.7575 6.4575 1.7575 9 P 0 ;1
L 6.4575 1.8075 6.4575 1.8075 9 P 0 ;1
L 6.4575 1.8575 6.4575 1.8575 9 P 0 ;1
L 6.4575 1.9075 6.4575 1.9075 9 P 0 ;1
L 6.4575 1.9575 6.4575 1.9575 9 P 0 ;1
L 6.4575 2.0075 6.4575 2.0075 9 P 0 ;1
L 6.4575 2.0575 6.4575 2.0575 9 P 0 ;1
L 6.4575 2.1075 6.4575 2.1075 9 P 0 ;1
L 6.4575 2.1575 6.4575 2.1575 9 P 0 ;1
L 6.4575 2.2075 6.4575 2.2075 9 P 0 ;1
L 6.4575 2.2575 6.4575 2.2575 9 P 0 ;1
L 6.4575 2.3075 6.4575 2.3075 9 P 0 ;1
L 6.4575 2.3575 6.4575 2.3575 9 P 0 ;1
L 6.4575 2.4075 6.4575 2.4075 9 P 0 ;1
L 6.4575 2.4575 6.4575 2.4575 9 P 0 ;1
L 6.4575 2.5075 6.4575 2.5075 9 P 0 ;1
L 6.4575 2.5575 6.4575 2.5575 9 P 0 ;1
L 6.4575 2.6075 6.4575 2.6075 9 P 0 ;1
L 6.4575 2.6575 6.4575 2.6575 9 P 0 ;1
L 6.4575 2.7075 6.4575 2.7075 9 P 0 ;1
L 6.4575 2.7575 6.4575 2.7575 9 P 0 ;1
L 6.4575 2.8075 6.4575 2.8075 9 P 0 ;1
L 6.4575 2.8575 6.4575 2.8575 9 P 0 ;1
L 6.4575 4.5075 6.4575 4.5075 9 P 0 ;1
L 6.4575 4.5575 6.4575 4.5575 9 P 0 ;1
L 6.4575 4.6075 6.4575 4.6075 9 P 0 ;1
L 6.4575 4.6575 6.4575 4.6575 9 P 0 ;1
L 6.4575 4.7075 6.4575 4.7075 9 P 0 ;1
L 6.4575 4.7575 6.4575 4.7575 9 P 0 ;1
L 6.4575 4.8075 6.4575 4.8075 9 P 0 ;1
L 6.4575 4.8575 6.4575 4.8575 9 P 0 ;1
L 6.5075 0.5575 6.5075 0.5575 9 P 0 ;1
L 6.5075 0.6075 6.5075 0.6075 9 P 0 ;1
L 6.5075 0.6575 6.5075 0.6575 9 P 0 ;1
L 6.5075 0.7075 6.5075 0.7075 9 P 0 ;1
L 6.5075 0.7575 6.5075 0.7575 9 P 0 ;1
L 6.5075 0.8075 6.5075 0.8075 9 P 0 ;1
L 6.5075 0.8575 6.5075 0.8575 9 P 0 ;1
L 6.5075 0.9075 6.5075 0.9075 9 P 0 ;1
L 6.5075 0.9575 6.5075 0.9575 9 P 0 ;1
L 6.5075 1.0075 6.5075 1.0075 9 P 0 ;1
L 6.5075 1.0575 6.5075 1.0575 9 P 0 ;1
L 6.5075 1.1075 6.5075 1.1075 9 P 0 ;1
L 6.5075 1.1575 6.5075 1.1575 9 P 0 ;1
L 6.5075 1.2075 6.5075 1.2075 9 P 0 ;1
L 6.5075 1.2575 6.5075 1.2575 9 P 0 ;1
L 6.5075 1.3075 6.5075 1.3075 9 P 0 ;1
L 6.5075 1.3575 6.5075 1.3575 9 P 0 ;1
L 6.5075 1.4075 6.5075 1.4075 9 P 0 ;1
L 6.5075 1.4575 6.5075 1.4575 9 P 0 ;1
L 6.5075 1.5075 6.5075 1.5075 9 P 0 ;1
L 6.5075 1.5575 6.5075 1.5575 9 P 0 ;1
L 6.5075 1.6075 6.5075 1.6075 9 P 0 ;1
L 6.5075 1.6575 6.5075 1.6575 9 P 0 ;1
L 6.5075 1.7075 6.5075 1.7075 9 P 0 ;1
L 6.5075 1.7575 6.5075 1.7575 9 P 0 ;1
L 6.5075 1.8075 6.5075 1.8075 9 P 0 ;1
L 6.5075 1.8575 6.5075 1.8575 9 P 0 ;1
L 6.5075 1.9075 6.5075 1.9075 9 P 0 ;1
L 6.5075 1.9575 6.5075 1.9575 9 P 0 ;1
L 6.5075 2.0075 6.5075 2.0075 9 P 0 ;1
L 6.5075 2.0575 6.5075 2.0575 9 P 0 ;1
L 6.5075 2.1075 6.5075 2.1075 9 P 0 ;1
L 6.5075 2.1575 6.5075 2.1575 9 P 0 ;1
L 6.5075 2.2075 6.5075 2.2075 9 P 0 ;1
L 6.5075 2.2575 6.5075 2.2575 9 P 0 ;1
L 6.5075 2.3075 6.5075 2.3075 9 P 0 ;1
L 6.5075 2.3575 6.5075 2.3575 9 P 0 ;1
L 6.5075 2.4075 6.5075 2.4075 9 P 0 ;1
L 6.5075 2.4575 6.5075 2.4575 9 P 0 ;1
L 6.5075 2.5075 6.5075 2.5075 9 P 0 ;1
L 6.5075 2.5575 6.5075 2.5575 9 P 0 ;1
L 6.5075 2.6075 6.5075 2.6075 9 P 0 ;1
L 6.5075 2.6575 6.5075 2.6575 9 P 0 ;1
L 6.5075 2.7075 6.5075 2.7075 9 P 0 ;1
L 6.5075 2.7575 6.5075 2.7575 9 P 0 ;1
L 6.5075 2.8075 6.5075 2.8075 9 P 0 ;1
L 6.5075 2.8575 6.5075 2.8575 9 P 0 ;1
L 6.5075 2.9075 6.5075 2.9075 9 P 0 ;1
L 6.5075 4.5575 6.5075 4.5575 9 P 0 ;1
L 6.5075 4.6075 6.5075 4.6075 9 P 0 ;1
L 6.5075 4.6575 6.5075 4.6575 9 P 0 ;1
L 6.5075 4.7075 6.5075 4.7075 9 P 0 ;1
L 6.5075 4.7575 6.5075 4.7575 9 P 0 ;1
L 6.5075 4.8075 6.5075 4.8075 9 P 0 ;1
L 6.5575 0.5575 6.5575 0.5575 9 P 0 ;1
L 6.5575 0.6075 6.5575 0.6075 9 P 0 ;1
L 6.5575 0.6575 6.5575 0.6575 9 P 0 ;1
L 6.5575 0.7075 6.5575 0.7075 9 P 0 ;1
L 6.5575 0.7575 6.5575 0.7575 9 P 0 ;1
L 6.5575 0.8075 6.5575 0.8075 9 P 0 ;1
L 6.5575 0.8575 6.5575 0.8575 9 P 0 ;1
L 6.5575 0.9075 6.5575 0.9075 9 P 0 ;1
L 6.5575 0.9575 6.5575 0.9575 9 P 0 ;1
L 6.5575 1.0075 6.5575 1.0075 9 P 0 ;1
L 6.5575 1.0575 6.5575 1.0575 9 P 0 ;1
L 6.5575 1.1075 6.5575 1.1075 9 P 0 ;1
L 6.5575 1.1575 6.5575 1.1575 9 P 0 ;1
L 6.5575 1.2075 6.5575 1.2075 9 P 0 ;1
L 6.5575 1.2575 6.5575 1.2575 9 P 0 ;1
L 6.5575 1.3075 6.5575 1.3075 9 P 0 ;1
L 6.5575 1.3575 6.5575 1.3575 9 P 0 ;1
L 6.5575 1.4075 6.5575 1.4075 9 P 0 ;1
L 6.5575 1.4575 6.5575 1.4575 9 P 0 ;1
L 6.5575 1.5075 6.5575 1.5075 9 P 0 ;1
L 6.5575 1.5575 6.5575 1.5575 9 P 0 ;1
L 6.5575 1.6075 6.5575 1.6075 9 P 0 ;1
L 6.5575 1.6575 6.5575 1.6575 9 P 0 ;1
L 6.5575 1.7075 6.5575 1.7075 9 P 0 ;1
L 6.5575 1.7575 6.5575 1.7575 9 P 0 ;1
L 6.5575 1.8075 6.5575 1.8075 9 P 0 ;1
L 6.5575 1.8575 6.5575 1.8575 9 P 0 ;1
L 6.5575 1.9075 6.5575 1.9075 9 P 0 ;1
L 6.5575 1.9575 6.5575 1.9575 9 P 0 ;1
L 6.5575 2.0075 6.5575 2.0075 9 P 0 ;1
L 6.5575 2.0575 6.5575 2.0575 9 P 0 ;1
L 6.5575 2.1075 6.5575 2.1075 9 P 0 ;1
L 6.5575 2.1575 6.5575 2.1575 9 P 0 ;1
L 6.5575 2.2075 6.5575 2.2075 9 P 0 ;1
L 6.5575 2.2575 6.5575 2.2575 9 P 0 ;1
L 6.5575 2.3075 6.5575 2.3075 9 P 0 ;1
L 6.5575 2.3575 6.5575 2.3575 9 P 0 ;1
L 6.5575 2.4075 6.5575 2.4075 9 P 0 ;1
L 6.5575 2.4575 6.5575 2.4575 9 P 0 ;1
L 6.5575 2.5075 6.5575 2.5075 9 P 0 ;1
L 6.5575 2.5575 6.5575 2.5575 9 P 0 ;1
L 6.5575 2.6075 6.5575 2.6075 9 P 0 ;1
L 6.5575 2.6575 6.5575 2.6575 9 P 0 ;1
L 6.5575 2.7075 6.5575 2.7075 9 P 0 ;1
L 6.5575 2.7575 6.5575 2.7575 9 P 0 ;1
L 6.5575 2.8075 6.5575 2.8075 9 P 0 ;1
L 6.5575 2.8575 6.5575 2.8575 9 P 0 ;1
L 6.5575 2.9075 6.5575 2.9075 9 P 0 ;1
L 6.5575 2.9575 6.5575 2.9575 9 P 0 ;1
L 6.6075 0.5575 6.6075 0.5575 9 P 0 ;1
L 6.6075 0.6075 6.6075 0.6075 9 P 0 ;1
L 6.6075 0.6575 6.6075 0.6575 9 P 0 ;1
L 6.6075 0.7075 6.6075 0.7075 9 P 0 ;1
L 6.6075 0.7575 6.6075 0.7575 9 P 0 ;1
L 6.6075 0.8075 6.6075 0.8075 9 P 0 ;1
L 6.6075 0.8575 6.6075 0.8575 9 P 0 ;1
L 6.6075 0.9075 6.6075 0.9075 9 P 0 ;1
L 6.6075 0.9575 6.6075 0.9575 9 P 0 ;1
L 6.6075 1.0075 6.6075 1.0075 9 P 0 ;1
L 6.6075 1.0575 6.6075 1.0575 9 P 0 ;1
L 6.6075 1.1075 6.6075 1.1075 9 P 0 ;1
L 6.6075 1.1575 6.6075 1.1575 9 P 0 ;1
L 6.6075 1.2075 6.6075 1.2075 9 P 0 ;1
L 6.6075 1.2575 6.6075 1.2575 9 P 0 ;1
L 6.6075 1.3075 6.6075 1.3075 9 P 0 ;1
L 6.6075 1.3575 6.6075 1.3575 9 P 0 ;1
L 6.6075 1.4075 6.6075 1.4075 9 P 0 ;1
L 6.6075 1.4575 6.6075 1.4575 9 P 0 ;1
L 6.6075 1.5075 6.6075 1.5075 9 P 0 ;1
L 6.6075 1.5575 6.6075 1.5575 9 P 0 ;1
L 6.6075 1.6075 6.6075 1.6075 9 P 0 ;1
L 6.6075 1.6575 6.6075 1.6575 9 P 0 ;1
L 6.6075 1.7075 6.6075 1.7075 9 P 0 ;1
L 6.6075 1.7575 6.6075 1.7575 9 P 0 ;1
L 6.6075 1.8075 6.6075 1.8075 9 P 0 ;1
L 6.6075 1.8575 6.6075 1.8575 9 P 0 ;1
L 6.6075 1.9075 6.6075 1.9075 9 P 0 ;1
L 6.6075 1.9575 6.6075 1.9575 9 P 0 ;1
L 6.6075 2.0075 6.6075 2.0075 9 P 0 ;1
L 6.6075 2.0575 6.6075 2.0575 9 P 0 ;1
L 6.6075 2.1075 6.6075 2.1075 9 P 0 ;1
L 6.6075 2.1575 6.6075 2.1575 9 P 0 ;1
L 6.6075 2.2075 6.6075 2.2075 9 P 0 ;1
L 6.6075 2.2575 6.6075 2.2575 9 P 0 ;1
L 6.6075 2.3075 6.6075 2.3075 9 P 0 ;1
L 6.6075 2.3575 6.6075 2.3575 9 P 0 ;1
L 6.6075 2.4075 6.6075 2.4075 9 P 0 ;1
L 6.6075 2.4575 6.6075 2.4575 9 P 0 ;1
L 6.6075 2.5075 6.6075 2.5075 9 P 0 ;1
L 6.6075 2.5575 6.6075 2.5575 9 P 0 ;1
L 6.6075 2.6075 6.6075 2.6075 9 P 0 ;1
L 6.6075 2.6575 6.6075 2.6575 9 P 0 ;1
L 6.6075 2.7075 6.6075 2.7075 9 P 0 ;1
L 6.6075 2.7575 6.6075 2.7575 9 P 0 ;1
L 6.6075 2.8075 6.6075 2.8075 9 P 0 ;1
L 6.6075 2.8575 6.6075 2.8575 9 P 0 ;1
L 6.6075 2.9075 6.6075 2.9075 9 P 0 ;1
L 6.6075 2.9575 6.6075 2.9575 9 P 0 ;1
L 6.6075 3.0075 6.6075 3.0075 9 P 0 ;1
L 6.6575 0.5075 6.6575 0.5075 9 P 0 ;1
L 6.6575 0.5575 6.6575 0.5575 9 P 0 ;1
L 6.6575 0.6075 6.6575 0.6075 9 P 0 ;1
L 6.6575 0.6575 6.6575 0.6575 9 P 0 ;1
L 6.6575 0.7075 6.6575 0.7075 9 P 0 ;1
L 6.6575 0.7575 6.6575 0.7575 9 P 0 ;1
L 6.6575 0.8075 6.6575 0.8075 9 P 0 ;1
L 6.6575 0.8575 6.6575 0.8575 9 P 0 ;1
L 6.6575 0.9075 6.6575 0.9075 9 P 0 ;1
L 6.6575 0.9575 6.6575 0.9575 9 P 0 ;1
L 6.6575 1.0075 6.6575 1.0075 9 P 0 ;1
L 6.6575 1.0575 6.6575 1.0575 9 P 0 ;1
L 6.6575 1.1075 6.6575 1.1075 9 P 0 ;1
L 6.6575 1.1575 6.6575 1.1575 9 P 0 ;1
L 6.6575 1.2075 6.6575 1.2075 9 P 0 ;1
L 6.6575 1.2575 6.6575 1.2575 9 P 0 ;1
L 6.6575 1.3075 6.6575 1.3075 9 P 0 ;1
L 6.6575 1.3575 6.6575 1.3575 9 P 0 ;1
L 6.6575 1.4075 6.6575 1.4075 9 P 0 ;1
L 6.6575 1.4575 6.6575 1.4575 9 P 0 ;1
L 6.6575 1.5075 6.6575 1.5075 9 P 0 ;1
L 6.6575 1.5575 6.6575 1.5575 9 P 0 ;1
L 6.6575 1.6075 6.6575 1.6075 9 P 0 ;1
L 6.6575 1.6575 6.6575 1.6575 9 P 0 ;1
L 6.6575 1.7075 6.6575 1.7075 9 P 0 ;1
L 6.6575 1.7575 6.6575 1.7575 9 P 0 ;1
L 6.6575 1.8075 6.6575 1.8075 9 P 0 ;1
L 6.6575 1.8575 6.6575 1.8575 9 P 0 ;1
L 6.6575 1.9075 6.6575 1.9075 9 P 0 ;1
L 6.6575 1.9575 6.6575 1.9575 9 P 0 ;1
L 6.6575 2.0075 6.6575 2.0075 9 P 0 ;1
L 6.6575 2.0575 6.6575 2.0575 9 P 0 ;1
L 6.6575 2.1075 6.6575 2.1075 9 P 0 ;1
L 6.6575 2.1575 6.6575 2.1575 9 P 0 ;1
L 6.6575 2.2075 6.6575 2.2075 9 P 0 ;1
L 6.6575 2.2575 6.6575 2.2575 9 P 0 ;1
L 6.6575 2.3075 6.6575 2.3075 9 P 0 ;1
L 6.6575 2.3575 6.6575 2.3575 9 P 0 ;1
L 6.6575 2.4075 6.6575 2.4075 9 P 0 ;1
L 6.6575 2.4575 6.6575 2.4575 9 P 0 ;1
L 6.6575 2.5075 6.6575 2.5075 9 P 0 ;1
L 6.6575 2.5575 6.6575 2.5575 9 P 0 ;1
L 6.6575 2.6075 6.6575 2.6075 9 P 0 ;1
L 6.6575 2.6575 6.6575 2.6575 9 P 0 ;1
L 6.6575 2.7075 6.6575 2.7075 9 P 0 ;1
L 6.6575 2.7575 6.6575 2.7575 9 P 0 ;1
L 6.6575 2.8075 6.6575 2.8075 9 P 0 ;1
L 6.6575 2.8575 6.6575 2.8575 9 P 0 ;1
L 6.6575 2.9075 6.6575 2.9075 9 P 0 ;1
L 6.6575 2.9575 6.6575 2.9575 9 P 0 ;1
L 6.6575 3.0075 6.6575 3.0075 9 P 0 ;1
L 6.6575 3.0575 6.6575 3.0575 9 P 0 ;1
L 6.7075 0.1575 6.7075 0.1575 9 P 0 ;1
L 6.7075 0.2075 6.7075 0.2075 9 P 0 ;1
L 6.7075 0.2575 6.7075 0.2575 9 P 0 ;1
L 6.7075 0.3075 6.7075 0.3075 9 P 0 ;1
L 6.7075 0.3575 6.7075 0.3575 9 P 0 ;1
L 6.7075 0.4075 6.7075 0.4075 9 P 0 ;1
L 6.7075 0.4575 6.7075 0.4575 9 P 0 ;1
L 6.7075 0.5075 6.7075 0.5075 9 P 0 ;1
L 6.7075 0.5575 6.7075 0.5575 9 P 0 ;1
L 6.7075 0.6075 6.7075 0.6075 9 P 0 ;1
L 6.7075 0.6575 6.7075 0.6575 9 P 0 ;1
L 6.7075 0.7075 6.7075 0.7075 9 P 0 ;1
L 6.7075 0.7575 6.7075 0.7575 9 P 0 ;1
L 6.7075 0.8075 6.7075 0.8075 9 P 0 ;1
L 6.7075 0.8575 6.7075 0.8575 9 P 0 ;1
L 6.7075 0.9075 6.7075 0.9075 9 P 0 ;1
L 6.7075 0.9575 6.7075 0.9575 9 P 0 ;1
L 6.7075 1.0075 6.7075 1.0075 9 P 0 ;1
L 6.7075 1.0575 6.7075 1.0575 9 P 0 ;1
L 6.7075 1.1075 6.7075 1.1075 9 P 0 ;1
L 6.7075 1.1575 6.7075 1.1575 9 P 0 ;1
L 6.7075 1.2075 6.7075 1.2075 9 P 0 ;1
L 6.7075 1.2575 6.7075 1.2575 9 P 0 ;1
L 6.7075 1.3075 6.7075 1.3075 9 P 0 ;1
L 6.7075 1.3575 6.7075 1.3575 9 P 0 ;1
L 6.7075 1.4075 6.7075 1.4075 9 P 0 ;1
L 6.7075 1.4575 6.7075 1.4575 9 P 0 ;1
L 6.7075 1.5075 6.7075 1.5075 9 P 0 ;1
L 6.7075 1.5575 6.7075 1.5575 9 P 0 ;1
L 6.7075 1.6075 6.7075 1.6075 9 P 0 ;1
L 6.7075 1.6575 6.7075 1.6575 9 P 0 ;1
L 6.7075 1.7075 6.7075 1.7075 9 P 0 ;1
L 6.7075 1.7575 6.7075 1.7575 9 P 0 ;1
L 6.7075 1.8075 6.7075 1.8075 9 P 0 ;1
L 6.7075 1.8575 6.7075 1.8575 9 P 0 ;1
L 6.7075 1.9075 6.7075 1.9075 9 P 0 ;1
L 6.7075 1.9575 6.7075 1.9575 9 P 0 ;1
L 6.7075 2.0075 6.7075 2.0075 9 P 0 ;1
L 6.7075 2.0575 6.7075 2.0575 9 P 0 ;1
L 6.7075 2.1075 6.7075 2.1075 9 P 0 ;1
L 6.7075 2.1575 6.7075 2.1575 9 P 0 ;1
L 6.7075 2.2075 6.7075 2.2075 9 P 0 ;1
L 6.7075 2.2575 6.7075 2.2575 9 P 0 ;1
L 6.7075 2.3075 6.7075 2.3075 9 P 0 ;1
L 6.7075 2.3575 6.7075 2.3575 9 P 0 ;1
L 6.7075 2.4075 6.7075 2.4075 9 P 0 ;1
L 6.7075 2.4575 6.7075 2.4575 9 P 0 ;1
L 6.7075 2.5075 6.7075 2.5075 9 P 0 ;1
L 6.7075 2.5575 6.7075 2.5575 9 P 0 ;1
L 6.7075 2.6075 6.7075 2.6075 9 P 0 ;1
L 6.7075 2.6575 6.7075 2.6575 9 P 0 ;1
L 6.7075 2.7075 6.7075 2.7075 9 P 0 ;1
L 6.7075 2.7575 6.7075 2.7575 9 P 0 ;1
L 6.7075 2.8075 6.7075 2.8075 9 P 0 ;1
L 6.7075 2.8575 6.7075 2.8575 9 P 0 ;1
L 6.7075 2.9075 6.7075 2.9075 9 P 0 ;1
L 6.7075 2.9575 6.7075 2.9575 9 P 0 ;1
L 6.7075 3.0075 6.7075 3.0075 9 P 0 ;1
L 6.7075 3.0575 6.7075 3.0575 9 P 0 ;1
L 6.7075 3.1075 6.7075 3.1075 9 P 0 ;1
L 6.7575 0.1575 6.7575 0.1575 9 P 0 ;1
L 6.7575 0.2075 6.7575 0.2075 9 P 0 ;1
L 6.7575 0.2575 6.7575 0.2575 9 P 0 ;1
L 6.7575 0.3075 6.7575 0.3075 9 P 0 ;1
L 6.7575 0.3575 6.7575 0.3575 9 P 0 ;1
L 6.7575 0.4075 6.7575 0.4075 9 P 0 ;1
L 6.7575 0.4575 6.7575 0.4575 9 P 0 ;1
L 6.7575 0.5075 6.7575 0.5075 9 P 0 ;1
L 6.7575 0.5575 6.7575 0.5575 9 P 0 ;1
L 6.7575 0.6075 6.7575 0.6075 9 P 0 ;1
L 6.7575 0.6575 6.7575 0.6575 9 P 0 ;1
L 6.7575 0.7075 6.7575 0.7075 9 P 0 ;1
L 6.7575 0.7575 6.7575 0.7575 9 P 0 ;1
L 6.7575 0.8075 6.7575 0.8075 9 P 0 ;1
L 6.7575 0.8575 6.7575 0.8575 9 P 0 ;1
L 6.7575 0.9075 6.7575 0.9075 9 P 0 ;1
L 6.7575 0.9575 6.7575 0.9575 9 P 0 ;1
L 6.7575 1.0075 6.7575 1.0075 9 P 0 ;1
L 6.7575 1.0575 6.7575 1.0575 9 P 0 ;1
L 6.7575 1.1075 6.7575 1.1075 9 P 0 ;1
L 6.7575 1.1575 6.7575 1.1575 9 P 0 ;1
L 6.7575 1.2075 6.7575 1.2075 9 P 0 ;1
L 6.7575 1.2575 6.7575 1.2575 9 P 0 ;1
L 6.7575 1.3075 6.7575 1.3075 9 P 0 ;1
L 6.7575 1.3575 6.7575 1.3575 9 P 0 ;1
L 6.7575 1.4075 6.7575 1.4075 9 P 0 ;1
L 6.7575 1.4575 6.7575 1.4575 9 P 0 ;1
L 6.7575 1.5075 6.7575 1.5075 9 P 0 ;1
L 6.7575 1.5575 6.7575 1.5575 9 P 0 ;1
L 6.7575 1.6075 6.7575 1.6075 9 P 0 ;1
L 6.7575 1.6575 6.7575 1.6575 9 P 0 ;1
L 6.7575 1.7075 6.7575 1.7075 9 P 0 ;1
L 6.7575 1.7575 6.7575 1.7575 9 P 0 ;1
L 6.7575 1.8075 6.7575 1.8075 9 P 0 ;1
L 6.7575 1.8575 6.7575 1.8575 9 P 0 ;1
L 6.7575 1.9075 6.7575 1.9075 9 P 0 ;1
L 6.7575 1.9575 6.7575 1.9575 9 P 0 ;1
L 6.7575 2.0075 6.7575 2.0075 9 P 0 ;1
L 6.7575 2.0575 6.7575 2.0575 9 P 0 ;1
L 6.7575 2.1075 6.7575 2.1075 9 P 0 ;1
L 6.7575 2.1575 6.7575 2.1575 9 P 0 ;1
L 6.7575 2.2075 6.7575 2.2075 9 P 0 ;1
L 6.7575 2.2575 6.7575 2.2575 9 P 0 ;1
L 6.7575 2.3075 6.7575 2.3075 9 P 0 ;1
L 6.7575 2.3575 6.7575 2.3575 9 P 0 ;1
L 6.7575 2.4075 6.7575 2.4075 9 P 0 ;1
L 6.7575 2.4575 6.7575 2.4575 9 P 0 ;1
L 6.7575 2.5075 6.7575 2.5075 9 P 0 ;1
L 6.7575 2.5575 6.7575 2.5575 9 P 0 ;1
L 6.7575 2.6075 6.7575 2.6075 9 P 0 ;1
L 6.7575 2.6575 6.7575 2.6575 9 P 0 ;1
L 6.7575 2.7075 6.7575 2.7075 9 P 0 ;1
L 6.7575 2.7575 6.7575 2.7575 9 P 0 ;1
L 6.7575 2.8075 6.7575 2.8075 9 P 0 ;1
L 6.7575 2.8575 6.7575 2.8575 9 P 0 ;1
L 6.7575 2.9075 6.7575 2.9075 9 P 0 ;1
L 6.7575 2.9575 6.7575 2.9575 9 P 0 ;1
L 6.7575 3.0075 6.7575 3.0075 9 P 0 ;1
L 6.7575 3.0575 6.7575 3.0575 9 P 0 ;1
L 6.7575 3.1075 6.7575 3.1075 9 P 0 ;1
L 6.7575 3.1575 6.7575 3.1575 9 P 0 ;1
L 6.8075 0.1575 6.8075 0.1575 9 P 0 ;1
L 6.8075 0.2075 6.8075 0.2075 9 P 0 ;1
L 6.8075 0.2575 6.8075 0.2575 9 P 0 ;1
L 6.8075 0.3075 6.8075 0.3075 9 P 0 ;1
L 6.8075 0.3575 6.8075 0.3575 9 P 0 ;1
L 6.8075 0.4075 6.8075 0.4075 9 P 0 ;1
L 6.8075 0.4575 6.8075 0.4575 9 P 0 ;1
L 6.8075 0.5075 6.8075 0.5075 9 P 0 ;1
L 6.8075 0.5575 6.8075 0.5575 9 P 0 ;1
L 6.8075 0.6075 6.8075 0.6075 9 P 0 ;1
L 6.8075 0.6575 6.8075 0.6575 9 P 0 ;1
L 6.8075 0.7075 6.8075 0.7075 9 P 0 ;1
L 6.8075 0.7575 6.8075 0.7575 9 P 0 ;1
L 6.8075 0.8075 6.8075 0.8075 9 P 0 ;1
L 6.8075 0.8575 6.8075 0.8575 9 P 0 ;1
L 6.8075 0.9075 6.8075 0.9075 9 P 0 ;1
L 6.8075 0.9575 6.8075 0.9575 9 P 0 ;1
L 6.8075 1.0075 6.8075 1.0075 9 P 0 ;1
L 6.8075 1.0575 6.8075 1.0575 9 P 0 ;1
L 6.8075 1.1075 6.8075 1.1075 9 P 0 ;1
L 6.8075 1.1575 6.8075 1.1575 9 P 0 ;1
L 6.8075 1.2075 6.8075 1.2075 9 P 0 ;1
L 6.8075 1.2575 6.8075 1.2575 9 P 0 ;1
L 6.8075 1.3075 6.8075 1.3075 9 P 0 ;1
L 6.8075 1.3575 6.8075 1.3575 9 P 0 ;1
L 6.8075 1.7075 6.8075 1.7075 9 P 0 ;1
L 6.8075 1.7575 6.8075 1.7575 9 P 0 ;1
L 6.8075 1.8075 6.8075 1.8075 9 P 0 ;1
L 6.8075 1.8575 6.8075 1.8575 9 P 0 ;1
L 6.8075 1.9075 6.8075 1.9075 9 P 0 ;1
L 6.8075 1.9575 6.8075 1.9575 9 P 0 ;1
L 6.8075 2.0075 6.8075 2.0075 9 P 0 ;1
L 6.8075 2.0575 6.8075 2.0575 9 P 0 ;1
L 6.8075 2.1075 6.8075 2.1075 9 P 0 ;1
L 6.8075 2.1575 6.8075 2.1575 9 P 0 ;1
L 6.8075 2.2075 6.8075 2.2075 9 P 0 ;1
L 6.8075 2.2575 6.8075 2.2575 9 P 0 ;1
L 6.8075 2.3075 6.8075 2.3075 9 P 0 ;1
L 6.8075 2.3575 6.8075 2.3575 9 P 0 ;1
L 6.8075 2.4075 6.8075 2.4075 9 P 0 ;1
L 6.8075 2.4575 6.8075 2.4575 9 P 0 ;1
L 6.8075 2.5075 6.8075 2.5075 9 P 0 ;1
L 6.8075 2.5575 6.8075 2.5575 9 P 0 ;1
L 6.8075 2.6075 6.8075 2.6075 9 P 0 ;1
L 6.8075 2.6575 6.8075 2.6575 9 P 0 ;1
L 6.8075 2.7075 6.8075 2.7075 9 P 0 ;1
L 6.8075 2.7575 6.8075 2.7575 9 P 0 ;1
L 6.8075 2.8075 6.8075 2.8075 9 P 0 ;1
L 6.8075 2.8575 6.8075 2.8575 9 P 0 ;1
L 6.8075 2.9075 6.8075 2.9075 9 P 0 ;1
L 6.8075 2.9575 6.8075 2.9575 9 P 0 ;1
L 6.8075 3.0075 6.8075 3.0075 9 P 0 ;1
L 6.8075 3.0575 6.8075 3.0575 9 P 0 ;1
L 6.8075 3.1075 6.8075 3.1075 9 P 0 ;1
L 6.8075 3.1575 6.8075 3.1575 9 P 0 ;1
L 6.8075 3.2075 6.8075 3.2075 9 P 0 ;1
L 6.8075 3.2575 6.8075 3.2575 9 P 0 ;1
L 6.8075 3.3075 6.8075 3.3075 9 P 0 ;1
L 6.8075 3.3575 6.8075 3.3575 9 P 0 ;1
L 6.8075 3.4075 6.8075 3.4075 9 P 0 ;1
L 6.8075 3.4575 6.8075 3.4575 9 P 0 ;1
L 6.8075 3.5075 6.8075 3.5075 9 P 0 ;1
L 6.8075 3.5575 6.8075 3.5575 9 P 0 ;1
L 6.8075 3.6075 6.8075 3.6075 9 P 0 ;1
L 6.8075 3.6575 6.8075 3.6575 9 P 0 ;1
L 6.8075 3.7075 6.8075 3.7075 9 P 0 ;1
L 6.8075 3.7575 6.8075 3.7575 9 P 0 ;1
L 6.8075 3.8075 6.8075 3.8075 9 P 0 ;1
L 6.8075 3.8575 6.8075 3.8575 9 P 0 ;1
L 6.8075 3.9075 6.8075 3.9075 9 P 0 ;1
L 6.8075 3.9575 6.8075 3.9575 9 P 0 ;1
L 6.8075 4.0075 6.8075 4.0075 9 P 0 ;1
L 6.8075 4.0575 6.8075 4.0575 9 P 0 ;1
L 6.8075 5.0575 6.8075 5.0575 9 P 0 ;1
L 6.8075 5.9075 6.8075 5.9075 9 P 0 ;1
L 6.8575 0.1575 6.8575 0.1575 9 P 0 ;1
L 6.8575 0.2075 6.8575 0.2075 9 P 0 ;1
L 6.8575 0.2575 6.8575 0.2575 9 P 0 ;1
L 6.8575 0.3075 6.8575 0.3075 9 P 0 ;1
L 6.8575 0.3575 6.8575 0.3575 9 P 0 ;1
L 6.8575 0.4075 6.8575 0.4075 9 P 0 ;1
L 6.8575 0.4575 6.8575 0.4575 9 P 0 ;1
L 6.8575 0.5075 6.8575 0.5075 9 P 0 ;1
L 6.8575 0.5575 6.8575 0.5575 9 P 0 ;1
L 6.8575 0.6075 6.8575 0.6075 9 P 0 ;1
L 6.8575 0.6575 6.8575 0.6575 9 P 0 ;1
L 6.8575 0.7075 6.8575 0.7075 9 P 0 ;1
L 6.8575 0.7575 6.8575 0.7575 9 P 0 ;1
L 6.8575 0.8075 6.8575 0.8075 9 P 0 ;1
L 6.8575 0.8575 6.8575 0.8575 9 P 0 ;1
L 6.8575 0.9075 6.8575 0.9075 9 P 0 ;1
L 6.8575 0.9575 6.8575 0.9575 9 P 0 ;1
L 6.8575 1.0075 6.8575 1.0075 9 P 0 ;1
L 6.8575 1.0575 6.8575 1.0575 9 P 0 ;1
L 6.8575 1.1075 6.8575 1.1075 9 P 0 ;1
L 6.8575 1.1575 6.8575 1.1575 9 P 0 ;1
L 6.8575 1.2075 6.8575 1.2075 9 P 0 ;1
L 6.8575 1.2575 6.8575 1.2575 9 P 0 ;1
L 6.8575 1.3075 6.8575 1.3075 9 P 0 ;1
L 6.8575 1.3575 6.8575 1.3575 9 P 0 ;1
L 6.8575 1.7075 6.8575 1.7075 9 P 0 ;1
L 6.8575 1.7575 6.8575 1.7575 9 P 0 ;1
L 6.8575 1.8075 6.8575 1.8075 9 P 0 ;1
L 6.8575 1.8575 6.8575 1.8575 9 P 0 ;1
L 6.8575 1.9075 6.8575 1.9075 9 P 0 ;1
L 6.8575 1.9575 6.8575 1.9575 9 P 0 ;1
L 6.8575 2.0075 6.8575 2.0075 9 P 0 ;1
L 6.8575 2.0575 6.8575 2.0575 9 P 0 ;1
L 6.8575 2.1075 6.8575 2.1075 9 P 0 ;1
L 6.8575 2.1575 6.8575 2.1575 9 P 0 ;1
L 6.8575 2.2075 6.8575 2.2075 9 P 0 ;1
L 6.8575 2.2575 6.8575 2.2575 9 P 0 ;1
L 6.8575 2.3075 6.8575 2.3075 9 P 0 ;1
L 6.8575 2.3575 6.8575 2.3575 9 P 0 ;1
L 6.8575 2.4075 6.8575 2.4075 9 P 0 ;1
L 6.8575 2.4575 6.8575 2.4575 9 P 0 ;1
L 6.8575 2.5075 6.8575 2.5075 9 P 0 ;1
L 6.8575 2.5575 6.8575 2.5575 9 P 0 ;1
L 6.8575 2.6075 6.8575 2.6075 9 P 0 ;1
L 6.8575 2.6575 6.8575 2.6575 9 P 0 ;1
L 6.8575 2.7075 6.8575 2.7075 9 P 0 ;1
L 6.8575 2.7575 6.8575 2.7575 9 P 0 ;1
L 6.8575 2.8075 6.8575 2.8075 9 P 0 ;1
L 6.8575 2.8575 6.8575 2.8575 9 P 0 ;1
L 6.8575 2.9075 6.8575 2.9075 9 P 0 ;1
L 6.8575 2.9575 6.8575 2.9575 9 P 0 ;1
L 6.8575 3.0075 6.8575 3.0075 9 P 0 ;1
L 6.8575 3.0575 6.8575 3.0575 9 P 0 ;1
L 6.8575 3.1075 6.8575 3.1075 9 P 0 ;1
L 6.8575 3.1575 6.8575 3.1575 9 P 0 ;1
L 6.8575 3.2075 6.8575 3.2075 9 P 0 ;1
L 6.8575 3.2575 6.8575 3.2575 9 P 0 ;1
L 6.8575 3.3075 6.8575 3.3075 9 P 0 ;1
L 6.8575 3.3575 6.8575 3.3575 9 P 0 ;1
L 6.8575 3.4075 6.8575 3.4075 9 P 0 ;1
L 6.8575 3.4575 6.8575 3.4575 9 P 0 ;1
L 6.8575 3.5075 6.8575 3.5075 9 P 0 ;1
L 6.8575 3.5575 6.8575 3.5575 9 P 0 ;1
L 6.8575 3.6075 6.8575 3.6075 9 P 0 ;1
L 6.8575 3.6575 6.8575 3.6575 9 P 0 ;1
L 6.8575 3.7075 6.8575 3.7075 9 P 0 ;1
L 6.8575 3.7575 6.8575 3.7575 9 P 0 ;1
L 6.8575 3.8075 6.8575 3.8075 9 P 0 ;1
L 6.8575 3.8575 6.8575 3.8575 9 P 0 ;1
L 6.8575 3.9075 6.8575 3.9075 9 P 0 ;1
L 6.8575 3.9575 6.8575 3.9575 9 P 0 ;1
L 6.8575 4.0075 6.8575 4.0075 9 P 0 ;1
L 6.8575 5.8575 6.8575 5.8575 9 P 0 ;1
L 6.8575 5.9075 6.8575 5.9075 9 P 0 ;1
L 6.9075 0.1575 6.9075 0.1575 9 P 0 ;1
L 6.9075 0.2075 6.9075 0.2075 9 P 0 ;1
L 6.9075 0.2575 6.9075 0.2575 9 P 0 ;1
L 6.9075 0.3075 6.9075 0.3075 9 P 0 ;1
L 6.9075 0.3575 6.9075 0.3575 9 P 0 ;1
L 6.9075 0.4075 6.9075 0.4075 9 P 0 ;1
L 6.9075 0.4575 6.9075 0.4575 9 P 0 ;1
L 6.9075 0.5075 6.9075 0.5075 9 P 0 ;1
L 6.9075 0.5575 6.9075 0.5575 9 P 0 ;1
L 6.9075 0.6075 6.9075 0.6075 9 P 0 ;1
L 6.9075 0.6575 6.9075 0.6575 9 P 0 ;1
L 6.9075 0.7075 6.9075 0.7075 9 P 0 ;1
L 6.9075 0.7575 6.9075 0.7575 9 P 0 ;1
L 6.9075 0.8075 6.9075 0.8075 9 P 0 ;1
L 6.9075 0.8575 6.9075 0.8575 9 P 0 ;1
L 6.9075 0.9075 6.9075 0.9075 9 P 0 ;1
L 6.9075 0.9575 6.9075 0.9575 9 P 0 ;1
L 6.9075 1.0075 6.9075 1.0075 9 P 0 ;1
L 6.9075 1.0575 6.9075 1.0575 9 P 0 ;1
L 6.9075 1.1075 6.9075 1.1075 9 P 0 ;1
L 6.9075 1.1575 6.9075 1.1575 9 P 0 ;1
L 6.9075 1.2075 6.9075 1.2075 9 P 0 ;1
L 6.9075 1.2575 6.9075 1.2575 9 P 0 ;1
L 6.9075 1.3075 6.9075 1.3075 9 P 0 ;1
L 6.9075 1.7575 6.9075 1.7575 9 P 0 ;1
L 6.9075 1.8075 6.9075 1.8075 9 P 0 ;1
L 6.9075 1.8575 6.9075 1.8575 9 P 0 ;1
L 6.9075 1.9075 6.9075 1.9075 9 P 0 ;1
L 6.9075 1.9575 6.9075 1.9575 9 P 0 ;1
L 6.9075 2.0075 6.9075 2.0075 9 P 0 ;1
L 6.9075 2.0575 6.9075 2.0575 9 P 0 ;1
L 6.9075 2.1075 6.9075 2.1075 9 P 0 ;1
L 6.9075 2.1575 6.9075 2.1575 9 P 0 ;1
L 6.9075 2.2075 6.9075 2.2075 9 P 0 ;1
L 6.9075 2.2575 6.9075 2.2575 9 P 0 ;1
L 6.9075 2.3075 6.9075 2.3075 9 P 0 ;1
L 6.9075 2.3575 6.9075 2.3575 9 P 0 ;1
L 6.9075 2.4075 6.9075 2.4075 9 P 0 ;1
L 6.9075 2.4575 6.9075 2.4575 9 P 0 ;1
L 6.9075 2.5075 6.9075 2.5075 9 P 0 ;1
L 6.9075 2.6575 6.9075 2.6575 9 P 0 ;1
L 6.9075 2.7075 6.9075 2.7075 9 P 0 ;1
L 6.9075 2.7575 6.9075 2.7575 9 P 0 ;1
L 6.9075 2.8075 6.9075 2.8075 9 P 0 ;1
L 6.9075 2.8575 6.9075 2.8575 9 P 0 ;1
L 6.9075 2.9075 6.9075 2.9075 9 P 0 ;1
L 6.9075 2.9575 6.9075 2.9575 9 P 0 ;1
L 6.9075 3.0075 6.9075 3.0075 9 P 0 ;1
L 6.9075 3.0575 6.9075 3.0575 9 P 0 ;1
L 6.9075 3.1075 6.9075 3.1075 9 P 0 ;1
L 6.9075 3.1575 6.9075 3.1575 9 P 0 ;1
L 6.9075 3.2075 6.9075 3.2075 9 P 0 ;1
L 6.9075 3.2575 6.9075 3.2575 9 P 0 ;1
L 6.9075 3.3075 6.9075 3.3075 9 P 0 ;1
L 6.9075 3.3575 6.9075 3.3575 9 P 0 ;1
L 6.9075 3.4075 6.9075 3.4075 9 P 0 ;1
L 6.9075 3.4575 6.9075 3.4575 9 P 0 ;1
L 6.9075 3.5075 6.9075 3.5075 9 P 0 ;1
L 6.9075 3.5575 6.9075 3.5575 9 P 0 ;1
L 6.9075 3.6075 6.9075 3.6075 9 P 0 ;1
L 6.9075 3.6575 6.9075 3.6575 9 P 0 ;1
L 6.9075 3.7075 6.9075 3.7075 9 P 0 ;1
L 6.9075 3.7575 6.9075 3.7575 9 P 0 ;1
L 6.9075 3.8075 6.9075 3.8075 9 P 0 ;1
L 6.9075 3.8575 6.9075 3.8575 9 P 0 ;1
L 6.9075 3.9075 6.9075 3.9075 9 P 0 ;1
L 6.9075 3.9575 6.9075 3.9575 9 P 0 ;1
L 6.9075 4.0075 6.9075 4.0075 9 P 0 ;1
L 6.9075 5.8075 6.9075 5.8075 9 P 0 ;1
L 6.9075 5.8575 6.9075 5.8575 9 P 0 ;1
L 6.9075 5.9075 6.9075 5.9075 9 P 0 ;1
L 6.9575 0.1575 6.9575 0.1575 9 P 0 ;1
L 6.9575 0.3075 6.9575 0.3075 9 P 0 ;1
L 6.9575 0.3575 6.9575 0.3575 9 P 0 ;1
L 6.9575 0.4075 6.9575 0.4075 9 P 0 ;1
L 6.9575 0.4575 6.9575 0.4575 9 P 0 ;1
L 6.9575 0.5075 6.9575 0.5075 9 P 0 ;1
L 6.9575 0.5575 6.9575 0.5575 9 P 0 ;1
L 6.9575 0.6075 6.9575 0.6075 9 P 0 ;1
L 6.9575 0.6575 6.9575 0.6575 9 P 0 ;1
L 6.9575 0.7075 6.9575 0.7075 9 P 0 ;1
L 6.9575 0.7575 6.9575 0.7575 9 P 0 ;1
L 6.9575 0.8075 6.9575 0.8075 9 P 0 ;1
L 6.9575 0.8575 6.9575 0.8575 9 P 0 ;1
L 6.9575 0.9075 6.9575 0.9075 9 P 0 ;1
L 6.9575 0.9575 6.9575 0.9575 9 P 0 ;1
L 6.9575 1.0075 6.9575 1.0075 9 P 0 ;1
L 6.9575 1.0575 6.9575 1.0575 9 P 0 ;1
L 6.9575 1.1075 6.9575 1.1075 9 P 0 ;1
L 6.9575 1.1575 6.9575 1.1575 9 P 0 ;1
L 6.9575 1.2075 6.9575 1.2075 9 P 0 ;1
L 6.9575 1.2575 6.9575 1.2575 9 P 0 ;1
L 6.9575 1.3075 6.9575 1.3075 9 P 0 ;1
L 6.9575 1.7575 6.9575 1.7575 9 P 0 ;1
L 6.9575 1.8075 6.9575 1.8075 9 P 0 ;1
L 6.9575 1.8575 6.9575 1.8575 9 P 0 ;1
L 6.9575 1.9075 6.9575 1.9075 9 P 0 ;1
L 6.9575 1.9575 6.9575 1.9575 9 P 0 ;1
L 6.9575 2.0075 6.9575 2.0075 9 P 0 ;1
L 6.9575 2.0575 6.9575 2.0575 9 P 0 ;1
L 6.9575 2.1075 6.9575 2.1075 9 P 0 ;1
L 6.9575 2.1575 6.9575 2.1575 9 P 0 ;1
L 6.9575 2.2075 6.9575 2.2075 9 P 0 ;1
L 6.9575 2.2575 6.9575 2.2575 9 P 0 ;1
L 6.9575 2.3075 6.9575 2.3075 9 P 0 ;1
L 6.9575 2.3575 6.9575 2.3575 9 P 0 ;1
L 6.9575 2.4075 6.9575 2.4075 9 P 0 ;1
L 6.9575 2.4575 6.9575 2.4575 9 P 0 ;1
L 6.9575 2.7075 6.9575 2.7075 9 P 0 ;1
L 6.9575 2.7575 6.9575 2.7575 9 P 0 ;1
L 6.9575 2.8075 6.9575 2.8075 9 P 0 ;1
L 6.9575 2.8575 6.9575 2.8575 9 P 0 ;1
L 6.9575 2.9075 6.9575 2.9075 9 P 0 ;1
L 6.9575 2.9575 6.9575 2.9575 9 P 0 ;1
L 6.9575 3.0075 6.9575 3.0075 9 P 0 ;1
L 6.9575 3.0575 6.9575 3.0575 9 P 0 ;1
L 6.9575 3.1075 6.9575 3.1075 9 P 0 ;1
L 6.9575 3.1575 6.9575 3.1575 9 P 0 ;1
L 6.9575 3.2075 6.9575 3.2075 9 P 0 ;1
L 6.9575 3.2575 6.9575 3.2575 9 P 0 ;1
L 6.9575 3.3075 6.9575 3.3075 9 P 0 ;1
L 6.9575 3.3575 6.9575 3.3575 9 P 0 ;1
L 6.9575 3.4075 6.9575 3.4075 9 P 0 ;1
L 6.9575 3.4575 6.9575 3.4575 9 P 0 ;1
L 6.9575 3.5075 6.9575 3.5075 9 P 0 ;1
L 6.9575 3.5575 6.9575 3.5575 9 P 0 ;1
L 6.9575 3.6075 6.9575 3.6075 9 P 0 ;1
L 6.9575 3.6575 6.9575 3.6575 9 P 0 ;1
L 6.9575 3.7075 6.9575 3.7075 9 P 0 ;1
L 6.9575 3.7575 6.9575 3.7575 9 P 0 ;1
L 6.9575 3.8075 6.9575 3.8075 9 P 0 ;1
L 6.9575 3.8575 6.9575 3.8575 9 P 0 ;1
L 6.9575 3.9075 6.9575 3.9075 9 P 0 ;1
L 6.9575 3.9575 6.9575 3.9575 9 P 0 ;1
L 6.9575 5.7575 6.9575 5.7575 9 P 0 ;1
L 6.9575 5.8575 6.9575 5.8575 9 P 0 ;1
L 6.9575 5.9075 6.9575 5.9075 9 P 0 ;1
L 7.0075 0.4075 7.0075 0.4075 9 P 0 ;1
L 7.0075 0.4575 7.0075 0.4575 9 P 0 ;1
L 7.0075 0.5075 7.0075 0.5075 9 P 0 ;1
L 7.0075 0.5575 7.0075 0.5575 9 P 0 ;1
L 7.0075 0.6075 7.0075 0.6075 9 P 0 ;1
L 7.0075 0.6575 7.0075 0.6575 9 P 0 ;1
L 7.0075 0.7075 7.0075 0.7075 9 P 0 ;1
L 7.0075 0.7575 7.0075 0.7575 9 P 0 ;1
L 7.0075 0.8075 7.0075 0.8075 9 P 0 ;1
L 7.0075 0.8575 7.0075 0.8575 9 P 0 ;1
L 7.0075 0.9075 7.0075 0.9075 9 P 0 ;1
L 7.0075 0.9575 7.0075 0.9575 9 P 0 ;1
L 7.0075 1.0075 7.0075 1.0075 9 P 0 ;1
L 7.0075 1.0575 7.0075 1.0575 9 P 0 ;1
L 7.0075 1.1075 7.0075 1.1075 9 P 0 ;1
L 7.0075 1.1575 7.0075 1.1575 9 P 0 ;1
L 7.0075 1.2075 7.0075 1.2075 9 P 0 ;1
L 7.0075 1.2575 7.0075 1.2575 9 P 0 ;1
L 7.0075 1.3075 7.0075 1.3075 9 P 0 ;1
L 7.0075 1.7575 7.0075 1.7575 9 P 0 ;1
L 7.0075 1.8075 7.0075 1.8075 9 P 0 ;1
L 7.0075 1.8575 7.0075 1.8575 9 P 0 ;1
L 7.0075 1.9075 7.0075 1.9075 9 P 0 ;1
L 7.0075 1.9575 7.0075 1.9575 9 P 0 ;1
L 7.0075 2.0075 7.0075 2.0075 9 P 0 ;1
L 7.0075 2.0575 7.0075 2.0575 9 P 0 ;1
L 7.0075 2.1075 7.0075 2.1075 9 P 0 ;1
L 7.0075 2.1575 7.0075 2.1575 9 P 0 ;1
L 7.0075 2.2075 7.0075 2.2075 9 P 0 ;1
L 7.0075 2.2575 7.0075 2.2575 9 P 0 ;1
L 7.0075 2.3075 7.0075 2.3075 9 P 0 ;1
L 7.0075 2.3575 7.0075 2.3575 9 P 0 ;1
L 7.0075 2.4075 7.0075 2.4075 9 P 0 ;1
L 7.0075 2.7575 7.0075 2.7575 9 P 0 ;1
L 7.0075 2.8075 7.0075 2.8075 9 P 0 ;1
L 7.0075 2.8575 7.0075 2.8575 9 P 0 ;1
L 7.0075 2.9075 7.0075 2.9075 9 P 0 ;1
L 7.0075 2.9575 7.0075 2.9575 9 P 0 ;1
L 7.0075 3.0075 7.0075 3.0075 9 P 0 ;1
L 7.0075 3.0575 7.0075 3.0575 9 P 0 ;1
L 7.0075 3.1075 7.0075 3.1075 9 P 0 ;1
L 7.0075 3.1575 7.0075 3.1575 9 P 0 ;1
L 7.0075 3.2075 7.0075 3.2075 9 P 0 ;1
L 7.0075 3.2575 7.0075 3.2575 9 P 0 ;1
L 7.0075 3.3075 7.0075 3.3075 9 P 0 ;1
L 7.0075 3.3575 7.0075 3.3575 9 P 0 ;1
L 7.0075 3.4075 7.0075 3.4075 9 P 0 ;1
L 7.0075 3.4575 7.0075 3.4575 9 P 0 ;1
L 7.0075 3.5075 7.0075 3.5075 9 P 0 ;1
L 7.0075 3.5575 7.0075 3.5575 9 P 0 ;1
L 7.0075 3.6075 7.0075 3.6075 9 P 0 ;1
L 7.0075 3.6575 7.0075 3.6575 9 P 0 ;1
L 7.0075 3.7075 7.0075 3.7075 9 P 0 ;1
L 7.0075 3.7575 7.0075 3.7575 9 P 0 ;1
L 7.0075 3.8075 7.0075 3.8075 9 P 0 ;1
L 7.0075 3.8575 7.0075 3.8575 9 P 0 ;1
L 7.0075 3.9075 7.0075 3.9075 9 P 0 ;1
L 7.0075 3.9575 7.0075 3.9575 9 P 0 ;1
L 7.0575 0.4575 7.0575 0.4575 9 P 0 ;1
L 7.0575 0.5075 7.0575 0.5075 9 P 0 ;1
L 7.0575 0.5575 7.0575 0.5575 9 P 0 ;1
L 7.0575 0.6075 7.0575 0.6075 9 P 0 ;1
L 7.0575 0.6575 7.0575 0.6575 9 P 0 ;1
L 7.0575 0.7075 7.0575 0.7075 9 P 0 ;1
L 7.0575 0.7575 7.0575 0.7575 9 P 0 ;1
L 7.0575 0.8075 7.0575 0.8075 9 P 0 ;1
L 7.0575 0.8575 7.0575 0.8575 9 P 0 ;1
L 7.0575 0.9075 7.0575 0.9075 9 P 0 ;1
L 7.0575 0.9575 7.0575 0.9575 9 P 0 ;1
L 7.0575 1.0075 7.0575 1.0075 9 P 0 ;1
L 7.0575 1.0575 7.0575 1.0575 9 P 0 ;1
L 7.0575 1.1075 7.0575 1.1075 9 P 0 ;1
L 7.0575 1.1575 7.0575 1.1575 9 P 0 ;1
L 7.0575 1.2075 7.0575 1.2075 9 P 0 ;1
L 7.0575 1.2575 7.0575 1.2575 9 P 0 ;1
L 7.0575 1.3075 7.0575 1.3075 9 P 0 ;1
L 7.0575 1.3575 7.0575 1.3575 9 P 0 ;1
L 7.0575 1.7075 7.0575 1.7075 9 P 0 ;1
L 7.0575 1.7575 7.0575 1.7575 9 P 0 ;1
L 7.0575 1.8075 7.0575 1.8075 9 P 0 ;1
L 7.0575 1.8575 7.0575 1.8575 9 P 0 ;1
L 7.0575 1.9075 7.0575 1.9075 9 P 0 ;1
L 7.0575 1.9575 7.0575 1.9575 9 P 0 ;1
L 7.0575 2.0075 7.0575 2.0075 9 P 0 ;1
L 7.0575 2.0575 7.0575 2.0575 9 P 0 ;1
L 7.0575 2.1075 7.0575 2.1075 9 P 0 ;1
L 7.0575 2.1575 7.0575 2.1575 9 P 0 ;1
L 7.0575 2.2075 7.0575 2.2075 9 P 0 ;1
L 7.0575 2.2575 7.0575 2.2575 9 P 0 ;1
L 7.0575 2.3075 7.0575 2.3075 9 P 0 ;1
L 7.0575 2.3575 7.0575 2.3575 9 P 0 ;1
L 7.0575 2.4075 7.0575 2.4075 9 P 0 ;1
L 7.0575 2.7575 7.0575 2.7575 9 P 0 ;1
L 7.0575 2.8075 7.0575 2.8075 9 P 0 ;1
L 7.0575 2.8575 7.0575 2.8575 9 P 0 ;1
L 7.0575 2.9075 7.0575 2.9075 9 P 0 ;1
L 7.0575 2.9575 7.0575 2.9575 9 P 0 ;1
L 7.0575 3.0075 7.0575 3.0075 9 P 0 ;1
L 7.0575 3.0575 7.0575 3.0575 9 P 0 ;1
L 7.0575 3.1075 7.0575 3.1075 9 P 0 ;1
L 7.0575 3.1575 7.0575 3.1575 9 P 0 ;1
L 7.0575 3.2075 7.0575 3.2075 9 P 0 ;1
L 7.0575 3.2575 7.0575 3.2575 9 P 0 ;1
L 7.0575 3.3075 7.0575 3.3075 9 P 0 ;1
L 7.0575 3.3575 7.0575 3.3575 9 P 0 ;1
L 7.0575 3.4075 7.0575 3.4075 9 P 0 ;1
L 7.0575 3.4575 7.0575 3.4575 9 P 0 ;1
L 7.0575 3.5075 7.0575 3.5075 9 P 0 ;1
L 7.0575 3.5575 7.0575 3.5575 9 P 0 ;1
L 7.0575 3.6075 7.0575 3.6075 9 P 0 ;1
L 7.0575 3.6575 7.0575 3.6575 9 P 0 ;1
L 7.0575 3.7075 7.0575 3.7075 9 P 0 ;1
L 7.0575 3.7575 7.0575 3.7575 9 P 0 ;1
L 7.0575 3.8075 7.0575 3.8075 9 P 0 ;1
L 7.0575 3.8575 7.0575 3.8575 9 P 0 ;1
L 7.0575 3.9075 7.0575 3.9075 9 P 0 ;1
L 7.0575 3.9575 7.0575 3.9575 9 P 0 ;1
L 7.0575 4.0075 7.0575 4.0075 9 P 0 ;1
L 7.0575 4.8575 7.0575 4.8575 9 P 0 ;1
L 7.1075 0.4575 7.1075 0.4575 9 P 0 ;1
L 7.1075 0.5075 7.1075 0.5075 9 P 0 ;1
L 7.1075 0.5575 7.1075 0.5575 9 P 0 ;1
L 7.1075 0.6075 7.1075 0.6075 9 P 0 ;1
L 7.1075 0.6575 7.1075 0.6575 9 P 0 ;1
L 7.1075 0.7075 7.1075 0.7075 9 P 0 ;1
L 7.1075 0.7575 7.1075 0.7575 9 P 0 ;1
L 7.1075 0.8075 7.1075 0.8075 9 P 0 ;1
L 7.1075 0.8575 7.1075 0.8575 9 P 0 ;1
L 7.1075 0.9075 7.1075 0.9075 9 P 0 ;1
L 7.1075 0.9575 7.1075 0.9575 9 P 0 ;1
L 7.1075 1.0075 7.1075 1.0075 9 P 0 ;1
L 7.1075 1.0575 7.1075 1.0575 9 P 0 ;1
L 7.1075 1.1075 7.1075 1.1075 9 P 0 ;1
L 7.1075 1.1575 7.1075 1.1575 9 P 0 ;1
L 7.1075 1.2075 7.1075 1.2075 9 P 0 ;1
L 7.1075 1.2575 7.1075 1.2575 9 P 0 ;1
L 7.1075 1.3075 7.1075 1.3075 9 P 0 ;1
L 7.1075 1.3575 7.1075 1.3575 9 P 0 ;1
L 7.1075 1.7075 7.1075 1.7075 9 P 0 ;1
L 7.1075 1.7575 7.1075 1.7575 9 P 0 ;1
L 7.1075 1.8075 7.1075 1.8075 9 P 0 ;1
L 7.1075 1.8575 7.1075 1.8575 9 P 0 ;1
L 7.1075 1.9075 7.1075 1.9075 9 P 0 ;1
L 7.1075 1.9575 7.1075 1.9575 9 P 0 ;1
L 7.1075 2.0075 7.1075 2.0075 9 P 0 ;1
L 7.1075 2.0575 7.1075 2.0575 9 P 0 ;1
L 7.1075 2.1075 7.1075 2.1075 9 P 0 ;1
L 7.1075 2.1575 7.1075 2.1575 9 P 0 ;1
L 7.1075 2.2075 7.1075 2.2075 9 P 0 ;1
L 7.1075 2.2575 7.1075 2.2575 9 P 0 ;1
L 7.1075 2.3075 7.1075 2.3075 9 P 0 ;1
L 7.1075 2.3575 7.1075 2.3575 9 P 0 ;1
L 7.1075 2.4075 7.1075 2.4075 9 P 0 ;1
L 7.1075 2.7575 7.1075 2.7575 9 P 0 ;1
L 7.1075 2.8075 7.1075 2.8075 9 P 0 ;1
L 7.1075 2.8575 7.1075 2.8575 9 P 0 ;1
L 7.1075 2.9075 7.1075 2.9075 9 P 0 ;1
L 7.1075 2.9575 7.1075 2.9575 9 P 0 ;1
L 7.1075 3.0075 7.1075 3.0075 9 P 0 ;1
L 7.1075 3.0575 7.1075 3.0575 9 P 0 ;1
L 7.1075 3.1075 7.1075 3.1075 9 P 0 ;1
L 7.1075 3.1575 7.1075 3.1575 9 P 0 ;1
L 7.1075 3.2075 7.1075 3.2075 9 P 0 ;1
L 7.1075 3.2575 7.1075 3.2575 9 P 0 ;1
L 7.1075 3.3075 7.1075 3.3075 9 P 0 ;1
L 7.1075 3.3575 7.1075 3.3575 9 P 0 ;1
L 7.1075 3.4075 7.1075 3.4075 9 P 0 ;1
L 7.1075 3.4575 7.1075 3.4575 9 P 0 ;1
L 7.1075 3.5075 7.1075 3.5075 9 P 0 ;1
L 7.1075 3.5575 7.1075 3.5575 9 P 0 ;1
L 7.1075 3.6075 7.1075 3.6075 9 P 0 ;1
L 7.1075 3.6575 7.1075 3.6575 9 P 0 ;1
L 7.1075 3.7075 7.1075 3.7075 9 P 0 ;1
L 7.1075 3.7575 7.1075 3.7575 9 P 0 ;1
L 7.1075 3.8075 7.1075 3.8075 9 P 0 ;1
L 7.1075 3.8575 7.1075 3.8575 9 P 0 ;1
L 7.1075 3.9075 7.1075 3.9075 9 P 0 ;1
L 7.1075 3.9575 7.1075 3.9575 9 P 0 ;1
L 7.1075 4.0075 7.1075 4.0075 9 P 0 ;1
L 7.1075 4.8575 7.1075 4.8575 9 P 0 ;1
L 7.1575 0.5075 7.1575 0.5075 9 P 0 ;1
L 7.1575 0.5575 7.1575 0.5575 9 P 0 ;1
L 7.1575 0.6075 7.1575 0.6075 9 P 0 ;1
L 7.1575 0.6575 7.1575 0.6575 9 P 0 ;1
L 7.1575 0.7075 7.1575 0.7075 9 P 0 ;1
L 7.1575 0.7575 7.1575 0.7575 9 P 0 ;1
L 7.1575 0.8075 7.1575 0.8075 9 P 0 ;1
L 7.1575 0.8575 7.1575 0.8575 9 P 0 ;1
L 7.1575 0.9075 7.1575 0.9075 9 P 0 ;1
L 7.1575 0.9575 7.1575 0.9575 9 P 0 ;1
L 7.1575 1.0075 7.1575 1.0075 9 P 0 ;1
L 7.1575 1.0575 7.1575 1.0575 9 P 0 ;1
L 7.1575 1.1075 7.1575 1.1075 9 P 0 ;1
L 7.1575 1.1575 7.1575 1.1575 9 P 0 ;1
L 7.1575 1.2075 7.1575 1.2075 9 P 0 ;1
L 7.1575 1.2575 7.1575 1.2575 9 P 0 ;1
L 7.1575 1.3075 7.1575 1.3075 9 P 0 ;1
L 7.1575 1.3575 7.1575 1.3575 9 P 0 ;1
L 7.1575 1.4075 7.1575 1.4075 9 P 0 ;1
L 7.1575 1.4575 7.1575 1.4575 9 P 0 ;1
L 7.1575 1.6075 7.1575 1.6075 9 P 0 ;1
L 7.1575 1.6575 7.1575 1.6575 9 P 0 ;1
L 7.1575 1.7075 7.1575 1.7075 9 P 0 ;1
L 7.1575 1.7575 7.1575 1.7575 9 P 0 ;1
L 7.1575 1.8075 7.1575 1.8075 9 P 0 ;1
L 7.1575 1.8575 7.1575 1.8575 9 P 0 ;1
L 7.1575 1.9075 7.1575 1.9075 9 P 0 ;1
L 7.1575 1.9575 7.1575 1.9575 9 P 0 ;1
L 7.1575 2.0075 7.1575 2.0075 9 P 0 ;1
L 7.1575 2.0575 7.1575 2.0575 9 P 0 ;1
L 7.1575 2.1075 7.1575 2.1075 9 P 0 ;1
L 7.1575 2.1575 7.1575 2.1575 9 P 0 ;1
L 7.1575 2.2075 7.1575 2.2075 9 P 0 ;1
L 7.1575 2.2575 7.1575 2.2575 9 P 0 ;1
L 7.1575 2.3075 7.1575 2.3075 9 P 0 ;1
L 7.1575 2.3575 7.1575 2.3575 9 P 0 ;1
L 7.1575 2.4075 7.1575 2.4075 9 P 0 ;1
L 7.1575 2.7575 7.1575 2.7575 9 P 0 ;1
L 7.1575 2.8075 7.1575 2.8075 9 P 0 ;1
L 7.1575 2.8575 7.1575 2.8575 9 P 0 ;1
L 7.1575 2.9075 7.1575 2.9075 9 P 0 ;1
L 7.1575 2.9575 7.1575 2.9575 9 P 0 ;1
L 7.1575 3.0075 7.1575 3.0075 9 P 0 ;1
L 7.1575 3.0575 7.1575 3.0575 9 P 0 ;1
L 7.1575 3.1075 7.1575 3.1075 9 P 0 ;1
L 7.1575 3.1575 7.1575 3.1575 9 P 0 ;1
L 7.1575 3.2075 7.1575 3.2075 9 P 0 ;1
L 7.1575 3.2575 7.1575 3.2575 9 P 0 ;1
L 7.1575 3.3075 7.1575 3.3075 9 P 0 ;1
L 7.1575 3.3575 7.1575 3.3575 9 P 0 ;1
L 7.1575 3.4075 7.1575 3.4075 9 P 0 ;1
L 7.1575 3.4575 7.1575 3.4575 9 P 0 ;1
L 7.1575 3.5075 7.1575 3.5075 9 P 0 ;1
L 7.1575 3.5575 7.1575 3.5575 9 P 0 ;1
L 7.1575 3.6075 7.1575 3.6075 9 P 0 ;1
L 7.1575 3.6575 7.1575 3.6575 9 P 0 ;1
L 7.1575 3.7075 7.1575 3.7075 9 P 0 ;1
L 7.1575 3.7575 7.1575 3.7575 9 P 0 ;1
L 7.1575 3.8075 7.1575 3.8075 9 P 0 ;1
L 7.1575 3.8575 7.1575 3.8575 9 P 0 ;1
L 7.1575 3.9075 7.1575 3.9075 9 P 0 ;1
L 7.1575 3.9575 7.1575 3.9575 9 P 0 ;1
L 7.1575 4.0075 7.1575 4.0075 9 P 0 ;1
L 7.1575 4.0575 7.1575 4.0575 9 P 0 ;1
L 7.1575 4.1075 7.1575 4.1075 9 P 0 ;1
L 7.1575 4.2575 7.1575 4.2575 9 P 0 ;1
L 7.1575 4.3075 7.1575 4.3075 9 P 0 ;1
L 7.1575 4.8575 7.1575 4.8575 9 P 0 ;1
L 7.2075 0.4575 7.2075 0.4575 9 P 0 ;1
L 7.2075 0.5075 7.2075 0.5075 9 P 0 ;1
L 7.2075 0.5575 7.2075 0.5575 9 P 0 ;1
L 7.2075 0.6075 7.2075 0.6075 9 P 0 ;1
L 7.2075 0.6575 7.2075 0.6575 9 P 0 ;1
L 7.2075 0.7075 7.2075 0.7075 9 P 0 ;1
L 7.2075 0.7575 7.2075 0.7575 9 P 0 ;1
L 7.2075 0.8075 7.2075 0.8075 9 P 0 ;1
L 7.2075 0.8575 7.2075 0.8575 9 P 0 ;1
L 7.2075 0.9075 7.2075 0.9075 9 P 0 ;1
L 7.2075 0.9575 7.2075 0.9575 9 P 0 ;1
L 7.2075 1.0075 7.2075 1.0075 9 P 0 ;1
L 7.2075 1.0575 7.2075 1.0575 9 P 0 ;1
L 7.2075 1.1075 7.2075 1.1075 9 P 0 ;1
L 7.2075 1.1575 7.2075 1.1575 9 P 0 ;1
L 7.2075 1.2075 7.2075 1.2075 9 P 0 ;1
L 7.2075 1.2575 7.2075 1.2575 9 P 0 ;1
L 7.2075 1.3075 7.2075 1.3075 9 P 0 ;1
L 7.2075 1.3575 7.2075 1.3575 9 P 0 ;1
L 7.2075 1.4075 7.2075 1.4075 9 P 0 ;1
L 7.2075 1.4575 7.2075 1.4575 9 P 0 ;1
L 7.2075 1.5075 7.2075 1.5075 9 P 0 ;1
L 7.2075 1.5575 7.2075 1.5575 9 P 0 ;1
L 7.2075 1.6075 7.2075 1.6075 9 P 0 ;1
L 7.2075 1.6575 7.2075 1.6575 9 P 0 ;1
L 7.2075 1.7075 7.2075 1.7075 9 P 0 ;1
L 7.2075 1.7575 7.2075 1.7575 9 P 0 ;1
L 7.2075 1.8075 7.2075 1.8075 9 P 0 ;1
L 7.2075 1.8575 7.2075 1.8575 9 P 0 ;1
L 7.2075 1.9075 7.2075 1.9075 9 P 0 ;1
L 7.2075 1.9575 7.2075 1.9575 9 P 0 ;1
L 7.2075 2.0075 7.2075 2.0075 9 P 0 ;1
L 7.2075 2.0575 7.2075 2.0575 9 P 0 ;1
L 7.2075 2.1075 7.2075 2.1075 9 P 0 ;1
L 7.2075 2.1575 7.2075 2.1575 9 P 0 ;1
L 7.2075 2.2075 7.2075 2.2075 9 P 0 ;1
L 7.2075 2.2575 7.2075 2.2575 9 P 0 ;1
L 7.2075 2.3075 7.2075 2.3075 9 P 0 ;1
L 7.2075 2.3575 7.2075 2.3575 9 P 0 ;1
L 7.2075 2.4075 7.2075 2.4075 9 P 0 ;1
L 7.2075 2.4575 7.2075 2.4575 9 P 0 ;1
L 7.2075 2.7075 7.2075 2.7075 9 P 0 ;1
L 7.2075 2.7575 7.2075 2.7575 9 P 0 ;1
L 7.2075 2.8075 7.2075 2.8075 9 P 0 ;1
L 7.2075 2.8575 7.2075 2.8575 9 P 0 ;1
L 7.2075 2.9075 7.2075 2.9075 9 P 0 ;1
L 7.2075 2.9575 7.2075 2.9575 9 P 0 ;1
L 7.2075 3.0075 7.2075 3.0075 9 P 0 ;1
L 7.2075 3.0575 7.2075 3.0575 9 P 0 ;1
L 7.2075 3.1075 7.2075 3.1075 9 P 0 ;1
L 7.2075 3.1575 7.2075 3.1575 9 P 0 ;1
L 7.2075 3.2075 7.2075 3.2075 9 P 0 ;1
L 7.2075 3.2575 7.2075 3.2575 9 P 0 ;1
L 7.2075 3.3075 7.2075 3.3075 9 P 0 ;1
L 7.2075 3.3575 7.2075 3.3575 9 P 0 ;1
L 7.2075 3.4075 7.2075 3.4075 9 P 0 ;1
L 7.2075 3.4575 7.2075 3.4575 9 P 0 ;1
L 7.2075 3.5075 7.2075 3.5075 9 P 0 ;1
L 7.2075 3.5575 7.2075 3.5575 9 P 0 ;1
L 7.2075 3.6075 7.2075 3.6075 9 P 0 ;1
L 7.2075 3.6575 7.2075 3.6575 9 P 0 ;1
L 7.2075 3.7075 7.2075 3.7075 9 P 0 ;1
L 7.2075 3.7575 7.2075 3.7575 9 P 0 ;1
L 7.2075 3.8075 7.2075 3.8075 9 P 0 ;1
L 7.2075 3.8575 7.2075 3.8575 9 P 0 ;1
L 7.2075 3.9075 7.2075 3.9075 9 P 0 ;1
L 7.2075 3.9575 7.2075 3.9575 9 P 0 ;1
L 7.2075 4.0075 7.2075 4.0075 9 P 0 ;1
L 7.2075 4.0575 7.2075 4.0575 9 P 0 ;1
L 7.2075 4.1075 7.2075 4.1075 9 P 0 ;1
L 7.2075 4.1575 7.2075 4.1575 9 P 0 ;1
L 7.2075 4.2075 7.2075 4.2075 9 P 0 ;1
L 7.2075 4.2575 7.2075 4.2575 9 P 0 ;1
L 7.2075 4.8575 7.2075 4.8575 9 P 0 ;1
L 7.2575 0.4575 7.2575 0.4575 9 P 0 ;1
L 7.2575 0.5075 7.2575 0.5075 9 P 0 ;1
L 7.2575 0.5575 7.2575 0.5575 9 P 0 ;1
L 7.2575 0.6075 7.2575 0.6075 9 P 0 ;1
L 7.2575 0.6575 7.2575 0.6575 9 P 0 ;1
L 7.2575 0.7075 7.2575 0.7075 9 P 0 ;1
L 7.2575 0.7575 7.2575 0.7575 9 P 0 ;1
L 7.2575 0.8075 7.2575 0.8075 9 P 0 ;1
L 7.2575 0.8575 7.2575 0.8575 9 P 0 ;1
L 7.2575 0.9075 7.2575 0.9075 9 P 0 ;1
L 7.2575 0.9575 7.2575 0.9575 9 P 0 ;1
L 7.2575 1.0075 7.2575 1.0075 9 P 0 ;1
L 7.2575 1.0575 7.2575 1.0575 9 P 0 ;1
L 7.2575 1.1075 7.2575 1.1075 9 P 0 ;1
L 7.2575 1.1575 7.2575 1.1575 9 P 0 ;1
L 7.2575 1.2075 7.2575 1.2075 9 P 0 ;1
L 7.2575 1.2575 7.2575 1.2575 9 P 0 ;1
L 7.2575 1.3075 7.2575 1.3075 9 P 0 ;1
L 7.2575 1.3575 7.2575 1.3575 9 P 0 ;1
L 7.2575 1.4075 7.2575 1.4075 9 P 0 ;1
L 7.2575 1.4575 7.2575 1.4575 9 P 0 ;1
L 7.2575 1.5075 7.2575 1.5075 9 P 0 ;1
L 7.2575 1.5575 7.2575 1.5575 9 P 0 ;1
L 7.2575 1.6075 7.2575 1.6075 9 P 0 ;1
L 7.2575 1.6575 7.2575 1.6575 9 P 0 ;1
L 7.2575 1.7075 7.2575 1.7075 9 P 0 ;1
L 7.2575 1.7575 7.2575 1.7575 9 P 0 ;1
L 7.2575 1.8075 7.2575 1.8075 9 P 0 ;1
L 7.2575 1.8575 7.2575 1.8575 9 P 0 ;1
L 7.2575 1.9075 7.2575 1.9075 9 P 0 ;1
L 7.2575 1.9575 7.2575 1.9575 9 P 0 ;1
L 7.2575 2.0075 7.2575 2.0075 9 P 0 ;1
L 7.2575 2.0575 7.2575 2.0575 9 P 0 ;1
L 7.2575 2.1075 7.2575 2.1075 9 P 0 ;1
L 7.2575 2.1575 7.2575 2.1575 9 P 0 ;1
L 7.2575 2.2075 7.2575 2.2075 9 P 0 ;1
L 7.2575 2.2575 7.2575 2.2575 9 P 0 ;1
L 7.2575 2.3075 7.2575 2.3075 9 P 0 ;1
L 7.2575 2.3575 7.2575 2.3575 9 P 0 ;1
L 7.2575 2.4075 7.2575 2.4075 9 P 0 ;1
L 7.2575 2.4575 7.2575 2.4575 9 P 0 ;1
L 7.2575 2.5075 7.2575 2.5075 9 P 0 ;1
L 7.2575 2.5575 7.2575 2.5575 9 P 0 ;1
L 7.2575 2.6075 7.2575 2.6075 9 P 0 ;1
L 7.2575 2.6575 7.2575 2.6575 9 P 0 ;1
L 7.2575 2.7075 7.2575 2.7075 9 P 0 ;1
L 7.2575 2.7575 7.2575 2.7575 9 P 0 ;1
L 7.2575 2.8075 7.2575 2.8075 9 P 0 ;1
L 7.2575 2.8575 7.2575 2.8575 9 P 0 ;1
L 7.2575 2.9075 7.2575 2.9075 9 P 0 ;1
L 7.2575 2.9575 7.2575 2.9575 9 P 0 ;1
L 7.2575 3.0075 7.2575 3.0075 9 P 0 ;1
L 7.2575 3.0575 7.2575 3.0575 9 P 0 ;1
L 7.2575 3.1075 7.2575 3.1075 9 P 0 ;1
L 7.2575 3.1575 7.2575 3.1575 9 P 0 ;1
L 7.2575 3.2075 7.2575 3.2075 9 P 0 ;1
L 7.2575 3.2575 7.2575 3.2575 9 P 0 ;1
L 7.2575 3.3075 7.2575 3.3075 9 P 0 ;1
L 7.2575 3.3575 7.2575 3.3575 9 P 0 ;1
L 7.2575 3.4075 7.2575 3.4075 9 P 0 ;1
L 7.2575 3.4575 7.2575 3.4575 9 P 0 ;1
L 7.2575 3.5075 7.2575 3.5075 9 P 0 ;1
L 7.2575 3.5575 7.2575 3.5575 9 P 0 ;1
L 7.2575 3.6075 7.2575 3.6075 9 P 0 ;1
L 7.2575 3.6575 7.2575 3.6575 9 P 0 ;1
L 7.2575 3.7075 7.2575 3.7075 9 P 0 ;1
L 7.2575 3.7575 7.2575 3.7575 9 P 0 ;1
L 7.2575 3.8075 7.2575 3.8075 9 P 0 ;1
L 7.2575 3.8575 7.2575 3.8575 9 P 0 ;1
L 7.2575 3.9075 7.2575 3.9075 9 P 0 ;1
L 7.2575 3.9575 7.2575 3.9575 9 P 0 ;1
L 7.2575 4.8575 7.2575 4.8575 9 P 0 ;1
L 7.3075 0.4575 7.3075 0.4575 9 P 0 ;1
L 7.3075 0.5075 7.3075 0.5075 9 P 0 ;1
L 7.3075 0.5575 7.3075 0.5575 9 P 0 ;1
L 7.3075 0.6075 7.3075 0.6075 9 P 0 ;1
L 7.3075 0.6575 7.3075 0.6575 9 P 0 ;1
L 7.3075 0.7075 7.3075 0.7075 9 P 0 ;1
L 7.3075 0.7575 7.3075 0.7575 9 P 0 ;1
L 7.3075 0.8075 7.3075 0.8075 9 P 0 ;1
L 7.3075 0.8575 7.3075 0.8575 9 P 0 ;1
L 7.3075 0.9075 7.3075 0.9075 9 P 0 ;1
L 7.3075 0.9575 7.3075 0.9575 9 P 0 ;1
L 7.3075 1.0075 7.3075 1.0075 9 P 0 ;1
L 7.3075 1.0575 7.3075 1.0575 9 P 0 ;1
L 7.3075 1.1075 7.3075 1.1075 9 P 0 ;1
L 7.3075 1.1575 7.3075 1.1575 9 P 0 ;1
L 7.3075 1.2075 7.3075 1.2075 9 P 0 ;1
L 7.3075 1.2575 7.3075 1.2575 9 P 0 ;1
L 7.3075 1.3075 7.3075 1.3075 9 P 0 ;1
L 7.3075 1.3575 7.3075 1.3575 9 P 0 ;1
L 7.3075 1.4075 7.3075 1.4075 9 P 0 ;1
L 7.3075 1.4575 7.3075 1.4575 9 P 0 ;1
L 7.3075 1.5075 7.3075 1.5075 9 P 0 ;1
L 7.3075 1.5575 7.3075 1.5575 9 P 0 ;1
L 7.3075 1.6075 7.3075 1.6075 9 P 0 ;1
L 7.3075 1.6575 7.3075 1.6575 9 P 0 ;1
L 7.3075 1.7075 7.3075 1.7075 9 P 0 ;1
L 7.3075 1.7575 7.3075 1.7575 9 P 0 ;1
L 7.3075 1.8075 7.3075 1.8075 9 P 0 ;1
L 7.3075 1.8575 7.3075 1.8575 9 P 0 ;1
L 7.3075 1.9075 7.3075 1.9075 9 P 0 ;1
L 7.3075 1.9575 7.3075 1.9575 9 P 0 ;1
L 7.3075 2.0075 7.3075 2.0075 9 P 0 ;1
L 7.3075 2.0575 7.3075 2.0575 9 P 0 ;1
L 7.3075 2.1075 7.3075 2.1075 9 P 0 ;1
L 7.3075 2.1575 7.3075 2.1575 9 P 0 ;1
L 7.3075 2.2075 7.3075 2.2075 9 P 0 ;1
L 7.3075 2.2575 7.3075 2.2575 9 P 0 ;1
L 7.3075 2.3075 7.3075 2.3075 9 P 0 ;1
L 7.3075 2.3575 7.3075 2.3575 9 P 0 ;1
L 7.3075 2.4075 7.3075 2.4075 9 P 0 ;1
L 7.3075 2.4575 7.3075 2.4575 9 P 0 ;1
L 7.3075 2.5075 7.3075 2.5075 9 P 0 ;1
L 7.3075 2.5575 7.3075 2.5575 9 P 0 ;1
L 7.3075 2.6075 7.3075 2.6075 9 P 0 ;1
L 7.3075 2.6575 7.3075 2.6575 9 P 0 ;1
L 7.3075 2.7075 7.3075 2.7075 9 P 0 ;1
L 7.3075 2.7575 7.3075 2.7575 9 P 0 ;1
L 7.3075 2.8075 7.3075 2.8075 9 P 0 ;1
L 7.3075 2.8575 7.3075 2.8575 9 P 0 ;1
L 7.3075 2.9075 7.3075 2.9075 9 P 0 ;1
L 7.3075 2.9575 7.3075 2.9575 9 P 0 ;1
L 7.3075 3.0075 7.3075 3.0075 9 P 0 ;1
L 7.3075 3.0575 7.3075 3.0575 9 P 0 ;1
L 7.3075 3.1075 7.3075 3.1075 9 P 0 ;1
L 7.3075 3.1575 7.3075 3.1575 9 P 0 ;1
L 7.3075 3.2075 7.3075 3.2075 9 P 0 ;1
L 7.3075 3.2575 7.3075 3.2575 9 P 0 ;1
L 7.3075 3.3075 7.3075 3.3075 9 P 0 ;1
L 7.3075 3.3575 7.3075 3.3575 9 P 0 ;1
L 7.3075 3.4075 7.3075 3.4075 9 P 0 ;1
L 7.3075 3.4575 7.3075 3.4575 9 P 0 ;1
L 7.3075 3.5075 7.3075 3.5075 9 P 0 ;1
L 7.3075 3.5575 7.3075 3.5575 9 P 0 ;1
L 7.3075 3.6075 7.3075 3.6075 9 P 0 ;1
L 7.3075 3.6575 7.3075 3.6575 9 P 0 ;1
L 7.3075 3.7075 7.3075 3.7075 9 P 0 ;1
L 7.3575 0.1575 7.3575 0.1575 9 P 0 ;1
L 7.3575 0.3575 7.3575 0.3575 9 P 0 ;1
L 7.3575 0.4075 7.3575 0.4075 9 P 0 ;1
L 7.3575 0.4575 7.3575 0.4575 9 P 0 ;1
L 7.3575 0.5075 7.3575 0.5075 9 P 0 ;1
L 7.3575 0.5575 7.3575 0.5575 9 P 0 ;1
L 7.3575 0.6075 7.3575 0.6075 9 P 0 ;1
L 7.3575 0.6575 7.3575 0.6575 9 P 0 ;1
L 7.3575 0.7075 7.3575 0.7075 9 P 0 ;1
L 7.3575 0.7575 7.3575 0.7575 9 P 0 ;1
L 7.3575 0.8075 7.3575 0.8075 9 P 0 ;1
L 7.3575 0.8575 7.3575 0.8575 9 P 0 ;1
L 7.3575 0.9075 7.3575 0.9075 9 P 0 ;1
L 7.3575 0.9575 7.3575 0.9575 9 P 0 ;1
L 7.3575 1.0075 7.3575 1.0075 9 P 0 ;1
L 7.3575 1.0575 7.3575 1.0575 9 P 0 ;1
L 7.3575 1.1075 7.3575 1.1075 9 P 0 ;1
L 7.3575 1.1575 7.3575 1.1575 9 P 0 ;1
L 7.3575 1.2075 7.3575 1.2075 9 P 0 ;1
L 7.3575 1.2575 7.3575 1.2575 9 P 0 ;1
L 7.3575 1.3075 7.3575 1.3075 9 P 0 ;1
L 7.3575 1.3575 7.3575 1.3575 9 P 0 ;1
L 7.3575 1.4075 7.3575 1.4075 9 P 0 ;1
L 7.3575 1.4575 7.3575 1.4575 9 P 0 ;1
L 7.3575 1.5075 7.3575 1.5075 9 P 0 ;1
L 7.3575 1.5575 7.3575 1.5575 9 P 0 ;1
L 7.3575 1.6075 7.3575 1.6075 9 P 0 ;1
L 7.3575 1.6575 7.3575 1.6575 9 P 0 ;1
L 7.3575 5.6575 7.3575 5.6575 9 P 0 ;1
L 7.3575 5.7075 7.3575 5.7075 9 P 0 ;1
L 7.3575 5.9075 7.3575 5.9075 9 P 0 ;1
L 7.4075 0.1575 7.4075 0.1575 9 P 0 ;1
L 7.4075 0.2075 7.4075 0.2075 9 P 0 ;1
L 7.4075 0.2575 7.4075 0.2575 9 P 0 ;1
L 7.4075 0.3075 7.4075 0.3075 9 P 0 ;1
L 7.4075 0.3575 7.4075 0.3575 9 P 0 ;1
L 7.4075 0.4075 7.4075 0.4075 9 P 0 ;1
L 7.4075 0.4575 7.4075 0.4575 9 P 0 ;1
L 7.4075 0.5075 7.4075 0.5075 9 P 0 ;1
L 7.4075 0.5575 7.4075 0.5575 9 P 0 ;1
L 7.4075 0.6075 7.4075 0.6075 9 P 0 ;1
L 7.4075 0.6575 7.4075 0.6575 9 P 0 ;1
L 7.4075 0.7075 7.4075 0.7075 9 P 0 ;1
L 7.4075 0.7575 7.4075 0.7575 9 P 0 ;1
L 7.4075 0.8075 7.4075 0.8075 9 P 0 ;1
L 7.4075 0.8575 7.4075 0.8575 9 P 0 ;1
L 7.4075 0.9075 7.4075 0.9075 9 P 0 ;1
L 7.4075 0.9575 7.4075 0.9575 9 P 0 ;1
L 7.4075 1.0075 7.4075 1.0075 9 P 0 ;1
L 7.4075 1.0575 7.4075 1.0575 9 P 0 ;1
L 7.4075 1.1075 7.4075 1.1075 9 P 0 ;1
L 7.4075 1.1575 7.4075 1.1575 9 P 0 ;1
L 7.4075 1.2075 7.4075 1.2075 9 P 0 ;1
L 7.4075 1.2575 7.4075 1.2575 9 P 0 ;1
L 7.4075 1.3075 7.4075 1.3075 9 P 0 ;1
L 7.4075 1.3575 7.4075 1.3575 9 P 0 ;1
L 7.4075 1.4075 7.4075 1.4075 9 P 0 ;1
L 7.4075 1.4575 7.4075 1.4575 9 P 0 ;1
L 7.4075 1.5075 7.4075 1.5075 9 P 0 ;1
L 7.4075 1.5575 7.4075 1.5575 9 P 0 ;1
L 7.4075 1.6075 7.4075 1.6075 9 P 0 ;1
L 7.4075 4.7575 7.4075 4.7575 9 P 0 ;1
L 7.4075 4.8075 7.4075 4.8075 9 P 0 ;1
L 7.4075 4.9075 7.4075 4.9075 9 P 0 ;1
L 7.4075 4.9575 7.4075 4.9575 9 P 0 ;1
L 7.4075 5.6575 7.4075 5.6575 9 P 0 ;1
L 7.4075 5.7075 7.4075 5.7075 9 P 0 ;1
L 7.4075 5.7575 7.4075 5.7575 9 P 0 ;1
L 7.4075 5.8075 7.4075 5.8075 9 P 0 ;1
L 7.4075 5.8575 7.4075 5.8575 9 P 0 ;1
L 7.4075 5.9075 7.4075 5.9075 9 P 0 ;1
L 7.4575 0.1575 7.4575 0.1575 9 P 0 ;1
L 7.4575 0.2075 7.4575 0.2075 9 P 0 ;1
L 7.4575 0.2575 7.4575 0.2575 9 P 0 ;1
L 7.4575 0.3075 7.4575 0.3075 9 P 0 ;1
L 7.4575 0.3575 7.4575 0.3575 9 P 0 ;1
L 7.4575 0.4075 7.4575 0.4075 9 P 0 ;1
L 7.4575 0.4575 7.4575 0.4575 9 P 0 ;1
L 7.4575 0.5075 7.4575 0.5075 9 P 0 ;1
L 7.4575 0.5575 7.4575 0.5575 9 P 0 ;1
L 7.4575 0.6075 7.4575 0.6075 9 P 0 ;1
L 7.4575 0.6575 7.4575 0.6575 9 P 0 ;1
L 7.4575 0.7075 7.4575 0.7075 9 P 0 ;1
L 7.4575 0.7575 7.4575 0.7575 9 P 0 ;1
L 7.4575 0.8075 7.4575 0.8075 9 P 0 ;1
L 7.4575 0.8575 7.4575 0.8575 9 P 0 ;1
L 7.4575 0.9075 7.4575 0.9075 9 P 0 ;1
L 7.4575 0.9575 7.4575 0.9575 9 P 0 ;1
L 7.4575 1.0075 7.4575 1.0075 9 P 0 ;1
L 7.4575 1.0575 7.4575 1.0575 9 P 0 ;1
L 7.4575 1.1075 7.4575 1.1075 9 P 0 ;1
L 7.4575 1.1575 7.4575 1.1575 9 P 0 ;1
L 7.4575 1.2075 7.4575 1.2075 9 P 0 ;1
L 7.4575 1.2575 7.4575 1.2575 9 P 0 ;1
L 7.4575 1.3075 7.4575 1.3075 9 P 0 ;1
L 7.4575 1.3575 7.4575 1.3575 9 P 0 ;1
L 7.4575 1.4075 7.4575 1.4075 9 P 0 ;1
L 7.4575 1.4575 7.4575 1.4575 9 P 0 ;1
L 7.4575 1.5075 7.4575 1.5075 9 P 0 ;1
L 7.4575 1.5575 7.4575 1.5575 9 P 0 ;1
L 7.4575 1.6075 7.4575 1.6075 9 P 0 ;1
L 7.4575 4.6575 7.4575 4.6575 9 P 0 ;1
L 7.4575 4.7075 7.4575 4.7075 9 P 0 ;1
L 7.4575 4.8575 7.4575 4.8575 9 P 0 ;1
L 7.4575 4.9075 7.4575 4.9075 9 P 0 ;1
L 7.4575 4.9575 7.4575 4.9575 9 P 0 ;1
L 7.4575 5.0075 7.4575 5.0075 9 P 0 ;1
L 7.4575 5.6075 7.4575 5.6075 9 P 0 ;1
L 7.4575 5.6575 7.4575 5.6575 9 P 0 ;1
L 7.4575 5.7075 7.4575 5.7075 9 P 0 ;1
L 7.4575 5.7575 7.4575 5.7575 9 P 0 ;1
L 7.4575 5.8075 7.4575 5.8075 9 P 0 ;1
L 7.4575 5.8575 7.4575 5.8575 9 P 0 ;1
L 7.4575 5.9075 7.4575 5.9075 9 P 0 ;1
L 7.5075 0.1575 7.5075 0.1575 9 P 0 ;1
L 7.5075 0.2075 7.5075 0.2075 9 P 0 ;1
L 7.5075 0.2575 7.5075 0.2575 9 P 0 ;1
L 7.5075 0.3075 7.5075 0.3075 9 P 0 ;1
L 7.5075 0.3575 7.5075 0.3575 9 P 0 ;1
L 7.5075 0.4075 7.5075 0.4075 9 P 0 ;1
L 7.5075 0.4575 7.5075 0.4575 9 P 0 ;1
L 7.5075 0.5075 7.5075 0.5075 9 P 0 ;1
L 7.5075 0.5575 7.5075 0.5575 9 P 0 ;1
L 7.5075 0.6075 7.5075 0.6075 9 P 0 ;1
L 7.5075 0.6575 7.5075 0.6575 9 P 0 ;1
L 7.5075 0.7075 7.5075 0.7075 9 P 0 ;1
L 7.5075 0.7575 7.5075 0.7575 9 P 0 ;1
L 7.5075 0.8075 7.5075 0.8075 9 P 0 ;1
L 7.5075 0.8575 7.5075 0.8575 9 P 0 ;1
L 7.5075 0.9075 7.5075 0.9075 9 P 0 ;1
L 7.5075 0.9575 7.5075 0.9575 9 P 0 ;1
L 7.5075 1.0075 7.5075 1.0075 9 P 0 ;1
L 7.5075 1.0575 7.5075 1.0575 9 P 0 ;1
L 7.5075 1.1075 7.5075 1.1075 9 P 0 ;1
L 7.5075 1.1575 7.5075 1.1575 9 P 0 ;1
L 7.5075 1.2075 7.5075 1.2075 9 P 0 ;1
L 7.5075 1.2575 7.5075 1.2575 9 P 0 ;1
L 7.5075 1.3075 7.5075 1.3075 9 P 0 ;1
L 7.5075 1.3575 7.5075 1.3575 9 P 0 ;1
L 7.5075 1.4075 7.5075 1.4075 9 P 0 ;1
L 7.5075 1.4575 7.5075 1.4575 9 P 0 ;1
L 7.5075 1.5075 7.5075 1.5075 9 P 0 ;1
L 7.5075 1.5575 7.5075 1.5575 9 P 0 ;1
L 7.5075 1.6075 7.5075 1.6075 9 P 0 ;1
L 7.5075 1.8075 7.5075 1.8075 9 P 0 ;1
L 7.5075 1.8575 7.5075 1.8575 9 P 0 ;1
L 7.5075 1.9075 7.5075 1.9075 9 P 0 ;1
L 7.5075 1.9575 7.5075 1.9575 9 P 0 ;1
L 7.5075 2.0075 7.5075 2.0075 9 P 0 ;1
L 7.5075 2.0575 7.5075 2.0575 9 P 0 ;1
L 7.5075 2.1075 7.5075 2.1075 9 P 0 ;1
L 7.5075 2.1575 7.5075 2.1575 9 P 0 ;1
L 7.5075 2.2075 7.5075 2.2075 9 P 0 ;1
L 7.5075 2.2575 7.5075 2.2575 9 P 0 ;1
L 7.5075 2.3075 7.5075 2.3075 9 P 0 ;1
L 7.5075 2.3575 7.5075 2.3575 9 P 0 ;1
L 7.5075 2.4075 7.5075 2.4075 9 P 0 ;1
L 7.5075 2.4575 7.5075 2.4575 9 P 0 ;1
L 7.5075 2.5075 7.5075 2.5075 9 P 0 ;1
L 7.5075 2.5575 7.5075 2.5575 9 P 0 ;1
L 7.5075 2.6075 7.5075 2.6075 9 P 0 ;1
L 7.5075 2.6575 7.5075 2.6575 9 P 0 ;1
L 7.5075 2.7075 7.5075 2.7075 9 P 0 ;1
L 7.5075 2.7575 7.5075 2.7575 9 P 0 ;1
L 7.5075 2.8075 7.5075 2.8075 9 P 0 ;1
L 7.5075 2.8575 7.5075 2.8575 9 P 0 ;1
L 7.5075 2.9075 7.5075 2.9075 9 P 0 ;1
L 7.5075 2.9575 7.5075 2.9575 9 P 0 ;1
L 7.5075 3.0075 7.5075 3.0075 9 P 0 ;1
L 7.5075 3.0575 7.5075 3.0575 9 P 0 ;1
L 7.5075 3.1075 7.5075 3.1075 9 P 0 ;1
L 7.5075 3.1575 7.5075 3.1575 9 P 0 ;1
L 7.5075 3.2075 7.5075 3.2075 9 P 0 ;1
L 7.5075 3.2575 7.5075 3.2575 9 P 0 ;1
L 7.5075 5.5575 7.5075 5.5575 9 P 0 ;1
L 7.5075 5.6075 7.5075 5.6075 9 P 0 ;1
L 7.5075 5.6575 7.5075 5.6575 9 P 0 ;1
L 7.5075 5.7075 7.5075 5.7075 9 P 0 ;1
L 7.5075 5.7575 7.5075 5.7575 9 P 0 ;1
L 7.5075 5.8075 7.5075 5.8075 9 P 0 ;1
L 7.5075 5.8575 7.5075 5.8575 9 P 0 ;1
L 7.5075 5.9075 7.5075 5.9075 9 P 0 ;1
L 7.5575 0.1575 7.5575 0.1575 9 P 0 ;1
L 7.5575 0.2075 7.5575 0.2075 9 P 0 ;1
L 7.5575 0.2575 7.5575 0.2575 9 P 0 ;1
L 7.5575 0.3075 7.5575 0.3075 9 P 0 ;1
L 7.5575 0.3575 7.5575 0.3575 9 P 0 ;1
L 7.5575 0.4075 7.5575 0.4075 9 P 0 ;1
L 7.5575 0.4575 7.5575 0.4575 9 P 0 ;1
L 7.5575 0.5075 7.5575 0.5075 9 P 0 ;1
L 7.5575 0.5575 7.5575 0.5575 9 P 0 ;1
L 7.5575 0.6075 7.5575 0.6075 9 P 0 ;1
L 7.5575 0.6575 7.5575 0.6575 9 P 0 ;1
L 7.5575 0.7075 7.5575 0.7075 9 P 0 ;1
L 7.5575 0.7575 7.5575 0.7575 9 P 0 ;1
L 7.5575 0.8075 7.5575 0.8075 9 P 0 ;1
L 7.5575 0.8575 7.5575 0.8575 9 P 0 ;1
L 7.5575 0.9075 7.5575 0.9075 9 P 0 ;1
L 7.5575 0.9575 7.5575 0.9575 9 P 0 ;1
L 7.5575 1.0075 7.5575 1.0075 9 P 0 ;1
L 7.5575 1.0575 7.5575 1.0575 9 P 0 ;1
L 7.5575 1.1075 7.5575 1.1075 9 P 0 ;1
L 7.5575 1.1575 7.5575 1.1575 9 P 0 ;1
L 7.5575 1.2075 7.5575 1.2075 9 P 0 ;1
L 7.5575 1.2575 7.5575 1.2575 9 P 0 ;1
L 7.5575 1.3075 7.5575 1.3075 9 P 0 ;1
L 7.5575 1.3575 7.5575 1.3575 9 P 0 ;1
L 7.5575 1.4075 7.5575 1.4075 9 P 0 ;1
L 7.5575 1.4575 7.5575 1.4575 9 P 0 ;1
L 7.5575 1.5075 7.5575 1.5075 9 P 0 ;1
L 7.5575 1.5575 7.5575 1.5575 9 P 0 ;1
L 7.5575 1.6075 7.5575 1.6075 9 P 0 ;1
L 7.5575 1.6575 7.5575 1.6575 9 P 0 ;1
L 7.5575 1.7075 7.5575 1.7075 9 P 0 ;1
L 7.5575 1.7575 7.5575 1.7575 9 P 0 ;1
L 7.5575 1.8075 7.5575 1.8075 9 P 0 ;1
L 7.5575 1.8575 7.5575 1.8575 9 P 0 ;1
L 7.5575 1.9075 7.5575 1.9075 9 P 0 ;1
L 7.5575 1.9575 7.5575 1.9575 9 P 0 ;1
L 7.5575 2.0075 7.5575 2.0075 9 P 0 ;1
L 7.5575 2.0575 7.5575 2.0575 9 P 0 ;1
L 7.5575 2.1075 7.5575 2.1075 9 P 0 ;1
L 7.5575 2.1575 7.5575 2.1575 9 P 0 ;1
L 7.5575 2.2075 7.5575 2.2075 9 P 0 ;1
L 7.5575 2.2575 7.5575 2.2575 9 P 0 ;1
L 7.5575 2.3075 7.5575 2.3075 9 P 0 ;1
L 7.5575 2.3575 7.5575 2.3575 9 P 0 ;1
L 7.5575 2.4075 7.5575 2.4075 9 P 0 ;1
L 7.5575 2.4575 7.5575 2.4575 9 P 0 ;1
L 7.5575 2.5075 7.5575 2.5075 9 P 0 ;1
L 7.5575 2.5575 7.5575 2.5575 9 P 0 ;1
L 7.5575 2.6075 7.5575 2.6075 9 P 0 ;1
L 7.5575 2.6575 7.5575 2.6575 9 P 0 ;1
L 7.5575 2.7075 7.5575 2.7075 9 P 0 ;1
L 7.5575 2.7575 7.5575 2.7575 9 P 0 ;1
L 7.5575 2.8075 7.5575 2.8075 9 P 0 ;1
L 7.5575 2.8575 7.5575 2.8575 9 P 0 ;1
L 7.5575 2.9075 7.5575 2.9075 9 P 0 ;1
L 7.5575 2.9575 7.5575 2.9575 9 P 0 ;1
L 7.5575 3.0075 7.5575 3.0075 9 P 0 ;1
L 7.5575 3.0575 7.5575 3.0575 9 P 0 ;1
L 7.5575 3.1075 7.5575 3.1075 9 P 0 ;1
L 7.5575 3.1575 7.5575 3.1575 9 P 0 ;1
L 7.5575 3.2075 7.5575 3.2075 9 P 0 ;1
L 7.5575 5.2575 7.5575 5.2575 9 P 0 ;1
L 7.5575 5.3075 7.5575 5.3075 9 P 0 ;1
L 7.5575 5.3575 7.5575 5.3575 9 P 0 ;1
L 7.5575 5.4075 7.5575 5.4075 9 P 0 ;1
L 7.5575 5.4575 7.5575 5.4575 9 P 0 ;1
L 7.5575 5.5075 7.5575 5.5075 9 P 0 ;1
L 7.5575 5.5575 7.5575 5.5575 9 P 0 ;1
L 7.5575 5.6075 7.5575 5.6075 9 P 0 ;1
L 7.5575 5.6575 7.5575 5.6575 9 P 0 ;1
L 7.5575 5.7075 7.5575 5.7075 9 P 0 ;1
L 7.5575 5.7575 7.5575 5.7575 9 P 0 ;1
L 7.5575 5.8075 7.5575 5.8075 9 P 0 ;1
L 7.5575 5.8575 7.5575 5.8575 9 P 0 ;1
L 7.5575 5.9075 7.5575 5.9075 9 P 0 ;1
L 7.6075 0.1575 7.6075 0.1575 9 P 0 ;1
L 7.6075 0.2075 7.6075 0.2075 9 P 0 ;1
L 7.6075 0.2575 7.6075 0.2575 9 P 0 ;1
L 7.6075 0.3075 7.6075 0.3075 9 P 0 ;1
L 7.6075 0.3575 7.6075 0.3575 9 P 0 ;1
L 7.6075 0.4075 7.6075 0.4075 9 P 0 ;1
L 7.6075 0.4575 7.6075 0.4575 9 P 0 ;1
L 7.6075 0.5075 7.6075 0.5075 9 P 0 ;1
L 7.6075 0.5575 7.6075 0.5575 9 P 0 ;1
L 7.6075 0.6075 7.6075 0.6075 9 P 0 ;1
L 7.6075 0.6575 7.6075 0.6575 9 P 0 ;1
L 7.6075 0.7075 7.6075 0.7075 9 P 0 ;1
L 7.6075 0.7575 7.6075 0.7575 9 P 0 ;1
L 7.6075 0.8075 7.6075 0.8075 9 P 0 ;1
L 7.6075 0.8575 7.6075 0.8575 9 P 0 ;1
L 7.6075 0.9075 7.6075 0.9075 9 P 0 ;1
L 7.6075 0.9575 7.6075 0.9575 9 P 0 ;1
L 7.6075 1.0075 7.6075 1.0075 9 P 0 ;1
L 7.6075 1.0575 7.6075 1.0575 9 P 0 ;1
L 7.6075 1.1075 7.6075 1.1075 9 P 0 ;1
L 7.6075 1.1575 7.6075 1.1575 9 P 0 ;1
L 7.6075 1.2075 7.6075 1.2075 9 P 0 ;1
L 7.6075 1.2575 7.6075 1.2575 9 P 0 ;1
L 7.6075 1.3075 7.6075 1.3075 9 P 0 ;1
L 7.6075 1.3575 7.6075 1.3575 9 P 0 ;1
L 7.6075 1.4075 7.6075 1.4075 9 P 0 ;1
L 7.6075 1.4575 7.6075 1.4575 9 P 0 ;1
L 7.6075 1.5075 7.6075 1.5075 9 P 0 ;1
L 7.6075 1.5575 7.6075 1.5575 9 P 0 ;1
L 7.6075 1.6075 7.6075 1.6075 9 P 0 ;1
L 7.6075 1.6575 7.6075 1.6575 9 P 0 ;1
L 7.6075 1.7075 7.6075 1.7075 9 P 0 ;1
L 7.6075 1.7575 7.6075 1.7575 9 P 0 ;1
L 7.6075 1.8075 7.6075 1.8075 9 P 0 ;1
L 7.6075 1.8575 7.6075 1.8575 9 P 0 ;1
L 7.6075 1.9075 7.6075 1.9075 9 P 0 ;1
L 7.6075 1.9575 7.6075 1.9575 9 P 0 ;1
L 7.6075 2.0075 7.6075 2.0075 9 P 0 ;1
L 7.6075 2.0575 7.6075 2.0575 9 P 0 ;1
L 7.6075 2.1075 7.6075 2.1075 9 P 0 ;1
L 7.6075 2.1575 7.6075 2.1575 9 P 0 ;1
L 7.6075 2.2075 7.6075 2.2075 9 P 0 ;1
L 7.6075 2.2575 7.6075 2.2575 9 P 0 ;1
L 7.6075 2.3075 7.6075 2.3075 9 P 0 ;1
L 7.6075 2.3575 7.6075 2.3575 9 P 0 ;1
L 7.6075 2.4075 7.6075 2.4075 9 P 0 ;1
L 7.6075 2.4575 7.6075 2.4575 9 P 0 ;1
L 7.6075 2.5075 7.6075 2.5075 9 P 0 ;1
L 7.6075 2.5575 7.6075 2.5575 9 P 0 ;1
L 7.6075 2.6075 7.6075 2.6075 9 P 0 ;1
L 7.6075 2.6575 7.6075 2.6575 9 P 0 ;1
L 7.6075 2.7075 7.6075 2.7075 9 P 0 ;1
L 7.6075 2.7575 7.6075 2.7575 9 P 0 ;1
L 7.6075 2.8075 7.6075 2.8075 9 P 0 ;1
L 7.6075 2.8575 7.6075 2.8575 9 P 0 ;1
L 7.6075 2.9075 7.6075 2.9075 9 P 0 ;1
L 7.6075 2.9575 7.6075 2.9575 9 P 0 ;1
L 7.6075 3.0075 7.6075 3.0075 9 P 0 ;1
L 7.6075 3.0575 7.6075 3.0575 9 P 0 ;1
L 7.6075 3.1075 7.6075 3.1075 9 P 0 ;1
L 7.6075 3.1575 7.6075 3.1575 9 P 0 ;1
L 7.6075 5.2575 7.6075 5.2575 9 P 0 ;1
L 7.6075 5.3075 7.6075 5.3075 9 P 0 ;1
L 7.6075 5.3575 7.6075 5.3575 9 P 0 ;1
L 7.6075 5.4075 7.6075 5.4075 9 P 0 ;1
L 7.6075 5.4575 7.6075 5.4575 9 P 0 ;1
L 7.6075 5.5075 7.6075 5.5075 9 P 0 ;1
L 7.6075 5.5575 7.6075 5.5575 9 P 0 ;1
L 7.6075 5.6075 7.6075 5.6075 9 P 0 ;1
L 7.6075 5.6575 7.6075 5.6575 9 P 0 ;1
L 7.6075 5.7075 7.6075 5.7075 9 P 0 ;1
L 7.6075 5.7575 7.6075 5.7575 9 P 0 ;1
L 7.6075 5.8075 7.6075 5.8075 9 P 0 ;1
L 7.6075 5.8575 7.6075 5.8575 9 P 0 ;1
L 7.6075 5.9075 7.6075 5.9075 9 P 0 ;1
L 7.6575 0.1575 7.6575 0.1575 9 P 0 ;1
L 7.6575 0.2075 7.6575 0.2075 9 P 0 ;1
L 7.6575 0.2575 7.6575 0.2575 9 P 0 ;1
L 7.6575 0.3075 7.6575 0.3075 9 P 0 ;1
L 7.6575 0.3575 7.6575 0.3575 9 P 0 ;1
L 7.6575 0.4075 7.6575 0.4075 9 P 0 ;1
L 7.6575 0.4575 7.6575 0.4575 9 P 0 ;1
L 7.6575 0.5075 7.6575 0.5075 9 P 0 ;1
L 7.6575 0.5575 7.6575 0.5575 9 P 0 ;1
L 7.6575 0.6075 7.6575 0.6075 9 P 0 ;1
L 7.6575 0.6575 7.6575 0.6575 9 P 0 ;1
L 7.6575 0.7075 7.6575 0.7075 9 P 0 ;1
L 7.6575 0.7575 7.6575 0.7575 9 P 0 ;1
L 7.6575 0.8075 7.6575 0.8075 9 P 0 ;1
L 7.6575 0.8575 7.6575 0.8575 9 P 0 ;1
L 7.6575 0.9075 7.6575 0.9075 9 P 0 ;1
L 7.6575 0.9575 7.6575 0.9575 9 P 0 ;1
L 7.6575 1.0075 7.6575 1.0075 9 P 0 ;1
L 7.6575 1.0575 7.6575 1.0575 9 P 0 ;1
L 7.6575 1.1075 7.6575 1.1075 9 P 0 ;1
L 7.6575 1.1575 7.6575 1.1575 9 P 0 ;1
L 7.6575 1.2075 7.6575 1.2075 9 P 0 ;1
L 7.6575 1.2575 7.6575 1.2575 9 P 0 ;1
L 7.6575 1.3075 7.6575 1.3075 9 P 0 ;1
L 7.6575 1.3575 7.6575 1.3575 9 P 0 ;1
L 7.6575 1.4075 7.6575 1.4075 9 P 0 ;1
L 7.6575 1.4575 7.6575 1.4575 9 P 0 ;1
L 7.6575 1.5075 7.6575 1.5075 9 P 0 ;1
L 7.6575 1.5575 7.6575 1.5575 9 P 0 ;1
L 7.6575 1.6075 7.6575 1.6075 9 P 0 ;1
L 7.6575 1.6575 7.6575 1.6575 9 P 0 ;1
L 7.6575 1.7075 7.6575 1.7075 9 P 0 ;1
L 7.6575 1.7575 7.6575 1.7575 9 P 0 ;1
L 7.6575 1.8075 7.6575 1.8075 9 P 0 ;1
L 7.6575 1.8575 7.6575 1.8575 9 P 0 ;1
L 7.6575 1.9075 7.6575 1.9075 9 P 0 ;1
L 7.6575 1.9575 7.6575 1.9575 9 P 0 ;1
L 7.6575 2.0075 7.6575 2.0075 9 P 0 ;1
L 7.6575 2.0575 7.6575 2.0575 9 P 0 ;1
L 7.6575 2.1075 7.6575 2.1075 9 P 0 ;1
L 7.6575 2.1575 7.6575 2.1575 9 P 0 ;1
L 7.6575 2.2075 7.6575 2.2075 9 P 0 ;1
L 7.6575 2.2575 7.6575 2.2575 9 P 0 ;1
L 7.6575 2.3075 7.6575 2.3075 9 P 0 ;1
L 7.6575 2.3575 7.6575 2.3575 9 P 0 ;1
L 7.6575 2.4075 7.6575 2.4075 9 P 0 ;1
L 7.6575 2.4575 7.6575 2.4575 9 P 0 ;1
L 7.6575 2.5075 7.6575 2.5075 9 P 0 ;1
L 7.6575 2.5575 7.6575 2.5575 9 P 0 ;1
L 7.6575 2.6075 7.6575 2.6075 9 P 0 ;1
L 7.6575 2.6575 7.6575 2.6575 9 P 0 ;1
L 7.6575 2.7075 7.6575 2.7075 9 P 0 ;1
L 7.6575 2.7575 7.6575 2.7575 9 P 0 ;1
L 7.6575 2.8075 7.6575 2.8075 9 P 0 ;1
L 7.6575 2.8575 7.6575 2.8575 9 P 0 ;1
L 7.6575 2.9075 7.6575 2.9075 9 P 0 ;1
L 7.6575 2.9575 7.6575 2.9575 9 P 0 ;1
L 7.6575 3.0075 7.6575 3.0075 9 P 0 ;1
L 7.6575 3.0575 7.6575 3.0575 9 P 0 ;1
L 7.6575 3.1075 7.6575 3.1075 9 P 0 ;1
L 7.6575 3.1575 7.6575 3.1575 9 P 0 ;1
L 7.6575 5.2575 7.6575 5.2575 9 P 0 ;1
L 7.6575 5.3075 7.6575 5.3075 9 P 0 ;1
L 7.6575 5.3575 7.6575 5.3575 9 P 0 ;1
L 7.6575 5.4075 7.6575 5.4075 9 P 0 ;1
L 7.6575 5.4575 7.6575 5.4575 9 P 0 ;1
L 7.6575 5.5075 7.6575 5.5075 9 P 0 ;1
L 7.6575 5.5575 7.6575 5.5575 9 P 0 ;1
L 7.6575 5.6075 7.6575 5.6075 9 P 0 ;1
L 7.6575 5.6575 7.6575 5.6575 9 P 0 ;1
L 7.6575 5.7075 7.6575 5.7075 9 P 0 ;1
L 7.6575 5.7575 7.6575 5.7575 9 P 0 ;1
L 7.6575 5.8075 7.6575 5.8075 9 P 0 ;1
L 7.6575 5.8575 7.6575 5.8575 9 P 0 ;1
L 7.6575 5.9075 7.6575 5.9075 9 P 0 ;1
L 7.7075 0.1575 7.7075 0.1575 9 P 0 ;1
L 7.7075 0.2075 7.7075 0.2075 9 P 0 ;1
L 7.7075 0.2575 7.7075 0.2575 9 P 0 ;1
L 7.7075 0.3075 7.7075 0.3075 9 P 0 ;1
L 7.7075 0.3575 7.7075 0.3575 9 P 0 ;1
L 7.7075 0.4075 7.7075 0.4075 9 P 0 ;1
L 7.7075 0.4575 7.7075 0.4575 9 P 0 ;1
L 7.7075 0.5075 7.7075 0.5075 9 P 0 ;1
L 7.7075 0.5575 7.7075 0.5575 9 P 0 ;1
L 7.7075 0.6075 7.7075 0.6075 9 P 0 ;1
L 7.7075 0.6575 7.7075 0.6575 9 P 0 ;1
L 7.7075 0.7075 7.7075 0.7075 9 P 0 ;1
L 7.7075 0.7575 7.7075 0.7575 9 P 0 ;1
L 7.7075 0.8075 7.7075 0.8075 9 P 0 ;1
L 7.7075 0.8575 7.7075 0.8575 9 P 0 ;1
L 7.7075 0.9075 7.7075 0.9075 9 P 0 ;1
L 7.7075 0.9575 7.7075 0.9575 9 P 0 ;1
L 7.7075 1.0075 7.7075 1.0075 9 P 0 ;1
L 7.7075 1.0575 7.7075 1.0575 9 P 0 ;1
L 7.7075 1.1075 7.7075 1.1075 9 P 0 ;1
L 7.7075 1.1575 7.7075 1.1575 9 P 0 ;1
L 7.7075 1.2075 7.7075 1.2075 9 P 0 ;1
L 7.7075 1.2575 7.7075 1.2575 9 P 0 ;1
L 7.7075 1.3075 7.7075 1.3075 9 P 0 ;1
L 7.7075 1.3575 7.7075 1.3575 9 P 0 ;1
L 7.7075 1.4075 7.7075 1.4075 9 P 0 ;1
L 7.7075 1.4575 7.7075 1.4575 9 P 0 ;1
L 7.7075 1.5075 7.7075 1.5075 9 P 0 ;1
L 7.7075 1.5575 7.7075 1.5575 9 P 0 ;1
L 7.7075 1.6075 7.7075 1.6075 9 P 0 ;1
L 7.7075 1.6575 7.7075 1.6575 9 P 0 ;1
L 7.7075 1.7075 7.7075 1.7075 9 P 0 ;1
L 7.7075 1.7575 7.7075 1.7575 9 P 0 ;1
L 7.7075 1.8075 7.7075 1.8075 9 P 0 ;1
L 7.7075 1.8575 7.7075 1.8575 9 P 0 ;1
L 7.7075 1.9075 7.7075 1.9075 9 P 0 ;1
L 7.7075 1.9575 7.7075 1.9575 9 P 0 ;1
L 7.7075 2.0075 7.7075 2.0075 9 P 0 ;1
L 7.7075 2.0575 7.7075 2.0575 9 P 0 ;1
L 7.7075 2.1075 7.7075 2.1075 9 P 0 ;1
L 7.7075 2.1575 7.7075 2.1575 9 P 0 ;1
L 7.7075 2.2075 7.7075 2.2075 9 P 0 ;1
L 7.7075 2.2575 7.7075 2.2575 9 P 0 ;1
L 7.7075 2.3075 7.7075 2.3075 9 P 0 ;1
L 7.7075 2.3575 7.7075 2.3575 9 P 0 ;1
L 7.7075 2.4075 7.7075 2.4075 9 P 0 ;1
L 7.7075 2.5575 7.7075 2.5575 9 P 0 ;1
L 7.7075 2.6075 7.7075 2.6075 9 P 0 ;1
L 7.7075 2.6575 7.7075 2.6575 9 P 0 ;1
L 7.7075 2.7075 7.7075 2.7075 9 P 0 ;1
L 7.7075 2.7575 7.7075 2.7575 9 P 0 ;1
L 7.7075 2.8075 7.7075 2.8075 9 P 0 ;1
L 7.7075 2.8575 7.7075 2.8575 9 P 0 ;1
L 7.7075 2.9075 7.7075 2.9075 9 P 0 ;1
L 7.7075 2.9575 7.7075 2.9575 9 P 0 ;1
L 7.7075 3.0075 7.7075 3.0075 9 P 0 ;1
L 7.7075 3.0575 7.7075 3.0575 9 P 0 ;1
L 7.7075 3.1075 7.7075 3.1075 9 P 0 ;1
L 7.7075 3.1575 7.7075 3.1575 9 P 0 ;1
L 7.7075 4.1575 7.7075 4.1575 9 P 0 ;1
L 7.7075 5.2075 7.7075 5.2075 9 P 0 ;1
L 7.7075 5.2575 7.7075 5.2575 9 P 0 ;1
L 7.7075 5.3075 7.7075 5.3075 9 P 0 ;1
L 7.7075 5.3575 7.7075 5.3575 9 P 0 ;1
L 7.7075 5.4075 7.7075 5.4075 9 P 0 ;1
L 7.7075 5.4575 7.7075 5.4575 9 P 0 ;1
L 7.7075 5.5075 7.7075 5.5075 9 P 0 ;1
L 7.7075 5.5575 7.7075 5.5575 9 P 0 ;1
L 7.7075 5.6075 7.7075 5.6075 9 P 0 ;1
L 7.7075 5.6575 7.7075 5.6575 9 P 0 ;1
L 7.7075 5.7075 7.7075 5.7075 9 P 0 ;1
L 7.7075 5.7575 7.7075 5.7575 9 P 0 ;1
L 7.7075 5.8075 7.7075 5.8075 9 P 0 ;1
L 7.7075 5.8575 7.7075 5.8575 9 P 0 ;1
L 7.7075 5.9075 7.7075 5.9075 9 P 0 ;1
L 7.7575 0.1575 7.7575 0.1575 9 P 0 ;1
L 7.7575 0.2075 7.7575 0.2075 9 P 0 ;1
L 7.7575 0.2575 7.7575 0.2575 9 P 0 ;1
L 7.7575 0.3075 7.7575 0.3075 9 P 0 ;1
L 7.7575 0.3575 7.7575 0.3575 9 P 0 ;1
L 7.7575 0.4075 7.7575 0.4075 9 P 0 ;1
L 7.7575 0.4575 7.7575 0.4575 9 P 0 ;1
L 7.7575 0.5075 7.7575 0.5075 9 P 0 ;1
L 7.7575 0.5575 7.7575 0.5575 9 P 0 ;1
L 7.7575 0.6075 7.7575 0.6075 9 P 0 ;1
L 7.7575 0.6575 7.7575 0.6575 9 P 0 ;1
L 7.7575 0.7075 7.7575 0.7075 9 P 0 ;1
L 7.7575 0.7575 7.7575 0.7575 9 P 0 ;1
L 7.7575 0.8075 7.7575 0.8075 9 P 0 ;1
L 7.7575 0.8575 7.7575 0.8575 9 P 0 ;1
L 7.7575 0.9075 7.7575 0.9075 9 P 0 ;1
L 7.7575 0.9575 7.7575 0.9575 9 P 0 ;1
L 7.7575 1.0075 7.7575 1.0075 9 P 0 ;1
L 7.7575 1.0575 7.7575 1.0575 9 P 0 ;1
L 7.7575 1.1075 7.7575 1.1075 9 P 0 ;1
L 7.7575 1.1575 7.7575 1.1575 9 P 0 ;1
L 7.7575 1.2075 7.7575 1.2075 9 P 0 ;1
L 7.7575 1.2575 7.7575 1.2575 9 P 0 ;1
L 7.7575 1.3075 7.7575 1.3075 9 P 0 ;1
L 7.7575 1.3575 7.7575 1.3575 9 P 0 ;1
L 7.7575 1.4075 7.7575 1.4075 9 P 0 ;1
L 7.7575 1.4575 7.7575 1.4575 9 P 0 ;1
L 7.7575 1.5075 7.7575 1.5075 9 P 0 ;1
L 7.7575 1.5575 7.7575 1.5575 9 P 0 ;1
L 7.7575 1.6075 7.7575 1.6075 9 P 0 ;1
L 7.7575 1.6575 7.7575 1.6575 9 P 0 ;1
L 7.7575 1.7075 7.7575 1.7075 9 P 0 ;1
L 7.7575 1.7575 7.7575 1.7575 9 P 0 ;1
L 7.7575 1.8075 7.7575 1.8075 9 P 0 ;1
L 7.7575 1.8575 7.7575 1.8575 9 P 0 ;1
L 7.7575 1.9075 7.7575 1.9075 9 P 0 ;1
L 7.7575 1.9575 7.7575 1.9575 9 P 0 ;1
L 7.7575 2.0075 7.7575 2.0075 9 P 0 ;1
L 7.7575 2.0575 7.7575 2.0575 9 P 0 ;1
L 7.7575 2.1075 7.7575 2.1075 9 P 0 ;1
L 7.7575 2.1575 7.7575 2.1575 9 P 0 ;1
L 7.7575 2.2075 7.7575 2.2075 9 P 0 ;1
L 7.7575 2.2575 7.7575 2.2575 9 P 0 ;1
L 7.7575 2.3075 7.7575 2.3075 9 P 0 ;1
L 7.7575 2.3575 7.7575 2.3575 9 P 0 ;1
L 7.7575 2.5575 7.7575 2.5575 9 P 0 ;1
L 7.7575 2.6075 7.7575 2.6075 9 P 0 ;1
L 7.7575 2.6575 7.7575 2.6575 9 P 0 ;1
L 7.7575 2.7075 7.7575 2.7075 9 P 0 ;1
L 7.7575 2.7575 7.7575 2.7575 9 P 0 ;1
L 7.7575 2.8075 7.7575 2.8075 9 P 0 ;1
L 7.7575 2.8575 7.7575 2.8575 9 P 0 ;1
L 7.7575 2.9075 7.7575 2.9075 9 P 0 ;1
L 7.7575 2.9575 7.7575 2.9575 9 P 0 ;1
L 7.7575 3.0075 7.7575 3.0075 9 P 0 ;1
L 7.7575 3.0575 7.7575 3.0575 9 P 0 ;1
L 7.7575 3.1075 7.7575 3.1075 9 P 0 ;1
L 7.7575 4.1575 7.7575 4.1575 9 P 0 ;1
L 7.7575 4.2075 7.7575 4.2075 9 P 0 ;1
L 7.7575 4.3575 7.7575 4.3575 9 P 0 ;1
L 7.7575 5.1575 7.7575 5.1575 9 P 0 ;1
L 7.7575 5.2075 7.7575 5.2075 9 P 0 ;1
L 7.7575 5.2575 7.7575 5.2575 9 P 0 ;1
L 7.7575 5.3075 7.7575 5.3075 9 P 0 ;1
L 7.7575 5.3575 7.7575 5.3575 9 P 0 ;1
L 7.7575 5.4075 7.7575 5.4075 9 P 0 ;1
L 7.7575 5.4575 7.7575 5.4575 9 P 0 ;1
L 7.7575 5.5075 7.7575 5.5075 9 P 0 ;1
L 7.7575 5.5575 7.7575 5.5575 9 P 0 ;1
L 7.7575 5.6075 7.7575 5.6075 9 P 0 ;1
L 7.7575 5.6575 7.7575 5.6575 9 P 0 ;1
L 7.7575 5.7075 7.7575 5.7075 9 P 0 ;1
L 7.7575 5.7575 7.7575 5.7575 9 P 0 ;1
L 7.7575 5.8075 7.7575 5.8075 9 P 0 ;1
L 7.7575 5.8575 7.7575 5.8575 9 P 0 ;1
L 7.7575 5.9075 7.7575 5.9075 9 P 0 ;1
L 7.8075 0.1575 7.8075 0.1575 9 P 0 ;1
L 7.8075 0.2075 7.8075 0.2075 9 P 0 ;1
L 7.8075 0.2575 7.8075 0.2575 9 P 0 ;1
L 7.8075 0.3075 7.8075 0.3075 9 P 0 ;1
L 7.8075 0.3575 7.8075 0.3575 9 P 0 ;1
L 7.8075 0.4075 7.8075 0.4075 9 P 0 ;1
L 7.8075 0.4575 7.8075 0.4575 9 P 0 ;1
L 7.8075 0.5075 7.8075 0.5075 9 P 0 ;1
L 7.8075 0.5575 7.8075 0.5575 9 P 0 ;1
L 7.8075 0.6075 7.8075 0.6075 9 P 0 ;1
L 7.8075 0.6575 7.8075 0.6575 9 P 0 ;1
L 7.8075 0.7075 7.8075 0.7075 9 P 0 ;1
L 7.8075 0.7575 7.8075 0.7575 9 P 0 ;1
L 7.8075 0.8075 7.8075 0.8075 9 P 0 ;1
L 7.8075 0.8575 7.8075 0.8575 9 P 0 ;1
L 7.8075 0.9075 7.8075 0.9075 9 P 0 ;1
L 7.8075 0.9575 7.8075 0.9575 9 P 0 ;1
L 7.8075 1.0075 7.8075 1.0075 9 P 0 ;1
L 7.8075 1.0575 7.8075 1.0575 9 P 0 ;1
L 7.8075 1.1075 7.8075 1.1075 9 P 0 ;1
L 7.8075 1.1575 7.8075 1.1575 9 P 0 ;1
L 7.8075 1.2075 7.8075 1.2075 9 P 0 ;1
L 7.8075 1.2575 7.8075 1.2575 9 P 0 ;1
L 7.8075 1.3075 7.8075 1.3075 9 P 0 ;1
L 7.8075 1.3575 7.8075 1.3575 9 P 0 ;1
L 7.8075 1.4075 7.8075 1.4075 9 P 0 ;1
L 7.8075 1.4575 7.8075 1.4575 9 P 0 ;1
L 7.8075 1.5075 7.8075 1.5075 9 P 0 ;1
L 7.8075 1.5575 7.8075 1.5575 9 P 0 ;1
L 7.8075 1.6075 7.8075 1.6075 9 P 0 ;1
L 7.8075 1.6575 7.8075 1.6575 9 P 0 ;1
L 7.8075 1.7075 7.8075 1.7075 9 P 0 ;1
L 7.8075 1.7575 7.8075 1.7575 9 P 0 ;1
L 7.8075 1.8075 7.8075 1.8075 9 P 0 ;1
L 7.8075 1.8575 7.8075 1.8575 9 P 0 ;1
L 7.8075 1.9075 7.8075 1.9075 9 P 0 ;1
L 7.8075 1.9575 7.8075 1.9575 9 P 0 ;1
L 7.8075 2.0075 7.8075 2.0075 9 P 0 ;1
L 7.8075 2.0575 7.8075 2.0575 9 P 0 ;1
L 7.8075 2.1075 7.8075 2.1075 9 P 0 ;1
L 7.8075 2.1575 7.8075 2.1575 9 P 0 ;1
L 7.8075 2.2075 7.8075 2.2075 9 P 0 ;1
L 7.8075 2.2575 7.8075 2.2575 9 P 0 ;1
L 7.8075 2.3075 7.8075 2.3075 9 P 0 ;1
L 7.8075 2.3575 7.8075 2.3575 9 P 0 ;1
L 7.8075 2.5575 7.8075 2.5575 9 P 0 ;1
L 7.8075 2.6075 7.8075 2.6075 9 P 0 ;1
L 7.8075 2.6575 7.8075 2.6575 9 P 0 ;1
L 7.8075 2.7075 7.8075 2.7075 9 P 0 ;1
L 7.8075 2.7575 7.8075 2.7575 9 P 0 ;1
L 7.8075 2.8075 7.8075 2.8075 9 P 0 ;1
L 7.8075 2.8575 7.8075 2.8575 9 P 0 ;1
L 7.8075 2.9075 7.8075 2.9075 9 P 0 ;1
L 7.8075 2.9575 7.8075 2.9575 9 P 0 ;1
L 7.8075 3.0075 7.8075 3.0075 9 P 0 ;1
L 7.8075 3.0575 7.8075 3.0575 9 P 0 ;1
L 7.8075 3.1075 7.8075 3.1075 9 P 0 ;1
L 7.8075 5.2575 7.8075 5.2575 9 P 0 ;1
L 7.8075 5.3075 7.8075 5.3075 9 P 0 ;1
L 7.8075 5.3575 7.8075 5.3575 9 P 0 ;1
L 7.8075 5.4075 7.8075 5.4075 9 P 0 ;1
L 7.8075 5.4575 7.8075 5.4575 9 P 0 ;1
L 7.8075 5.5075 7.8075 5.5075 9 P 0 ;1
L 7.8075 5.5575 7.8075 5.5575 9 P 0 ;1
L 7.8075 5.6075 7.8075 5.6075 9 P 0 ;1
L 7.8075 5.6575 7.8075 5.6575 9 P 0 ;1
L 7.8075 5.7075 7.8075 5.7075 9 P 0 ;1
L 7.8075 5.7575 7.8075 5.7575 9 P 0 ;1
L 7.8075 5.8075 7.8075 5.8075 9 P 0 ;1
L 7.8075 5.8575 7.8075 5.8575 9 P 0 ;1
L 7.8075 5.9075 7.8075 5.9075 9 P 0 ;1
L 7.8575 0.1575 7.8575 0.1575 9 P 0 ;1
L 7.8575 0.2075 7.8575 0.2075 9 P 0 ;1
L 7.8575 0.2575 7.8575 0.2575 9 P 0 ;1
L 7.8575 0.3075 7.8575 0.3075 9 P 0 ;1
L 7.8575 0.3575 7.8575 0.3575 9 P 0 ;1
L 7.8575 0.4075 7.8575 0.4075 9 P 0 ;1
L 7.8575 0.4575 7.8575 0.4575 9 P 0 ;1
L 7.8575 0.5075 7.8575 0.5075 9 P 0 ;1
L 7.8575 0.5575 7.8575 0.5575 9 P 0 ;1
L 7.8575 0.6075 7.8575 0.6075 9 P 0 ;1
L 7.8575 0.6575 7.8575 0.6575 9 P 0 ;1
L 7.8575 0.7075 7.8575 0.7075 9 P 0 ;1
L 7.8575 0.7575 7.8575 0.7575 9 P 0 ;1
L 7.8575 0.8075 7.8575 0.8075 9 P 0 ;1
L 7.8575 0.8575 7.8575 0.8575 9 P 0 ;1
L 7.8575 0.9075 7.8575 0.9075 9 P 0 ;1
L 7.8575 0.9575 7.8575 0.9575 9 P 0 ;1
L 7.8575 1.0075 7.8575 1.0075 9 P 0 ;1
L 7.8575 1.0575 7.8575 1.0575 9 P 0 ;1
L 7.8575 1.1075 7.8575 1.1075 9 P 0 ;1
L 7.8575 1.1575 7.8575 1.1575 9 P 0 ;1
L 7.8575 1.2075 7.8575 1.2075 9 P 0 ;1
L 7.8575 1.2575 7.8575 1.2575 9 P 0 ;1
L 7.8575 1.3075 7.8575 1.3075 9 P 0 ;1
L 7.8575 1.3575 7.8575 1.3575 9 P 0 ;1
L 7.8575 1.4075 7.8575 1.4075 9 P 0 ;1
L 7.8575 1.4575 7.8575 1.4575 9 P 0 ;1
L 7.8575 1.5075 7.8575 1.5075 9 P 0 ;1
L 7.8575 1.5575 7.8575 1.5575 9 P 0 ;1
L 7.8575 1.6075 7.8575 1.6075 9 P 0 ;1
L 7.8575 1.6575 7.8575 1.6575 9 P 0 ;1
L 7.8575 1.7075 7.8575 1.7075 9 P 0 ;1
L 7.8575 1.7575 7.8575 1.7575 9 P 0 ;1
L 7.8575 1.8075 7.8575 1.8075 9 P 0 ;1
L 7.8575 1.8575 7.8575 1.8575 9 P 0 ;1
L 7.8575 1.9075 7.8575 1.9075 9 P 0 ;1
L 7.8575 1.9575 7.8575 1.9575 9 P 0 ;1
L 7.8575 2.0075 7.8575 2.0075 9 P 0 ;1
L 7.8575 2.0575 7.8575 2.0575 9 P 0 ;1
L 7.8575 2.1075 7.8575 2.1075 9 P 0 ;1
L 7.8575 2.1575 7.8575 2.1575 9 P 0 ;1
L 7.8575 2.2075 7.8575 2.2075 9 P 0 ;1
L 7.8575 2.2575 7.8575 2.2575 9 P 0 ;1
L 7.8575 2.3075 7.8575 2.3075 9 P 0 ;1
L 7.8575 2.3575 7.8575 2.3575 9 P 0 ;1
L 7.8575 2.4075 7.8575 2.4075 9 P 0 ;1
L 7.8575 2.4575 7.8575 2.4575 9 P 0 ;1
L 7.8575 2.5075 7.8575 2.5075 9 P 0 ;1
L 7.8575 2.5575 7.8575 2.5575 9 P 0 ;1
L 7.8575 2.6075 7.8575 2.6075 9 P 0 ;1
L 7.8575 2.6575 7.8575 2.6575 9 P 0 ;1
L 7.8575 2.7075 7.8575 2.7075 9 P 0 ;1
L 7.8575 2.7575 7.8575 2.7575 9 P 0 ;1
L 7.8575 2.8075 7.8575 2.8075 9 P 0 ;1
L 7.8575 2.8575 7.8575 2.8575 9 P 0 ;1
L 7.8575 2.9075 7.8575 2.9075 9 P 0 ;1
L 7.8575 2.9575 7.8575 2.9575 9 P 0 ;1
L 7.8575 3.0075 7.8575 3.0075 9 P 0 ;1
L 7.8575 3.0575 7.8575 3.0575 9 P 0 ;1
L 7.8575 3.1075 7.8575 3.1075 9 P 0 ;1
L 7.8575 3.7075 7.8575 3.7075 9 P 0 ;1
L 7.8575 3.8575 7.8575 3.8575 9 P 0 ;1
L 7.8575 3.9075 7.8575 3.9075 9 P 0 ;1
L 7.8575 4.1075 7.8575 4.1075 9 P 0 ;1
L 7.8575 5.2575 7.8575 5.2575 9 P 0 ;1
L 7.8575 5.3075 7.8575 5.3075 9 P 0 ;1
L 7.8575 5.4575 7.8575 5.4575 9 P 0 ;1
L 7.8575 5.5075 7.8575 5.5075 9 P 0 ;1
L 7.8575 5.5575 7.8575 5.5575 9 P 0 ;1
L 7.8575 5.6075 7.8575 5.6075 9 P 0 ;1
L 7.8575 5.6575 7.8575 5.6575 9 P 0 ;1
L 7.8575 5.7075 7.8575 5.7075 9 P 0 ;1
L 7.8575 5.7575 7.8575 5.7575 9 P 0 ;1
L 7.8575 5.8075 7.8575 5.8075 9 P 0 ;1
L 7.8575 5.8575 7.8575 5.8575 9 P 0 ;1
L 7.8575 5.9075 7.8575 5.9075 9 P 0 ;1
L 7.9075 0.1575 7.9075 0.1575 9 P 0 ;1
L 7.9075 0.2075 7.9075 0.2075 9 P 0 ;1
L 7.9075 0.2575 7.9075 0.2575 9 P 0 ;1
L 7.9075 0.3075 7.9075 0.3075 9 P 0 ;1
L 7.9075 0.3575 7.9075 0.3575 9 P 0 ;1
L 7.9075 0.4075 7.9075 0.4075 9 P 0 ;1
L 7.9075 0.4575 7.9075 0.4575 9 P 0 ;1
L 7.9075 0.5075 7.9075 0.5075 9 P 0 ;1
L 7.9075 0.5575 7.9075 0.5575 9 P 0 ;1
L 7.9075 0.6075 7.9075 0.6075 9 P 0 ;1
L 7.9075 0.6575 7.9075 0.6575 9 P 0 ;1
L 7.9075 0.7075 7.9075 0.7075 9 P 0 ;1
L 7.9075 0.7575 7.9075 0.7575 9 P 0 ;1
L 7.9075 0.8075 7.9075 0.8075 9 P 0 ;1
L 7.9075 0.8575 7.9075 0.8575 9 P 0 ;1
L 7.9075 0.9075 7.9075 0.9075 9 P 0 ;1
L 7.9075 0.9575 7.9075 0.9575 9 P 0 ;1
L 7.9075 1.0075 7.9075 1.0075 9 P 0 ;1
L 7.9075 1.0575 7.9075 1.0575 9 P 0 ;1
L 7.9075 1.1075 7.9075 1.1075 9 P 0 ;1
L 7.9075 1.1575 7.9075 1.1575 9 P 0 ;1
L 7.9075 1.2075 7.9075 1.2075 9 P 0 ;1
L 7.9075 1.2575 7.9075 1.2575 9 P 0 ;1
L 7.9075 1.3075 7.9075 1.3075 9 P 0 ;1
L 7.9075 1.3575 7.9075 1.3575 9 P 0 ;1
L 7.9075 1.4075 7.9075 1.4075 9 P 0 ;1
L 7.9075 1.4575 7.9075 1.4575 9 P 0 ;1
L 7.9075 1.5075 7.9075 1.5075 9 P 0 ;1
L 7.9075 1.5575 7.9075 1.5575 9 P 0 ;1
L 7.9075 1.6075 7.9075 1.6075 9 P 0 ;1
L 7.9075 1.6575 7.9075 1.6575 9 P 0 ;1
L 7.9075 1.7075 7.9075 1.7075 9 P 0 ;1
L 7.9075 1.7575 7.9075 1.7575 9 P 0 ;1
L 7.9075 1.8075 7.9075 1.8075 9 P 0 ;1
L 7.9075 1.8575 7.9075 1.8575 9 P 0 ;1
L 7.9075 1.9075 7.9075 1.9075 9 P 0 ;1
L 7.9075 1.9575 7.9075 1.9575 9 P 0 ;1
L 7.9075 2.0075 7.9075 2.0075 9 P 0 ;1
L 7.9075 2.0575 7.9075 2.0575 9 P 0 ;1
L 7.9075 2.1075 7.9075 2.1075 9 P 0 ;1
L 7.9075 2.1575 7.9075 2.1575 9 P 0 ;1
L 7.9075 2.2075 7.9075 2.2075 9 P 0 ;1
L 7.9075 2.2575 7.9075 2.2575 9 P 0 ;1
L 7.9075 2.3075 7.9075 2.3075 9 P 0 ;1
L 7.9075 2.3575 7.9075 2.3575 9 P 0 ;1
L 7.9075 2.4075 7.9075 2.4075 9 P 0 ;1
L 7.9075 2.4575 7.9075 2.4575 9 P 0 ;1
L 7.9075 2.5075 7.9075 2.5075 9 P 0 ;1
L 7.9075 2.5575 7.9075 2.5575 9 P 0 ;1
L 7.9075 2.6075 7.9075 2.6075 9 P 0 ;1
L 7.9075 2.6575 7.9075 2.6575 9 P 0 ;1
L 7.9075 2.7075 7.9075 2.7075 9 P 0 ;1
L 7.9075 2.7575 7.9075 2.7575 9 P 0 ;1
L 7.9075 2.8075 7.9075 2.8075 9 P 0 ;1
L 7.9075 2.8575 7.9075 2.8575 9 P 0 ;1
L 7.9075 2.9075 7.9075 2.9075 9 P 0 ;1
L 7.9075 2.9575 7.9075 2.9575 9 P 0 ;1
L 7.9075 3.0075 7.9075 3.0075 9 P 0 ;1
L 7.9075 3.0575 7.9075 3.0575 9 P 0 ;1
L 7.9075 3.1075 7.9075 3.1075 9 P 0 ;1
L 7.9075 3.6575 7.9075 3.6575 9 P 0 ;1
L 7.9075 3.7075 7.9075 3.7075 9 P 0 ;1
L 7.9075 3.7575 7.9075 3.7575 9 P 0 ;1
L 7.9075 3.8075 7.9075 3.8075 9 P 0 ;1
L 7.9075 3.8575 7.9075 3.8575 9 P 0 ;1
L 7.9075 3.9075 7.9075 3.9075 9 P 0 ;1
L 7.9075 3.9575 7.9075 3.9575 9 P 0 ;1
L 7.9075 4.0075 7.9075 4.0075 9 P 0 ;1
L 7.9075 5.2575 7.9075 5.2575 9 P 0 ;1
L 7.9075 5.4575 7.9075 5.4575 9 P 0 ;1
L 7.9075 5.5075 7.9075 5.5075 9 P 0 ;1
L 7.9075 5.5575 7.9075 5.5575 9 P 0 ;1
L 7.9075 5.6075 7.9075 5.6075 9 P 0 ;1
L 7.9075 5.6575 7.9075 5.6575 9 P 0 ;1
L 7.9075 5.7075 7.9075 5.7075 9 P 0 ;1
L 7.9075 5.7575 7.9075 5.7575 9 P 0 ;1
L 7.9075 5.8075 7.9075 5.8075 9 P 0 ;1
L 7.9075 5.8575 7.9075 5.8575 9 P 0 ;1
L 7.9075 5.9075 7.9075 5.9075 9 P 0 ;1
L 7.9575 0.1575 7.9575 0.1575 9 P 0 ;1
L 7.9575 0.2075 7.9575 0.2075 9 P 0 ;1
L 7.9575 0.2575 7.9575 0.2575 9 P 0 ;1
L 7.9575 0.3075 7.9575 0.3075 9 P 0 ;1
L 7.9575 0.3575 7.9575 0.3575 9 P 0 ;1
L 7.9575 0.4075 7.9575 0.4075 9 P 0 ;1
L 7.9575 0.4575 7.9575 0.4575 9 P 0 ;1
L 7.9575 0.5075 7.9575 0.5075 9 P 0 ;1
L 7.9575 0.5575 7.9575 0.5575 9 P 0 ;1
L 7.9575 0.6075 7.9575 0.6075 9 P 0 ;1
L 7.9575 0.6575 7.9575 0.6575 9 P 0 ;1
L 7.9575 0.7075 7.9575 0.7075 9 P 0 ;1
L 7.9575 0.7575 7.9575 0.7575 9 P 0 ;1
L 7.9575 0.8075 7.9575 0.8075 9 P 0 ;1
L 7.9575 0.8575 7.9575 0.8575 9 P 0 ;1
L 7.9575 0.9075 7.9575 0.9075 9 P 0 ;1
L 7.9575 0.9575 7.9575 0.9575 9 P 0 ;1
L 7.9575 1.0075 7.9575 1.0075 9 P 0 ;1
L 7.9575 1.0575 7.9575 1.0575 9 P 0 ;1
L 7.9575 1.1075 7.9575 1.1075 9 P 0 ;1
L 7.9575 1.1575 7.9575 1.1575 9 P 0 ;1
L 7.9575 1.2075 7.9575 1.2075 9 P 0 ;1
L 7.9575 1.2575 7.9575 1.2575 9 P 0 ;1
L 7.9575 1.3075 7.9575 1.3075 9 P 0 ;1
L 7.9575 1.3575 7.9575 1.3575 9 P 0 ;1
L 7.9575 1.4075 7.9575 1.4075 9 P 0 ;1
L 7.9575 1.4575 7.9575 1.4575 9 P 0 ;1
L 7.9575 1.5075 7.9575 1.5075 9 P 0 ;1
L 7.9575 1.5575 7.9575 1.5575 9 P 0 ;1
L 7.9575 1.6075 7.9575 1.6075 9 P 0 ;1
L 7.9575 1.6575 7.9575 1.6575 9 P 0 ;1
L 7.9575 1.7075 7.9575 1.7075 9 P 0 ;1
L 7.9575 1.7575 7.9575 1.7575 9 P 0 ;1
L 7.9575 1.8075 7.9575 1.8075 9 P 0 ;1
L 7.9575 1.8575 7.9575 1.8575 9 P 0 ;1
L 7.9575 1.9075 7.9575 1.9075 9 P 0 ;1
L 7.9575 1.9575 7.9575 1.9575 9 P 0 ;1
L 7.9575 2.0075 7.9575 2.0075 9 P 0 ;1
L 7.9575 2.0575 7.9575 2.0575 9 P 0 ;1
L 7.9575 2.1075 7.9575 2.1075 9 P 0 ;1
L 7.9575 2.1575 7.9575 2.1575 9 P 0 ;1
L 7.9575 2.2075 7.9575 2.2075 9 P 0 ;1
L 7.9575 2.2575 7.9575 2.2575 9 P 0 ;1
L 7.9575 2.3075 7.9575 2.3075 9 P 0 ;1
L 7.9575 2.3575 7.9575 2.3575 9 P 0 ;1
L 7.9575 2.4075 7.9575 2.4075 9 P 0 ;1
L 7.9575 2.4575 7.9575 2.4575 9 P 0 ;1
L 7.9575 2.5075 7.9575 2.5075 9 P 0 ;1
L 7.9575 2.5575 7.9575 2.5575 9 P 0 ;1
L 7.9575 2.6075 7.9575 2.6075 9 P 0 ;1
L 7.9575 2.9575 7.9575 2.9575 9 P 0 ;1
L 7.9575 3.0075 7.9575 3.0075 9 P 0 ;1
L 7.9575 3.0575 7.9575 3.0575 9 P 0 ;1
L 7.9575 3.1075 7.9575 3.1075 9 P 0 ;1
L 7.9575 3.6575 7.9575 3.6575 9 P 0 ;1
L 7.9575 3.7075 7.9575 3.7075 9 P 0 ;1
L 7.9575 3.7575 7.9575 3.7575 9 P 0 ;1
L 7.9575 3.8075 7.9575 3.8075 9 P 0 ;1
L 7.9575 3.8575 7.9575 3.8575 9 P 0 ;1
L 7.9575 3.9075 7.9575 3.9075 9 P 0 ;1
L 7.9575 3.9575 7.9575 3.9575 9 P 0 ;1
L 7.9575 5.4575 7.9575 5.4575 9 P 0 ;1
L 7.9575 5.5075 7.9575 5.5075 9 P 0 ;1
L 7.9575 5.5575 7.9575 5.5575 9 P 0 ;1
L 7.9575 5.6075 7.9575 5.6075 9 P 0 ;1
L 7.9575 5.6575 7.9575 5.6575 9 P 0 ;1
L 7.9575 5.7075 7.9575 5.7075 9 P 0 ;1
L 7.9575 5.7575 7.9575 5.7575 9 P 0 ;1
L 7.9575 5.8075 7.9575 5.8075 9 P 0 ;1
L 7.9575 5.8575 7.9575 5.8575 9 P 0 ;1
L 7.9575 5.9075 7.9575 5.9075 9 P 0 ;1
L 8.0075 0.1575 8.0075 0.1575 9 P 0 ;1
L 8.0075 0.2075 8.0075 0.2075 9 P 0 ;1
L 8.0075 0.2575 8.0075 0.2575 9 P 0 ;1
L 8.0075 0.3075 8.0075 0.3075 9 P 0 ;1
L 8.0075 0.3575 8.0075 0.3575 9 P 0 ;1
L 8.0075 0.4075 8.0075 0.4075 9 P 0 ;1
L 8.0075 0.4575 8.0075 0.4575 9 P 0 ;1
L 8.0075 0.5075 8.0075 0.5075 9 P 0 ;1
L 8.0075 0.5575 8.0075 0.5575 9 P 0 ;1
L 8.0075 0.6075 8.0075 0.6075 9 P 0 ;1
L 8.0075 0.6575 8.0075 0.6575 9 P 0 ;1
L 8.0075 0.7075 8.0075 0.7075 9 P 0 ;1
L 8.0075 0.7575 8.0075 0.7575 9 P 0 ;1
L 8.0075 0.8075 8.0075 0.8075 9 P 0 ;1
L 8.0075 0.8575 8.0075 0.8575 9 P 0 ;1
L 8.0075 0.9075 8.0075 0.9075 9 P 0 ;1
L 8.0075 0.9575 8.0075 0.9575 9 P 0 ;1
L 8.0075 1.0075 8.0075 1.0075 9 P 0 ;1
L 8.0075 1.0575 8.0075 1.0575 9 P 0 ;1
L 8.0075 1.1075 8.0075 1.1075 9 P 0 ;1
L 8.0075 1.1575 8.0075 1.1575 9 P 0 ;1
L 8.0075 1.2075 8.0075 1.2075 9 P 0 ;1
L 8.0075 1.2575 8.0075 1.2575 9 P 0 ;1
L 8.0075 1.3075 8.0075 1.3075 9 P 0 ;1
L 8.0075 1.3575 8.0075 1.3575 9 P 0 ;1
L 8.0075 1.4075 8.0075 1.4075 9 P 0 ;1
L 8.0075 1.4575 8.0075 1.4575 9 P 0 ;1
L 8.0075 1.5075 8.0075 1.5075 9 P 0 ;1
L 8.0075 1.5575 8.0075 1.5575 9 P 0 ;1
L 8.0075 1.6075 8.0075 1.6075 9 P 0 ;1
L 8.0075 1.6575 8.0075 1.6575 9 P 0 ;1
L 8.0075 1.7075 8.0075 1.7075 9 P 0 ;1
L 8.0075 1.7575 8.0075 1.7575 9 P 0 ;1
L 8.0075 5.4075 8.0075 5.4075 9 P 0 ;1
L 8.0075 5.4575 8.0075 5.4575 9 P 0 ;1
L 8.0075 5.5075 8.0075 5.5075 9 P 0 ;1
L 8.0075 5.5575 8.0075 5.5575 9 P 0 ;1
L 8.0075 5.6075 8.0075 5.6075 9 P 0 ;1
L 8.0075 5.6575 8.0075 5.6575 9 P 0 ;1
L 8.0075 5.7075 8.0075 5.7075 9 P 0 ;1
L 8.0075 5.7575 8.0075 5.7575 9 P 0 ;1
L 8.0075 5.8075 8.0075 5.8075 9 P 0 ;1
L 8.0075 5.8575 8.0075 5.8575 9 P 0 ;1
L 8.0075 5.9075 8.0075 5.9075 9 P 0 ;1
L 8.0575 0.1575 8.0575 0.1575 9 P 0 ;1
L 8.0575 0.2075 8.0575 0.2075 9 P 0 ;1
L 8.0575 0.2575 8.0575 0.2575 9 P 0 ;1
L 8.0575 0.3075 8.0575 0.3075 9 P 0 ;1
L 8.0575 0.3575 8.0575 0.3575 9 P 0 ;1
L 8.0575 0.4075 8.0575 0.4075 9 P 0 ;1
L 8.0575 0.4575 8.0575 0.4575 9 P 0 ;1
L 8.0575 0.5075 8.0575 0.5075 9 P 0 ;1
L 8.0575 0.5575 8.0575 0.5575 9 P 0 ;1
L 8.0575 0.6075 8.0575 0.6075 9 P 0 ;1
L 8.0575 0.6575 8.0575 0.6575 9 P 0 ;1
L 8.0575 0.7075 8.0575 0.7075 9 P 0 ;1
L 8.0575 0.7575 8.0575 0.7575 9 P 0 ;1
L 8.0575 0.8075 8.0575 0.8075 9 P 0 ;1
L 8.0575 0.8575 8.0575 0.8575 9 P 0 ;1
L 8.0575 0.9075 8.0575 0.9075 9 P 0 ;1
L 8.0575 0.9575 8.0575 0.9575 9 P 0 ;1
L 8.0575 1.0075 8.0575 1.0075 9 P 0 ;1
L 8.0575 1.0575 8.0575 1.0575 9 P 0 ;1
L 8.0575 1.1075 8.0575 1.1075 9 P 0 ;1
L 8.0575 1.1575 8.0575 1.1575 9 P 0 ;1
L 8.0575 1.2075 8.0575 1.2075 9 P 0 ;1
L 8.0575 1.2575 8.0575 1.2575 9 P 0 ;1
L 8.0575 1.3075 8.0575 1.3075 9 P 0 ;1
L 8.0575 1.3575 8.0575 1.3575 9 P 0 ;1
L 8.0575 1.4075 8.0575 1.4075 9 P 0 ;1
L 8.0575 1.6075 8.0575 1.6075 9 P 0 ;1
L 8.0575 1.6575 8.0575 1.6575 9 P 0 ;1
L 8.0575 1.7075 8.0575 1.7075 9 P 0 ;1
L 8.0575 1.7575 8.0575 1.7575 9 P 0 ;1
L 8.0575 5.4075 8.0575 5.4075 9 P 0 ;1
L 8.0575 5.4575 8.0575 5.4575 9 P 0 ;1
L 8.0575 5.5075 8.0575 5.5075 9 P 0 ;1
L 8.0575 5.5575 8.0575 5.5575 9 P 0 ;1
L 8.0575 5.6075 8.0575 5.6075 9 P 0 ;1
L 8.0575 5.6575 8.0575 5.6575 9 P 0 ;1
L 8.0575 5.7075 8.0575 5.7075 9 P 0 ;1
L 8.0575 5.7575 8.0575 5.7575 9 P 0 ;1
L 8.0575 5.8075 8.0575 5.8075 9 P 0 ;1
L 8.0575 5.8575 8.0575 5.8575 9 P 0 ;1
L 8.0575 5.9075 8.0575 5.9075 9 P 0 ;1
L 8.1075 0.1575 8.1075 0.1575 9 P 0 ;1
L 8.1075 0.2075 8.1075 0.2075 9 P 0 ;1
L 8.1075 0.2575 8.1075 0.2575 9 P 0 ;1
L 8.1075 0.3075 8.1075 0.3075 9 P 0 ;1
L 8.1075 0.3575 8.1075 0.3575 9 P 0 ;1
L 8.1075 0.4075 8.1075 0.4075 9 P 0 ;1
L 8.1075 0.4575 8.1075 0.4575 9 P 0 ;1
L 8.1075 0.5075 8.1075 0.5075 9 P 0 ;1
L 8.1075 0.5575 8.1075 0.5575 9 P 0 ;1
L 8.1075 0.6075 8.1075 0.6075 9 P 0 ;1
L 8.1075 0.6575 8.1075 0.6575 9 P 0 ;1
L 8.1075 0.7075 8.1075 0.7075 9 P 0 ;1
L 8.1075 0.7575 8.1075 0.7575 9 P 0 ;1
L 8.1075 0.8075 8.1075 0.8075 9 P 0 ;1
L 8.1075 0.8575 8.1075 0.8575 9 P 0 ;1
L 8.1075 0.9075 8.1075 0.9075 9 P 0 ;1
L 8.1075 0.9575 8.1075 0.9575 9 P 0 ;1
L 8.1075 1.0075 8.1075 1.0075 9 P 0 ;1
L 8.1075 1.0575 8.1075 1.0575 9 P 0 ;1
L 8.1075 1.1075 8.1075 1.1075 9 P 0 ;1
L 8.1075 1.1575 8.1075 1.1575 9 P 0 ;1
L 8.1075 1.2075 8.1075 1.2075 9 P 0 ;1
L 8.1075 1.2575 8.1075 1.2575 9 P 0 ;1
L 8.1075 1.3075 8.1075 1.3075 9 P 0 ;1
L 8.1075 1.7075 8.1075 1.7075 9 P 0 ;1
L 8.1075 1.7575 8.1075 1.7575 9 P 0 ;1
L 8.1075 5.4575 8.1075 5.4575 9 P 0 ;1
L 8.1075 5.5075 8.1075 5.5075 9 P 0 ;1
L 8.1075 5.5575 8.1075 5.5575 9 P 0 ;1
L 8.1075 5.6075 8.1075 5.6075 9 P 0 ;1
L 8.1075 5.6575 8.1075 5.6575 9 P 0 ;1
L 8.1075 5.7075 8.1075 5.7075 9 P 0 ;1
L 8.1075 5.7575 8.1075 5.7575 9 P 0 ;1
L 8.1075 5.8075 8.1075 5.8075 9 P 0 ;1
L 8.1075 5.8575 8.1075 5.8575 9 P 0 ;1
L 8.1075 5.9075 8.1075 5.9075 9 P 0 ;1
L 8.1575 0.1575 8.1575 0.1575 9 P 0 ;1
L 8.1575 0.2075 8.1575 0.2075 9 P 0 ;1
L 8.1575 0.2575 8.1575 0.2575 9 P 0 ;1
L 8.1575 0.3075 8.1575 0.3075 9 P 0 ;1
L 8.1575 0.3575 8.1575 0.3575 9 P 0 ;1
L 8.1575 0.4075 8.1575 0.4075 9 P 0 ;1
L 8.1575 0.4575 8.1575 0.4575 9 P 0 ;1
L 8.1575 0.5075 8.1575 0.5075 9 P 0 ;1
L 8.1575 0.5575 8.1575 0.5575 9 P 0 ;1
L 8.1575 0.6075 8.1575 0.6075 9 P 0 ;1
L 8.1575 0.6575 8.1575 0.6575 9 P 0 ;1
L 8.1575 0.7075 8.1575 0.7075 9 P 0 ;1
L 8.1575 0.7575 8.1575 0.7575 9 P 0 ;1
L 8.1575 0.8075 8.1575 0.8075 9 P 0 ;1
L 8.1575 0.8575 8.1575 0.8575 9 P 0 ;1
L 8.1575 0.9075 8.1575 0.9075 9 P 0 ;1
L 8.1575 0.9575 8.1575 0.9575 9 P 0 ;1
L 8.1575 1.0075 8.1575 1.0075 9 P 0 ;1
L 8.1575 1.0575 8.1575 1.0575 9 P 0 ;1
L 8.1575 1.1075 8.1575 1.1075 9 P 0 ;1
L 8.1575 1.1575 8.1575 1.1575 9 P 0 ;1
L 8.1575 1.2075 8.1575 1.2075 9 P 0 ;1
L 8.1575 1.2575 8.1575 1.2575 9 P 0 ;1
L 8.1575 1.3075 8.1575 1.3075 9 P 0 ;1
L 8.1575 1.7075 8.1575 1.7075 9 P 0 ;1
L 8.1575 1.7575 8.1575 1.7575 9 P 0 ;1
L 8.1575 5.2575 8.1575 5.2575 9 P 0 ;1
L 8.1575 5.4575 8.1575 5.4575 9 P 0 ;1
L 8.1575 5.5075 8.1575 5.5075 9 P 0 ;1
L 8.1575 5.5575 8.1575 5.5575 9 P 0 ;1
L 8.1575 5.6075 8.1575 5.6075 9 P 0 ;1
L 8.1575 5.6575 8.1575 5.6575 9 P 0 ;1
L 8.1575 5.7075 8.1575 5.7075 9 P 0 ;1
L 8.1575 5.7575 8.1575 5.7575 9 P 0 ;1
L 8.1575 5.8075 8.1575 5.8075 9 P 0 ;1
L 8.1575 5.8575 8.1575 5.8575 9 P 0 ;1
L 8.1575 5.9075 8.1575 5.9075 9 P 0 ;1
L 8.2075 0.1575 8.2075 0.1575 9 P 0 ;1
L 8.2075 0.2075 8.2075 0.2075 9 P 0 ;1
L 8.2075 0.2575 8.2075 0.2575 9 P 0 ;1
L 8.2075 0.3075 8.2075 0.3075 9 P 0 ;1
L 8.2075 0.3575 8.2075 0.3575 9 P 0 ;1
L 8.2075 0.4075 8.2075 0.4075 9 P 0 ;1
L 8.2075 0.4575 8.2075 0.4575 9 P 0 ;1
L 8.2075 0.5075 8.2075 0.5075 9 P 0 ;1
L 8.2075 0.5575 8.2075 0.5575 9 P 0 ;1
L 8.2075 0.6075 8.2075 0.6075 9 P 0 ;1
L 8.2075 0.6575 8.2075 0.6575 9 P 0 ;1
L 8.2075 0.7075 8.2075 0.7075 9 P 0 ;1
L 8.2075 0.7575 8.2075 0.7575 9 P 0 ;1
L 8.2075 0.8075 8.2075 0.8075 9 P 0 ;1
L 8.2075 0.8575 8.2075 0.8575 9 P 0 ;1
L 8.2075 0.9075 8.2075 0.9075 9 P 0 ;1
L 8.2075 0.9575 8.2075 0.9575 9 P 0 ;1
L 8.2075 1.0075 8.2075 1.0075 9 P 0 ;1
L 8.2075 1.0575 8.2075 1.0575 9 P 0 ;1
L 8.2075 1.1075 8.2075 1.1075 9 P 0 ;1
L 8.2075 1.1575 8.2075 1.1575 9 P 0 ;1
L 8.2075 1.2075 8.2075 1.2075 9 P 0 ;1
L 8.2075 1.2575 8.2075 1.2575 9 P 0 ;1
L 8.2075 1.3075 8.2075 1.3075 9 P 0 ;1
L 8.2075 1.7075 8.2075 1.7075 9 P 0 ;1
L 8.2075 1.7575 8.2075 1.7575 9 P 0 ;1
L 8.2075 5.2075 8.2075 5.2075 9 P 0 ;1
L 8.2075 5.2575 8.2075 5.2575 9 P 0 ;1
L 8.2075 5.3075 8.2075 5.3075 9 P 0 ;1
L 8.2075 5.4575 8.2075 5.4575 9 P 0 ;1
L 8.2075 5.5075 8.2075 5.5075 9 P 0 ;1
L 8.2075 5.5575 8.2075 5.5575 9 P 0 ;1
L 8.2075 5.6075 8.2075 5.6075 9 P 0 ;1
L 8.2075 5.6575 8.2075 5.6575 9 P 0 ;1
L 8.2075 5.7075 8.2075 5.7075 9 P 0 ;1
L 8.2075 5.7575 8.2075 5.7575 9 P 0 ;1
L 8.2075 5.8075 8.2075 5.8075 9 P 0 ;1
L 8.2075 5.8575 8.2075 5.8575 9 P 0 ;1
L 8.2075 5.9075 8.2075 5.9075 9 P 0 ;1
L 8.2575 0.1575 8.2575 0.1575 9 P 0 ;1
L 8.2575 0.2075 8.2575 0.2075 9 P 0 ;1
L 8.2575 0.2575 8.2575 0.2575 9 P 0 ;1
L 8.2575 0.3075 8.2575 0.3075 9 P 0 ;1
L 8.2575 0.3575 8.2575 0.3575 9 P 0 ;1
L 8.2575 0.4075 8.2575 0.4075 9 P 0 ;1
L 8.2575 0.4575 8.2575 0.4575 9 P 0 ;1
L 8.2575 0.5075 8.2575 0.5075 9 P 0 ;1
L 8.2575 0.5575 8.2575 0.5575 9 P 0 ;1
L 8.2575 0.6075 8.2575 0.6075 9 P 0 ;1
L 8.2575 0.6575 8.2575 0.6575 9 P 0 ;1
L 8.2575 0.7075 8.2575 0.7075 9 P 0 ;1
L 8.2575 0.7575 8.2575 0.7575 9 P 0 ;1
L 8.2575 0.8075 8.2575 0.8075 9 P 0 ;1
L 8.2575 0.8575 8.2575 0.8575 9 P 0 ;1
L 8.2575 0.9075 8.2575 0.9075 9 P 0 ;1
L 8.2575 0.9575 8.2575 0.9575 9 P 0 ;1
L 8.2575 1.0075 8.2575 1.0075 9 P 0 ;1
L 8.2575 1.0575 8.2575 1.0575 9 P 0 ;1
L 8.2575 1.1075 8.2575 1.1075 9 P 0 ;1
L 8.2575 1.1575 8.2575 1.1575 9 P 0 ;1
L 8.2575 1.2075 8.2575 1.2075 9 P 0 ;1
L 8.2575 1.2575 8.2575 1.2575 9 P 0 ;1
L 8.2575 1.7575 8.2575 1.7575 9 P 0 ;1
L 8.2575 5.1575 8.2575 5.1575 9 P 0 ;1
L 8.2575 5.2075 8.2575 5.2075 9 P 0 ;1
L 8.2575 5.2575 8.2575 5.2575 9 P 0 ;1
L 8.2575 5.3075 8.2575 5.3075 9 P 0 ;1
L 8.2575 5.3575 8.2575 5.3575 9 P 0 ;1
L 8.2575 5.4075 8.2575 5.4075 9 P 0 ;1
L 8.2575 5.4575 8.2575 5.4575 9 P 0 ;1
L 8.2575 5.5075 8.2575 5.5075 9 P 0 ;1
L 8.2575 5.5575 8.2575 5.5575 9 P 0 ;1
L 8.2575 5.6075 8.2575 5.6075 9 P 0 ;1
L 8.2575 5.6575 8.2575 5.6575 9 P 0 ;1
L 8.2575 5.7075 8.2575 5.7075 9 P 0 ;1
L 8.2575 5.7575 8.2575 5.7575 9 P 0 ;1
L 8.2575 5.8075 8.2575 5.8075 9 P 0 ;1
L 8.2575 5.8575 8.2575 5.8575 9 P 0 ;1
L 8.2575 5.9075 8.2575 5.9075 9 P 0 ;1
L 8.3075 0.1575 8.3075 0.1575 9 P 0 ;1
L 8.3075 0.2075 8.3075 0.2075 9 P 0 ;1
L 8.3075 0.2575 8.3075 0.2575 9 P 0 ;1
L 8.3075 0.3075 8.3075 0.3075 9 P 0 ;1
L 8.3075 0.3575 8.3075 0.3575 9 P 0 ;1
L 8.3075 0.4075 8.3075 0.4075 9 P 0 ;1
L 8.3075 0.4575 8.3075 0.4575 9 P 0 ;1
L 8.3075 0.5075 8.3075 0.5075 9 P 0 ;1
L 8.3075 0.5575 8.3075 0.5575 9 P 0 ;1
L 8.3075 0.6075 8.3075 0.6075 9 P 0 ;1
L 8.3075 0.6575 8.3075 0.6575 9 P 0 ;1
L 8.3075 0.7075 8.3075 0.7075 9 P 0 ;1
L 8.3075 0.7575 8.3075 0.7575 9 P 0 ;1
L 8.3075 0.8075 8.3075 0.8075 9 P 0 ;1
L 8.3075 0.8575 8.3075 0.8575 9 P 0 ;1
L 8.3075 0.9075 8.3075 0.9075 9 P 0 ;1
L 8.3075 0.9575 8.3075 0.9575 9 P 0 ;1
L 8.3075 1.0075 8.3075 1.0075 9 P 0 ;1
L 8.3075 1.0575 8.3075 1.0575 9 P 0 ;1
L 8.3075 1.1075 8.3075 1.1075 9 P 0 ;1
L 8.3075 1.1575 8.3075 1.1575 9 P 0 ;1
L 8.3075 1.2075 8.3075 1.2075 9 P 0 ;1
L 8.3075 1.2575 8.3075 1.2575 9 P 0 ;1
L 8.3075 1.3075 8.3075 1.3075 9 P 0 ;1
L 8.3075 1.7075 8.3075 1.7075 9 P 0 ;1
L 8.3075 1.7575 8.3075 1.7575 9 P 0 ;1
L 8.3075 5.2575 8.3075 5.2575 9 P 0 ;1
L 8.3075 5.3075 8.3075 5.3075 9 P 0 ;1
L 8.3075 5.3575 8.3075 5.3575 9 P 0 ;1
L 8.3075 5.4075 8.3075 5.4075 9 P 0 ;1
L 8.3075 5.4575 8.3075 5.4575 9 P 0 ;1
L 8.3075 5.5075 8.3075 5.5075 9 P 0 ;1
L 8.3075 5.5575 8.3075 5.5575 9 P 0 ;1
L 8.3075 5.6075 8.3075 5.6075 9 P 0 ;1
L 8.3075 5.6575 8.3075 5.6575 9 P 0 ;1
L 8.3075 5.7075 8.3075 5.7075 9 P 0 ;1
L 8.3075 5.7575 8.3075 5.7575 9 P 0 ;1
L 8.3075 5.8075 8.3075 5.8075 9 P 0 ;1
L 8.3075 5.8575 8.3075 5.8575 9 P 0 ;1
L 8.3075 5.9075 8.3075 5.9075 9 P 0 ;1
L 8.3575 0.1575 8.3575 0.1575 9 P 0 ;1
L 8.3575 0.2075 8.3575 0.2075 9 P 0 ;1
L 8.3575 0.2575 8.3575 0.2575 9 P 0 ;1
L 8.3575 0.3075 8.3575 0.3075 9 P 0 ;1
L 8.3575 0.3575 8.3575 0.3575 9 P 0 ;1
L 8.3575 0.4075 8.3575 0.4075 9 P 0 ;1
L 8.3575 0.4575 8.3575 0.4575 9 P 0 ;1
L 8.3575 0.5075 8.3575 0.5075 9 P 0 ;1
L 8.3575 0.5575 8.3575 0.5575 9 P 0 ;1
L 8.3575 0.6075 8.3575 0.6075 9 P 0 ;1
L 8.3575 0.6575 8.3575 0.6575 9 P 0 ;1
L 8.3575 0.7075 8.3575 0.7075 9 P 0 ;1
L 8.3575 0.7575 8.3575 0.7575 9 P 0 ;1
L 8.3575 0.8075 8.3575 0.8075 9 P 0 ;1
L 8.3575 0.8575 8.3575 0.8575 9 P 0 ;1
L 8.3575 0.9075 8.3575 0.9075 9 P 0 ;1
L 8.3575 0.9575 8.3575 0.9575 9 P 0 ;1
L 8.3575 1.0075 8.3575 1.0075 9 P 0 ;1
L 8.3575 1.0575 8.3575 1.0575 9 P 0 ;1
L 8.3575 1.1075 8.3575 1.1075 9 P 0 ;1
L 8.3575 1.1575 8.3575 1.1575 9 P 0 ;1
L 8.3575 1.2075 8.3575 1.2075 9 P 0 ;1
L 8.3575 1.2575 8.3575 1.2575 9 P 0 ;1
L 8.3575 1.3075 8.3575 1.3075 9 P 0 ;1
L 8.3575 1.7075 8.3575 1.7075 9 P 0 ;1
L 8.3575 1.7575 8.3575 1.7575 9 P 0 ;1
L 8.3575 5.2575 8.3575 5.2575 9 P 0 ;1
L 8.3575 5.3075 8.3575 5.3075 9 P 0 ;1
L 8.3575 5.3575 8.3575 5.3575 9 P 0 ;1
L 8.3575 5.4075 8.3575 5.4075 9 P 0 ;1
L 8.3575 5.4575 8.3575 5.4575 9 P 0 ;1
L 8.3575 5.5075 8.3575 5.5075 9 P 0 ;1
L 8.3575 5.5575 8.3575 5.5575 9 P 0 ;1
L 8.3575 5.6075 8.3575 5.6075 9 P 0 ;1
L 8.3575 5.6575 8.3575 5.6575 9 P 0 ;1
L 8.3575 5.7075 8.3575 5.7075 9 P 0 ;1
L 8.3575 5.7575 8.3575 5.7575 9 P 0 ;1
L 8.3575 5.8075 8.3575 5.8075 9 P 0 ;1
L 8.3575 5.8575 8.3575 5.8575 9 P 0 ;1
L 8.3575 5.9075 8.3575 5.9075 9 P 0 ;1
L 8.4075 0.1575 8.4075 0.1575 9 P 0 ;1
L 8.4075 0.2075 8.4075 0.2075 9 P 0 ;1
L 8.4075 0.2575 8.4075 0.2575 9 P 0 ;1
L 8.4075 0.3075 8.4075 0.3075 9 P 0 ;1
L 8.4075 0.3575 8.4075 0.3575 9 P 0 ;1
L 8.4075 0.4075 8.4075 0.4075 9 P 0 ;1
L 8.4075 0.4575 8.4075 0.4575 9 P 0 ;1
L 8.4075 0.5075 8.4075 0.5075 9 P 0 ;1
L 8.4075 0.5575 8.4075 0.5575 9 P 0 ;1
L 8.4075 0.6075 8.4075 0.6075 9 P 0 ;1
L 8.4075 0.6575 8.4075 0.6575 9 P 0 ;1
L 8.4075 0.7075 8.4075 0.7075 9 P 0 ;1
L 8.4075 0.7575 8.4075 0.7575 9 P 0 ;1
L 8.4075 0.8075 8.4075 0.8075 9 P 0 ;1
L 8.4075 0.8575 8.4075 0.8575 9 P 0 ;1
L 8.4075 0.9075 8.4075 0.9075 9 P 0 ;1
L 8.4075 0.9575 8.4075 0.9575 9 P 0 ;1
L 8.4075 1.0075 8.4075 1.0075 9 P 0 ;1
L 8.4075 1.0575 8.4075 1.0575 9 P 0 ;1
L 8.4075 1.1075 8.4075 1.1075 9 P 0 ;1
L 8.4075 1.1575 8.4075 1.1575 9 P 0 ;1
L 8.4075 1.2075 8.4075 1.2075 9 P 0 ;1
L 8.4075 1.2575 8.4075 1.2575 9 P 0 ;1
L 8.4075 1.3075 8.4075 1.3075 9 P 0 ;1
L 8.4075 1.3575 8.4075 1.3575 9 P 0 ;1
L 8.4075 1.6575 8.4075 1.6575 9 P 0 ;1
L 8.4075 1.7075 8.4075 1.7075 9 P 0 ;1
L 8.4075 1.7575 8.4075 1.7575 9 P 0 ;1
L 8.4075 5.2575 8.4075 5.2575 9 P 0 ;1
L 8.4075 5.3075 8.4075 5.3075 9 P 0 ;1
L 8.4075 5.3575 8.4075 5.3575 9 P 0 ;1
L 8.4075 5.4075 8.4075 5.4075 9 P 0 ;1
L 8.4075 5.4575 8.4075 5.4575 9 P 0 ;1
L 8.4075 5.5075 8.4075 5.5075 9 P 0 ;1
L 8.4075 5.5575 8.4075 5.5575 9 P 0 ;1
L 8.4075 5.6075 8.4075 5.6075 9 P 0 ;1
L 8.4075 5.6575 8.4075 5.6575 9 P 0 ;1
L 8.4075 5.7075 8.4075 5.7075 9 P 0 ;1
L 8.4075 5.7575 8.4075 5.7575 9 P 0 ;1
L 8.4075 5.8075 8.4075 5.8075 9 P 0 ;1
L 8.4075 5.8575 8.4075 5.8575 9 P 0 ;1
L 8.4075 5.9075 8.4075 5.9075 9 P 0 ;1
L 8.4575 0.1575 8.4575 0.1575 9 P 0 ;1
L 8.4575 0.2075 8.4575 0.2075 9 P 0 ;1
L 8.4575 0.2575 8.4575 0.2575 9 P 0 ;1
L 8.4575 0.3075 8.4575 0.3075 9 P 0 ;1
L 8.4575 0.3575 8.4575 0.3575 9 P 0 ;1
L 8.4575 0.4075 8.4575 0.4075 9 P 0 ;1
L 8.4575 0.4575 8.4575 0.4575 9 P 0 ;1
L 8.4575 0.5075 8.4575 0.5075 9 P 0 ;1
L 8.4575 0.5575 8.4575 0.5575 9 P 0 ;1
L 8.4575 0.6075 8.4575 0.6075 9 P 0 ;1
L 8.4575 0.6575 8.4575 0.6575 9 P 0 ;1
L 8.4575 0.7075 8.4575 0.7075 9 P 0 ;1
L 8.4575 0.7575 8.4575 0.7575 9 P 0 ;1
L 8.4575 0.8075 8.4575 0.8075 9 P 0 ;1
L 8.4575 0.8575 8.4575 0.8575 9 P 0 ;1
L 8.4575 0.9075 8.4575 0.9075 9 P 0 ;1
L 8.4575 0.9575 8.4575 0.9575 9 P 0 ;1
L 8.4575 1.0075 8.4575 1.0075 9 P 0 ;1
L 8.4575 1.0575 8.4575 1.0575 9 P 0 ;1
L 8.4575 1.1075 8.4575 1.1075 9 P 0 ;1
L 8.4575 1.1575 8.4575 1.1575 9 P 0 ;1
L 8.4575 1.2075 8.4575 1.2075 9 P 0 ;1
L 8.4575 1.2575 8.4575 1.2575 9 P 0 ;1
L 8.4575 1.3075 8.4575 1.3075 9 P 0 ;1
L 8.4575 1.3575 8.4575 1.3575 9 P 0 ;1
L 8.4575 1.4075 8.4575 1.4075 9 P 0 ;1
L 8.4575 1.4575 8.4575 1.4575 9 P 0 ;1
L 8.4575 1.5075 8.4575 1.5075 9 P 0 ;1
L 8.4575 1.5575 8.4575 1.5575 9 P 0 ;1
L 8.4575 1.6075 8.4575 1.6075 9 P 0 ;1
L 8.4575 1.6575 8.4575 1.6575 9 P 0 ;1
L 8.4575 1.7075 8.4575 1.7075 9 P 0 ;1
L 8.4575 1.7575 8.4575 1.7575 9 P 0 ;1
L 8.4575 5.2575 8.4575 5.2575 9 P 0 ;1
L 8.4575 5.3075 8.4575 5.3075 9 P 0 ;1
L 8.4575 5.3575 8.4575 5.3575 9 P 0 ;1
L 8.4575 5.4075 8.4575 5.4075 9 P 0 ;1
L 8.4575 5.4575 8.4575 5.4575 9 P 0 ;1
L 8.4575 5.5075 8.4575 5.5075 9 P 0 ;1
L 8.4575 5.5575 8.4575 5.5575 9 P 0 ;1
L 8.4575 5.6075 8.4575 5.6075 9 P 0 ;1
L 8.4575 5.6575 8.4575 5.6575 9 P 0 ;1
L 8.4575 5.7075 8.4575 5.7075 9 P 0 ;1
L 8.4575 5.7575 8.4575 5.7575 9 P 0 ;1
L 8.4575 5.8075 8.4575 5.8075 9 P 0 ;1
L 8.4575 5.8575 8.4575 5.8575 9 P 0 ;1
L 8.4575 5.9075 8.4575 5.9075 9 P 0 ;1
L 8.5075 0.1575 8.5075 0.1575 9 P 0 ;1
L 8.5075 0.2075 8.5075 0.2075 9 P 0 ;1
L 8.5075 0.2575 8.5075 0.2575 9 P 0 ;1
L 8.5075 0.3075 8.5075 0.3075 9 P 0 ;1
L 8.5075 0.3575 8.5075 0.3575 9 P 0 ;1
L 8.5075 0.4075 8.5075 0.4075 9 P 0 ;1
L 8.5075 0.4575 8.5075 0.4575 9 P 0 ;1
L 8.5075 0.5075 8.5075 0.5075 9 P 0 ;1
L 8.5075 0.5575 8.5075 0.5575 9 P 0 ;1
L 8.5075 0.6075 8.5075 0.6075 9 P 0 ;1
L 8.5075 0.6575 8.5075 0.6575 9 P 0 ;1
L 8.5075 0.7075 8.5075 0.7075 9 P 0 ;1
L 8.5075 0.7575 8.5075 0.7575 9 P 0 ;1
L 8.5075 0.8075 8.5075 0.8075 9 P 0 ;1
L 8.5075 0.8575 8.5075 0.8575 9 P 0 ;1
L 8.5075 0.9075 8.5075 0.9075 9 P 0 ;1
L 8.5075 0.9575 8.5075 0.9575 9 P 0 ;1
L 8.5075 1.0075 8.5075 1.0075 9 P 0 ;1
L 8.5075 1.0575 8.5075 1.0575 9 P 0 ;1
L 8.5075 1.1075 8.5075 1.1075 9 P 0 ;1
L 8.5075 1.1575 8.5075 1.1575 9 P 0 ;1
L 8.5075 1.2075 8.5075 1.2075 9 P 0 ;1
L 8.5075 1.2575 8.5075 1.2575 9 P 0 ;1
L 8.5075 1.3075 8.5075 1.3075 9 P 0 ;1
L 8.5075 1.3575 8.5075 1.3575 9 P 0 ;1
L 8.5075 1.4075 8.5075 1.4075 9 P 0 ;1
L 8.5075 1.4575 8.5075 1.4575 9 P 0 ;1
L 8.5075 1.5075 8.5075 1.5075 9 P 0 ;1
L 8.5075 1.5575 8.5075 1.5575 9 P 0 ;1
L 8.5075 1.6075 8.5075 1.6075 9 P 0 ;1
L 8.5075 1.6575 8.5075 1.6575 9 P 0 ;1
L 8.5075 1.7075 8.5075 1.7075 9 P 0 ;1
L 8.5075 1.7575 8.5075 1.7575 9 P 0 ;1
L 8.5075 4.8575 8.5075 4.8575 9 P 0 ;1
L 8.5075 5.1575 8.5075 5.1575 9 P 0 ;1
L 8.5075 5.2075 8.5075 5.2075 9 P 0 ;1
L 8.5075 5.2575 8.5075 5.2575 9 P 0 ;1
L 8.5075 5.3075 8.5075 5.3075 9 P 0 ;1
L 8.5075 5.3575 8.5075 5.3575 9 P 0 ;1
L 8.5075 5.4075 8.5075 5.4075 9 P 0 ;1
L 8.5075 5.4575 8.5075 5.4575 9 P 0 ;1
L 8.5075 5.5075 8.5075 5.5075 9 P 0 ;1
L 8.5075 5.5575 8.5075 5.5575 9 P 0 ;1
L 8.5075 5.6075 8.5075 5.6075 9 P 0 ;1
L 8.5075 5.6575 8.5075 5.6575 9 P 0 ;1
L 8.5075 5.7075 8.5075 5.7075 9 P 0 ;1
L 8.5075 5.7575 8.5075 5.7575 9 P 0 ;1
L 8.5075 5.8075 8.5075 5.8075 9 P 0 ;1
L 8.5075 5.8575 8.5075 5.8575 9 P 0 ;1
L 8.5075 5.9075 8.5075 5.9075 9 P 0 ;1
L 8.5575 0.1575 8.5575 0.1575 9 P 0 ;1
L 8.5575 0.2075 8.5575 0.2075 9 P 0 ;1
L 8.5575 0.2575 8.5575 0.2575 9 P 0 ;1
L 8.5575 0.3075 8.5575 0.3075 9 P 0 ;1
L 8.5575 0.3575 8.5575 0.3575 9 P 0 ;1
L 8.5575 0.4075 8.5575 0.4075 9 P 0 ;1
L 8.5575 0.4575 8.5575 0.4575 9 P 0 ;1
L 8.5575 0.5075 8.5575 0.5075 9 P 0 ;1
L 8.5575 0.5575 8.5575 0.5575 9 P 0 ;1
L 8.5575 0.6075 8.5575 0.6075 9 P 0 ;1
L 8.5575 0.6575 8.5575 0.6575 9 P 0 ;1
L 8.5575 0.7075 8.5575 0.7075 9 P 0 ;1
L 8.5575 0.7575 8.5575 0.7575 9 P 0 ;1
L 8.5575 0.8075 8.5575 0.8075 9 P 0 ;1
L 8.5575 0.8575 8.5575 0.8575 9 P 0 ;1
L 8.5575 0.9075 8.5575 0.9075 9 P 0 ;1
L 8.5575 0.9575 8.5575 0.9575 9 P 0 ;1
L 8.5575 1.0075 8.5575 1.0075 9 P 0 ;1
L 8.5575 1.0575 8.5575 1.0575 9 P 0 ;1
L 8.5575 1.1075 8.5575 1.1075 9 P 0 ;1
L 8.5575 1.1575 8.5575 1.1575 9 P 0 ;1
L 8.5575 1.2075 8.5575 1.2075 9 P 0 ;1
L 8.5575 1.2575 8.5575 1.2575 9 P 0 ;1
L 8.5575 1.3075 8.5575 1.3075 9 P 0 ;1
L 8.5575 1.3575 8.5575 1.3575 9 P 0 ;1
L 8.5575 1.4075 8.5575 1.4075 9 P 0 ;1
L 8.5575 1.4575 8.5575 1.4575 9 P 0 ;1
L 8.5575 1.5075 8.5575 1.5075 9 P 0 ;1
L 8.5575 1.5575 8.5575 1.5575 9 P 0 ;1
L 8.5575 1.6075 8.5575 1.6075 9 P 0 ;1
L 8.5575 1.6575 8.5575 1.6575 9 P 0 ;1
L 8.5575 1.7075 8.5575 1.7075 9 P 0 ;1
L 8.5575 1.7575 8.5575 1.7575 9 P 0 ;1
L 8.5575 1.8075 8.5575 1.8075 9 P 0 ;1
L 8.5575 4.8075 8.5575 4.8075 9 P 0 ;1
L 8.5575 4.8575 8.5575 4.8575 9 P 0 ;1
L 8.5575 4.9075 8.5575 4.9075 9 P 0 ;1
L 8.5575 4.9575 8.5575 4.9575 9 P 0 ;1
L 8.5575 5.0075 8.5575 5.0075 9 P 0 ;1
L 8.5575 5.0575 8.5575 5.0575 9 P 0 ;1
L 8.5575 5.1075 8.5575 5.1075 9 P 0 ;1
L 8.5575 5.1575 8.5575 5.1575 9 P 0 ;1
L 8.5575 5.2075 8.5575 5.2075 9 P 0 ;1
L 8.5575 5.2575 8.5575 5.2575 9 P 0 ;1
L 8.5575 5.3075 8.5575 5.3075 9 P 0 ;1
L 8.5575 5.3575 8.5575 5.3575 9 P 0 ;1
L 8.5575 5.4075 8.5575 5.4075 9 P 0 ;1
L 8.5575 5.4575 8.5575 5.4575 9 P 0 ;1
L 8.5575 5.5075 8.5575 5.5075 9 P 0 ;1
L 8.5575 5.5575 8.5575 5.5575 9 P 0 ;1
L 8.5575 5.6075 8.5575 5.6075 9 P 0 ;1
L 8.5575 5.6575 8.5575 5.6575 9 P 0 ;1
L 8.5575 5.7075 8.5575 5.7075 9 P 0 ;1
L 8.5575 5.7575 8.5575 5.7575 9 P 0 ;1
L 8.5575 5.8075 8.5575 5.8075 9 P 0 ;1
L 8.5575 5.8575 8.5575 5.8575 9 P 0 ;1
L 8.5575 5.9075 8.5575 5.9075 9 P 0 ;1
L 8.6075 0.1575 8.6075 0.1575 9 P 0 ;1
L 8.6075 0.2075 8.6075 0.2075 9 P 0 ;1
L 8.6075 0.2575 8.6075 0.2575 9 P 0 ;1
L 8.6075 0.3075 8.6075 0.3075 9 P 0 ;1
L 8.6075 0.3575 8.6075 0.3575 9 P 0 ;1
L 8.6075 0.4075 8.6075 0.4075 9 P 0 ;1
L 8.6075 0.4575 8.6075 0.4575 9 P 0 ;1
L 8.6075 0.5075 8.6075 0.5075 9 P 0 ;1
L 8.6075 0.5575 8.6075 0.5575 9 P 0 ;1
L 8.6075 0.6075 8.6075 0.6075 9 P 0 ;1
L 8.6075 0.6575 8.6075 0.6575 9 P 0 ;1
L 8.6075 0.7075 8.6075 0.7075 9 P 0 ;1
L 8.6075 0.7575 8.6075 0.7575 9 P 0 ;1
L 8.6075 0.8075 8.6075 0.8075 9 P 0 ;1
L 8.6075 0.8575 8.6075 0.8575 9 P 0 ;1
L 8.6075 0.9075 8.6075 0.9075 9 P 0 ;1
L 8.6075 0.9575 8.6075 0.9575 9 P 0 ;1
L 8.6075 1.0075 8.6075 1.0075 9 P 0 ;1
L 8.6075 1.0575 8.6075 1.0575 9 P 0 ;1
L 8.6075 1.1075 8.6075 1.1075 9 P 0 ;1
L 8.6075 1.1575 8.6075 1.1575 9 P 0 ;1
L 8.6075 1.2075 8.6075 1.2075 9 P 0 ;1
L 8.6075 1.2575 8.6075 1.2575 9 P 0 ;1
L 8.6075 1.3075 8.6075 1.3075 9 P 0 ;1
L 8.6075 1.3575 8.6075 1.3575 9 P 0 ;1
L 8.6075 1.4075 8.6075 1.4075 9 P 0 ;1
L 8.6075 1.4575 8.6075 1.4575 9 P 0 ;1
L 8.6075 1.5075 8.6075 1.5075 9 P 0 ;1
L 8.6075 1.5575 8.6075 1.5575 9 P 0 ;1
L 8.6075 1.6075 8.6075 1.6075 9 P 0 ;1
L 8.6075 1.6575 8.6075 1.6575 9 P 0 ;1
L 8.6075 1.7075 8.6075 1.7075 9 P 0 ;1
L 8.6075 1.7575 8.6075 1.7575 9 P 0 ;1
L 8.6075 1.8075 8.6075 1.8075 9 P 0 ;1
L 8.6075 1.8575 8.6075 1.8575 9 P 0 ;1
L 8.6075 1.9075 8.6075 1.9075 9 P 0 ;1
L 8.6075 1.9575 8.6075 1.9575 9 P 0 ;1
L 8.6075 2.0075 8.6075 2.0075 9 P 0 ;1
L 8.6075 2.0575 8.6075 2.0575 9 P 0 ;1
L 8.6075 2.1075 8.6075 2.1075 9 P 0 ;1
L 8.6075 2.1575 8.6075 2.1575 9 P 0 ;1
L 8.6075 2.2075 8.6075 2.2075 9 P 0 ;1
L 8.6075 2.2575 8.6075 2.2575 9 P 0 ;1
L 8.6075 2.3075 8.6075 2.3075 9 P 0 ;1
L 8.6075 2.3575 8.6075 2.3575 9 P 0 ;1
L 8.6075 2.4075 8.6075 2.4075 9 P 0 ;1
L 8.6075 2.4575 8.6075 2.4575 9 P 0 ;1
L 8.6075 2.5075 8.6075 2.5075 9 P 0 ;1
L 8.6075 2.5575 8.6075 2.5575 9 P 0 ;1
L 8.6075 2.6075 8.6075 2.6075 9 P 0 ;1
L 8.6075 2.6575 8.6075 2.6575 9 P 0 ;1
L 8.6075 2.7075 8.6075 2.7075 9 P 0 ;1
L 8.6075 2.7575 8.6075 2.7575 9 P 0 ;1
L 8.6075 2.8075 8.6075 2.8075 9 P 0 ;1
L 8.6075 2.8575 8.6075 2.8575 9 P 0 ;1
L 8.6075 2.9075 8.6075 2.9075 9 P 0 ;1
L 8.6075 2.9575 8.6075 2.9575 9 P 0 ;1
L 8.6075 3.0075 8.6075 3.0075 9 P 0 ;1
L 8.6075 3.0575 8.6075 3.0575 9 P 0 ;1
L 8.6075 3.1075 8.6075 3.1075 9 P 0 ;1
L 8.6075 3.1575 8.6075 3.1575 9 P 0 ;1
L 8.6075 4.8575 8.6075 4.8575 9 P 0 ;1
L 8.6075 4.9075 8.6075 4.9075 9 P 0 ;1
L 8.6075 4.9575 8.6075 4.9575 9 P 0 ;1
L 8.6075 5.0075 8.6075 5.0075 9 P 0 ;1
L 8.6075 5.0575 8.6075 5.0575 9 P 0 ;1
L 8.6075 5.1075 8.6075 5.1075 9 P 0 ;1
L 8.6075 5.1575 8.6075 5.1575 9 P 0 ;1
L 8.6075 5.2075 8.6075 5.2075 9 P 0 ;1
L 8.6075 5.2575 8.6075 5.2575 9 P 0 ;1
L 8.6075 5.3075 8.6075 5.3075 9 P 0 ;1
L 8.6075 5.3575 8.6075 5.3575 9 P 0 ;1
L 8.6075 5.4075 8.6075 5.4075 9 P 0 ;1
L 8.6075 5.4575 8.6075 5.4575 9 P 0 ;1
L 8.6075 5.5075 8.6075 5.5075 9 P 0 ;1
L 8.6075 5.5575 8.6075 5.5575 9 P 0 ;1
L 8.6075 5.6075 8.6075 5.6075 9 P 0 ;1
L 8.6075 5.6575 8.6075 5.6575 9 P 0 ;1
L 8.6075 5.7075 8.6075 5.7075 9 P 0 ;1
L 8.6075 5.7575 8.6075 5.7575 9 P 0 ;1
L 8.6075 5.8075 8.6075 5.8075 9 P 0 ;1
L 8.6075 5.8575 8.6075 5.8575 9 P 0 ;1
L 8.6075 5.9075 8.6075 5.9075 9 P 0 ;1
L 8.6575 0.1575 8.6575 0.1575 9 P 0 ;1
L 8.6575 0.2075 8.6575 0.2075 9 P 0 ;1
L 8.6575 0.2575 8.6575 0.2575 9 P 0 ;1
L 8.6575 0.3075 8.6575 0.3075 9 P 0 ;1
L 8.6575 0.3575 8.6575 0.3575 9 P 0 ;1
L 8.6575 0.4075 8.6575 0.4075 9 P 0 ;1
L 8.6575 0.4575 8.6575 0.4575 9 P 0 ;1
L 8.6575 0.5075 8.6575 0.5075 9 P 0 ;1
L 8.6575 0.5575 8.6575 0.5575 9 P 0 ;1
L 8.6575 0.6075 8.6575 0.6075 9 P 0 ;1
L 8.6575 0.6575 8.6575 0.6575 9 P 0 ;1
L 8.6575 0.7075 8.6575 0.7075 9 P 0 ;1
L 8.6575 0.7575 8.6575 0.7575 9 P 0 ;1
L 8.6575 0.8075 8.6575 0.8075 9 P 0 ;1
L 8.6575 0.8575 8.6575 0.8575 9 P 0 ;1
L 8.6575 0.9075 8.6575 0.9075 9 P 0 ;1
L 8.6575 0.9575 8.6575 0.9575 9 P 0 ;1
L 8.6575 1.0075 8.6575 1.0075 9 P 0 ;1
L 8.6575 1.0575 8.6575 1.0575 9 P 0 ;1
L 8.6575 1.1075 8.6575 1.1075 9 P 0 ;1
L 8.6575 1.1575 8.6575 1.1575 9 P 0 ;1
L 8.6575 1.2075 8.6575 1.2075 9 P 0 ;1
L 8.6575 1.2575 8.6575 1.2575 9 P 0 ;1
L 8.6575 1.3075 8.6575 1.3075 9 P 0 ;1
L 8.6575 1.3575 8.6575 1.3575 9 P 0 ;1
L 8.6575 1.4075 8.6575 1.4075 9 P 0 ;1
L 8.6575 1.4575 8.6575 1.4575 9 P 0 ;1
L 8.6575 1.5075 8.6575 1.5075 9 P 0 ;1
L 8.6575 1.5575 8.6575 1.5575 9 P 0 ;1
L 8.6575 1.6075 8.6575 1.6075 9 P 0 ;1
L 8.6575 1.6575 8.6575 1.6575 9 P 0 ;1
L 8.6575 1.7075 8.6575 1.7075 9 P 0 ;1
L 8.6575 1.7575 8.6575 1.7575 9 P 0 ;1
L 8.6575 1.8075 8.6575 1.8075 9 P 0 ;1
L 8.6575 1.8575 8.6575 1.8575 9 P 0 ;1
L 8.6575 1.9075 8.6575 1.9075 9 P 0 ;1
L 8.6575 1.9575 8.6575 1.9575 9 P 0 ;1
L 8.6575 2.0075 8.6575 2.0075 9 P 0 ;1
L 8.6575 2.0575 8.6575 2.0575 9 P 0 ;1
L 8.6575 2.1075 8.6575 2.1075 9 P 0 ;1
L 8.6575 2.1575 8.6575 2.1575 9 P 0 ;1
L 8.6575 2.2075 8.6575 2.2075 9 P 0 ;1
L 8.6575 2.2575 8.6575 2.2575 9 P 0 ;1
L 8.6575 2.3075 8.6575 2.3075 9 P 0 ;1
L 8.6575 2.3575 8.6575 2.3575 9 P 0 ;1
L 8.6575 2.4075 8.6575 2.4075 9 P 0 ;1
L 8.6575 2.4575 8.6575 2.4575 9 P 0 ;1
L 8.6575 2.5075 8.6575 2.5075 9 P 0 ;1
L 8.6575 2.5575 8.6575 2.5575 9 P 0 ;1
L 8.6575 2.6075 8.6575 2.6075 9 P 0 ;1
L 8.6575 2.6575 8.6575 2.6575 9 P 0 ;1
L 8.6575 2.7075 8.6575 2.7075 9 P 0 ;1
L 8.6575 2.7575 8.6575 2.7575 9 P 0 ;1
L 8.6575 2.8075 8.6575 2.8075 9 P 0 ;1
L 8.6575 2.8575 8.6575 2.8575 9 P 0 ;1
L 8.6575 2.9075 8.6575 2.9075 9 P 0 ;1
L 8.6575 2.9575 8.6575 2.9575 9 P 0 ;1
L 8.6575 3.0075 8.6575 3.0075 9 P 0 ;1
L 8.6575 3.0575 8.6575 3.0575 9 P 0 ;1
L 8.6575 3.1075 8.6575 3.1075 9 P 0 ;1
L 8.6575 3.1575 8.6575 3.1575 9 P 0 ;1
L 8.6575 4.5075 8.6575 4.5075 9 P 0 ;1
L 8.6575 4.5575 8.6575 4.5575 9 P 0 ;1
L 8.6575 4.6075 8.6575 4.6075 9 P 0 ;1
L 8.6575 4.6575 8.6575 4.6575 9 P 0 ;1
L 8.6575 5.1575 8.6575 5.1575 9 P 0 ;1
L 8.6575 5.2075 8.6575 5.2075 9 P 0 ;1
L 8.6575 5.2575 8.6575 5.2575 9 P 0 ;1
L 8.6575 5.3075 8.6575 5.3075 9 P 0 ;1
L 8.6575 5.3575 8.6575 5.3575 9 P 0 ;1
L 8.6575 5.4075 8.6575 5.4075 9 P 0 ;1
L 8.6575 5.4575 8.6575 5.4575 9 P 0 ;1
L 8.6575 5.5075 8.6575 5.5075 9 P 0 ;1
L 8.6575 5.5575 8.6575 5.5575 9 P 0 ;1
L 8.6575 5.6075 8.6575 5.6075 9 P 0 ;1
L 8.6575 5.6575 8.6575 5.6575 9 P 0 ;1
L 8.6575 5.7075 8.6575 5.7075 9 P 0 ;1
L 8.6575 5.7575 8.6575 5.7575 9 P 0 ;1
L 8.6575 5.8075 8.6575 5.8075 9 P 0 ;1
L 8.6575 5.8575 8.6575 5.8575 9 P 0 ;1
L 8.6575 5.9075 8.6575 5.9075 9 P 0 ;1
L 8.7075 0.1575 8.7075 0.1575 9 P 0 ;1
L 8.7075 0.2075 8.7075 0.2075 9 P 0 ;1
L 8.7075 0.2575 8.7075 0.2575 9 P 0 ;1
L 8.7075 0.3075 8.7075 0.3075 9 P 0 ;1
L 8.7075 0.3575 8.7075 0.3575 9 P 0 ;1
L 8.7075 0.4075 8.7075 0.4075 9 P 0 ;1
L 8.7075 0.4575 8.7075 0.4575 9 P 0 ;1
L 8.7075 0.5075 8.7075 0.5075 9 P 0 ;1
L 8.7075 0.5575 8.7075 0.5575 9 P 0 ;1
L 8.7075 0.6075 8.7075 0.6075 9 P 0 ;1
L 8.7075 0.6575 8.7075 0.6575 9 P 0 ;1
L 8.7075 0.7075 8.7075 0.7075 9 P 0 ;1
L 8.7075 0.7575 8.7075 0.7575 9 P 0 ;1
L 8.7075 0.8075 8.7075 0.8075 9 P 0 ;1
L 8.7075 0.8575 8.7075 0.8575 9 P 0 ;1
L 8.7075 0.9075 8.7075 0.9075 9 P 0 ;1
L 8.7075 0.9575 8.7075 0.9575 9 P 0 ;1
L 8.7075 1.0075 8.7075 1.0075 9 P 0 ;1
L 8.7075 1.0575 8.7075 1.0575 9 P 0 ;1
L 8.7075 1.1075 8.7075 1.1075 9 P 0 ;1
L 8.7075 1.1575 8.7075 1.1575 9 P 0 ;1
L 8.7075 1.2075 8.7075 1.2075 9 P 0 ;1
L 8.7075 1.2575 8.7075 1.2575 9 P 0 ;1
L 8.7075 1.3075 8.7075 1.3075 9 P 0 ;1
L 8.7075 1.3575 8.7075 1.3575 9 P 0 ;1
L 8.7075 1.4075 8.7075 1.4075 9 P 0 ;1
L 8.7075 1.4575 8.7075 1.4575 9 P 0 ;1
L 8.7075 1.5075 8.7075 1.5075 9 P 0 ;1
L 8.7075 1.5575 8.7075 1.5575 9 P 0 ;1
L 8.7075 1.6075 8.7075 1.6075 9 P 0 ;1
L 8.7075 1.6575 8.7075 1.6575 9 P 0 ;1
L 8.7075 1.7075 8.7075 1.7075 9 P 0 ;1
L 8.7075 1.7575 8.7075 1.7575 9 P 0 ;1
L 8.7075 1.8075 8.7075 1.8075 9 P 0 ;1
L 8.7075 1.8575 8.7075 1.8575 9 P 0 ;1
L 8.7075 1.9075 8.7075 1.9075 9 P 0 ;1
L 8.7075 1.9575 8.7075 1.9575 9 P 0 ;1
L 8.7075 2.0075 8.7075 2.0075 9 P 0 ;1
L 8.7075 2.0575 8.7075 2.0575 9 P 0 ;1
L 8.7075 2.1075 8.7075 2.1075 9 P 0 ;1
L 8.7075 2.1575 8.7075 2.1575 9 P 0 ;1
L 8.7075 2.2075 8.7075 2.2075 9 P 0 ;1
L 8.7075 2.2575 8.7075 2.2575 9 P 0 ;1
L 8.7075 2.3075 8.7075 2.3075 9 P 0 ;1
L 8.7075 2.3575 8.7075 2.3575 9 P 0 ;1
L 8.7075 2.4075 8.7075 2.4075 9 P 0 ;1
L 8.7075 2.4575 8.7075 2.4575 9 P 0 ;1
L 8.7075 2.5075 8.7075 2.5075 9 P 0 ;1
L 8.7075 2.5575 8.7075 2.5575 9 P 0 ;1
L 8.7075 2.6075 8.7075 2.6075 9 P 0 ;1
L 8.7075 2.6575 8.7075 2.6575 9 P 0 ;1
L 8.7075 2.7075 8.7075 2.7075 9 P 0 ;1
L 8.7075 2.7575 8.7075 2.7575 9 P 0 ;1
L 8.7075 2.8075 8.7075 2.8075 9 P 0 ;1
L 8.7075 2.8575 8.7075 2.8575 9 P 0 ;1
L 8.7075 2.9075 8.7075 2.9075 9 P 0 ;1
L 8.7075 2.9575 8.7075 2.9575 9 P 0 ;1
L 8.7075 3.0075 8.7075 3.0075 9 P 0 ;1
L 8.7075 3.0575 8.7075 3.0575 9 P 0 ;1
L 8.7075 3.1075 8.7075 3.1075 9 P 0 ;1
L 8.7075 3.1575 8.7075 3.1575 9 P 0 ;1
L 8.7075 3.2075 8.7075 3.2075 9 P 0 ;1
L 8.7075 4.4575 8.7075 4.4575 9 P 0 ;1
L 8.7075 4.5075 8.7075 4.5075 9 P 0 ;1
L 8.7075 4.5575 8.7075 4.5575 9 P 0 ;1
L 8.7075 5.2575 8.7075 5.2575 9 P 0 ;1
L 8.7075 5.3075 8.7075 5.3075 9 P 0 ;1
L 8.7075 5.3575 8.7075 5.3575 9 P 0 ;1
L 8.7075 5.4075 8.7075 5.4075 9 P 0 ;1
L 8.7075 5.4575 8.7075 5.4575 9 P 0 ;1
L 8.7075 5.5075 8.7075 5.5075 9 P 0 ;1
L 8.7075 5.5575 8.7075 5.5575 9 P 0 ;1
L 8.7075 5.6075 8.7075 5.6075 9 P 0 ;1
L 8.7075 5.6575 8.7075 5.6575 9 P 0 ;1
L 8.7075 5.7075 8.7075 5.7075 9 P 0 ;1
L 8.7075 5.7575 8.7075 5.7575 9 P 0 ;1
L 8.7075 5.8075 8.7075 5.8075 9 P 0 ;1
L 8.7075 5.8575 8.7075 5.8575 9 P 0 ;1
L 8.7075 5.9075 8.7075 5.9075 9 P 0 ;1
L 8.7575 0.1575 8.7575 0.1575 9 P 0 ;1
L 8.7575 0.2075 8.7575 0.2075 9 P 0 ;1
L 8.7575 0.2575 8.7575 0.2575 9 P 0 ;1
L 8.7575 0.3075 8.7575 0.3075 9 P 0 ;1
L 8.7575 0.3575 8.7575 0.3575 9 P 0 ;1
L 8.7575 0.4075 8.7575 0.4075 9 P 0 ;1
L 8.7575 0.4575 8.7575 0.4575 9 P 0 ;1
L 8.7575 0.5075 8.7575 0.5075 9 P 0 ;1
L 8.7575 0.5575 8.7575 0.5575 9 P 0 ;1
L 8.7575 0.6075 8.7575 0.6075 9 P 0 ;1
L 8.7575 0.6575 8.7575 0.6575 9 P 0 ;1
L 8.7575 0.7075 8.7575 0.7075 9 P 0 ;1
L 8.7575 0.7575 8.7575 0.7575 9 P 0 ;1
L 8.7575 0.8075 8.7575 0.8075 9 P 0 ;1
L 8.7575 0.8575 8.7575 0.8575 9 P 0 ;1
L 8.7575 0.9075 8.7575 0.9075 9 P 0 ;1
L 8.7575 0.9575 8.7575 0.9575 9 P 0 ;1
L 8.7575 1.0075 8.7575 1.0075 9 P 0 ;1
L 8.7575 1.0575 8.7575 1.0575 9 P 0 ;1
L 8.7575 1.1075 8.7575 1.1075 9 P 0 ;1
L 8.7575 1.1575 8.7575 1.1575 9 P 0 ;1
L 8.7575 1.2075 8.7575 1.2075 9 P 0 ;1
L 8.7575 1.2575 8.7575 1.2575 9 P 0 ;1
L 8.7575 1.3075 8.7575 1.3075 9 P 0 ;1
L 8.7575 1.3575 8.7575 1.3575 9 P 0 ;1
L 8.7575 1.4075 8.7575 1.4075 9 P 0 ;1
L 8.7575 1.4575 8.7575 1.4575 9 P 0 ;1
L 8.7575 1.5075 8.7575 1.5075 9 P 0 ;1
L 8.7575 1.5575 8.7575 1.5575 9 P 0 ;1
L 8.7575 1.6075 8.7575 1.6075 9 P 0 ;1
L 8.7575 1.6575 8.7575 1.6575 9 P 0 ;1
L 8.7575 1.7075 8.7575 1.7075 9 P 0 ;1
L 8.7575 1.7575 8.7575 1.7575 9 P 0 ;1
L 8.7575 1.8075 8.7575 1.8075 9 P 0 ;1
L 8.7575 1.8575 8.7575 1.8575 9 P 0 ;1
L 8.7575 1.9075 8.7575 1.9075 9 P 0 ;1
L 8.7575 1.9575 8.7575 1.9575 9 P 0 ;1
L 8.7575 2.0075 8.7575 2.0075 9 P 0 ;1
L 8.7575 2.0575 8.7575 2.0575 9 P 0 ;1
L 8.7575 2.1075 8.7575 2.1075 9 P 0 ;1
L 8.7575 2.1575 8.7575 2.1575 9 P 0 ;1
L 8.7575 2.2075 8.7575 2.2075 9 P 0 ;1
L 8.7575 2.2575 8.7575 2.2575 9 P 0 ;1
L 8.7575 2.3075 8.7575 2.3075 9 P 0 ;1
L 8.7575 2.3575 8.7575 2.3575 9 P 0 ;1
L 8.7575 2.4075 8.7575 2.4075 9 P 0 ;1
L 8.7575 2.4575 8.7575 2.4575 9 P 0 ;1
L 8.7575 2.5075 8.7575 2.5075 9 P 0 ;1
L 8.7575 2.5575 8.7575 2.5575 9 P 0 ;1
L 8.7575 2.6075 8.7575 2.6075 9 P 0 ;1
L 8.7575 2.6575 8.7575 2.6575 9 P 0 ;1
L 8.7575 2.7075 8.7575 2.7075 9 P 0 ;1
L 8.7575 2.7575 8.7575 2.7575 9 P 0 ;1
L 8.7575 2.8075 8.7575 2.8075 9 P 0 ;1
L 8.7575 2.8575 8.7575 2.8575 9 P 0 ;1
L 8.7575 2.9075 8.7575 2.9075 9 P 0 ;1
L 8.7575 2.9575 8.7575 2.9575 9 P 0 ;1
L 8.7575 3.0075 8.7575 3.0075 9 P 0 ;1
L 8.7575 3.0575 8.7575 3.0575 9 P 0 ;1
L 8.7575 3.1075 8.7575 3.1075 9 P 0 ;1
L 8.7575 3.1575 8.7575 3.1575 9 P 0 ;1
L 8.7575 3.2075 8.7575 3.2075 9 P 0 ;1
L 8.7575 3.2575 8.7575 3.2575 9 P 0 ;1
L 8.7575 4.4075 8.7575 4.4075 9 P 0 ;1
L 8.7575 4.4575 8.7575 4.4575 9 P 0 ;1
L 8.7575 4.5075 8.7575 4.5075 9 P 0 ;1
L 8.7575 4.5575 8.7575 4.5575 9 P 0 ;1
L 8.7575 5.2575 8.7575 5.2575 9 P 0 ;1
L 8.7575 5.3075 8.7575 5.3075 9 P 0 ;1
L 8.7575 5.3575 8.7575 5.3575 9 P 0 ;1
L 8.7575 5.4075 8.7575 5.4075 9 P 0 ;1
L 8.7575 5.4575 8.7575 5.4575 9 P 0 ;1
L 8.7575 5.5075 8.7575 5.5075 9 P 0 ;1
L 8.7575 5.5575 8.7575 5.5575 9 P 0 ;1
L 8.7575 5.6075 8.7575 5.6075 9 P 0 ;1
L 8.7575 5.6575 8.7575 5.6575 9 P 0 ;1
L 8.7575 5.7075 8.7575 5.7075 9 P 0 ;1
L 8.7575 5.7575 8.7575 5.7575 9 P 0 ;1
L 8.7575 5.8075 8.7575 5.8075 9 P 0 ;1
L 8.7575 5.8575 8.7575 5.8575 9 P 0 ;1
L 8.7575 5.9075 8.7575 5.9075 9 P 0 ;1
L 8.8075 0.1575 8.8075 0.1575 9 P 0 ;1
L 8.8075 0.2075 8.8075 0.2075 9 P 0 ;1
L 8.8075 0.2575 8.8075 0.2575 9 P 0 ;1
L 8.8075 0.3075 8.8075 0.3075 9 P 0 ;1
L 8.8075 0.3575 8.8075 0.3575 9 P 0 ;1
L 8.8075 0.4075 8.8075 0.4075 9 P 0 ;1
L 8.8075 0.4575 8.8075 0.4575 9 P 0 ;1
L 8.8075 0.5075 8.8075 0.5075 9 P 0 ;1
L 8.8075 0.5575 8.8075 0.5575 9 P 0 ;1
L 8.8075 0.6075 8.8075 0.6075 9 P 0 ;1
L 8.8075 0.6575 8.8075 0.6575 9 P 0 ;1
L 8.8075 0.7075 8.8075 0.7075 9 P 0 ;1
L 8.8075 0.7575 8.8075 0.7575 9 P 0 ;1
L 8.8075 0.8075 8.8075 0.8075 9 P 0 ;1
L 8.8075 0.8575 8.8075 0.8575 9 P 0 ;1
L 8.8075 0.9075 8.8075 0.9075 9 P 0 ;1
L 8.8075 0.9575 8.8075 0.9575 9 P 0 ;1
L 8.8075 1.0075 8.8075 1.0075 9 P 0 ;1
L 8.8075 1.0575 8.8075 1.0575 9 P 0 ;1
L 8.8075 1.1075 8.8075 1.1075 9 P 0 ;1
L 8.8075 1.1575 8.8075 1.1575 9 P 0 ;1
L 8.8075 1.2075 8.8075 1.2075 9 P 0 ;1
L 8.8075 1.2575 8.8075 1.2575 9 P 0 ;1
L 8.8075 1.3075 8.8075 1.3075 9 P 0 ;1
L 8.8075 1.3575 8.8075 1.3575 9 P 0 ;1
L 8.8075 1.4075 8.8075 1.4075 9 P 0 ;1
L 8.8075 1.4575 8.8075 1.4575 9 P 0 ;1
L 8.8075 1.5075 8.8075 1.5075 9 P 0 ;1
L 8.8075 1.5575 8.8075 1.5575 9 P 0 ;1
L 8.8075 1.6075 8.8075 1.6075 9 P 0 ;1
L 8.8075 1.6575 8.8075 1.6575 9 P 0 ;1
L 8.8075 1.7075 8.8075 1.7075 9 P 0 ;1
L 8.8075 1.7575 8.8075 1.7575 9 P 0 ;1
L 8.8075 1.8075 8.8075 1.8075 9 P 0 ;1
L 8.8075 1.8575 8.8075 1.8575 9 P 0 ;1
L 8.8075 1.9075 8.8075 1.9075 9 P 0 ;1
L 8.8075 1.9575 8.8075 1.9575 9 P 0 ;1
L 8.8075 2.0075 8.8075 2.0075 9 P 0 ;1
L 8.8075 2.0575 8.8075 2.0575 9 P 0 ;1
L 8.8075 2.1075 8.8075 2.1075 9 P 0 ;1
L 8.8075 2.1575 8.8075 2.1575 9 P 0 ;1
L 8.8075 2.2075 8.8075 2.2075 9 P 0 ;1
L 8.8075 2.2575 8.8075 2.2575 9 P 0 ;1
L 8.8075 2.3075 8.8075 2.3075 9 P 0 ;1
L 8.8075 2.3575 8.8075 2.3575 9 P 0 ;1
L 8.8075 2.4075 8.8075 2.4075 9 P 0 ;1
L 8.8075 2.4575 8.8075 2.4575 9 P 0 ;1
L 8.8075 2.5075 8.8075 2.5075 9 P 0 ;1
L 8.8075 2.5575 8.8075 2.5575 9 P 0 ;1
L 8.8075 2.6075 8.8075 2.6075 9 P 0 ;1
L 8.8075 2.6575 8.8075 2.6575 9 P 0 ;1
L 8.8075 2.7075 8.8075 2.7075 9 P 0 ;1
L 8.8075 2.7575 8.8075 2.7575 9 P 0 ;1
L 8.8075 2.8075 8.8075 2.8075 9 P 0 ;1
L 8.8075 2.8575 8.8075 2.8575 9 P 0 ;1
L 8.8075 2.9075 8.8075 2.9075 9 P 0 ;1
L 8.8075 2.9575 8.8075 2.9575 9 P 0 ;1
L 8.8075 3.0075 8.8075 3.0075 9 P 0 ;1
L 8.8075 3.0575 8.8075 3.0575 9 P 0 ;1
L 8.8075 3.1075 8.8075 3.1075 9 P 0 ;1
L 8.8075 3.1575 8.8075 3.1575 9 P 0 ;1
L 8.8075 3.2075 8.8075 3.2075 9 P 0 ;1
L 8.8075 3.2575 8.8075 3.2575 9 P 0 ;1
L 8.8075 3.3075 8.8075 3.3075 9 P 0 ;1
L 8.8075 3.3575 8.8075 3.3575 9 P 0 ;1
L 8.8075 4.0075 8.8075 4.0075 9 P 0 ;1
L 8.8075 4.0575 8.8075 4.0575 9 P 0 ;1
L 8.8075 4.1075 8.8075 4.1075 9 P 0 ;1
L 8.8075 4.1575 8.8075 4.1575 9 P 0 ;1
L 8.8075 4.2075 8.8075 4.2075 9 P 0 ;1
L 8.8075 4.2575 8.8075 4.2575 9 P 0 ;1
L 8.8075 4.3075 8.8075 4.3075 9 P 0 ;1
L 8.8075 4.3575 8.8075 4.3575 9 P 0 ;1
L 8.8075 4.4075 8.8075 4.4075 9 P 0 ;1
L 8.8075 4.4575 8.8075 4.4575 9 P 0 ;1
L 8.8075 4.5075 8.8075 4.5075 9 P 0 ;1
L 8.8075 4.5575 8.8075 4.5575 9 P 0 ;1
L 8.8075 5.2575 8.8075 5.2575 9 P 0 ;1
L 8.8075 5.3075 8.8075 5.3075 9 P 0 ;1
L 8.8075 5.3575 8.8075 5.3575 9 P 0 ;1
L 8.8075 5.4075 8.8075 5.4075 9 P 0 ;1
L 8.8075 5.4575 8.8075 5.4575 9 P 0 ;1
L 8.8075 5.5075 8.8075 5.5075 9 P 0 ;1
L 8.8075 5.5575 8.8075 5.5575 9 P 0 ;1
L 8.8075 5.6075 8.8075 5.6075 9 P 0 ;1
L 8.8075 5.6575 8.8075 5.6575 9 P 0 ;1
L 8.8075 5.7075 8.8075 5.7075 9 P 0 ;1
L 8.8075 5.7575 8.8075 5.7575 9 P 0 ;1
L 8.8075 5.8075 8.8075 5.8075 9 P 0 ;1
L 8.8075 5.8575 8.8075 5.8575 9 P 0 ;1
L 8.8075 5.9075 8.8075 5.9075 9 P 0 ;1
L 8.8575 0.1575 8.8575 0.1575 9 P 0 ;1
L 8.8575 0.2075 8.8575 0.2075 9 P 0 ;1
L 8.8575 0.2575 8.8575 0.2575 9 P 0 ;1
L 8.8575 0.3075 8.8575 0.3075 9 P 0 ;1
L 8.8575 0.3575 8.8575 0.3575 9 P 0 ;1
L 8.8575 0.4075 8.8575 0.4075 9 P 0 ;1
L 8.8575 0.4575 8.8575 0.4575 9 P 0 ;1
L 8.8575 0.5075 8.8575 0.5075 9 P 0 ;1
L 8.8575 0.5575 8.8575 0.5575 9 P 0 ;1
L 8.8575 0.6075 8.8575 0.6075 9 P 0 ;1
L 8.8575 0.6575 8.8575 0.6575 9 P 0 ;1
L 8.8575 0.7075 8.8575 0.7075 9 P 0 ;1
L 8.8575 0.7575 8.8575 0.7575 9 P 0 ;1
L 8.8575 0.8075 8.8575 0.8075 9 P 0 ;1
L 8.8575 0.8575 8.8575 0.8575 9 P 0 ;1
L 8.8575 0.9075 8.8575 0.9075 9 P 0 ;1
L 8.8575 0.9575 8.8575 0.9575 9 P 0 ;1
L 8.8575 1.0075 8.8575 1.0075 9 P 0 ;1
L 8.8575 1.0575 8.8575 1.0575 9 P 0 ;1
L 8.8575 1.1075 8.8575 1.1075 9 P 0 ;1
L 8.8575 1.1575 8.8575 1.1575 9 P 0 ;1
L 8.8575 1.2075 8.8575 1.2075 9 P 0 ;1
L 8.8575 1.2575 8.8575 1.2575 9 P 0 ;1
L 8.8575 1.3075 8.8575 1.3075 9 P 0 ;1
L 8.8575 1.3575 8.8575 1.3575 9 P 0 ;1
L 8.8575 1.4075 8.8575 1.4075 9 P 0 ;1
L 8.8575 1.4575 8.8575 1.4575 9 P 0 ;1
L 8.8575 1.5075 8.8575 1.5075 9 P 0 ;1
L 8.8575 1.5575 8.8575 1.5575 9 P 0 ;1
L 8.8575 1.6075 8.8575 1.6075 9 P 0 ;1
L 8.8575 1.6575 8.8575 1.6575 9 P 0 ;1
L 8.8575 1.7075 8.8575 1.7075 9 P 0 ;1
L 8.8575 1.7575 8.8575 1.7575 9 P 0 ;1
L 8.8575 1.8075 8.8575 1.8075 9 P 0 ;1
L 8.8575 1.8575 8.8575 1.8575 9 P 0 ;1
L 8.8575 1.9075 8.8575 1.9075 9 P 0 ;1
L 8.8575 1.9575 8.8575 1.9575 9 P 0 ;1
L 8.8575 2.0075 8.8575 2.0075 9 P 0 ;1
L 8.8575 2.0575 8.8575 2.0575 9 P 0 ;1
L 8.8575 2.1075 8.8575 2.1075 9 P 0 ;1
L 8.8575 2.1575 8.8575 2.1575 9 P 0 ;1
L 8.8575 2.2075 8.8575 2.2075 9 P 0 ;1
L 8.8575 2.2575 8.8575 2.2575 9 P 0 ;1
L 8.8575 2.3075 8.8575 2.3075 9 P 0 ;1
L 8.8575 2.3575 8.8575 2.3575 9 P 0 ;1
L 8.8575 2.4075 8.8575 2.4075 9 P 0 ;1
L 8.8575 2.4575 8.8575 2.4575 9 P 0 ;1
L 8.8575 2.5075 8.8575 2.5075 9 P 0 ;1
L 8.8575 2.5575 8.8575 2.5575 9 P 0 ;1
L 8.8575 2.6075 8.8575 2.6075 9 P 0 ;1
L 8.8575 2.6575 8.8575 2.6575 9 P 0 ;1
L 8.8575 2.7075 8.8575 2.7075 9 P 0 ;1
L 8.8575 2.7575 8.8575 2.7575 9 P 0 ;1
L 8.8575 2.8075 8.8575 2.8075 9 P 0 ;1
L 8.8575 2.8575 8.8575 2.8575 9 P 0 ;1
L 8.8575 2.9075 8.8575 2.9075 9 P 0 ;1
L 8.8575 2.9575 8.8575 2.9575 9 P 0 ;1
L 8.8575 3.0075 8.8575 3.0075 9 P 0 ;1
L 8.8575 3.0575 8.8575 3.0575 9 P 0 ;1
L 8.8575 3.1075 8.8575 3.1075 9 P 0 ;1
L 8.8575 3.1575 8.8575 3.1575 9 P 0 ;1
L 8.8575 3.2075 8.8575 3.2075 9 P 0 ;1
L 8.8575 3.2575 8.8575 3.2575 9 P 0 ;1
L 8.8575 3.3075 8.8575 3.3075 9 P 0 ;1
L 8.8575 3.3575 8.8575 3.3575 9 P 0 ;1
L 8.8575 3.4075 8.8575 3.4075 9 P 0 ;1
L 8.8575 3.4575 8.8575 3.4575 9 P 0 ;1
L 8.8575 3.5075 8.8575 3.5075 9 P 0 ;1
L 8.8575 3.5575 8.8575 3.5575 9 P 0 ;1
L 8.8575 3.6075 8.8575 3.6075 9 P 0 ;1
L 8.8575 3.6575 8.8575 3.6575 9 P 0 ;1
L 8.8575 3.7575 8.8575 3.7575 9 P 0 ;1
L 8.8575 3.8075 8.8575 3.8075 9 P 0 ;1
L 8.8575 3.8575 8.8575 3.8575 9 P 0 ;1
L 8.8575 3.9075 8.8575 3.9075 9 P 0 ;1
L 8.8575 3.9575 8.8575 3.9575 9 P 0 ;1
L 8.8575 4.0075 8.8575 4.0075 9 P 0 ;1
L 8.8575 4.0575 8.8575 4.0575 9 P 0 ;1
L 8.8575 4.1075 8.8575 4.1075 9 P 0 ;1
L 8.8575 4.1575 8.8575 4.1575 9 P 0 ;1
L 8.8575 4.2075 8.8575 4.2075 9 P 0 ;1
L 8.8575 4.2575 8.8575 4.2575 9 P 0 ;1
L 8.8575 4.3075 8.8575 4.3075 9 P 0 ;1
L 8.8575 4.3575 8.8575 4.3575 9 P 0 ;1
L 8.8575 4.4075 8.8575 4.4075 9 P 0 ;1
L 8.8575 4.4575 8.8575 4.4575 9 P 0 ;1
L 8.8575 4.5075 8.8575 4.5075 9 P 0 ;1
L 8.8575 4.5575 8.8575 4.5575 9 P 0 ;1
L 8.8575 5.3075 8.8575 5.3075 9 P 0 ;1
L 8.8575 5.3575 8.8575 5.3575 9 P 0 ;1
L 8.8575 5.4075 8.8575 5.4075 9 P 0 ;1
L 8.8575 5.4575 8.8575 5.4575 9 P 0 ;1
L 8.8575 5.5075 8.8575 5.5075 9 P 0 ;1
L 8.8575 5.5575 8.8575 5.5575 9 P 0 ;1
L 8.8575 5.6075 8.8575 5.6075 9 P 0 ;1
L 8.8575 5.6575 8.8575 5.6575 9 P 0 ;1
L 8.8575 5.7075 8.8575 5.7075 9 P 0 ;1
L 8.8575 5.7575 8.8575 5.7575 9 P 0 ;1
L 8.8575 5.8075 8.8575 5.8075 9 P 0 ;1
L 8.8575 5.8575 8.8575 5.8575 9 P 0 ;1
L 8.8575 5.9075 8.8575 5.9075 9 P 0 ;1
L 8.9075 0.1575 8.9075 0.1575 9 P 0 ;1
L 8.9075 0.2075 8.9075 0.2075 9 P 0 ;1
L 8.9075 0.2575 8.9075 0.2575 9 P 0 ;1
L 8.9075 0.3075 8.9075 0.3075 9 P 0 ;1
L 8.9075 0.3575 8.9075 0.3575 9 P 0 ;1
L 8.9075 0.4075 8.9075 0.4075 9 P 0 ;1
L 8.9075 0.4575 8.9075 0.4575 9 P 0 ;1
L 8.9075 0.5075 8.9075 0.5075 9 P 0 ;1
L 8.9075 0.5575 8.9075 0.5575 9 P 0 ;1
L 8.9075 0.6075 8.9075 0.6075 9 P 0 ;1
L 8.9075 0.6575 8.9075 0.6575 9 P 0 ;1
L 8.9075 0.7075 8.9075 0.7075 9 P 0 ;1
L 8.9075 0.7575 8.9075 0.7575 9 P 0 ;1
L 8.9075 0.8075 8.9075 0.8075 9 P 0 ;1
L 8.9075 0.8575 8.9075 0.8575 9 P 0 ;1
L 8.9075 0.9075 8.9075 0.9075 9 P 0 ;1
L 8.9075 0.9575 8.9075 0.9575 9 P 0 ;1
L 8.9075 1.0075 8.9075 1.0075 9 P 0 ;1
L 8.9075 1.0575 8.9075 1.0575 9 P 0 ;1
L 8.9075 1.1075 8.9075 1.1075 9 P 0 ;1
L 8.9075 1.1575 8.9075 1.1575 9 P 0 ;1
L 8.9075 1.2075 8.9075 1.2075 9 P 0 ;1
L 8.9075 1.2575 8.9075 1.2575 9 P 0 ;1
L 8.9075 1.3075 8.9075 1.3075 9 P 0 ;1
L 8.9075 1.3575 8.9075 1.3575 9 P 0 ;1
L 8.9075 1.4075 8.9075 1.4075 9 P 0 ;1
L 8.9075 1.4575 8.9075 1.4575 9 P 0 ;1
L 8.9075 1.5075 8.9075 1.5075 9 P 0 ;1
L 8.9075 1.5575 8.9075 1.5575 9 P 0 ;1
L 8.9075 1.6075 8.9075 1.6075 9 P 0 ;1
L 8.9075 1.6575 8.9075 1.6575 9 P 0 ;1
L 8.9075 1.7075 8.9075 1.7075 9 P 0 ;1
L 8.9075 1.7575 8.9075 1.7575 9 P 0 ;1
L 8.9075 1.8075 8.9075 1.8075 9 P 0 ;1
L 8.9075 1.8575 8.9075 1.8575 9 P 0 ;1
L 8.9075 1.9075 8.9075 1.9075 9 P 0 ;1
L 8.9075 1.9575 8.9075 1.9575 9 P 0 ;1
L 8.9075 2.0075 8.9075 2.0075 9 P 0 ;1
L 8.9075 2.0575 8.9075 2.0575 9 P 0 ;1
L 8.9075 2.1075 8.9075 2.1075 9 P 0 ;1
L 8.9075 2.1575 8.9075 2.1575 9 P 0 ;1
L 8.9075 2.2075 8.9075 2.2075 9 P 0 ;1
L 8.9075 2.2575 8.9075 2.2575 9 P 0 ;1
L 8.9075 2.3075 8.9075 2.3075 9 P 0 ;1
L 8.9075 2.3575 8.9075 2.3575 9 P 0 ;1
L 8.9075 2.4075 8.9075 2.4075 9 P 0 ;1
L 8.9075 2.4575 8.9075 2.4575 9 P 0 ;1
L 8.9075 2.5075 8.9075 2.5075 9 P 0 ;1
L 8.9075 2.5575 8.9075 2.5575 9 P 0 ;1
L 8.9075 2.6075 8.9075 2.6075 9 P 0 ;1
L 8.9075 2.6575 8.9075 2.6575 9 P 0 ;1
L 8.9075 2.7075 8.9075 2.7075 9 P 0 ;1
L 8.9075 3.0075 8.9075 3.0075 9 P 0 ;1
L 8.9075 3.0575 8.9075 3.0575 9 P 0 ;1
L 8.9075 3.1075 8.9075 3.1075 9 P 0 ;1
L 8.9075 3.1575 8.9075 3.1575 9 P 0 ;1
L 8.9075 3.2075 8.9075 3.2075 9 P 0 ;1
L 8.9075 3.2575 8.9075 3.2575 9 P 0 ;1
L 8.9075 3.3075 8.9075 3.3075 9 P 0 ;1
L 8.9075 3.3575 8.9075 3.3575 9 P 0 ;1
L 8.9075 3.4075 8.9075 3.4075 9 P 0 ;1
L 8.9075 3.4575 8.9075 3.4575 9 P 0 ;1
L 8.9075 3.5075 8.9075 3.5075 9 P 0 ;1
L 8.9075 3.5575 8.9075 3.5575 9 P 0 ;1
L 8.9075 3.6075 8.9075 3.6075 9 P 0 ;1
L 8.9075 3.6575 8.9075 3.6575 9 P 0 ;1
L 8.9075 3.7075 8.9075 3.7075 9 P 0 ;1
L 8.9075 3.7575 8.9075 3.7575 9 P 0 ;1
L 8.9075 3.8075 8.9075 3.8075 9 P 0 ;1
L 8.9075 3.8575 8.9075 3.8575 9 P 0 ;1
L 8.9075 3.9075 8.9075 3.9075 9 P 0 ;1
L 8.9075 3.9575 8.9075 3.9575 9 P 0 ;1
L 8.9075 4.0075 8.9075 4.0075 9 P 0 ;1
L 8.9075 4.0575 8.9075 4.0575 9 P 0 ;1
L 8.9075 4.1075 8.9075 4.1075 9 P 0 ;1
L 8.9075 4.1575 8.9075 4.1575 9 P 0 ;1
L 8.9075 4.2075 8.9075 4.2075 9 P 0 ;1
L 8.9075 4.2575 8.9075 4.2575 9 P 0 ;1
L 8.9075 4.3075 8.9075 4.3075 9 P 0 ;1
L 8.9075 4.3575 8.9075 4.3575 9 P 0 ;1
L 8.9075 4.4075 8.9075 4.4075 9 P 0 ;1
L 8.9075 4.4575 8.9075 4.4575 9 P 0 ;1
L 8.9075 4.5075 8.9075 4.5075 9 P 0 ;1
L 8.9075 4.5575 8.9075 4.5575 9 P 0 ;1
L 8.9075 5.3075 8.9075 5.3075 9 P 0 ;1
L 8.9075 5.3575 8.9075 5.3575 9 P 0 ;1
L 8.9075 5.4075 8.9075 5.4075 9 P 0 ;1
L 8.9075 5.4575 8.9075 5.4575 9 P 0 ;1
L 8.9075 5.5075 8.9075 5.5075 9 P 0 ;1
L 8.9075 5.5575 8.9075 5.5575 9 P 0 ;1
L 8.9075 5.6075 8.9075 5.6075 9 P 0 ;1
L 8.9075 5.6575 8.9075 5.6575 9 P 0 ;1
L 8.9075 5.7075 8.9075 5.7075 9 P 0 ;1
L 8.9075 5.7575 8.9075 5.7575 9 P 0 ;1
L 8.9075 5.8075 8.9075 5.8075 9 P 0 ;1
L 8.9075 5.8575 8.9075 5.8575 9 P 0 ;1
L 8.9075 5.9075 8.9075 5.9075 9 P 0 ;1
L 8.9575 0.1575 8.9575 0.1575 9 P 0 ;1
L 8.9575 0.2075 8.9575 0.2075 9 P 0 ;1
L 8.9575 0.2575 8.9575 0.2575 9 P 0 ;1
L 8.9575 0.3075 8.9575 0.3075 9 P 0 ;1
L 8.9575 0.3575 8.9575 0.3575 9 P 0 ;1
L 8.9575 0.4075 8.9575 0.4075 9 P 0 ;1
L 8.9575 0.4575 8.9575 0.4575 9 P 0 ;1
L 8.9575 0.5075 8.9575 0.5075 9 P 0 ;1
L 8.9575 0.5575 8.9575 0.5575 9 P 0 ;1
L 8.9575 0.6075 8.9575 0.6075 9 P 0 ;1
L 8.9575 0.6575 8.9575 0.6575 9 P 0 ;1
L 8.9575 0.7075 8.9575 0.7075 9 P 0 ;1
L 8.9575 0.7575 8.9575 0.7575 9 P 0 ;1
L 8.9575 0.8075 8.9575 0.8075 9 P 0 ;1
L 8.9575 0.8575 8.9575 0.8575 9 P 0 ;1
L 8.9575 0.9075 8.9575 0.9075 9 P 0 ;1
L 8.9575 0.9575 8.9575 0.9575 9 P 0 ;1
L 8.9575 1.0075 8.9575 1.0075 9 P 0 ;1
L 8.9575 1.0575 8.9575 1.0575 9 P 0 ;1
L 8.9575 1.1075 8.9575 1.1075 9 P 0 ;1
L 8.9575 1.1575 8.9575 1.1575 9 P 0 ;1
L 8.9575 1.2075 8.9575 1.2075 9 P 0 ;1
L 8.9575 1.2575 8.9575 1.2575 9 P 0 ;1
L 8.9575 1.3075 8.9575 1.3075 9 P 0 ;1
L 8.9575 1.3575 8.9575 1.3575 9 P 0 ;1
L 8.9575 1.4075 8.9575 1.4075 9 P 0 ;1
L 8.9575 1.4575 8.9575 1.4575 9 P 0 ;1
L 8.9575 1.5075 8.9575 1.5075 9 P 0 ;1
L 8.9575 1.5575 8.9575 1.5575 9 P 0 ;1
L 8.9575 1.6075 8.9575 1.6075 9 P 0 ;1
L 8.9575 1.6575 8.9575 1.6575 9 P 0 ;1
L 8.9575 1.7075 8.9575 1.7075 9 P 0 ;1
L 8.9575 1.7575 8.9575 1.7575 9 P 0 ;1
L 8.9575 1.8075 8.9575 1.8075 9 P 0 ;1
L 8.9575 1.8575 8.9575 1.8575 9 P 0 ;1
L 8.9575 1.9075 8.9575 1.9075 9 P 0 ;1
L 8.9575 1.9575 8.9575 1.9575 9 P 0 ;1
L 8.9575 2.0075 8.9575 2.0075 9 P 0 ;1
L 8.9575 2.0575 8.9575 2.0575 9 P 0 ;1
L 8.9575 2.1075 8.9575 2.1075 9 P 0 ;1
L 8.9575 2.1575 8.9575 2.1575 9 P 0 ;1
L 8.9575 2.2075 8.9575 2.2075 9 P 0 ;1
L 8.9575 2.2575 8.9575 2.2575 9 P 0 ;1
L 8.9575 2.3075 8.9575 2.3075 9 P 0 ;1
L 8.9575 2.3575 8.9575 2.3575 9 P 0 ;1
L 8.9575 2.4075 8.9575 2.4075 9 P 0 ;1
L 8.9575 2.4575 8.9575 2.4575 9 P 0 ;1
L 8.9575 2.5075 8.9575 2.5075 9 P 0 ;1
L 8.9575 2.5575 8.9575 2.5575 9 P 0 ;1
L 8.9575 2.6075 8.9575 2.6075 9 P 0 ;1
L 8.9575 2.6575 8.9575 2.6575 9 P 0 ;1
L 8.9575 2.7075 8.9575 2.7075 9 P 0 ;1
L 8.9575 3.0075 8.9575 3.0075 9 P 0 ;1
L 8.9575 3.0575 8.9575 3.0575 9 P 0 ;1
L 8.9575 3.1075 8.9575 3.1075 9 P 0 ;1
L 8.9575 3.1575 8.9575 3.1575 9 P 0 ;1
L 8.9575 3.2075 8.9575 3.2075 9 P 0 ;1
L 8.9575 3.2575 8.9575 3.2575 9 P 0 ;1
L 8.9575 3.3075 8.9575 3.3075 9 P 0 ;1
L 8.9575 3.3575 8.9575 3.3575 9 P 0 ;1
L 8.9575 3.4075 8.9575 3.4075 9 P 0 ;1
L 8.9575 3.4575 8.9575 3.4575 9 P 0 ;1
L 8.9575 3.5075 8.9575 3.5075 9 P 0 ;1
L 8.9575 3.5575 8.9575 3.5575 9 P 0 ;1
L 8.9575 3.6075 8.9575 3.6075 9 P 0 ;1
L 8.9575 3.6575 8.9575 3.6575 9 P 0 ;1
L 8.9575 3.7075 8.9575 3.7075 9 P 0 ;1
L 8.9575 3.7575 8.9575 3.7575 9 P 0 ;1
L 8.9575 3.8075 8.9575 3.8075 9 P 0 ;1
L 8.9575 3.8575 8.9575 3.8575 9 P 0 ;1
L 8.9575 3.9075 8.9575 3.9075 9 P 0 ;1
L 8.9575 3.9575 8.9575 3.9575 9 P 0 ;1
L 8.9575 4.0075 8.9575 4.0075 9 P 0 ;1
L 8.9575 4.0575 8.9575 4.0575 9 P 0 ;1
L 8.9575 4.1075 8.9575 4.1075 9 P 0 ;1
L 8.9575 4.1575 8.9575 4.1575 9 P 0 ;1
L 8.9575 4.2075 8.9575 4.2075 9 P 0 ;1
L 8.9575 4.2575 8.9575 4.2575 9 P 0 ;1
L 8.9575 4.3075 8.9575 4.3075 9 P 0 ;1
L 8.9575 4.3575 8.9575 4.3575 9 P 0 ;1
L 8.9575 4.4075 8.9575 4.4075 9 P 0 ;1
L 8.9575 4.4575 8.9575 4.4575 9 P 0 ;1
L 8.9575 4.5075 8.9575 4.5075 9 P 0 ;1
L 8.9575 4.5575 8.9575 4.5575 9 P 0 ;1
L 8.9575 5.3075 8.9575 5.3075 9 P 0 ;1
L 8.9575 5.3575 8.9575 5.3575 9 P 0 ;1
L 8.9575 5.4075 8.9575 5.4075 9 P 0 ;1
L 8.9575 5.4575 8.9575 5.4575 9 P 0 ;1
L 8.9575 5.5075 8.9575 5.5075 9 P 0 ;1
L 8.9575 5.5575 8.9575 5.5575 9 P 0 ;1
L 8.9575 5.6075 8.9575 5.6075 9 P 0 ;1
L 8.9575 5.6575 8.9575 5.6575 9 P 0 ;1
L 8.9575 5.7075 8.9575 5.7075 9 P 0 ;1
L 8.9575 5.7575 8.9575 5.7575 9 P 0 ;1
L 8.9575 5.8075 8.9575 5.8075 9 P 0 ;1
L 8.9575 5.8575 8.9575 5.8575 9 P 0 ;1
L 8.9575 5.9075 8.9575 5.9075 9 P 0 ;1
L 9.0075 0.1575 9.0075 0.1575 9 P 0 ;1
L 9.0075 0.2075 9.0075 0.2075 9 P 0 ;1
L 9.0075 0.2575 9.0075 0.2575 9 P 0 ;1
L 9.0075 0.3075 9.0075 0.3075 9 P 0 ;1
L 9.0075 0.3575 9.0075 0.3575 9 P 0 ;1
L 9.0075 0.4075 9.0075 0.4075 9 P 0 ;1
L 9.0075 0.4575 9.0075 0.4575 9 P 0 ;1
L 9.0075 0.5075 9.0075 0.5075 9 P 0 ;1
L 9.0075 0.5575 9.0075 0.5575 9 P 0 ;1
L 9.0075 0.6075 9.0075 0.6075 9 P 0 ;1
L 9.0075 0.6575 9.0075 0.6575 9 P 0 ;1
L 9.0075 0.7075 9.0075 0.7075 9 P 0 ;1
L 9.0075 0.7575 9.0075 0.7575 9 P 0 ;1
L 9.0075 0.8075 9.0075 0.8075 9 P 0 ;1
L 9.0075 0.8575 9.0075 0.8575 9 P 0 ;1
L 9.0075 0.9075 9.0075 0.9075 9 P 0 ;1
L 9.0075 0.9575 9.0075 0.9575 9 P 0 ;1
L 9.0075 1.0075 9.0075 1.0075 9 P 0 ;1
L 9.0075 1.0575 9.0075 1.0575 9 P 0 ;1
L 9.0075 1.1075 9.0075 1.1075 9 P 0 ;1
L 9.0075 1.1575 9.0075 1.1575 9 P 0 ;1
L 9.0075 1.2075 9.0075 1.2075 9 P 0 ;1
L 9.0075 1.2575 9.0075 1.2575 9 P 0 ;1
L 9.0075 1.3075 9.0075 1.3075 9 P 0 ;1
L 9.0075 1.3575 9.0075 1.3575 9 P 0 ;1
L 9.0075 1.4075 9.0075 1.4075 9 P 0 ;1
L 9.0075 1.4575 9.0075 1.4575 9 P 0 ;1
L 9.0075 1.5075 9.0075 1.5075 9 P 0 ;1
L 9.0075 1.5575 9.0075 1.5575 9 P 0 ;1
L 9.0075 1.6075 9.0075 1.6075 9 P 0 ;1
L 9.0075 1.6575 9.0075 1.6575 9 P 0 ;1
L 9.0075 1.7075 9.0075 1.7075 9 P 0 ;1
L 9.0075 1.7575 9.0075 1.7575 9 P 0 ;1
L 9.0075 1.8075 9.0075 1.8075 9 P 0 ;1
L 9.0075 1.8575 9.0075 1.8575 9 P 0 ;1
L 9.0075 1.9075 9.0075 1.9075 9 P 0 ;1
L 9.0075 1.9575 9.0075 1.9575 9 P 0 ;1
L 9.0075 2.0075 9.0075 2.0075 9 P 0 ;1
L 9.0075 2.0575 9.0075 2.0575 9 P 0 ;1
L 9.0075 2.1075 9.0075 2.1075 9 P 0 ;1
L 9.0075 2.1575 9.0075 2.1575 9 P 0 ;1
L 9.0075 2.2075 9.0075 2.2075 9 P 0 ;1
L 9.0075 2.2575 9.0075 2.2575 9 P 0 ;1
L 9.0075 2.3075 9.0075 2.3075 9 P 0 ;1
L 9.0075 2.3575 9.0075 2.3575 9 P 0 ;1
L 9.0075 2.4075 9.0075 2.4075 9 P 0 ;1
L 9.0075 2.4575 9.0075 2.4575 9 P 0 ;1
L 9.0075 2.5075 9.0075 2.5075 9 P 0 ;1
L 9.0075 2.5575 9.0075 2.5575 9 P 0 ;1
L 9.0075 2.6075 9.0075 2.6075 9 P 0 ;1
L 9.0075 2.6575 9.0075 2.6575 9 P 0 ;1
L 9.0075 2.7075 9.0075 2.7075 9 P 0 ;1
L 9.0075 3.0075 9.0075 3.0075 9 P 0 ;1
L 9.0075 3.0575 9.0075 3.0575 9 P 0 ;1
L 9.0075 3.1075 9.0075 3.1075 9 P 0 ;1
L 9.0075 3.1575 9.0075 3.1575 9 P 0 ;1
L 9.0075 3.2075 9.0075 3.2075 9 P 0 ;1
L 9.0075 3.2575 9.0075 3.2575 9 P 0 ;1
L 9.0075 3.3075 9.0075 3.3075 9 P 0 ;1
L 9.0075 3.3575 9.0075 3.3575 9 P 0 ;1
L 9.0075 3.4075 9.0075 3.4075 9 P 0 ;1
L 9.0075 3.4575 9.0075 3.4575 9 P 0 ;1
L 9.0075 3.5075 9.0075 3.5075 9 P 0 ;1
L 9.0075 3.5575 9.0075 3.5575 9 P 0 ;1
L 9.0075 3.6075 9.0075 3.6075 9 P 0 ;1
L 9.0075 3.6575 9.0075 3.6575 9 P 0 ;1
L 9.0075 3.7075 9.0075 3.7075 9 P 0 ;1
L 9.0075 3.7575 9.0075 3.7575 9 P 0 ;1
L 9.0075 3.8075 9.0075 3.8075 9 P 0 ;1
L 9.0075 3.8575 9.0075 3.8575 9 P 0 ;1
L 9.0075 3.9075 9.0075 3.9075 9 P 0 ;1
L 9.0075 3.9575 9.0075 3.9575 9 P 0 ;1
L 9.0075 4.0075 9.0075 4.0075 9 P 0 ;1
L 9.0075 4.0575 9.0075 4.0575 9 P 0 ;1
L 9.0075 4.1075 9.0075 4.1075 9 P 0 ;1
L 9.0075 4.1575 9.0075 4.1575 9 P 0 ;1
L 9.0075 4.2075 9.0075 4.2075 9 P 0 ;1
L 9.0075 4.2575 9.0075 4.2575 9 P 0 ;1
L 9.0075 4.3075 9.0075 4.3075 9 P 0 ;1
L 9.0075 4.3575 9.0075 4.3575 9 P 0 ;1
L 9.0075 4.5075 9.0075 4.5075 9 P 0 ;1
L 9.0075 4.5575 9.0075 4.5575 9 P 0 ;1
L 9.0075 5.4075 9.0075 5.4075 9 P 0 ;1
L 9.0075 5.4575 9.0075 5.4575 9 P 0 ;1
L 9.0075 5.5075 9.0075 5.5075 9 P 0 ;1
L 9.0075 5.5575 9.0075 5.5575 9 P 0 ;1
L 9.0075 5.6075 9.0075 5.6075 9 P 0 ;1
L 9.0075 5.6575 9.0075 5.6575 9 P 0 ;1
L 9.0075 5.7075 9.0075 5.7075 9 P 0 ;1
L 9.0075 5.7575 9.0075 5.7575 9 P 0 ;1
L 9.0075 5.8075 9.0075 5.8075 9 P 0 ;1
L 9.0075 5.8575 9.0075 5.8575 9 P 0 ;1
L 9.0075 5.9075 9.0075 5.9075 9 P 0 ;1
L 9.0575 0.1575 9.0575 0.1575 9 P 0 ;1
L 9.0575 0.2075 9.0575 0.2075 9 P 0 ;1
L 9.0575 0.2575 9.0575 0.2575 9 P 0 ;1
L 9.0575 0.3075 9.0575 0.3075 9 P 0 ;1
L 9.0575 0.3575 9.0575 0.3575 9 P 0 ;1
L 9.0575 0.4075 9.0575 0.4075 9 P 0 ;1
L 9.0575 0.4575 9.0575 0.4575 9 P 0 ;1
L 9.0575 0.5075 9.0575 0.5075 9 P 0 ;1
L 9.0575 0.5575 9.0575 0.5575 9 P 0 ;1
L 9.0575 0.6075 9.0575 0.6075 9 P 0 ;1
L 9.0575 0.6575 9.0575 0.6575 9 P 0 ;1
L 9.0575 0.7075 9.0575 0.7075 9 P 0 ;1
L 9.0575 0.7575 9.0575 0.7575 9 P 0 ;1
L 9.0575 0.8075 9.0575 0.8075 9 P 0 ;1
L 9.0575 0.8575 9.0575 0.8575 9 P 0 ;1
L 9.0575 0.9075 9.0575 0.9075 9 P 0 ;1
L 9.0575 0.9575 9.0575 0.9575 9 P 0 ;1
L 9.0575 1.0075 9.0575 1.0075 9 P 0 ;1
L 9.0575 1.0575 9.0575 1.0575 9 P 0 ;1
L 9.0575 1.1075 9.0575 1.1075 9 P 0 ;1
L 9.0575 1.1575 9.0575 1.1575 9 P 0 ;1
L 9.0575 1.2075 9.0575 1.2075 9 P 0 ;1
L 9.0575 1.2575 9.0575 1.2575 9 P 0 ;1
L 9.0575 1.3075 9.0575 1.3075 9 P 0 ;1
L 9.0575 1.3575 9.0575 1.3575 9 P 0 ;1
L 9.0575 1.4075 9.0575 1.4075 9 P 0 ;1
L 9.0575 1.4575 9.0575 1.4575 9 P 0 ;1
L 9.0575 1.5075 9.0575 1.5075 9 P 0 ;1
L 9.0575 1.5575 9.0575 1.5575 9 P 0 ;1
L 9.0575 1.6075 9.0575 1.6075 9 P 0 ;1
L 9.0575 1.6575 9.0575 1.6575 9 P 0 ;1
L 9.0575 1.7075 9.0575 1.7075 9 P 0 ;1
L 9.0575 1.7575 9.0575 1.7575 9 P 0 ;1
L 9.0575 1.8075 9.0575 1.8075 9 P 0 ;1
L 9.0575 1.8575 9.0575 1.8575 9 P 0 ;1
L 9.0575 1.9075 9.0575 1.9075 9 P 0 ;1
L 9.0575 1.9575 9.0575 1.9575 9 P 0 ;1
L 9.0575 2.0075 9.0575 2.0075 9 P 0 ;1
L 9.0575 2.0575 9.0575 2.0575 9 P 0 ;1
L 9.0575 2.1075 9.0575 2.1075 9 P 0 ;1
L 9.0575 2.1575 9.0575 2.1575 9 P 0 ;1
L 9.0575 2.2075 9.0575 2.2075 9 P 0 ;1
L 9.0575 2.2575 9.0575 2.2575 9 P 0 ;1
L 9.0575 2.3075 9.0575 2.3075 9 P 0 ;1
L 9.0575 2.3575 9.0575 2.3575 9 P 0 ;1
L 9.0575 2.4075 9.0575 2.4075 9 P 0 ;1
L 9.0575 2.4575 9.0575 2.4575 9 P 0 ;1
L 9.0575 2.5075 9.0575 2.5075 9 P 0 ;1
L 9.0575 2.5575 9.0575 2.5575 9 P 0 ;1
L 9.0575 2.6075 9.0575 2.6075 9 P 0 ;1
L 9.0575 2.6575 9.0575 2.6575 9 P 0 ;1
L 9.0575 2.7075 9.0575 2.7075 9 P 0 ;1
L 9.0575 2.7575 9.0575 2.7575 9 P 0 ;1
L 9.0575 3.0075 9.0575 3.0075 9 P 0 ;1
L 9.0575 3.0575 9.0575 3.0575 9 P 0 ;1
L 9.0575 3.1075 9.0575 3.1075 9 P 0 ;1
L 9.0575 3.1575 9.0575 3.1575 9 P 0 ;1
L 9.0575 3.2075 9.0575 3.2075 9 P 0 ;1
L 9.0575 3.2575 9.0575 3.2575 9 P 0 ;1
L 9.0575 3.3075 9.0575 3.3075 9 P 0 ;1
L 9.0575 3.3575 9.0575 3.3575 9 P 0 ;1
L 9.0575 3.4075 9.0575 3.4075 9 P 0 ;1
L 9.0575 3.4575 9.0575 3.4575 9 P 0 ;1
L 9.0575 3.5075 9.0575 3.5075 9 P 0 ;1
L 9.0575 3.5575 9.0575 3.5575 9 P 0 ;1
L 9.0575 3.6075 9.0575 3.6075 9 P 0 ;1
L 9.0575 3.6575 9.0575 3.6575 9 P 0 ;1
L 9.0575 3.7075 9.0575 3.7075 9 P 0 ;1
L 9.0575 3.7575 9.0575 3.7575 9 P 0 ;1
L 9.0575 3.8075 9.0575 3.8075 9 P 0 ;1
L 9.0575 3.8575 9.0575 3.8575 9 P 0 ;1
L 9.0575 3.9075 9.0575 3.9075 9 P 0 ;1
L 9.0575 3.9575 9.0575 3.9575 9 P 0 ;1
L 9.0575 4.0075 9.0575 4.0075 9 P 0 ;1
L 9.0575 4.0575 9.0575 4.0575 9 P 0 ;1
L 9.0575 4.1075 9.0575 4.1075 9 P 0 ;1
L 9.0575 4.1575 9.0575 4.1575 9 P 0 ;1
L 9.0575 4.2075 9.0575 4.2075 9 P 0 ;1
L 9.0575 4.2575 9.0575 4.2575 9 P 0 ;1
L 9.0575 4.3075 9.0575 4.3075 9 P 0 ;1
L 9.0575 4.5575 9.0575 4.5575 9 P 0 ;1
L 9.0575 5.4575 9.0575 5.4575 9 P 0 ;1
L 9.0575 5.5075 9.0575 5.5075 9 P 0 ;1
L 9.0575 5.5575 9.0575 5.5575 9 P 0 ;1
L 9.0575 5.6075 9.0575 5.6075 9 P 0 ;1
L 9.0575 5.6575 9.0575 5.6575 9 P 0 ;1
L 9.0575 5.7075 9.0575 5.7075 9 P 0 ;1
L 9.0575 5.7575 9.0575 5.7575 9 P 0 ;1
L 9.0575 5.8075 9.0575 5.8075 9 P 0 ;1
L 9.0575 5.8575 9.0575 5.8575 9 P 0 ;1
L 9.0575 5.9075 9.0575 5.9075 9 P 0 ;1
L 9.1075 0.1575 9.1075 0.1575 9 P 0 ;1
L 9.1075 0.2075 9.1075 0.2075 9 P 0 ;1
L 9.1075 0.2575 9.1075 0.2575 9 P 0 ;1
L 9.1075 0.3075 9.1075 0.3075 9 P 0 ;1
L 9.1075 0.3575 9.1075 0.3575 9 P 0 ;1
L 9.1075 0.4075 9.1075 0.4075 9 P 0 ;1
L 9.1075 0.4575 9.1075 0.4575 9 P 0 ;1
L 9.1075 0.5075 9.1075 0.5075 9 P 0 ;1
L 9.1075 0.5575 9.1075 0.5575 9 P 0 ;1
L 9.1075 0.6075 9.1075 0.6075 9 P 0 ;1
L 9.1075 0.6575 9.1075 0.6575 9 P 0 ;1
L 9.1075 0.7075 9.1075 0.7075 9 P 0 ;1
L 9.1075 0.7575 9.1075 0.7575 9 P 0 ;1
L 9.1075 0.8075 9.1075 0.8075 9 P 0 ;1
L 9.1075 0.8575 9.1075 0.8575 9 P 0 ;1
L 9.1075 0.9075 9.1075 0.9075 9 P 0 ;1
L 9.1075 0.9575 9.1075 0.9575 9 P 0 ;1
L 9.1075 1.0075 9.1075 1.0075 9 P 0 ;1
L 9.1075 1.0575 9.1075 1.0575 9 P 0 ;1
L 9.1075 1.1075 9.1075 1.1075 9 P 0 ;1
L 9.1075 1.1575 9.1075 1.1575 9 P 0 ;1
L 9.1075 1.2075 9.1075 1.2075 9 P 0 ;1
L 9.1075 1.2575 9.1075 1.2575 9 P 0 ;1
L 9.1075 1.3075 9.1075 1.3075 9 P 0 ;1
L 9.1075 1.3575 9.1075 1.3575 9 P 0 ;1
L 9.1075 1.4075 9.1075 1.4075 9 P 0 ;1
L 9.1075 1.4575 9.1075 1.4575 9 P 0 ;1
L 9.1075 1.5075 9.1075 1.5075 9 P 0 ;1
L 9.1075 1.5575 9.1075 1.5575 9 P 0 ;1
L 9.1075 1.6075 9.1075 1.6075 9 P 0 ;1
L 9.1075 1.6575 9.1075 1.6575 9 P 0 ;1
L 9.1075 1.7075 9.1075 1.7075 9 P 0 ;1
L 9.1075 1.7575 9.1075 1.7575 9 P 0 ;1
L 9.1075 1.8075 9.1075 1.8075 9 P 0 ;1
L 9.1075 1.8575 9.1075 1.8575 9 P 0 ;1
L 9.1075 1.9075 9.1075 1.9075 9 P 0 ;1
L 9.1075 1.9575 9.1075 1.9575 9 P 0 ;1
L 9.1075 2.0075 9.1075 2.0075 9 P 0 ;1
L 9.1075 2.0575 9.1075 2.0575 9 P 0 ;1
L 9.1075 2.1075 9.1075 2.1075 9 P 0 ;1
L 9.1075 2.1575 9.1075 2.1575 9 P 0 ;1
L 9.1075 2.2075 9.1075 2.2075 9 P 0 ;1
L 9.1075 2.2575 9.1075 2.2575 9 P 0 ;1
L 9.1075 2.3075 9.1075 2.3075 9 P 0 ;1
L 9.1075 2.3575 9.1075 2.3575 9 P 0 ;1
L 9.1075 2.4075 9.1075 2.4075 9 P 0 ;1
L 9.1075 2.4575 9.1075 2.4575 9 P 0 ;1
L 9.1075 2.5075 9.1075 2.5075 9 P 0 ;1
L 9.1075 2.5575 9.1075 2.5575 9 P 0 ;1
L 9.1075 2.6075 9.1075 2.6075 9 P 0 ;1
L 9.1075 2.6575 9.1075 2.6575 9 P 0 ;1
L 9.1075 2.7075 9.1075 2.7075 9 P 0 ;1
L 9.1075 2.7575 9.1075 2.7575 9 P 0 ;1
L 9.1075 3.2575 9.1075 3.2575 9 P 0 ;1
L 9.1075 3.3075 9.1075 3.3075 9 P 0 ;1
L 9.1075 3.3575 9.1075 3.3575 9 P 0 ;1
L 9.1075 3.4075 9.1075 3.4075 9 P 0 ;1
L 9.1075 3.4575 9.1075 3.4575 9 P 0 ;1
L 9.1075 3.5075 9.1075 3.5075 9 P 0 ;1
L 9.1075 3.5575 9.1075 3.5575 9 P 0 ;1
L 9.1075 3.6075 9.1075 3.6075 9 P 0 ;1
L 9.1075 3.6575 9.1075 3.6575 9 P 0 ;1
L 9.1075 3.7075 9.1075 3.7075 9 P 0 ;1
L 9.1075 3.7575 9.1075 3.7575 9 P 0 ;1
L 9.1075 3.8075 9.1075 3.8075 9 P 0 ;1
L 9.1075 3.8575 9.1075 3.8575 9 P 0 ;1
L 9.1075 3.9075 9.1075 3.9075 9 P 0 ;1
L 9.1075 3.9575 9.1075 3.9575 9 P 0 ;1
L 9.1075 4.0075 9.1075 4.0075 9 P 0 ;1
L 9.1075 4.0575 9.1075 4.0575 9 P 0 ;1
L 9.1075 4.1075 9.1075 4.1075 9 P 0 ;1
L 9.1075 4.1575 9.1075 4.1575 9 P 0 ;1
L 9.1075 4.2075 9.1075 4.2075 9 P 0 ;1
L 9.1075 4.2575 9.1075 4.2575 9 P 0 ;1
L 9.1075 4.3075 9.1075 4.3075 9 P 0 ;1
L 9.1075 4.5575 9.1075 4.5575 9 P 0 ;1
L 9.1075 5.4075 9.1075 5.4075 9 P 0 ;1
L 9.1075 5.4575 9.1075 5.4575 9 P 0 ;1
L 9.1075 5.5075 9.1075 5.5075 9 P 0 ;1
L 9.1075 5.5575 9.1075 5.5575 9 P 0 ;1
L 9.1075 5.6075 9.1075 5.6075 9 P 0 ;1
L 9.1075 5.6575 9.1075 5.6575 9 P 0 ;1
L 9.1075 5.7075 9.1075 5.7075 9 P 0 ;1
L 9.1075 5.7575 9.1075 5.7575 9 P 0 ;1
L 9.1075 5.8075 9.1075 5.8075 9 P 0 ;1
L 9.1075 5.8575 9.1075 5.8575 9 P 0 ;1
L 9.1075 5.9075 9.1075 5.9075 9 P 0 ;1
L 9.1575 0.1575 9.1575 0.1575 9 P 0 ;1
L 9.1575 0.2075 9.1575 0.2075 9 P 0 ;1
L 9.1575 0.2575 9.1575 0.2575 9 P 0 ;1
L 9.1575 0.3075 9.1575 0.3075 9 P 0 ;1
L 9.1575 0.3575 9.1575 0.3575 9 P 0 ;1
L 9.1575 0.4075 9.1575 0.4075 9 P 0 ;1
L 9.1575 0.4575 9.1575 0.4575 9 P 0 ;1
L 9.1575 0.5075 9.1575 0.5075 9 P 0 ;1
L 9.1575 0.5575 9.1575 0.5575 9 P 0 ;1
L 9.1575 0.6075 9.1575 0.6075 9 P 0 ;1
L 9.1575 0.6575 9.1575 0.6575 9 P 0 ;1
L 9.1575 0.7075 9.1575 0.7075 9 P 0 ;1
L 9.1575 0.7575 9.1575 0.7575 9 P 0 ;1
L 9.1575 0.8075 9.1575 0.8075 9 P 0 ;1
L 9.1575 0.8575 9.1575 0.8575 9 P 0 ;1
L 9.1575 0.9075 9.1575 0.9075 9 P 0 ;1
L 9.1575 0.9575 9.1575 0.9575 9 P 0 ;1
L 9.1575 1.0075 9.1575 1.0075 9 P 0 ;1
L 9.1575 1.0575 9.1575 1.0575 9 P 0 ;1
L 9.1575 1.1075 9.1575 1.1075 9 P 0 ;1
L 9.1575 1.1575 9.1575 1.1575 9 P 0 ;1
L 9.1575 1.2075 9.1575 1.2075 9 P 0 ;1
L 9.1575 1.2575 9.1575 1.2575 9 P 0 ;1
L 9.1575 1.3075 9.1575 1.3075 9 P 0 ;1
L 9.1575 1.3575 9.1575 1.3575 9 P 0 ;1
L 9.1575 1.4075 9.1575 1.4075 9 P 0 ;1
L 9.1575 1.4575 9.1575 1.4575 9 P 0 ;1
L 9.1575 1.5075 9.1575 1.5075 9 P 0 ;1
L 9.1575 1.5575 9.1575 1.5575 9 P 0 ;1
L 9.1575 1.6075 9.1575 1.6075 9 P 0 ;1
L 9.1575 1.6575 9.1575 1.6575 9 P 0 ;1
L 9.1575 1.7075 9.1575 1.7075 9 P 0 ;1
L 9.1575 1.7575 9.1575 1.7575 9 P 0 ;1
L 9.1575 1.8075 9.1575 1.8075 9 P 0 ;1
L 9.1575 1.8575 9.1575 1.8575 9 P 0 ;1
L 9.1575 1.9075 9.1575 1.9075 9 P 0 ;1
L 9.1575 1.9575 9.1575 1.9575 9 P 0 ;1
L 9.1575 2.0075 9.1575 2.0075 9 P 0 ;1
L 9.1575 2.0575 9.1575 2.0575 9 P 0 ;1
L 9.1575 2.1075 9.1575 2.1075 9 P 0 ;1
L 9.1575 2.1575 9.1575 2.1575 9 P 0 ;1
L 9.1575 2.2075 9.1575 2.2075 9 P 0 ;1
L 9.1575 2.2575 9.1575 2.2575 9 P 0 ;1
L 9.1575 2.3075 9.1575 2.3075 9 P 0 ;1
L 9.1575 2.3575 9.1575 2.3575 9 P 0 ;1
L 9.1575 2.4075 9.1575 2.4075 9 P 0 ;1
L 9.1575 2.4575 9.1575 2.4575 9 P 0 ;1
L 9.1575 2.5075 9.1575 2.5075 9 P 0 ;1
L 9.1575 2.5575 9.1575 2.5575 9 P 0 ;1
L 9.1575 2.6075 9.1575 2.6075 9 P 0 ;1
L 9.1575 2.6575 9.1575 2.6575 9 P 0 ;1
L 9.1575 2.7075 9.1575 2.7075 9 P 0 ;1
L 9.1575 2.7575 9.1575 2.7575 9 P 0 ;1
L 9.1575 2.8075 9.1575 2.8075 9 P 0 ;1
L 9.1575 3.5075 9.1575 3.5075 9 P 0 ;1
L 9.1575 3.5575 9.1575 3.5575 9 P 0 ;1
L 9.1575 3.6075 9.1575 3.6075 9 P 0 ;1
L 9.1575 3.6575 9.1575 3.6575 9 P 0 ;1
L 9.1575 3.7075 9.1575 3.7075 9 P 0 ;1
L 9.1575 3.7575 9.1575 3.7575 9 P 0 ;1
L 9.1575 3.8075 9.1575 3.8075 9 P 0 ;1
L 9.1575 3.8575 9.1575 3.8575 9 P 0 ;1
L 9.1575 3.9075 9.1575 3.9075 9 P 0 ;1
L 9.1575 3.9575 9.1575 3.9575 9 P 0 ;1
L 9.1575 4.0075 9.1575 4.0075 9 P 0 ;1
L 9.1575 4.0575 9.1575 4.0575 9 P 0 ;1
L 9.1575 4.1075 9.1575 4.1075 9 P 0 ;1
L 9.1575 4.1575 9.1575 4.1575 9 P 0 ;1
L 9.1575 4.2075 9.1575 4.2075 9 P 0 ;1
L 9.1575 4.2575 9.1575 4.2575 9 P 0 ;1
L 9.1575 4.3075 9.1575 4.3075 9 P 0 ;1
L 9.1575 4.3575 9.1575 4.3575 9 P 0 ;1
L 9.1575 4.5575 9.1575 4.5575 9 P 0 ;1
L 9.1575 4.6075 9.1575 4.6075 9 P 0 ;1
L 9.1575 5.3575 9.1575 5.3575 9 P 0 ;1
L 9.1575 5.4075 9.1575 5.4075 9 P 0 ;1
L 9.1575 5.4575 9.1575 5.4575 9 P 0 ;1
L 9.1575 5.5075 9.1575 5.5075 9 P 0 ;1
L 9.1575 5.5575 9.1575 5.5575 9 P 0 ;1
L 9.1575 5.6075 9.1575 5.6075 9 P 0 ;1
L 9.1575 5.6575 9.1575 5.6575 9 P 0 ;1
L 9.1575 5.7075 9.1575 5.7075 9 P 0 ;1
L 9.1575 5.7575 9.1575 5.7575 9 P 0 ;1
L 9.1575 5.8075 9.1575 5.8075 9 P 0 ;1
L 9.1575 5.8575 9.1575 5.8575 9 P 0 ;1
L 9.1575 5.9075 9.1575 5.9075 9 P 0 ;1
L 9.2075 0.1575 9.2075 0.1575 9 P 0 ;1
L 9.2075 0.2075 9.2075 0.2075 9 P 0 ;1
L 9.2075 0.2575 9.2075 0.2575 9 P 0 ;1
L 9.2075 0.3075 9.2075 0.3075 9 P 0 ;1
L 9.2075 0.3575 9.2075 0.3575 9 P 0 ;1
L 9.2075 0.4075 9.2075 0.4075 9 P 0 ;1
L 9.2075 0.4575 9.2075 0.4575 9 P 0 ;1
L 9.2075 0.5075 9.2075 0.5075 9 P 0 ;1
L 9.2075 0.5575 9.2075 0.5575 9 P 0 ;1
L 9.2075 0.6075 9.2075 0.6075 9 P 0 ;1
L 9.2075 0.6575 9.2075 0.6575 9 P 0 ;1
L 9.2075 0.7075 9.2075 0.7075 9 P 0 ;1
L 9.2075 0.7575 9.2075 0.7575 9 P 0 ;1
L 9.2075 0.8075 9.2075 0.8075 9 P 0 ;1
L 9.2075 0.8575 9.2075 0.8575 9 P 0 ;1
L 9.2075 0.9075 9.2075 0.9075 9 P 0 ;1
L 9.2075 0.9575 9.2075 0.9575 9 P 0 ;1
L 9.2075 1.0075 9.2075 1.0075 9 P 0 ;1
L 9.2075 1.0575 9.2075 1.0575 9 P 0 ;1
L 9.2075 1.1075 9.2075 1.1075 9 P 0 ;1
L 9.2075 1.1575 9.2075 1.1575 9 P 0 ;1
L 9.2075 1.2075 9.2075 1.2075 9 P 0 ;1
L 9.2075 1.2575 9.2075 1.2575 9 P 0 ;1
L 9.2075 1.3075 9.2075 1.3075 9 P 0 ;1
L 9.2075 1.3575 9.2075 1.3575 9 P 0 ;1
L 9.2075 1.4075 9.2075 1.4075 9 P 0 ;1
L 9.2075 1.4575 9.2075 1.4575 9 P 0 ;1
L 9.2075 1.5075 9.2075 1.5075 9 P 0 ;1
L 9.2075 1.5575 9.2075 1.5575 9 P 0 ;1
L 9.2075 1.6075 9.2075 1.6075 9 P 0 ;1
L 9.2075 1.6575 9.2075 1.6575 9 P 0 ;1
L 9.2075 1.7075 9.2075 1.7075 9 P 0 ;1
L 9.2075 1.7575 9.2075 1.7575 9 P 0 ;1
L 9.2075 1.8075 9.2075 1.8075 9 P 0 ;1
L 9.2075 1.8575 9.2075 1.8575 9 P 0 ;1
L 9.2075 1.9075 9.2075 1.9075 9 P 0 ;1
L 9.2075 1.9575 9.2075 1.9575 9 P 0 ;1
L 9.2075 2.0075 9.2075 2.0075 9 P 0 ;1
L 9.2075 2.0575 9.2075 2.0575 9 P 0 ;1
L 9.2075 2.1075 9.2075 2.1075 9 P 0 ;1
L 9.2075 2.1575 9.2075 2.1575 9 P 0 ;1
L 9.2075 2.2075 9.2075 2.2075 9 P 0 ;1
L 9.2075 2.2575 9.2075 2.2575 9 P 0 ;1
L 9.2075 2.3075 9.2075 2.3075 9 P 0 ;1
L 9.2075 2.3575 9.2075 2.3575 9 P 0 ;1
L 9.2075 2.4075 9.2075 2.4075 9 P 0 ;1
L 9.2075 2.4575 9.2075 2.4575 9 P 0 ;1
L 9.2075 2.5075 9.2075 2.5075 9 P 0 ;1
L 9.2075 2.5575 9.2075 2.5575 9 P 0 ;1
L 9.2075 2.6075 9.2075 2.6075 9 P 0 ;1
L 9.2075 2.6575 9.2075 2.6575 9 P 0 ;1
L 9.2075 2.7075 9.2075 2.7075 9 P 0 ;1
L 9.2075 2.7575 9.2075 2.7575 9 P 0 ;1
L 9.2075 2.8075 9.2075 2.8075 9 P 0 ;1
L 9.2075 2.8575 9.2075 2.8575 9 P 0 ;1
L 9.2075 2.9075 9.2075 2.9075 9 P 0 ;1
L 9.2075 4.2075 9.2075 4.2075 9 P 0 ;1
L 9.2075 4.2575 9.2075 4.2575 9 P 0 ;1
L 9.2075 4.3075 9.2075 4.3075 9 P 0 ;1
L 9.2075 4.3575 9.2075 4.3575 9 P 0 ;1
L 9.2075 4.4075 9.2075 4.4075 9 P 0 ;1
L 9.2075 4.4575 9.2075 4.4575 9 P 0 ;1
L 9.2075 4.5075 9.2075 4.5075 9 P 0 ;1
L 9.2075 4.5575 9.2075 4.5575 9 P 0 ;1
L 9.2075 5.4075 9.2075 5.4075 9 P 0 ;1
L 9.2075 5.4575 9.2075 5.4575 9 P 0 ;1
L 9.2075 5.5075 9.2075 5.5075 9 P 0 ;1
L 9.2075 5.5575 9.2075 5.5575 9 P 0 ;1
L 9.2075 5.6075 9.2075 5.6075 9 P 0 ;1
L 9.2075 5.6575 9.2075 5.6575 9 P 0 ;1
L 9.2075 5.7075 9.2075 5.7075 9 P 0 ;1
L 9.2075 5.7575 9.2075 5.7575 9 P 0 ;1
L 9.2075 5.8075 9.2075 5.8075 9 P 0 ;1
L 9.2075 5.8575 9.2075 5.8575 9 P 0 ;1
L 9.2075 5.9075 9.2075 5.9075 9 P 0 ;1
L 9.2575 0.1575 9.2575 0.1575 9 P 0 ;1
L 9.2575 0.2075 9.2575 0.2075 9 P 0 ;1
L 9.2575 0.2575 9.2575 0.2575 9 P 0 ;1
L 9.2575 0.3075 9.2575 0.3075 9 P 0 ;1
L 9.2575 0.3575 9.2575 0.3575 9 P 0 ;1
L 9.2575 0.4075 9.2575 0.4075 9 P 0 ;1
L 9.2575 0.4575 9.2575 0.4575 9 P 0 ;1
L 9.2575 0.5075 9.2575 0.5075 9 P 0 ;1
L 9.2575 0.5575 9.2575 0.5575 9 P 0 ;1
L 9.2575 0.6075 9.2575 0.6075 9 P 0 ;1
L 9.2575 0.6575 9.2575 0.6575 9 P 0 ;1
L 9.2575 0.7075 9.2575 0.7075 9 P 0 ;1
L 9.2575 0.7575 9.2575 0.7575 9 P 0 ;1
L 9.2575 0.8075 9.2575 0.8075 9 P 0 ;1
L 9.2575 0.8575 9.2575 0.8575 9 P 0 ;1
L 9.2575 0.9075 9.2575 0.9075 9 P 0 ;1
L 9.2575 0.9575 9.2575 0.9575 9 P 0 ;1
L 9.2575 1.0075 9.2575 1.0075 9 P 0 ;1
L 9.2575 1.0575 9.2575 1.0575 9 P 0 ;1
L 9.2575 1.1075 9.2575 1.1075 9 P 0 ;1
L 9.2575 1.1575 9.2575 1.1575 9 P 0 ;1
L 9.2575 1.2075 9.2575 1.2075 9 P 0 ;1
L 9.2575 1.2575 9.2575 1.2575 9 P 0 ;1
L 9.2575 1.3075 9.2575 1.3075 9 P 0 ;1
L 9.2575 1.3575 9.2575 1.3575 9 P 0 ;1
L 9.2575 1.4075 9.2575 1.4075 9 P 0 ;1
L 9.2575 1.4575 9.2575 1.4575 9 P 0 ;1
L 9.2575 1.5075 9.2575 1.5075 9 P 0 ;1
L 9.2575 1.5575 9.2575 1.5575 9 P 0 ;1
L 9.2575 1.6075 9.2575 1.6075 9 P 0 ;1
L 9.2575 1.6575 9.2575 1.6575 9 P 0 ;1
L 9.2575 1.7075 9.2575 1.7075 9 P 0 ;1
L 9.2575 1.7575 9.2575 1.7575 9 P 0 ;1
L 9.2575 1.8075 9.2575 1.8075 9 P 0 ;1
L 9.2575 1.8575 9.2575 1.8575 9 P 0 ;1
L 9.2575 1.9075 9.2575 1.9075 9 P 0 ;1
L 9.2575 1.9575 9.2575 1.9575 9 P 0 ;1
L 9.2575 2.0075 9.2575 2.0075 9 P 0 ;1
L 9.2575 2.0575 9.2575 2.0575 9 P 0 ;1
L 9.2575 2.1075 9.2575 2.1075 9 P 0 ;1
L 9.2575 2.1575 9.2575 2.1575 9 P 0 ;1
L 9.2575 2.2075 9.2575 2.2075 9 P 0 ;1
L 9.2575 2.2575 9.2575 2.2575 9 P 0 ;1
L 9.2575 2.3075 9.2575 2.3075 9 P 0 ;1
L 9.2575 2.3575 9.2575 2.3575 9 P 0 ;1
L 9.2575 2.4075 9.2575 2.4075 9 P 0 ;1
L 9.2575 2.4575 9.2575 2.4575 9 P 0 ;1
L 9.2575 2.5075 9.2575 2.5075 9 P 0 ;1
L 9.2575 2.5575 9.2575 2.5575 9 P 0 ;1
L 9.2575 2.6075 9.2575 2.6075 9 P 0 ;1
L 9.2575 2.6575 9.2575 2.6575 9 P 0 ;1
L 9.2575 2.7075 9.2575 2.7075 9 P 0 ;1
L 9.2575 2.7575 9.2575 2.7575 9 P 0 ;1
L 9.2575 2.8075 9.2575 2.8075 9 P 0 ;1
L 9.2575 2.8575 9.2575 2.8575 9 P 0 ;1
L 9.2575 2.9075 9.2575 2.9075 9 P 0 ;1
L 9.2575 2.9575 9.2575 2.9575 9 P 0 ;1
L 9.2575 3.0075 9.2575 3.0075 9 P 0 ;1
L 9.2575 3.0575 9.2575 3.0575 9 P 0 ;1
L 9.2575 3.1075 9.2575 3.1075 9 P 0 ;1
L 9.2575 4.5075 9.2575 4.5075 9 P 0 ;1
L 9.2575 4.5575 9.2575 4.5575 9 P 0 ;1
L 9.2575 5.4575 9.2575 5.4575 9 P 0 ;1
L 9.2575 5.5075 9.2575 5.5075 9 P 0 ;1
L 9.2575 5.5575 9.2575 5.5575 9 P 0 ;1
L 9.2575 5.6075 9.2575 5.6075 9 P 0 ;1
L 9.2575 5.6575 9.2575 5.6575 9 P 0 ;1
L 9.2575 5.7075 9.2575 5.7075 9 P 0 ;1
L 9.2575 5.7575 9.2575 5.7575 9 P 0 ;1
L 9.2575 5.8075 9.2575 5.8075 9 P 0 ;1
L 9.2575 5.8575 9.2575 5.8575 9 P 0 ;1
L 9.2575 5.9075 9.2575 5.9075 9 P 0 ;1
L 9.3075 0.1575 9.3075 0.1575 9 P 0 ;1
L 9.3075 0.2075 9.3075 0.2075 9 P 0 ;1
L 9.3075 0.2575 9.3075 0.2575 9 P 0 ;1
L 9.3075 0.3075 9.3075 0.3075 9 P 0 ;1
L 9.3075 0.3575 9.3075 0.3575 9 P 0 ;1
L 9.3075 0.4075 9.3075 0.4075 9 P 0 ;1
L 9.3075 0.5575 9.3075 0.5575 9 P 0 ;1
L 9.3075 0.6075 9.3075 0.6075 9 P 0 ;1
L 9.3075 0.6575 9.3075 0.6575 9 P 0 ;1
L 9.3075 0.7075 9.3075 0.7075 9 P 0 ;1
L 9.3075 0.7575 9.3075 0.7575 9 P 0 ;1
L 9.3075 0.8075 9.3075 0.8075 9 P 0 ;1
L 9.3075 0.8575 9.3075 0.8575 9 P 0 ;1
L 9.3075 0.9075 9.3075 0.9075 9 P 0 ;1
L 9.3075 0.9575 9.3075 0.9575 9 P 0 ;1
L 9.3075 1.0075 9.3075 1.0075 9 P 0 ;1
L 9.3075 1.0575 9.3075 1.0575 9 P 0 ;1
L 9.3075 1.1075 9.3075 1.1075 9 P 0 ;1
L 9.3075 1.1575 9.3075 1.1575 9 P 0 ;1
L 9.3075 1.2075 9.3075 1.2075 9 P 0 ;1
L 9.3075 1.2575 9.3075 1.2575 9 P 0 ;1
L 9.3075 1.3075 9.3075 1.3075 9 P 0 ;1
L 9.3075 1.3575 9.3075 1.3575 9 P 0 ;1
L 9.3075 1.4075 9.3075 1.4075 9 P 0 ;1
L 9.3075 1.4575 9.3075 1.4575 9 P 0 ;1
L 9.3075 1.5075 9.3075 1.5075 9 P 0 ;1
L 9.3075 1.5575 9.3075 1.5575 9 P 0 ;1
L 9.3075 1.6075 9.3075 1.6075 9 P 0 ;1
L 9.3075 1.6575 9.3075 1.6575 9 P 0 ;1
L 9.3075 1.7075 9.3075 1.7075 9 P 0 ;1
L 9.3075 1.7575 9.3075 1.7575 9 P 0 ;1
L 9.3075 1.8075 9.3075 1.8075 9 P 0 ;1
L 9.3075 1.8575 9.3075 1.8575 9 P 0 ;1
L 9.3075 1.9075 9.3075 1.9075 9 P 0 ;1
L 9.3075 1.9575 9.3075 1.9575 9 P 0 ;1
L 9.3075 2.0075 9.3075 2.0075 9 P 0 ;1
L 9.3075 2.0575 9.3075 2.0575 9 P 0 ;1
L 9.3075 2.1075 9.3075 2.1075 9 P 0 ;1
L 9.3075 2.1575 9.3075 2.1575 9 P 0 ;1
L 9.3075 2.2075 9.3075 2.2075 9 P 0 ;1
L 9.3075 2.2575 9.3075 2.2575 9 P 0 ;1
L 9.3075 2.3075 9.3075 2.3075 9 P 0 ;1
L 9.3075 2.3575 9.3075 2.3575 9 P 0 ;1
L 9.3075 2.4075 9.3075 2.4075 9 P 0 ;1
L 9.3075 2.4575 9.3075 2.4575 9 P 0 ;1
L 9.3075 2.5075 9.3075 2.5075 9 P 0 ;1
L 9.3075 2.5575 9.3075 2.5575 9 P 0 ;1
L 9.3075 2.6075 9.3075 2.6075 9 P 0 ;1
L 9.3075 2.6575 9.3075 2.6575 9 P 0 ;1
L 9.3075 2.7075 9.3075 2.7075 9 P 0 ;1
L 9.3075 2.7575 9.3075 2.7575 9 P 0 ;1
L 9.3075 2.8075 9.3075 2.8075 9 P 0 ;1
L 9.3075 2.8575 9.3075 2.8575 9 P 0 ;1
L 9.3075 2.9075 9.3075 2.9075 9 P 0 ;1
L 9.3075 2.9575 9.3075 2.9575 9 P 0 ;1
L 9.3075 3.0075 9.3075 3.0075 9 P 0 ;1
L 9.3075 3.0575 9.3075 3.0575 9 P 0 ;1
L 9.3075 3.1075 9.3075 3.1075 9 P 0 ;1
L 9.3075 3.1575 9.3075 3.1575 9 P 0 ;1
L 9.3075 3.2075 9.3075 3.2075 9 P 0 ;1
L 9.3075 3.2575 9.3075 3.2575 9 P 0 ;1
L 9.3075 3.3075 9.3075 3.3075 9 P 0 ;1
L 9.3075 3.3575 9.3075 3.3575 9 P 0 ;1
L 9.3075 3.4075 9.3075 3.4075 9 P 0 ;1
L 9.3075 5.4075 9.3075 5.4075 9 P 0 ;1
L 9.3075 5.4575 9.3075 5.4575 9 P 0 ;1
L 9.3075 5.5075 9.3075 5.5075 9 P 0 ;1
L 9.3075 5.5575 9.3075 5.5575 9 P 0 ;1
L 9.3075 5.6075 9.3075 5.6075 9 P 0 ;1
L 9.3075 5.6575 9.3075 5.6575 9 P 0 ;1
L 9.3075 5.7075 9.3075 5.7075 9 P 0 ;1
L 9.3075 5.7575 9.3075 5.7575 9 P 0 ;1
L 9.3075 5.8075 9.3075 5.8075 9 P 0 ;1
L 9.3075 5.8575 9.3075 5.8575 9 P 0 ;1
L 9.3075 5.9075 9.3075 5.9075 9 P 0 ;1
L 9.3575 0.1575 9.3575 0.1575 9 P 0 ;1
L 9.3575 0.3575 9.3575 0.3575 9 P 0 ;1
L 9.3575 0.4075 9.3575 0.4075 9 P 0 ;1
L 9.3575 0.6075 9.3575 0.6075 9 P 0 ;1
L 9.3575 0.6575 9.3575 0.6575 9 P 0 ;1
L 9.3575 0.7075 9.3575 0.7075 9 P 0 ;1
L 9.3575 0.8075 9.3575 0.8075 9 P 0 ;1
L 9.3575 0.8575 9.3575 0.8575 9 P 0 ;1
L 9.3575 0.9075 9.3575 0.9075 9 P 0 ;1
L 9.3575 0.9575 9.3575 0.9575 9 P 0 ;1
L 9.3575 1.0075 9.3575 1.0075 9 P 0 ;1
L 9.3575 1.0575 9.3575 1.0575 9 P 0 ;1
L 9.3575 1.1075 9.3575 1.1075 9 P 0 ;1
L 9.3575 1.1575 9.3575 1.1575 9 P 0 ;1
L 9.3575 1.2075 9.3575 1.2075 9 P 0 ;1
L 9.3575 1.2575 9.3575 1.2575 9 P 0 ;1
L 9.3575 1.3075 9.3575 1.3075 9 P 0 ;1
L 9.3575 1.3575 9.3575 1.3575 9 P 0 ;1
L 9.3575 1.4075 9.3575 1.4075 9 P 0 ;1
L 9.3575 1.4575 9.3575 1.4575 9 P 0 ;1
L 9.3575 1.5075 9.3575 1.5075 9 P 0 ;1
L 9.3575 1.5575 9.3575 1.5575 9 P 0 ;1
L 9.3575 1.6075 9.3575 1.6075 9 P 0 ;1
L 9.3575 1.6575 9.3575 1.6575 9 P 0 ;1
L 9.3575 1.7075 9.3575 1.7075 9 P 0 ;1
L 9.3575 1.7575 9.3575 1.7575 9 P 0 ;1
L 9.3575 1.8075 9.3575 1.8075 9 P 0 ;1
L 9.3575 1.8575 9.3575 1.8575 9 P 0 ;1
L 9.3575 1.9075 9.3575 1.9075 9 P 0 ;1
L 9.3575 1.9575 9.3575 1.9575 9 P 0 ;1
L 9.3575 2.0075 9.3575 2.0075 9 P 0 ;1
L 9.3575 2.0575 9.3575 2.0575 9 P 0 ;1
L 9.3575 2.1075 9.3575 2.1075 9 P 0 ;1
L 9.3575 2.1575 9.3575 2.1575 9 P 0 ;1
L 9.3575 2.2075 9.3575 2.2075 9 P 0 ;1
L 9.3575 2.2575 9.3575 2.2575 9 P 0 ;1
L 9.3575 2.3075 9.3575 2.3075 9 P 0 ;1
L 9.3575 2.3575 9.3575 2.3575 9 P 0 ;1
L 9.3575 2.4075 9.3575 2.4075 9 P 0 ;1
L 9.3575 2.4575 9.3575 2.4575 9 P 0 ;1
L 9.3575 2.5075 9.3575 2.5075 9 P 0 ;1
L 9.3575 2.5575 9.3575 2.5575 9 P 0 ;1
L 9.3575 2.6075 9.3575 2.6075 9 P 0 ;1
L 9.3575 2.6575 9.3575 2.6575 9 P 0 ;1
L 9.3575 2.7075 9.3575 2.7075 9 P 0 ;1
L 9.3575 2.7575 9.3575 2.7575 9 P 0 ;1
L 9.3575 2.8075 9.3575 2.8075 9 P 0 ;1
L 9.3575 2.8575 9.3575 2.8575 9 P 0 ;1
L 9.3575 2.9075 9.3575 2.9075 9 P 0 ;1
L 9.3575 2.9575 9.3575 2.9575 9 P 0 ;1
L 9.3575 3.0075 9.3575 3.0075 9 P 0 ;1
L 9.3575 3.0575 9.3575 3.0575 9 P 0 ;1
L 9.3575 3.1075 9.3575 3.1075 9 P 0 ;1
L 9.3575 3.1575 9.3575 3.1575 9 P 0 ;1
L 9.3575 3.2075 9.3575 3.2075 9 P 0 ;1
L 9.3575 3.2575 9.3575 3.2575 9 P 0 ;1
L 9.3575 3.3075 9.3575 3.3075 9 P 0 ;1
L 9.3575 3.3575 9.3575 3.3575 9 P 0 ;1
L 9.3575 3.4075 9.3575 3.4075 9 P 0 ;1
L 9.3575 3.4575 9.3575 3.4575 9 P 0 ;1
L 9.3575 3.5075 9.3575 3.5075 9 P 0 ;1
L 9.3575 3.5575 9.3575 3.5575 9 P 0 ;1
L 9.3575 3.6075 9.3575 3.6075 9 P 0 ;1
L 9.3575 3.6575 9.3575 3.6575 9 P 0 ;1
L 9.3575 3.7075 9.3575 3.7075 9 P 0 ;1
L 9.3575 3.7575 9.3575 3.7575 9 P 0 ;1
L 9.3575 3.8075 9.3575 3.8075 9 P 0 ;1
L 9.3575 3.8575 9.3575 3.8575 9 P 0 ;1
L 9.3575 3.9075 9.3575 3.9075 9 P 0 ;1
L 9.3575 3.9575 9.3575 3.9575 9 P 0 ;1
L 9.3575 4.0075 9.3575 4.0075 9 P 0 ;1
L 9.3575 4.0575 9.3575 4.0575 9 P 0 ;1
L 9.3575 4.1075 9.3575 4.1075 9 P 0 ;1
L 9.3575 5.4075 9.3575 5.4075 9 P 0 ;1
L 9.3575 5.4575 9.3575 5.4575 9 P 0 ;1
L 9.3575 5.5075 9.3575 5.5075 9 P 0 ;1
L 9.3575 5.5575 9.3575 5.5575 9 P 0 ;1
L 9.3575 5.6075 9.3575 5.6075 9 P 0 ;1
L 9.3575 5.6575 9.3575 5.6575 9 P 0 ;1
L 9.3575 5.7075 9.3575 5.7075 9 P 0 ;1
L 9.3575 5.7575 9.3575 5.7575 9 P 0 ;1
L 9.3575 5.8075 9.3575 5.8075 9 P 0 ;1
L 9.3575 5.8575 9.3575 5.8575 9 P 0 ;1
L 9.3575 5.9075 9.3575 5.9075 9 P 0 ;1
L 9.4075 0.1575 9.4075 0.1575 9 P 0 ;1
L 9.4075 0.6075 9.4075 0.6075 9 P 0 ;1
L 9.4075 0.6575 9.4075 0.6575 9 P 0 ;1
L 9.4075 0.9075 9.4075 0.9075 9 P 0 ;1
L 9.4075 0.9575 9.4075 0.9575 9 P 0 ;1
L 9.4075 1.0075 9.4075 1.0075 9 P 0 ;1
L 9.4075 1.0575 9.4075 1.0575 9 P 0 ;1
L 9.4075 1.1075 9.4075 1.1075 9 P 0 ;1
L 9.4075 1.1575 9.4075 1.1575 9 P 0 ;1
L 9.4075 1.2075 9.4075 1.2075 9 P 0 ;1
L 9.4075 1.2575 9.4075 1.2575 9 P 0 ;1
L 9.4075 1.3075 9.4075 1.3075 9 P 0 ;1
L 9.4075 1.3575 9.4075 1.3575 9 P 0 ;1
L 9.4075 1.4075 9.4075 1.4075 9 P 0 ;1
L 9.4075 1.4575 9.4075 1.4575 9 P 0 ;1
L 9.4075 1.5075 9.4075 1.5075 9 P 0 ;1
L 9.4075 1.5575 9.4075 1.5575 9 P 0 ;1
L 9.4075 1.6075 9.4075 1.6075 9 P 0 ;1
L 9.4075 1.6575 9.4075 1.6575 9 P 0 ;1
L 9.4075 1.7075 9.4075 1.7075 9 P 0 ;1
L 9.4075 1.7575 9.4075 1.7575 9 P 0 ;1
L 9.4075 1.8075 9.4075 1.8075 9 P 0 ;1
L 9.4075 1.8575 9.4075 1.8575 9 P 0 ;1
L 9.4075 1.9075 9.4075 1.9075 9 P 0 ;1
L 9.4075 1.9575 9.4075 1.9575 9 P 0 ;1
L 9.4075 2.0075 9.4075 2.0075 9 P 0 ;1
L 9.4075 2.0575 9.4075 2.0575 9 P 0 ;1
L 9.4075 2.1075 9.4075 2.1075 9 P 0 ;1
L 9.4075 2.1575 9.4075 2.1575 9 P 0 ;1
L 9.4075 2.2075 9.4075 2.2075 9 P 0 ;1
L 9.4075 2.2575 9.4075 2.2575 9 P 0 ;1
L 9.4075 2.3075 9.4075 2.3075 9 P 0 ;1
L 9.4075 2.3575 9.4075 2.3575 9 P 0 ;1
L 9.4075 2.4075 9.4075 2.4075 9 P 0 ;1
L 9.4075 2.4575 9.4075 2.4575 9 P 0 ;1
L 9.4075 2.5075 9.4075 2.5075 9 P 0 ;1
L 9.4075 2.5575 9.4075 2.5575 9 P 0 ;1
L 9.4075 2.6075 9.4075 2.6075 9 P 0 ;1
L 9.4075 2.6575 9.4075 2.6575 9 P 0 ;1
L 9.4075 2.7075 9.4075 2.7075 9 P 0 ;1
L 9.4075 2.7575 9.4075 2.7575 9 P 0 ;1
L 9.4075 2.8075 9.4075 2.8075 9 P 0 ;1
L 9.4075 2.8575 9.4075 2.8575 9 P 0 ;1
L 9.4075 2.9075 9.4075 2.9075 9 P 0 ;1
L 9.4075 2.9575 9.4075 2.9575 9 P 0 ;1
L 9.4075 3.0075 9.4075 3.0075 9 P 0 ;1
L 9.4075 3.0575 9.4075 3.0575 9 P 0 ;1
L 9.4075 3.1075 9.4075 3.1075 9 P 0 ;1
L 9.4075 3.1575 9.4075 3.1575 9 P 0 ;1
L 9.4075 3.2075 9.4075 3.2075 9 P 0 ;1
L 9.4075 3.2575 9.4075 3.2575 9 P 0 ;1
L 9.4075 3.3075 9.4075 3.3075 9 P 0 ;1
L 9.4075 3.3575 9.4075 3.3575 9 P 0 ;1
L 9.4075 3.4075 9.4075 3.4075 9 P 0 ;1
L 9.4075 3.4575 9.4075 3.4575 9 P 0 ;1
L 9.4075 3.5075 9.4075 3.5075 9 P 0 ;1
L 9.4075 3.5575 9.4075 3.5575 9 P 0 ;1
L 9.4075 3.6075 9.4075 3.6075 9 P 0 ;1
L 9.4075 3.6575 9.4075 3.6575 9 P 0 ;1
L 9.4075 3.7075 9.4075 3.7075 9 P 0 ;1
L 9.4075 3.7575 9.4075 3.7575 9 P 0 ;1
L 9.4075 3.8075 9.4075 3.8075 9 P 0 ;1
L 9.4075 3.8575 9.4075 3.8575 9 P 0 ;1
L 9.4075 3.9075 9.4075 3.9075 9 P 0 ;1
L 9.4075 3.9575 9.4075 3.9575 9 P 0 ;1
L 9.4075 4.0075 9.4075 4.0075 9 P 0 ;1
L 9.4075 4.0575 9.4075 4.0575 9 P 0 ;1
L 9.4075 4.1075 9.4075 4.1075 9 P 0 ;1
L 9.4075 4.1575 9.4075 4.1575 9 P 0 ;1
L 9.4075 4.2075 9.4075 4.2075 9 P 0 ;1
L 9.4075 4.2575 9.4075 4.2575 9 P 0 ;1
L 9.4075 4.3075 9.4075 4.3075 9 P 0 ;1
L 9.4075 4.3575 9.4075 4.3575 9 P 0 ;1
L 9.4075 4.4075 9.4075 4.4075 9 P 0 ;1
L 9.4075 5.4575 9.4075 5.4575 9 P 0 ;1
L 9.4075 5.5075 9.4075 5.5075 9 P 0 ;1
L 9.4075 5.5575 9.4075 5.5575 9 P 0 ;1
L 9.4075 5.6075 9.4075 5.6075 9 P 0 ;1
L 9.4075 5.6575 9.4075 5.6575 9 P 0 ;1
L 9.4075 5.7075 9.4075 5.7075 9 P 0 ;1
L 9.4075 5.7575 9.4075 5.7575 9 P 0 ;1
L 9.4075 5.8075 9.4075 5.8075 9 P 0 ;1
L 9.4075 5.8575 9.4075 5.8575 9 P 0 ;1
L 9.4075 5.9075 9.4075 5.9075 9 P 0 ;1
L 9.4575 0.1575 9.4575 0.1575 9 P 0 ;1
L 9.4575 0.6075 9.4575 0.6075 9 P 0 ;1
L 9.4575 0.6575 9.4575 0.6575 9 P 0 ;1
L 9.4575 0.9075 9.4575 0.9075 9 P 0 ;1
L 9.4575 0.9575 9.4575 0.9575 9 P 0 ;1
L 9.4575 1.0075 9.4575 1.0075 9 P 0 ;1
L 9.4575 1.0575 9.4575 1.0575 9 P 0 ;1
L 9.4575 1.1075 9.4575 1.1075 9 P 0 ;1
L 9.4575 1.1575 9.4575 1.1575 9 P 0 ;1
L 9.4575 1.2075 9.4575 1.2075 9 P 0 ;1
L 9.4575 1.2575 9.4575 1.2575 9 P 0 ;1
L 9.4575 1.3075 9.4575 1.3075 9 P 0 ;1
L 9.4575 1.3575 9.4575 1.3575 9 P 0 ;1
L 9.4575 1.4075 9.4575 1.4075 9 P 0 ;1
L 9.4575 1.4575 9.4575 1.4575 9 P 0 ;1
L 9.4575 1.5075 9.4575 1.5075 9 P 0 ;1
L 9.4575 1.5575 9.4575 1.5575 9 P 0 ;1
L 9.4575 1.6075 9.4575 1.6075 9 P 0 ;1
L 9.4575 1.6575 9.4575 1.6575 9 P 0 ;1
L 9.4575 1.7075 9.4575 1.7075 9 P 0 ;1
L 9.4575 1.7575 9.4575 1.7575 9 P 0 ;1
L 9.4575 1.8075 9.4575 1.8075 9 P 0 ;1
L 9.4575 1.8575 9.4575 1.8575 9 P 0 ;1
L 9.4575 1.9075 9.4575 1.9075 9 P 0 ;1
L 9.4575 1.9575 9.4575 1.9575 9 P 0 ;1
L 9.4575 2.0075 9.4575 2.0075 9 P 0 ;1
L 9.4575 2.0575 9.4575 2.0575 9 P 0 ;1
L 9.4575 2.1075 9.4575 2.1075 9 P 0 ;1
L 9.4575 2.1575 9.4575 2.1575 9 P 0 ;1
L 9.4575 2.2075 9.4575 2.2075 9 P 0 ;1
L 9.4575 2.2575 9.4575 2.2575 9 P 0 ;1
L 9.4575 2.3075 9.4575 2.3075 9 P 0 ;1
L 9.4575 2.3575 9.4575 2.3575 9 P 0 ;1
L 9.4575 2.4075 9.4575 2.4075 9 P 0 ;1
L 9.4575 2.4575 9.4575 2.4575 9 P 0 ;1
L 9.4575 2.5075 9.4575 2.5075 9 P 0 ;1
L 9.4575 2.5575 9.4575 2.5575 9 P 0 ;1
L 9.4575 2.6075 9.4575 2.6075 9 P 0 ;1
L 9.4575 2.6575 9.4575 2.6575 9 P 0 ;1
L 9.4575 2.7075 9.4575 2.7075 9 P 0 ;1
L 9.4575 2.7575 9.4575 2.7575 9 P 0 ;1
L 9.4575 2.8075 9.4575 2.8075 9 P 0 ;1
L 9.4575 2.8575 9.4575 2.8575 9 P 0 ;1
L 9.4575 2.9075 9.4575 2.9075 9 P 0 ;1
L 9.4575 2.9575 9.4575 2.9575 9 P 0 ;1
L 9.4575 3.0075 9.4575 3.0075 9 P 0 ;1
L 9.4575 3.0575 9.4575 3.0575 9 P 0 ;1
L 9.4575 3.1075 9.4575 3.1075 9 P 0 ;1
L 9.4575 3.1575 9.4575 3.1575 9 P 0 ;1
L 9.4575 3.2075 9.4575 3.2075 9 P 0 ;1
L 9.4575 3.2575 9.4575 3.2575 9 P 0 ;1
L 9.4575 3.3075 9.4575 3.3075 9 P 0 ;1
L 9.4575 3.3575 9.4575 3.3575 9 P 0 ;1
L 9.4575 3.4075 9.4575 3.4075 9 P 0 ;1
L 9.4575 3.4575 9.4575 3.4575 9 P 0 ;1
L 9.4575 3.5075 9.4575 3.5075 9 P 0 ;1
L 9.4575 3.5575 9.4575 3.5575 9 P 0 ;1
L 9.4575 3.6075 9.4575 3.6075 9 P 0 ;1
L 9.4575 3.6575 9.4575 3.6575 9 P 0 ;1
L 9.4575 3.7075 9.4575 3.7075 9 P 0 ;1
L 9.4575 3.7575 9.4575 3.7575 9 P 0 ;1
L 9.4575 3.8075 9.4575 3.8075 9 P 0 ;1
L 9.4575 3.8575 9.4575 3.8575 9 P 0 ;1
L 9.4575 3.9075 9.4575 3.9075 9 P 0 ;1
L 9.4575 3.9575 9.4575 3.9575 9 P 0 ;1
L 9.4575 4.0075 9.4575 4.0075 9 P 0 ;1
L 9.4575 4.0575 9.4575 4.0575 9 P 0 ;1
L 9.4575 4.1075 9.4575 4.1075 9 P 0 ;1
L 9.4575 4.1575 9.4575 4.1575 9 P 0 ;1
L 9.4575 4.2075 9.4575 4.2075 9 P 0 ;1
L 9.4575 4.2575 9.4575 4.2575 9 P 0 ;1
L 9.4575 4.3075 9.4575 4.3075 9 P 0 ;1
L 9.4575 4.3575 9.4575 4.3575 9 P 0 ;1
L 9.4575 4.4075 9.4575 4.4075 9 P 0 ;1
L 9.4575 4.4575 9.4575 4.4575 9 P 0 ;1
L 9.4575 4.5075 9.4575 4.5075 9 P 0 ;1
L 9.4575 5.4075 9.4575 5.4075 9 P 0 ;1
L 9.4575 5.4575 9.4575 5.4575 9 P 0 ;1
L 9.4575 5.5075 9.4575 5.5075 9 P 0 ;1
L 9.4575 5.5575 9.4575 5.5575 9 P 0 ;1
L 9.4575 5.6075 9.4575 5.6075 9 P 0 ;1
L 9.4575 5.6575 9.4575 5.6575 9 P 0 ;1
L 9.4575 5.7075 9.4575 5.7075 9 P 0 ;1
L 9.4575 5.7575 9.4575 5.7575 9 P 0 ;1
L 9.4575 5.8075 9.4575 5.8075 9 P 0 ;1
L 9.4575 5.8575 9.4575 5.8575 9 P 0 ;1
L 9.4575 5.9075 9.4575 5.9075 9 P 0 ;1
L 9.5075 0.1575 9.5075 0.1575 9 P 0 ;1
L 9.5075 0.4575 9.5075 0.4575 9 P 0 ;1
L 9.5075 0.5575 9.5075 0.5575 9 P 0 ;1
L 9.5075 0.6075 9.5075 0.6075 9 P 0 ;1
L 9.5075 0.9075 9.5075 0.9075 9 P 0 ;1
L 9.5075 0.9575 9.5075 0.9575 9 P 0 ;1
L 9.5075 1.0075 9.5075 1.0075 9 P 0 ;1
L 9.5075 1.0575 9.5075 1.0575 9 P 0 ;1
L 9.5075 1.1075 9.5075 1.1075 9 P 0 ;1
L 9.5075 1.1575 9.5075 1.1575 9 P 0 ;1
L 9.5075 1.2075 9.5075 1.2075 9 P 0 ;1
L 9.5075 1.2575 9.5075 1.2575 9 P 0 ;1
L 9.5075 1.3075 9.5075 1.3075 9 P 0 ;1
L 9.5075 1.3575 9.5075 1.3575 9 P 0 ;1
L 9.5075 1.4075 9.5075 1.4075 9 P 0 ;1
L 9.5075 1.4575 9.5075 1.4575 9 P 0 ;1
L 9.5075 1.5075 9.5075 1.5075 9 P 0 ;1
L 9.5075 1.5575 9.5075 1.5575 9 P 0 ;1
L 9.5075 1.6075 9.5075 1.6075 9 P 0 ;1
L 9.5075 1.6575 9.5075 1.6575 9 P 0 ;1
L 9.5075 1.7075 9.5075 1.7075 9 P 0 ;1
L 9.5075 1.7575 9.5075 1.7575 9 P 0 ;1
L 9.5075 1.8075 9.5075 1.8075 9 P 0 ;1
L 9.5075 1.8575 9.5075 1.8575 9 P 0 ;1
L 9.5075 1.9075 9.5075 1.9075 9 P 0 ;1
L 9.5075 1.9575 9.5075 1.9575 9 P 0 ;1
L 9.5075 2.0075 9.5075 2.0075 9 P 0 ;1
L 9.5075 2.0575 9.5075 2.0575 9 P 0 ;1
L 9.5075 2.1075 9.5075 2.1075 9 P 0 ;1
L 9.5075 2.1575 9.5075 2.1575 9 P 0 ;1
L 9.5075 2.2075 9.5075 2.2075 9 P 0 ;1
L 9.5075 2.2575 9.5075 2.2575 9 P 0 ;1
L 9.5075 2.3075 9.5075 2.3075 9 P 0 ;1
L 9.5075 2.3575 9.5075 2.3575 9 P 0 ;1
L 9.5075 2.4075 9.5075 2.4075 9 P 0 ;1
L 9.5075 2.4575 9.5075 2.4575 9 P 0 ;1
L 9.5075 2.5075 9.5075 2.5075 9 P 0 ;1
L 9.5075 2.5575 9.5075 2.5575 9 P 0 ;1
L 9.5075 2.6075 9.5075 2.6075 9 P 0 ;1
L 9.5075 2.6575 9.5075 2.6575 9 P 0 ;1
L 9.5075 2.7075 9.5075 2.7075 9 P 0 ;1
L 9.5075 2.7575 9.5075 2.7575 9 P 0 ;1
L 9.5075 2.8075 9.5075 2.8075 9 P 0 ;1
L 9.5075 2.8575 9.5075 2.8575 9 P 0 ;1
L 9.5075 2.9075 9.5075 2.9075 9 P 0 ;1
L 9.5075 2.9575 9.5075 2.9575 9 P 0 ;1
L 9.5075 3.0075 9.5075 3.0075 9 P 0 ;1
L 9.5075 3.0575 9.5075 3.0575 9 P 0 ;1
L 9.5075 3.1075 9.5075 3.1075 9 P 0 ;1
L 9.5075 3.1575 9.5075 3.1575 9 P 0 ;1
L 9.5075 3.2075 9.5075 3.2075 9 P 0 ;1
L 9.5075 3.2575 9.5075 3.2575 9 P 0 ;1
L 9.5075 3.3075 9.5075 3.3075 9 P 0 ;1
L 9.5075 3.3575 9.5075 3.3575 9 P 0 ;1
L 9.5075 3.4075 9.5075 3.4075 9 P 0 ;1
L 9.5075 3.4575 9.5075 3.4575 9 P 0 ;1
L 9.5075 3.5075 9.5075 3.5075 9 P 0 ;1
L 9.5075 3.5575 9.5075 3.5575 9 P 0 ;1
L 9.5075 3.6075 9.5075 3.6075 9 P 0 ;1
L 9.5075 3.6575 9.5075 3.6575 9 P 0 ;1
L 9.5075 3.7075 9.5075 3.7075 9 P 0 ;1
L 9.5075 3.7575 9.5075 3.7575 9 P 0 ;1
L 9.5075 3.8075 9.5075 3.8075 9 P 0 ;1
L 9.5075 3.8575 9.5075 3.8575 9 P 0 ;1
L 9.5075 3.9075 9.5075 3.9075 9 P 0 ;1
L 9.5075 3.9575 9.5075 3.9575 9 P 0 ;1
L 9.5075 4.0075 9.5075 4.0075 9 P 0 ;1
L 9.5075 4.0575 9.5075 4.0575 9 P 0 ;1
L 9.5075 4.1075 9.5075 4.1075 9 P 0 ;1
L 9.5075 4.1575 9.5075 4.1575 9 P 0 ;1
L 9.5075 4.2075 9.5075 4.2075 9 P 0 ;1
L 9.5075 4.2575 9.5075 4.2575 9 P 0 ;1
L 9.5075 4.3075 9.5075 4.3075 9 P 0 ;1
L 9.5075 4.3575 9.5075 4.3575 9 P 0 ;1
L 9.5075 4.4075 9.5075 4.4075 9 P 0 ;1
L 9.5075 4.4575 9.5075 4.4575 9 P 0 ;1
L 9.5075 4.5075 9.5075 4.5075 9 P 0 ;1
L 9.5075 5.4075 9.5075 5.4075 9 P 0 ;1
L 9.5075 5.4575 9.5075 5.4575 9 P 0 ;1
L 9.5075 5.5075 9.5075 5.5075 9 P 0 ;1
L 9.5075 5.5575 9.5075 5.5575 9 P 0 ;1
L 9.5075 5.6075 9.5075 5.6075 9 P 0 ;1
L 9.5075 5.6575 9.5075 5.6575 9 P 0 ;1
L 9.5075 5.7075 9.5075 5.7075 9 P 0 ;1
L 9.5075 5.7575 9.5075 5.7575 9 P 0 ;1
L 9.5075 5.8075 9.5075 5.8075 9 P 0 ;1
L 9.5075 5.8575 9.5075 5.8575 9 P 0 ;1
L 9.5075 5.9075 9.5075 5.9075 9 P 0 ;1
L 9.5575 0.1575 9.5575 0.1575 9 P 0 ;1
L 9.5575 0.4575 9.5575 0.4575 9 P 0 ;1
L 9.5575 0.5075 9.5575 0.5075 9 P 0 ;1
L 9.5575 0.5575 9.5575 0.5575 9 P 0 ;1
L 9.5575 0.6075 9.5575 0.6075 9 P 0 ;1
L 9.5575 0.8075 9.5575 0.8075 9 P 0 ;1
L 9.5575 0.8575 9.5575 0.8575 9 P 0 ;1
L 9.5575 0.9075 9.5575 0.9075 9 P 0 ;1
L 9.5575 0.9575 9.5575 0.9575 9 P 0 ;1
L 9.5575 1.0075 9.5575 1.0075 9 P 0 ;1
L 9.5575 1.0575 9.5575 1.0575 9 P 0 ;1
L 9.5575 1.1075 9.5575 1.1075 9 P 0 ;1
L 9.5575 1.1575 9.5575 1.1575 9 P 0 ;1
L 9.5575 1.2075 9.5575 1.2075 9 P 0 ;1
L 9.5575 1.2575 9.5575 1.2575 9 P 0 ;1
L 9.5575 1.3075 9.5575 1.3075 9 P 0 ;1
L 9.5575 1.3575 9.5575 1.3575 9 P 0 ;1
L 9.5575 1.4075 9.5575 1.4075 9 P 0 ;1
L 9.5575 1.4575 9.5575 1.4575 9 P 0 ;1
L 9.5575 1.5075 9.5575 1.5075 9 P 0 ;1
L 9.5575 1.5575 9.5575 1.5575 9 P 0 ;1
L 9.5575 1.6075 9.5575 1.6075 9 P 0 ;1
L 9.5575 1.6575 9.5575 1.6575 9 P 0 ;1
L 9.5575 1.7075 9.5575 1.7075 9 P 0 ;1
L 9.5575 1.7575 9.5575 1.7575 9 P 0 ;1
L 9.5575 1.8075 9.5575 1.8075 9 P 0 ;1
L 9.5575 1.8575 9.5575 1.8575 9 P 0 ;1
L 9.5575 1.9075 9.5575 1.9075 9 P 0 ;1
L 9.5575 1.9575 9.5575 1.9575 9 P 0 ;1
L 9.5575 2.0075 9.5575 2.0075 9 P 0 ;1
L 9.5575 2.0575 9.5575 2.0575 9 P 0 ;1
L 9.5575 2.1075 9.5575 2.1075 9 P 0 ;1
L 9.5575 2.1575 9.5575 2.1575 9 P 0 ;1
L 9.5575 2.2075 9.5575 2.2075 9 P 0 ;1
L 9.5575 2.2575 9.5575 2.2575 9 P 0 ;1
L 9.5575 2.3075 9.5575 2.3075 9 P 0 ;1
L 9.5575 2.3575 9.5575 2.3575 9 P 0 ;1
L 9.5575 2.4075 9.5575 2.4075 9 P 0 ;1
L 9.5575 2.4575 9.5575 2.4575 9 P 0 ;1
L 9.5575 2.5075 9.5575 2.5075 9 P 0 ;1
L 9.5575 2.5575 9.5575 2.5575 9 P 0 ;1
L 9.5575 2.6075 9.5575 2.6075 9 P 0 ;1
L 9.5575 2.6575 9.5575 2.6575 9 P 0 ;1
L 9.5575 2.7075 9.5575 2.7075 9 P 0 ;1
L 9.5575 2.7575 9.5575 2.7575 9 P 0 ;1
L 9.5575 2.8075 9.5575 2.8075 9 P 0 ;1
L 9.5575 2.8575 9.5575 2.8575 9 P 0 ;1
L 9.5575 2.9075 9.5575 2.9075 9 P 0 ;1
L 9.5575 2.9575 9.5575 2.9575 9 P 0 ;1
L 9.5575 3.0075 9.5575 3.0075 9 P 0 ;1
L 9.5575 3.0575 9.5575 3.0575 9 P 0 ;1
L 9.5575 3.1075 9.5575 3.1075 9 P 0 ;1
L 9.5575 3.1575 9.5575 3.1575 9 P 0 ;1
L 9.5575 3.2075 9.5575 3.2075 9 P 0 ;1
L 9.5575 3.2575 9.5575 3.2575 9 P 0 ;1
L 9.5575 3.3075 9.5575 3.3075 9 P 0 ;1
L 9.5575 3.3575 9.5575 3.3575 9 P 0 ;1
L 9.5575 3.4075 9.5575 3.4075 9 P 0 ;1
L 9.5575 3.4575 9.5575 3.4575 9 P 0 ;1
L 9.5575 3.5075 9.5575 3.5075 9 P 0 ;1
L 9.5575 3.5575 9.5575 3.5575 9 P 0 ;1
L 9.5575 3.6075 9.5575 3.6075 9 P 0 ;1
L 9.5575 3.6575 9.5575 3.6575 9 P 0 ;1
L 9.5575 3.7075 9.5575 3.7075 9 P 0 ;1
L 9.5575 3.7575 9.5575 3.7575 9 P 0 ;1
L 9.5575 3.8075 9.5575 3.8075 9 P 0 ;1
L 9.5575 3.8575 9.5575 3.8575 9 P 0 ;1
L 9.5575 3.9075 9.5575 3.9075 9 P 0 ;1
L 9.5575 3.9575 9.5575 3.9575 9 P 0 ;1
L 9.5575 4.0075 9.5575 4.0075 9 P 0 ;1
L 9.5575 4.0575 9.5575 4.0575 9 P 0 ;1
L 9.5575 4.1075 9.5575 4.1075 9 P 0 ;1
L 9.5575 4.1575 9.5575 4.1575 9 P 0 ;1
L 9.5575 4.2075 9.5575 4.2075 9 P 0 ;1
L 9.5575 4.2575 9.5575 4.2575 9 P 0 ;1
L 9.5575 4.3075 9.5575 4.3075 9 P 0 ;1
L 9.5575 4.3575 9.5575 4.3575 9 P 0 ;1
L 9.5575 4.4075 9.5575 4.4075 9 P 0 ;1
L 9.5575 4.4575 9.5575 4.4575 9 P 0 ;1
L 9.5575 4.5075 9.5575 4.5075 9 P 0 ;1
L 9.5575 5.2575 9.5575 5.2575 9 P 0 ;1
L 9.5575 5.3075 9.5575 5.3075 9 P 0 ;1
L 9.5575 5.3575 9.5575 5.3575 9 P 0 ;1
L 9.5575 5.4075 9.5575 5.4075 9 P 0 ;1
L 9.5575 5.4575 9.5575 5.4575 9 P 0 ;1
L 9.5575 5.5075 9.5575 5.5075 9 P 0 ;1
L 9.5575 5.5575 9.5575 5.5575 9 P 0 ;1
L 9.5575 5.6075 9.5575 5.6075 9 P 0 ;1
L 9.5575 5.6575 9.5575 5.6575 9 P 0 ;1
L 9.5575 5.7075 9.5575 5.7075 9 P 0 ;1
L 9.5575 5.7575 9.5575 5.7575 9 P 0 ;1
L 9.5575 5.8075 9.5575 5.8075 9 P 0 ;1
L 9.5575 5.8575 9.5575 5.8575 9 P 0 ;1
L 9.5575 5.9075 9.5575 5.9075 9 P 0 ;1
L 9.6075 0.1575 9.6075 0.1575 9 P 0 ;1
L 9.6075 0.4575 9.6075 0.4575 9 P 0 ;1
L 9.6075 0.5075 9.6075 0.5075 9 P 0 ;1
L 9.6075 0.5575 9.6075 0.5575 9 P 0 ;1
L 9.6075 0.6075 9.6075 0.6075 9 P 0 ;1
L 9.6075 0.9075 9.6075 0.9075 9 P 0 ;1
L 9.6075 0.9575 9.6075 0.9575 9 P 0 ;1
L 9.6075 1.0075 9.6075 1.0075 9 P 0 ;1
L 9.6075 1.0575 9.6075 1.0575 9 P 0 ;1
L 9.6075 1.1075 9.6075 1.1075 9 P 0 ;1
L 9.6075 1.1575 9.6075 1.1575 9 P 0 ;1
L 9.6075 1.2075 9.6075 1.2075 9 P 0 ;1
L 9.6075 1.2575 9.6075 1.2575 9 P 0 ;1
L 9.6075 1.3075 9.6075 1.3075 9 P 0 ;1
L 9.6075 1.3575 9.6075 1.3575 9 P 0 ;1
L 9.6075 1.4075 9.6075 1.4075 9 P 0 ;1
L 9.6075 1.4575 9.6075 1.4575 9 P 0 ;1
L 9.6075 1.5075 9.6075 1.5075 9 P 0 ;1
L 9.6075 1.5575 9.6075 1.5575 9 P 0 ;1
L 9.6075 1.6075 9.6075 1.6075 9 P 0 ;1
L 9.6075 1.6575 9.6075 1.6575 9 P 0 ;1
L 9.6075 1.7075 9.6075 1.7075 9 P 0 ;1
L 9.6075 1.7575 9.6075 1.7575 9 P 0 ;1
L 9.6075 1.8075 9.6075 1.8075 9 P 0 ;1
L 9.6075 1.8575 9.6075 1.8575 9 P 0 ;1
L 9.6075 1.9075 9.6075 1.9075 9 P 0 ;1
L 9.6075 1.9575 9.6075 1.9575 9 P 0 ;1
L 9.6075 2.0075 9.6075 2.0075 9 P 0 ;1
L 9.6075 2.0575 9.6075 2.0575 9 P 0 ;1
L 9.6075 2.1075 9.6075 2.1075 9 P 0 ;1
L 9.6075 2.1575 9.6075 2.1575 9 P 0 ;1
L 9.6075 2.2075 9.6075 2.2075 9 P 0 ;1
L 9.6075 2.2575 9.6075 2.2575 9 P 0 ;1
L 9.6075 2.3075 9.6075 2.3075 9 P 0 ;1
L 9.6075 2.3575 9.6075 2.3575 9 P 0 ;1
L 9.6075 2.4075 9.6075 2.4075 9 P 0 ;1
L 9.6075 2.4575 9.6075 2.4575 9 P 0 ;1
L 9.6075 2.5075 9.6075 2.5075 9 P 0 ;1
L 9.6075 2.5575 9.6075 2.5575 9 P 0 ;1
L 9.6075 2.6075 9.6075 2.6075 9 P 0 ;1
L 9.6075 2.6575 9.6075 2.6575 9 P 0 ;1
L 9.6075 2.7075 9.6075 2.7075 9 P 0 ;1
L 9.6075 2.7575 9.6075 2.7575 9 P 0 ;1
L 9.6075 2.8075 9.6075 2.8075 9 P 0 ;1
L 9.6075 2.8575 9.6075 2.8575 9 P 0 ;1
L 9.6075 2.9075 9.6075 2.9075 9 P 0 ;1
L 9.6075 2.9575 9.6075 2.9575 9 P 0 ;1
L 9.6075 3.0075 9.6075 3.0075 9 P 0 ;1
L 9.6075 3.0575 9.6075 3.0575 9 P 0 ;1
L 9.6075 3.1075 9.6075 3.1075 9 P 0 ;1
L 9.6075 3.1575 9.6075 3.1575 9 P 0 ;1
L 9.6075 3.2075 9.6075 3.2075 9 P 0 ;1
L 9.6075 3.2575 9.6075 3.2575 9 P 0 ;1
L 9.6075 3.3075 9.6075 3.3075 9 P 0 ;1
L 9.6075 3.3575 9.6075 3.3575 9 P 0 ;1
L 9.6075 3.4075 9.6075 3.4075 9 P 0 ;1
L 9.6075 3.4575 9.6075 3.4575 9 P 0 ;1
L 9.6075 3.5075 9.6075 3.5075 9 P 0 ;1
L 9.6075 3.5575 9.6075 3.5575 9 P 0 ;1
L 9.6075 3.6075 9.6075 3.6075 9 P 0 ;1
L 9.6075 3.6575 9.6075 3.6575 9 P 0 ;1
L 9.6075 3.7075 9.6075 3.7075 9 P 0 ;1
L 9.6075 3.7575 9.6075 3.7575 9 P 0 ;1
L 9.6075 3.8075 9.6075 3.8075 9 P 0 ;1
L 9.6075 3.8575 9.6075 3.8575 9 P 0 ;1
L 9.6075 3.9075 9.6075 3.9075 9 P 0 ;1
L 9.6075 3.9575 9.6075 3.9575 9 P 0 ;1
L 9.6075 4.0075 9.6075 4.0075 9 P 0 ;1
L 9.6075 4.0575 9.6075 4.0575 9 P 0 ;1
L 9.6075 4.1075 9.6075 4.1075 9 P 0 ;1
L 9.6075 4.1575 9.6075 4.1575 9 P 0 ;1
L 9.6075 4.2075 9.6075 4.2075 9 P 0 ;1
L 9.6075 4.2575 9.6075 4.2575 9 P 0 ;1
L 9.6075 4.3075 9.6075 4.3075 9 P 0 ;1
L 9.6075 4.3575 9.6075 4.3575 9 P 0 ;1
L 9.6075 4.4075 9.6075 4.4075 9 P 0 ;1
L 9.6075 4.4575 9.6075 4.4575 9 P 0 ;1
L 9.6075 4.5075 9.6075 4.5075 9 P 0 ;1
L 9.6075 4.5575 9.6075 4.5575 9 P 0 ;1
L 9.6075 4.6075 9.6075 4.6075 9 P 0 ;1
L 9.6075 5.2575 9.6075 5.2575 9 P 0 ;1
L 9.6075 5.3075 9.6075 5.3075 9 P 0 ;1
L 9.6075 5.3575 9.6075 5.3575 9 P 0 ;1
L 9.6075 5.4075 9.6075 5.4075 9 P 0 ;1
L 9.6075 5.4575 9.6075 5.4575 9 P 0 ;1
L 9.6075 5.5075 9.6075 5.5075 9 P 0 ;1
L 9.6075 5.5575 9.6075 5.5575 9 P 0 ;1
L 9.6075 5.6075 9.6075 5.6075 9 P 0 ;1
L 9.6075 5.6575 9.6075 5.6575 9 P 0 ;1
L 9.6075 5.7075 9.6075 5.7075 9 P 0 ;1
L 9.6075 5.7575 9.6075 5.7575 9 P 0 ;1
L 9.6075 5.8075 9.6075 5.8075 9 P 0 ;1
L 9.6075 5.8575 9.6075 5.8575 9 P 0 ;1
L 9.6075 5.9075 9.6075 5.9075 9 P 0 ;1
L 9.6575 0.1575 9.6575 0.1575 9 P 0 ;1
L 9.6575 0.2075 9.6575 0.2075 9 P 0 ;1
L 9.6575 0.2575 9.6575 0.2575 9 P 0 ;1
L 9.6575 0.3075 9.6575 0.3075 9 P 0 ;1
L 9.6575 0.3575 9.6575 0.3575 9 P 0 ;1
L 9.6575 0.4075 9.6575 0.4075 9 P 0 ;1
L 9.6575 0.4575 9.6575 0.4575 9 P 0 ;1
L 9.6575 0.5075 9.6575 0.5075 9 P 0 ;1
L 9.6575 0.5575 9.6575 0.5575 9 P 0 ;1
L 9.6575 0.6075 9.6575 0.6075 9 P 0 ;1
L 9.6575 0.9075 9.6575 0.9075 9 P 0 ;1
L 9.6575 0.9575 9.6575 0.9575 9 P 0 ;1
L 9.6575 1.0075 9.6575 1.0075 9 P 0 ;1
L 9.6575 1.0575 9.6575 1.0575 9 P 0 ;1
L 9.6575 1.1075 9.6575 1.1075 9 P 0 ;1
L 9.6575 1.1575 9.6575 1.1575 9 P 0 ;1
L 9.6575 1.2075 9.6575 1.2075 9 P 0 ;1
L 9.6575 1.2575 9.6575 1.2575 9 P 0 ;1
L 9.6575 1.3075 9.6575 1.3075 9 P 0 ;1
L 9.6575 1.3575 9.6575 1.3575 9 P 0 ;1
L 9.6575 1.4075 9.6575 1.4075 9 P 0 ;1
L 9.6575 1.4575 9.6575 1.4575 9 P 0 ;1
L 9.6575 1.5075 9.6575 1.5075 9 P 0 ;1
L 9.6575 1.5575 9.6575 1.5575 9 P 0 ;1
L 9.6575 1.6075 9.6575 1.6075 9 P 0 ;1
L 9.6575 1.6575 9.6575 1.6575 9 P 0 ;1
L 9.6575 1.7075 9.6575 1.7075 9 P 0 ;1
L 9.6575 1.7575 9.6575 1.7575 9 P 0 ;1
L 9.6575 1.8075 9.6575 1.8075 9 P 0 ;1
L 9.6575 1.8575 9.6575 1.8575 9 P 0 ;1
L 9.6575 1.9075 9.6575 1.9075 9 P 0 ;1
L 9.6575 1.9575 9.6575 1.9575 9 P 0 ;1
L 9.6575 2.0075 9.6575 2.0075 9 P 0 ;1
L 9.6575 2.0575 9.6575 2.0575 9 P 0 ;1
L 9.6575 2.1075 9.6575 2.1075 9 P 0 ;1
L 9.6575 2.1575 9.6575 2.1575 9 P 0 ;1
L 9.6575 2.2075 9.6575 2.2075 9 P 0 ;1
L 9.6575 2.2575 9.6575 2.2575 9 P 0 ;1
L 9.6575 2.3075 9.6575 2.3075 9 P 0 ;1
L 9.6575 2.3575 9.6575 2.3575 9 P 0 ;1
L 9.6575 2.4075 9.6575 2.4075 9 P 0 ;1
L 9.6575 2.4575 9.6575 2.4575 9 P 0 ;1
L 9.6575 2.5075 9.6575 2.5075 9 P 0 ;1
L 9.6575 2.5575 9.6575 2.5575 9 P 0 ;1
L 9.6575 2.6075 9.6575 2.6075 9 P 0 ;1
L 9.6575 2.6575 9.6575 2.6575 9 P 0 ;1
L 9.6575 2.7075 9.6575 2.7075 9 P 0 ;1
L 9.6575 2.7575 9.6575 2.7575 9 P 0 ;1
L 9.6575 2.8075 9.6575 2.8075 9 P 0 ;1
L 9.6575 2.8575 9.6575 2.8575 9 P 0 ;1
L 9.6575 2.9075 9.6575 2.9075 9 P 0 ;1
L 9.6575 2.9575 9.6575 2.9575 9 P 0 ;1
L 9.6575 3.0075 9.6575 3.0075 9 P 0 ;1
L 9.6575 3.0575 9.6575 3.0575 9 P 0 ;1
L 9.6575 3.1075 9.6575 3.1075 9 P 0 ;1
L 9.6575 3.1575 9.6575 3.1575 9 P 0 ;1
L 9.6575 3.2075 9.6575 3.2075 9 P 0 ;1
L 9.6575 3.2575 9.6575 3.2575 9 P 0 ;1
L 9.6575 3.3075 9.6575 3.3075 9 P 0 ;1
L 9.6575 3.3575 9.6575 3.3575 9 P 0 ;1
L 9.6575 3.4075 9.6575 3.4075 9 P 0 ;1
L 9.6575 3.4575 9.6575 3.4575 9 P 0 ;1
L 9.6575 3.5075 9.6575 3.5075 9 P 0 ;1
L 9.6575 3.5575 9.6575 3.5575 9 P 0 ;1
L 9.6575 3.6075 9.6575 3.6075 9 P 0 ;1
L 9.6575 3.6575 9.6575 3.6575 9 P 0 ;1
L 9.6575 3.7075 9.6575 3.7075 9 P 0 ;1
L 9.6575 3.7575 9.6575 3.7575 9 P 0 ;1
L 9.6575 3.8075 9.6575 3.8075 9 P 0 ;1
L 9.6575 3.8575 9.6575 3.8575 9 P 0 ;1
L 9.6575 3.9075 9.6575 3.9075 9 P 0 ;1
L 9.6575 3.9575 9.6575 3.9575 9 P 0 ;1
L 9.6575 4.0075 9.6575 4.0075 9 P 0 ;1
L 9.6575 4.0575 9.6575 4.0575 9 P 0 ;1
L 9.6575 4.1075 9.6575 4.1075 9 P 0 ;1
L 9.6575 4.1575 9.6575 4.1575 9 P 0 ;1
L 9.6575 4.2075 9.6575 4.2075 9 P 0 ;1
L 9.6575 4.2575 9.6575 4.2575 9 P 0 ;1
L 9.6575 4.3075 9.6575 4.3075 9 P 0 ;1
L 9.6575 4.3575 9.6575 4.3575 9 P 0 ;1
L 9.6575 4.4075 9.6575 4.4075 9 P 0 ;1
L 9.6575 4.4575 9.6575 4.4575 9 P 0 ;1
L 9.6575 4.5075 9.6575 4.5075 9 P 0 ;1
L 9.6575 4.5575 9.6575 4.5575 9 P 0 ;1
L 9.6575 4.6075 9.6575 4.6075 9 P 0 ;1
L 9.6575 4.6575 9.6575 4.6575 9 P 0 ;1
L 9.6575 5.1575 9.6575 5.1575 9 P 0 ;1
L 9.6575 5.2075 9.6575 5.2075 9 P 0 ;1
L 9.6575 5.2575 9.6575 5.2575 9 P 0 ;1
L 9.6575 5.3075 9.6575 5.3075 9 P 0 ;1
L 9.6575 5.3575 9.6575 5.3575 9 P 0 ;1
L 9.6575 5.4075 9.6575 5.4075 9 P 0 ;1
L 9.6575 5.4575 9.6575 5.4575 9 P 0 ;1
L 9.6575 5.5075 9.6575 5.5075 9 P 0 ;1
L 9.6575 5.5575 9.6575 5.5575 9 P 0 ;1
L 9.6575 5.6075 9.6575 5.6075 9 P 0 ;1
L 9.6575 5.6575 9.6575 5.6575 9 P 0 ;1
L 9.6575 5.7075 9.6575 5.7075 9 P 0 ;1
L 9.6575 5.7575 9.6575 5.7575 9 P 0 ;1
L 9.6575 5.8075 9.6575 5.8075 9 P 0 ;1
L 9.6575 5.8575 9.6575 5.8575 9 P 0 ;1
L 9.6575 5.9075 9.6575 5.9075 9 P 0 ;1
L 9.7075 0.1575 9.7075 0.1575 9 P 0 ;1
L 9.7075 0.2075 9.7075 0.2075 9 P 0 ;1
L 9.7075 0.2575 9.7075 0.2575 9 P 0 ;1
L 9.7075 0.3075 9.7075 0.3075 9 P 0 ;1
L 9.7075 0.3575 9.7075 0.3575 9 P 0 ;1
L 9.7075 0.4075 9.7075 0.4075 9 P 0 ;1
L 9.7075 0.4575 9.7075 0.4575 9 P 0 ;1
L 9.7075 0.5075 9.7075 0.5075 9 P 0 ;1
L 9.7075 0.5575 9.7075 0.5575 9 P 0 ;1
L 9.7075 0.6075 9.7075 0.6075 9 P 0 ;1
L 9.7075 0.6575 9.7075 0.6575 9 P 0 ;1
L 9.7075 0.8575 9.7075 0.8575 9 P 0 ;1
L 9.7075 0.9075 9.7075 0.9075 9 P 0 ;1
L 9.7075 0.9575 9.7075 0.9575 9 P 0 ;1
L 9.7075 1.0075 9.7075 1.0075 9 P 0 ;1
L 9.7075 1.0575 9.7075 1.0575 9 P 0 ;1
L 9.7075 1.1075 9.7075 1.1075 9 P 0 ;1
L 9.7075 1.1575 9.7075 1.1575 9 P 0 ;1
L 9.7075 1.2075 9.7075 1.2075 9 P 0 ;1
L 9.7075 1.2575 9.7075 1.2575 9 P 0 ;1
L 9.7075 1.3075 9.7075 1.3075 9 P 0 ;1
L 9.7075 1.3575 9.7075 1.3575 9 P 0 ;1
L 9.7075 1.4075 9.7075 1.4075 9 P 0 ;1
L 9.7075 1.4575 9.7075 1.4575 9 P 0 ;1
L 9.7075 1.5075 9.7075 1.5075 9 P 0 ;1
L 9.7075 1.5575 9.7075 1.5575 9 P 0 ;1
L 9.7075 1.6075 9.7075 1.6075 9 P 0 ;1
L 9.7075 1.6575 9.7075 1.6575 9 P 0 ;1
L 9.7075 1.7075 9.7075 1.7075 9 P 0 ;1
L 9.7075 1.7575 9.7075 1.7575 9 P 0 ;1
L 9.7075 1.8075 9.7075 1.8075 9 P 0 ;1
L 9.7075 1.8575 9.7075 1.8575 9 P 0 ;1
L 9.7075 1.9075 9.7075 1.9075 9 P 0 ;1
L 9.7075 1.9575 9.7075 1.9575 9 P 0 ;1
L 9.7075 2.0075 9.7075 2.0075 9 P 0 ;1
L 9.7075 2.0575 9.7075 2.0575 9 P 0 ;1
L 9.7075 2.1075 9.7075 2.1075 9 P 0 ;1
L 9.7075 2.1575 9.7075 2.1575 9 P 0 ;1
L 9.7075 2.2075 9.7075 2.2075 9 P 0 ;1
L 9.7075 2.2575 9.7075 2.2575 9 P 0 ;1
L 9.7075 2.3075 9.7075 2.3075 9 P 0 ;1
L 9.7075 2.3575 9.7075 2.3575 9 P 0 ;1
L 9.7075 2.4075 9.7075 2.4075 9 P 0 ;1
L 9.7075 2.4575 9.7075 2.4575 9 P 0 ;1
L 9.7075 2.5075 9.7075 2.5075 9 P 0 ;1
L 9.7075 2.5575 9.7075 2.5575 9 P 0 ;1
L 9.7075 2.6075 9.7075 2.6075 9 P 0 ;1
L 9.7075 2.6575 9.7075 2.6575 9 P 0 ;1
L 9.7075 2.7075 9.7075 2.7075 9 P 0 ;1
L 9.7075 2.7575 9.7075 2.7575 9 P 0 ;1
L 9.7075 2.8075 9.7075 2.8075 9 P 0 ;1
L 9.7075 2.8575 9.7075 2.8575 9 P 0 ;1
L 9.7075 2.9075 9.7075 2.9075 9 P 0 ;1
L 9.7075 2.9575 9.7075 2.9575 9 P 0 ;1
L 9.7075 3.0075 9.7075 3.0075 9 P 0 ;1
L 9.7075 3.0575 9.7075 3.0575 9 P 0 ;1
L 9.7075 3.1075 9.7075 3.1075 9 P 0 ;1
L 9.7075 3.1575 9.7075 3.1575 9 P 0 ;1
L 9.7075 3.2075 9.7075 3.2075 9 P 0 ;1
L 9.7075 3.2575 9.7075 3.2575 9 P 0 ;1
L 9.7075 3.3075 9.7075 3.3075 9 P 0 ;1
L 9.7075 3.3575 9.7075 3.3575 9 P 0 ;1
L 9.7075 3.4075 9.7075 3.4075 9 P 0 ;1
L 9.7075 3.4575 9.7075 3.4575 9 P 0 ;1
L 9.7075 3.5075 9.7075 3.5075 9 P 0 ;1
L 9.7075 3.5575 9.7075 3.5575 9 P 0 ;1
L 9.7075 3.6075 9.7075 3.6075 9 P 0 ;1
L 9.7075 3.6575 9.7075 3.6575 9 P 0 ;1
L 9.7075 3.7075 9.7075 3.7075 9 P 0 ;1
L 9.7075 3.7575 9.7075 3.7575 9 P 0 ;1
L 9.7075 3.8075 9.7075 3.8075 9 P 0 ;1
L 9.7075 3.8575 9.7075 3.8575 9 P 0 ;1
L 9.7075 3.9075 9.7075 3.9075 9 P 0 ;1
L 9.7075 3.9575 9.7075 3.9575 9 P 0 ;1
L 9.7075 4.0075 9.7075 4.0075 9 P 0 ;1
L 9.7075 4.0575 9.7075 4.0575 9 P 0 ;1
L 9.7075 4.1075 9.7075 4.1075 9 P 0 ;1
L 9.7075 4.1575 9.7075 4.1575 9 P 0 ;1
L 9.7075 4.2075 9.7075 4.2075 9 P 0 ;1
L 9.7075 4.2575 9.7075 4.2575 9 P 0 ;1
L 9.7075 4.3075 9.7075 4.3075 9 P 0 ;1
L 9.7075 4.3575 9.7075 4.3575 9 P 0 ;1
L 9.7075 4.4075 9.7075 4.4075 9 P 0 ;1
L 9.7075 4.4575 9.7075 4.4575 9 P 0 ;1
L 9.7075 4.5075 9.7075 4.5075 9 P 0 ;1
L 9.7075 4.5575 9.7075 4.5575 9 P 0 ;1
L 9.7075 4.6075 9.7075 4.6075 9 P 0 ;1
L 9.7075 4.6575 9.7075 4.6575 9 P 0 ;1
L 9.7075 4.7075 9.7075 4.7075 9 P 0 ;1
L 9.7075 4.7575 9.7075 4.7575 9 P 0 ;1
L 9.7075 4.8075 9.7075 4.8075 9 P 0 ;1
L 9.7075 4.8575 9.7075 4.8575 9 P 0 ;1
L 9.7075 4.9075 9.7075 4.9075 9 P 0 ;1
L 9.7075 4.9575 9.7075 4.9575 9 P 0 ;1
L 9.7075 5.0075 9.7075 5.0075 9 P 0 ;1
L 9.7075 5.0575 9.7075 5.0575 9 P 0 ;1
L 9.7075 5.1075 9.7075 5.1075 9 P 0 ;1
L 9.7075 5.1575 9.7075 5.1575 9 P 0 ;1
L 9.7075 5.2075 9.7075 5.2075 9 P 0 ;1
L 9.7075 5.2575 9.7075 5.2575 9 P 0 ;1
L 9.7075 5.3075 9.7075 5.3075 9 P 0 ;1
L 9.7075 5.3575 9.7075 5.3575 9 P 0 ;1
L 9.7075 5.4075 9.7075 5.4075 9 P 0 ;1
L 9.7075 5.4575 9.7075 5.4575 9 P 0 ;1
L 9.7075 5.5075 9.7075 5.5075 9 P 0 ;1
L 9.7075 5.5575 9.7075 5.5575 9 P 0 ;1
L 9.7075 5.6075 9.7075 5.6075 9 P 0 ;1
L 9.7075 5.6575 9.7075 5.6575 9 P 0 ;1
L 9.7075 5.7075 9.7075 5.7075 9 P 0 ;1
L 9.7075 5.7575 9.7075 5.7575 9 P 0 ;1
L 9.7075 5.8075 9.7075 5.8075 9 P 0 ;1
L 9.7075 5.8575 9.7075 5.8575 9 P 0 ;1
L 9.7075 5.9075 9.7075 5.9075 9 P 0 ;1
L 9.7575 0.1575 9.7575 0.1575 9 P 0 ;1
L 9.7575 0.2075 9.7575 0.2075 9 P 0 ;1
L 9.7575 0.2575 9.7575 0.2575 9 P 0 ;1
L 9.7575 0.3075 9.7575 0.3075 9 P 0 ;1
L 9.7575 0.3575 9.7575 0.3575 9 P 0 ;1
L 9.7575 0.4075 9.7575 0.4075 9 P 0 ;1
L 9.7575 0.4575 9.7575 0.4575 9 P 0 ;1
L 9.7575 0.5075 9.7575 0.5075 9 P 0 ;1
L 9.7575 0.5575 9.7575 0.5575 9 P 0 ;1
L 9.7575 0.6075 9.7575 0.6075 9 P 0 ;1
L 9.7575 0.6575 9.7575 0.6575 9 P 0 ;1
L 9.7575 0.7075 9.7575 0.7075 9 P 0 ;1
L 9.7575 0.7575 9.7575 0.7575 9 P 0 ;1
L 9.7575 0.8075 9.7575 0.8075 9 P 0 ;1
L 9.7575 0.8575 9.7575 0.8575 9 P 0 ;1
L 9.7575 0.9075 9.7575 0.9075 9 P 0 ;1
L 9.7575 0.9575 9.7575 0.9575 9 P 0 ;1
L 9.7575 1.0075 9.7575 1.0075 9 P 0 ;1
L 9.7575 1.0575 9.7575 1.0575 9 P 0 ;1
L 9.7575 1.1075 9.7575 1.1075 9 P 0 ;1
L 9.7575 1.1575 9.7575 1.1575 9 P 0 ;1
L 9.7575 1.2075 9.7575 1.2075 9 P 0 ;1
L 9.7575 1.2575 9.7575 1.2575 9 P 0 ;1
L 9.7575 1.3075 9.7575 1.3075 9 P 0 ;1
L 9.7575 1.3575 9.7575 1.3575 9 P 0 ;1
L 9.7575 1.4075 9.7575 1.4075 9 P 0 ;1
L 9.7575 1.4575 9.7575 1.4575 9 P 0 ;1
L 9.7575 1.5075 9.7575 1.5075 9 P 0 ;1
L 9.7575 1.5575 9.7575 1.5575 9 P 0 ;1
L 9.7575 1.6075 9.7575 1.6075 9 P 0 ;1
L 9.7575 1.6575 9.7575 1.6575 9 P 0 ;1
L 9.7575 1.7075 9.7575 1.7075 9 P 0 ;1
L 9.7575 1.7575 9.7575 1.7575 9 P 0 ;1
L 9.7575 1.8075 9.7575 1.8075 9 P 0 ;1
L 9.7575 1.8575 9.7575 1.8575 9 P 0 ;1
L 9.7575 1.9075 9.7575 1.9075 9 P 0 ;1
L 9.7575 1.9575 9.7575 1.9575 9 P 0 ;1
L 9.7575 2.0075 9.7575 2.0075 9 P 0 ;1
L 9.7575 2.0575 9.7575 2.0575 9 P 0 ;1
L 9.7575 2.1075 9.7575 2.1075 9 P 0 ;1
L 9.7575 2.1575 9.7575 2.1575 9 P 0 ;1
L 9.7575 2.2075 9.7575 2.2075 9 P 0 ;1
L 9.7575 2.2575 9.7575 2.2575 9 P 0 ;1
L 9.7575 2.3075 9.7575 2.3075 9 P 0 ;1
L 9.7575 2.3575 9.7575 2.3575 9 P 0 ;1
L 9.7575 2.4075 9.7575 2.4075 9 P 0 ;1
L 9.7575 2.4575 9.7575 2.4575 9 P 0 ;1
L 9.7575 2.5075 9.7575 2.5075 9 P 0 ;1
L 9.7575 2.5575 9.7575 2.5575 9 P 0 ;1
L 9.7575 2.6075 9.7575 2.6075 9 P 0 ;1
L 9.7575 2.6575 9.7575 2.6575 9 P 0 ;1
L 9.7575 2.7075 9.7575 2.7075 9 P 0 ;1
L 9.7575 2.7575 9.7575 2.7575 9 P 0 ;1
L 9.7575 2.8075 9.7575 2.8075 9 P 0 ;1
L 9.7575 2.8575 9.7575 2.8575 9 P 0 ;1
L 9.7575 2.9075 9.7575 2.9075 9 P 0 ;1
L 9.7575 2.9575 9.7575 2.9575 9 P 0 ;1
L 9.7575 3.0075 9.7575 3.0075 9 P 0 ;1
L 9.7575 3.0575 9.7575 3.0575 9 P 0 ;1
L 9.7575 3.1075 9.7575 3.1075 9 P 0 ;1
L 9.7575 3.1575 9.7575 3.1575 9 P 0 ;1
L 9.7575 3.2075 9.7575 3.2075 9 P 0 ;1
L 9.7575 3.2575 9.7575 3.2575 9 P 0 ;1
L 9.7575 3.3075 9.7575 3.3075 9 P 0 ;1
L 9.7575 3.3575 9.7575 3.3575 9 P 0 ;1
L 9.7575 3.4075 9.7575 3.4075 9 P 0 ;1
L 9.7575 3.4575 9.7575 3.4575 9 P 0 ;1
L 9.7575 3.5075 9.7575 3.5075 9 P 0 ;1
L 9.7575 3.5575 9.7575 3.5575 9 P 0 ;1
L 9.7575 3.6075 9.7575 3.6075 9 P 0 ;1
L 9.7575 3.6575 9.7575 3.6575 9 P 0 ;1
L 9.7575 3.7075 9.7575 3.7075 9 P 0 ;1
L 9.7575 3.7575 9.7575 3.7575 9 P 0 ;1
L 9.7575 3.8075 9.7575 3.8075 9 P 0 ;1
L 9.7575 3.8575 9.7575 3.8575 9 P 0 ;1
L 9.7575 3.9075 9.7575 3.9075 9 P 0 ;1
L 9.7575 3.9575 9.7575 3.9575 9 P 0 ;1
L 9.7575 4.0075 9.7575 4.0075 9 P 0 ;1
L 9.7575 4.0575 9.7575 4.0575 9 P 0 ;1
L 9.7575 4.1075 9.7575 4.1075 9 P 0 ;1
L 9.7575 4.1575 9.7575 4.1575 9 P 0 ;1
L 9.7575 4.2075 9.7575 4.2075 9 P 0 ;1
L 9.7575 4.2575 9.7575 4.2575 9 P 0 ;1
L 9.7575 4.3075 9.7575 4.3075 9 P 0 ;1
L 9.7575 4.3575 9.7575 4.3575 9 P 0 ;1
L 9.7575 4.4075 9.7575 4.4075 9 P 0 ;1
L 9.7575 4.4575 9.7575 4.4575 9 P 0 ;1
L 9.7575 4.5075 9.7575 4.5075 9 P 0 ;1
L 9.7575 4.5575 9.7575 4.5575 9 P 0 ;1
L 9.7575 4.6075 9.7575 4.6075 9 P 0 ;1
L 9.7575 4.6575 9.7575 4.6575 9 P 0 ;1
L 9.7575 4.7075 9.7575 4.7075 9 P 0 ;1
L 9.7575 4.7575 9.7575 4.7575 9 P 0 ;1
L 9.7575 4.8075 9.7575 4.8075 9 P 0 ;1
L 9.7575 4.8575 9.7575 4.8575 9 P 0 ;1
L 9.7575 4.9075 9.7575 4.9075 9 P 0 ;1
L 9.7575 4.9575 9.7575 4.9575 9 P 0 ;1
L 9.7575 5.0075 9.7575 5.0075 9 P 0 ;1
L 9.7575 5.0575 9.7575 5.0575 9 P 0 ;1
L 9.7575 5.1075 9.7575 5.1075 9 P 0 ;1
L 9.7575 5.1575 9.7575 5.1575 9 P 0 ;1
L 9.7575 5.2075 9.7575 5.2075 9 P 0 ;1
L 9.7575 5.2575 9.7575 5.2575 9 P 0 ;1
L 9.7575 5.3075 9.7575 5.3075 9 P 0 ;1
L 9.7575 5.3575 9.7575 5.3575 9 P 0 ;1
L 9.7575 5.4075 9.7575 5.4075 9 P 0 ;1
L 9.7575 5.4575 9.7575 5.4575 9 P 0 ;1
L 9.7575 5.5075 9.7575 5.5075 9 P 0 ;1
L 9.7575 5.5575 9.7575 5.5575 9 P 0 ;1
L 9.7575 5.6075 9.7575 5.6075 9 P 0 ;1
L 9.7575 5.6575 9.7575 5.6575 9 P 0 ;1
L 9.7575 5.7075 9.7575 5.7075 9 P 0 ;1
L 9.7575 5.7575 9.7575 5.7575 9 P 0 ;1
L 9.7575 5.8075 9.7575 5.8075 9 P 0 ;1
L 9.7575 5.8575 9.7575 5.8575 9 P 0 ;1
L 9.7575 5.9075 9.7575 5.9075 9 P 0 ;1
L 9.8075 0.1575 9.8075 0.1575 9 P 0 ;1
L 9.8075 0.2075 9.8075 0.2075 9 P 0 ;1
L 9.8075 0.2575 9.8075 0.2575 9 P 0 ;1
L 9.8075 0.3075 9.8075 0.3075 9 P 0 ;1
L 9.8075 0.3575 9.8075 0.3575 9 P 0 ;1
L 9.8075 0.4075 9.8075 0.4075 9 P 0 ;1
L 9.8075 0.4575 9.8075 0.4575 9 P 0 ;1
L 9.8075 0.5075 9.8075 0.5075 9 P 0 ;1
L 9.8075 0.5575 9.8075 0.5575 9 P 0 ;1
L 9.8075 0.6075 9.8075 0.6075 9 P 0 ;1
L 9.8075 0.6575 9.8075 0.6575 9 P 0 ;1
L 9.8075 0.7075 9.8075 0.7075 9 P 0 ;1
L 9.8075 0.7575 9.8075 0.7575 9 P 0 ;1
L 9.8075 0.8075 9.8075 0.8075 9 P 0 ;1
L 9.8075 0.8575 9.8075 0.8575 9 P 0 ;1
L 9.8075 0.9075 9.8075 0.9075 9 P 0 ;1
L 9.8075 0.9575 9.8075 0.9575 9 P 0 ;1
L 9.8075 1.0075 9.8075 1.0075 9 P 0 ;1
L 9.8075 1.0575 9.8075 1.0575 9 P 0 ;1
L 9.8075 1.1075 9.8075 1.1075 9 P 0 ;1
L 9.8075 1.1575 9.8075 1.1575 9 P 0 ;1
L 9.8075 1.2075 9.8075 1.2075 9 P 0 ;1
L 9.8075 1.2575 9.8075 1.2575 9 P 0 ;1
L 9.8075 1.3075 9.8075 1.3075 9 P 0 ;1
L 9.8075 1.3575 9.8075 1.3575 9 P 0 ;1
L 9.8075 1.4075 9.8075 1.4075 9 P 0 ;1
L 9.8075 1.4575 9.8075 1.4575 9 P 0 ;1
L 9.8075 1.5075 9.8075 1.5075 9 P 0 ;1
L 9.8075 1.5575 9.8075 1.5575 9 P 0 ;1
L 9.8075 1.6075 9.8075 1.6075 9 P 0 ;1
L 9.8075 1.6575 9.8075 1.6575 9 P 0 ;1
L 9.8075 1.7075 9.8075 1.7075 9 P 0 ;1
L 9.8075 1.7575 9.8075 1.7575 9 P 0 ;1
L 9.8075 1.8075 9.8075 1.8075 9 P 0 ;1
L 9.8075 1.8575 9.8075 1.8575 9 P 0 ;1
L 9.8075 1.9075 9.8075 1.9075 9 P 0 ;1
L 9.8075 1.9575 9.8075 1.9575 9 P 0 ;1
L 9.8075 2.0075 9.8075 2.0075 9 P 0 ;1
L 9.8075 2.0575 9.8075 2.0575 9 P 0 ;1
L 9.8075 2.1075 9.8075 2.1075 9 P 0 ;1
L 9.8075 2.1575 9.8075 2.1575 9 P 0 ;1
L 9.8075 2.2075 9.8075 2.2075 9 P 0 ;1
L 9.8075 2.2575 9.8075 2.2575 9 P 0 ;1
L 9.8075 2.3075 9.8075 2.3075 9 P 0 ;1
L 9.8075 2.3575 9.8075 2.3575 9 P 0 ;1
L 9.8075 2.4075 9.8075 2.4075 9 P 0 ;1
L 9.8075 2.4575 9.8075 2.4575 9 P 0 ;1
L 9.8075 2.5075 9.8075 2.5075 9 P 0 ;1
L 9.8075 2.5575 9.8075 2.5575 9 P 0 ;1
L 9.8075 2.6075 9.8075 2.6075 9 P 0 ;1
L 9.8075 2.6575 9.8075 2.6575 9 P 0 ;1
L 9.8075 2.7075 9.8075 2.7075 9 P 0 ;1
L 9.8075 2.7575 9.8075 2.7575 9 P 0 ;1
L 9.8075 2.8075 9.8075 2.8075 9 P 0 ;1
L 9.8075 2.8575 9.8075 2.8575 9 P 0 ;1
L 9.8075 4.6575 9.8075 4.6575 9 P 0 ;1
L 9.8075 4.7075 9.8075 4.7075 9 P 0 ;1
L 9.8075 4.7575 9.8075 4.7575 9 P 0 ;1
L 9.8075 4.8075 9.8075 4.8075 9 P 0 ;1
L 9.8075 4.8575 9.8075 4.8575 9 P 0 ;1
L 9.8075 4.9075 9.8075 4.9075 9 P 0 ;1
L 9.8075 4.9575 9.8075 4.9575 9 P 0 ;1
L 9.8075 5.0075 9.8075 5.0075 9 P 0 ;1
L 9.8075 5.0575 9.8075 5.0575 9 P 0 ;1
L 9.8075 5.1075 9.8075 5.1075 9 P 0 ;1
L 9.8075 5.1575 9.8075 5.1575 9 P 0 ;1
L 9.8075 5.2075 9.8075 5.2075 9 P 0 ;1
L 9.8075 5.2575 9.8075 5.2575 9 P 0 ;1
L 9.8075 5.3075 9.8075 5.3075 9 P 0 ;1
L 9.8075 5.3575 9.8075 5.3575 9 P 0 ;1
L 9.8075 5.4075 9.8075 5.4075 9 P 0 ;1
L 9.8075 5.4575 9.8075 5.4575 9 P 0 ;1
L 9.8075 5.5075 9.8075 5.5075 9 P 0 ;1
L 9.8075 5.5575 9.8075 5.5575 9 P 0 ;1
L 9.8075 5.6075 9.8075 5.6075 9 P 0 ;1
L 9.8075 5.6575 9.8075 5.6575 9 P 0 ;1
L 9.8075 5.7075 9.8075 5.7075 9 P 0 ;1
L 9.8075 5.7575 9.8075 5.7575 9 P 0 ;1
L 9.8075 5.8075 9.8075 5.8075 9 P 0 ;1
L 9.8075 5.8575 9.8075 5.8575 9 P 0 ;1
L 9.8075 5.9075 9.8075 5.9075 9 P 0 ;1
L 9.8575 0.1575 9.8575 0.1575 9 P 0 ;1
L 9.8575 0.2075 9.8575 0.2075 9 P 0 ;1
L 9.8575 0.2575 9.8575 0.2575 9 P 0 ;1
L 9.8575 0.3075 9.8575 0.3075 9 P 0 ;1
L 9.8575 0.3575 9.8575 0.3575 9 P 0 ;1
L 9.8575 0.4075 9.8575 0.4075 9 P 0 ;1
L 9.8575 0.4575 9.8575 0.4575 9 P 0 ;1
L 9.8575 0.5075 9.8575 0.5075 9 P 0 ;1
L 9.8575 0.5575 9.8575 0.5575 9 P 0 ;1
L 9.8575 0.6075 9.8575 0.6075 9 P 0 ;1
L 9.8575 0.6575 9.8575 0.6575 9 P 0 ;1
L 9.8575 0.7075 9.8575 0.7075 9 P 0 ;1
L 9.8575 0.7575 9.8575 0.7575 9 P 0 ;1
L 9.8575 0.8075 9.8575 0.8075 9 P 0 ;1
L 9.8575 0.8575 9.8575 0.8575 9 P 0 ;1
L 9.8575 0.9075 9.8575 0.9075 9 P 0 ;1
L 9.8575 0.9575 9.8575 0.9575 9 P 0 ;1
L 9.8575 1.0075 9.8575 1.0075 9 P 0 ;1
L 9.8575 1.0575 9.8575 1.0575 9 P 0 ;1
L 9.8575 1.1075 9.8575 1.1075 9 P 0 ;1
L 9.8575 1.1575 9.8575 1.1575 9 P 0 ;1
L 9.8575 1.2075 9.8575 1.2075 9 P 0 ;1
L 9.8575 1.2575 9.8575 1.2575 9 P 0 ;1
L 9.8575 1.3075 9.8575 1.3075 9 P 0 ;1
L 9.8575 1.3575 9.8575 1.3575 9 P 0 ;1
L 9.8575 1.4075 9.8575 1.4075 9 P 0 ;1
L 9.8575 1.4575 9.8575 1.4575 9 P 0 ;1
L 9.8575 1.5075 9.8575 1.5075 9 P 0 ;1
L 9.8575 1.5575 9.8575 1.5575 9 P 0 ;1
L 9.8575 1.6075 9.8575 1.6075 9 P 0 ;1
L 9.8575 1.6575 9.8575 1.6575 9 P 0 ;1
L 9.8575 1.7075 9.8575 1.7075 9 P 0 ;1
L 9.8575 1.7575 9.8575 1.7575 9 P 0 ;1
L 9.8575 1.8075 9.8575 1.8075 9 P 0 ;1
L 9.8575 1.8575 9.8575 1.8575 9 P 0 ;1
L 9.8575 1.9075 9.8575 1.9075 9 P 0 ;1
L 9.8575 1.9575 9.8575 1.9575 9 P 0 ;1
L 9.8575 2.0075 9.8575 2.0075 9 P 0 ;1
L 9.8575 2.0575 9.8575 2.0575 9 P 0 ;1
L 9.8575 2.1075 9.8575 2.1075 9 P 0 ;1
L 9.8575 2.1575 9.8575 2.1575 9 P 0 ;1
L 9.8575 2.2075 9.8575 2.2075 9 P 0 ;1
L 9.8575 2.2575 9.8575 2.2575 9 P 0 ;1
L 9.8575 2.3075 9.8575 2.3075 9 P 0 ;1
L 9.8575 2.3575 9.8575 2.3575 9 P 0 ;1
L 9.8575 2.4075 9.8575 2.4075 9 P 0 ;1
L 9.8575 2.4575 9.8575 2.4575 9 P 0 ;1
L 9.8575 2.5075 9.8575 2.5075 9 P 0 ;1
L 9.8575 2.5575 9.8575 2.5575 9 P 0 ;1
L 9.8575 2.6075 9.8575 2.6075 9 P 0 ;1
L 9.8575 2.6575 9.8575 2.6575 9 P 0 ;1
L 9.8575 2.7075 9.8575 2.7075 9 P 0 ;1
L 9.8575 2.7575 9.8575 2.7575 9 P 0 ;1
L 9.8575 2.8075 9.8575 2.8075 9 P 0 ;1
L 9.8575 4.8075 9.8575 4.8075 9 P 0 ;1
L 9.8575 4.8575 9.8575 4.8575 9 P 0 ;1
L 9.8575 4.9075 9.8575 4.9075 9 P 0 ;1
L 9.8575 4.9575 9.8575 4.9575 9 P 0 ;1
L 9.8575 5.0075 9.8575 5.0075 9 P 0 ;1
L 9.8575 5.0575 9.8575 5.0575 9 P 0 ;1
L 9.8575 5.1075 9.8575 5.1075 9 P 0 ;1
L 9.8575 5.1575 9.8575 5.1575 9 P 0 ;1
L 9.8575 5.2075 9.8575 5.2075 9 P 0 ;1
L 9.8575 5.2575 9.8575 5.2575 9 P 0 ;1
L 9.8575 5.3075 9.8575 5.3075 9 P 0 ;1
L 9.8575 5.3575 9.8575 5.3575 9 P 0 ;1
L 9.8575 5.4075 9.8575 5.4075 9 P 0 ;1
L 9.8575 5.4575 9.8575 5.4575 9 P 0 ;1
L 9.8575 5.5075 9.8575 5.5075 9 P 0 ;1
L 9.8575 5.5575 9.8575 5.5575 9 P 0 ;1
L 9.8575 5.6075 9.8575 5.6075 9 P 0 ;1
L 9.8575 5.6575 9.8575 5.6575 9 P 0 ;1
L 9.8575 5.7075 9.8575 5.7075 9 P 0 ;1
L 9.8575 5.7575 9.8575 5.7575 9 P 0 ;1
L 9.8575 5.8075 9.8575 5.8075 9 P 0 ;1
L 9.8575 5.8575 9.8575 5.8575 9 P 0 ;1
L 9.8575 5.9075 9.8575 5.9075 9 P 0 ;1
L 9.9075 0.1575 9.9075 0.1575 9 P 0 ;1
L 9.9075 0.2075 9.9075 0.2075 9 P 0 ;1
L 9.9075 0.2575 9.9075 0.2575 9 P 0 ;1
L 9.9075 0.3075 9.9075 0.3075 9 P 0 ;1
L 9.9075 0.3575 9.9075 0.3575 9 P 0 ;1
L 9.9075 0.4075 9.9075 0.4075 9 P 0 ;1
L 9.9075 0.4575 9.9075 0.4575 9 P 0 ;1
L 9.9075 0.5075 9.9075 0.5075 9 P 0 ;1
L 9.9075 0.5575 9.9075 0.5575 9 P 0 ;1
L 9.9075 0.6075 9.9075 0.6075 9 P 0 ;1
L 9.9075 0.6575 9.9075 0.6575 9 P 0 ;1
L 9.9075 0.7075 9.9075 0.7075 9 P 0 ;1
L 9.9075 0.7575 9.9075 0.7575 9 P 0 ;1
L 9.9075 0.8075 9.9075 0.8075 9 P 0 ;1
L 9.9075 0.8575 9.9075 0.8575 9 P 0 ;1
L 9.9075 0.9075 9.9075 0.9075 9 P 0 ;1
L 9.9075 0.9575 9.9075 0.9575 9 P 0 ;1
L 9.9075 1.0075 9.9075 1.0075 9 P 0 ;1
L 9.9075 1.0575 9.9075 1.0575 9 P 0 ;1
L 9.9075 1.1075 9.9075 1.1075 9 P 0 ;1
L 9.9075 1.1575 9.9075 1.1575 9 P 0 ;1
L 9.9075 1.2075 9.9075 1.2075 9 P 0 ;1
L 9.9075 1.2575 9.9075 1.2575 9 P 0 ;1
L 9.9075 1.3075 9.9075 1.3075 9 P 0 ;1
L 9.9075 1.3575 9.9075 1.3575 9 P 0 ;1
L 9.9075 1.4075 9.9075 1.4075 9 P 0 ;1
L 9.9075 1.4575 9.9075 1.4575 9 P 0 ;1
L 9.9075 1.5075 9.9075 1.5075 9 P 0 ;1
L 9.9075 1.5575 9.9075 1.5575 9 P 0 ;1
L 9.9075 1.6075 9.9075 1.6075 9 P 0 ;1
L 9.9075 1.6575 9.9075 1.6575 9 P 0 ;1
L 9.9075 1.7075 9.9075 1.7075 9 P 0 ;1
L 9.9075 1.7575 9.9075 1.7575 9 P 0 ;1
L 9.9075 1.8075 9.9075 1.8075 9 P 0 ;1
L 9.9075 1.8575 9.9075 1.8575 9 P 0 ;1
L 9.9075 1.9075 9.9075 1.9075 9 P 0 ;1
L 9.9075 1.9575 9.9075 1.9575 9 P 0 ;1
L 9.9075 2.0075 9.9075 2.0075 9 P 0 ;1
L 9.9075 2.0575 9.9075 2.0575 9 P 0 ;1
L 9.9075 2.1075 9.9075 2.1075 9 P 0 ;1
L 9.9075 2.7575 9.9075 2.7575 9 P 0 ;1
L 9.9075 4.8075 9.9075 4.8075 9 P 0 ;1
L 9.9075 4.8575 9.9075 4.8575 9 P 0 ;1
L 9.9075 4.9075 9.9075 4.9075 9 P 0 ;1
L 9.9075 4.9575 9.9075 4.9575 9 P 0 ;1
L 9.9075 5.0075 9.9075 5.0075 9 P 0 ;1
L 9.9075 5.0575 9.9075 5.0575 9 P 0 ;1
L 9.9075 5.1075 9.9075 5.1075 9 P 0 ;1
L 9.9075 5.1575 9.9075 5.1575 9 P 0 ;1
L 9.9075 5.2075 9.9075 5.2075 9 P 0 ;1
L 9.9075 5.2575 9.9075 5.2575 9 P 0 ;1
L 9.9075 5.3075 9.9075 5.3075 9 P 0 ;1
L 9.9075 5.3575 9.9075 5.3575 9 P 0 ;1
L 9.9075 5.4075 9.9075 5.4075 9 P 0 ;1
L 9.9075 5.4575 9.9075 5.4575 9 P 0 ;1
L 9.9075 5.5075 9.9075 5.5075 9 P 0 ;1
L 9.9075 5.5575 9.9075 5.5575 9 P 0 ;1
L 9.9075 5.6075 9.9075 5.6075 9 P 0 ;1
L 9.9075 5.6575 9.9075 5.6575 9 P 0 ;1
L 9.9075 5.7075 9.9075 5.7075 9 P 0 ;1
L 9.9075 5.7575 9.9075 5.7575 9 P 0 ;1
L 9.9075 5.8075 9.9075 5.8075 9 P 0 ;1
L 9.9075 5.8575 9.9075 5.8575 9 P 0 ;1
L 9.9075 5.9075 9.9075 5.9075 9 P 0 ;1
L 9.9575 0.1575 9.9575 0.1575 9 P 0 ;1
L 9.9575 0.2075 9.9575 0.2075 9 P 0 ;1
L 9.9575 0.2575 9.9575 0.2575 9 P 0 ;1
L 9.9575 0.3075 9.9575 0.3075 9 P 0 ;1
L 9.9575 0.3575 9.9575 0.3575 9 P 0 ;1
L 9.9575 0.4075 9.9575 0.4075 9 P 0 ;1
L 9.9575 0.4575 9.9575 0.4575 9 P 0 ;1
L 9.9575 0.5075 9.9575 0.5075 9 P 0 ;1
L 9.9575 0.5575 9.9575 0.5575 9 P 0 ;1
L 9.9575 0.6075 9.9575 0.6075 9 P 0 ;1
L 9.9575 0.6575 9.9575 0.6575 9 P 0 ;1
L 9.9575 0.7075 9.9575 0.7075 9 P 0 ;1
L 9.9575 0.7575 9.9575 0.7575 9 P 0 ;1
L 9.9575 0.8075 9.9575 0.8075 9 P 0 ;1
L 9.9575 0.8575 9.9575 0.8575 9 P 0 ;1
L 9.9575 0.9075 9.9575 0.9075 9 P 0 ;1
L 9.9575 0.9575 9.9575 0.9575 9 P 0 ;1
L 9.9575 1.0075 9.9575 1.0075 9 P 0 ;1
L 9.9575 1.0575 9.9575 1.0575 9 P 0 ;1
L 9.9575 1.1075 9.9575 1.1075 9 P 0 ;1
L 9.9575 1.1575 9.9575 1.1575 9 P 0 ;1
L 9.9575 1.2075 9.9575 1.2075 9 P 0 ;1
L 9.9575 1.2575 9.9575 1.2575 9 P 0 ;1
L 9.9575 1.3075 9.9575 1.3075 9 P 0 ;1
L 9.9575 1.3575 9.9575 1.3575 9 P 0 ;1
L 9.9575 1.4075 9.9575 1.4075 9 P 0 ;1
L 9.9575 1.4575 9.9575 1.4575 9 P 0 ;1
L 9.9575 1.5075 9.9575 1.5075 9 P 0 ;1
L 9.9575 1.5575 9.9575 1.5575 9 P 0 ;1
L 9.9575 1.6075 9.9575 1.6075 9 P 0 ;1
L 9.9575 1.6575 9.9575 1.6575 9 P 0 ;1
L 9.9575 1.7075 9.9575 1.7075 9 P 0 ;1
L 9.9575 1.7575 9.9575 1.7575 9 P 0 ;1
L 9.9575 1.8075 9.9575 1.8075 9 P 0 ;1
L 9.9575 1.8575 9.9575 1.8575 9 P 0 ;1
L 9.9575 1.9075 9.9575 1.9075 9 P 0 ;1
L 9.9575 1.9575 9.9575 1.9575 9 P 0 ;1
L 9.9575 2.0075 9.9575 2.0075 9 P 0 ;1
L 9.9575 2.0575 9.9575 2.0575 9 P 0 ;1
L 9.9575 2.1075 9.9575 2.1075 9 P 0 ;1
L 9.9575 4.8075 9.9575 4.8075 9 P 0 ;1
L 9.9575 4.8575 9.9575 4.8575 9 P 0 ;1
L 9.9575 4.9075 9.9575 4.9075 9 P 0 ;1
L 9.9575 4.9575 9.9575 4.9575 9 P 0 ;1
L 9.9575 5.0075 9.9575 5.0075 9 P 0 ;1
L 9.9575 5.0575 9.9575 5.0575 9 P 0 ;1
L 9.9575 5.1075 9.9575 5.1075 9 P 0 ;1
L 9.9575 5.1575 9.9575 5.1575 9 P 0 ;1
L 9.9575 5.2075 9.9575 5.2075 9 P 0 ;1
L 9.9575 5.2575 9.9575 5.2575 9 P 0 ;1
L 9.9575 5.3075 9.9575 5.3075 9 P 0 ;1
L 9.9575 5.5575 9.9575 5.5575 9 P 0 ;1
L 9.9575 5.6075 9.9575 5.6075 9 P 0 ;1
L 9.9575 5.6575 9.9575 5.6575 9 P 0 ;1
L 9.9575 5.7075 9.9575 5.7075 9 P 0 ;1
L 9.9575 5.7575 9.9575 5.7575 9 P 0 ;1
L 9.9575 5.8075 9.9575 5.8075 9 P 0 ;1
L 9.9575 5.8575 9.9575 5.8575 9 P 0 ;1
L 9.9575 5.9075 9.9575 5.9075 9 P 0 ;1
L 10.0075 0.1575 10.0075 0.1575 9 P 0 ;1
L 10.0075 0.2075 10.0075 0.2075 9 P 0 ;1
L 10.0075 0.2575 10.0075 0.2575 9 P 0 ;1
L 10.0075 0.3075 10.0075 0.3075 9 P 0 ;1
L 10.0075 0.3575 10.0075 0.3575 9 P 0 ;1
L 10.0075 0.4075 10.0075 0.4075 9 P 0 ;1
L 10.0075 0.4575 10.0075 0.4575 9 P 0 ;1
L 10.0075 0.5075 10.0075 0.5075 9 P 0 ;1
L 10.0075 0.5575 10.0075 0.5575 9 P 0 ;1
L 10.0075 0.6075 10.0075 0.6075 9 P 0 ;1
L 10.0075 0.6575 10.0075 0.6575 9 P 0 ;1
L 10.0075 0.7075 10.0075 0.7075 9 P 0 ;1
L 10.0075 0.7575 10.0075 0.7575 9 P 0 ;1
L 10.0075 0.8075 10.0075 0.8075 9 P 0 ;1
L 10.0075 0.8575 10.0075 0.8575 9 P 0 ;1
L 10.0075 0.9075 10.0075 0.9075 9 P 0 ;1
L 10.0075 0.9575 10.0075 0.9575 9 P 0 ;1
L 10.0075 1.0075 10.0075 1.0075 9 P 0 ;1
L 10.0075 1.0575 10.0075 1.0575 9 P 0 ;1
L 10.0075 1.1075 10.0075 1.1075 9 P 0 ;1
L 10.0075 1.1575 10.0075 1.1575 9 P 0 ;1
L 10.0075 1.2075 10.0075 1.2075 9 P 0 ;1
L 10.0075 1.2575 10.0075 1.2575 9 P 0 ;1
L 10.0075 1.3075 10.0075 1.3075 9 P 0 ;1
L 10.0075 1.3575 10.0075 1.3575 9 P 0 ;1
L 10.0075 1.4075 10.0075 1.4075 9 P 0 ;1
L 10.0075 1.4575 10.0075 1.4575 9 P 0 ;1
L 10.0075 1.5075 10.0075 1.5075 9 P 0 ;1
L 10.0075 1.5575 10.0075 1.5575 9 P 0 ;1
L 10.0075 1.6075 10.0075 1.6075 9 P 0 ;1
L 10.0075 1.6575 10.0075 1.6575 9 P 0 ;1
L 10.0075 1.7075 10.0075 1.7075 9 P 0 ;1
L 10.0075 1.7575 10.0075 1.7575 9 P 0 ;1
L 10.0075 1.8075 10.0075 1.8075 9 P 0 ;1
L 10.0075 1.8575 10.0075 1.8575 9 P 0 ;1
L 10.0075 1.9075 10.0075 1.9075 9 P 0 ;1
L 10.0075 1.9575 10.0075 1.9575 9 P 0 ;1
L 10.0075 2.0075 10.0075 2.0075 9 P 0 ;1
L 10.0075 2.0575 10.0075 2.0575 9 P 0 ;1
L 10.0075 2.1075 10.0075 2.1075 9 P 0 ;1
L 10.0075 3.0575 10.0075 3.0575 9 P 0 ;1
L 10.0075 3.1075 10.0075 3.1075 9 P 0 ;1
L 10.0075 3.1575 10.0075 3.1575 9 P 0 ;1
L 10.0075 3.2075 10.0075 3.2075 9 P 0 ;1
L 10.0075 3.2575 10.0075 3.2575 9 P 0 ;1
L 10.0075 3.3075 10.0075 3.3075 9 P 0 ;1
L 10.0075 3.3575 10.0075 3.3575 9 P 0 ;1
L 10.0075 3.4075 10.0075 3.4075 9 P 0 ;1
L 10.0075 3.4575 10.0075 3.4575 9 P 0 ;1
L 10.0075 3.5075 10.0075 3.5075 9 P 0 ;1
L 10.0075 3.5575 10.0075 3.5575 9 P 0 ;1
L 10.0075 3.6075 10.0075 3.6075 9 P 0 ;1
L 10.0075 3.6575 10.0075 3.6575 9 P 0 ;1
L 10.0075 3.7075 10.0075 3.7075 9 P 0 ;1
L 10.0075 3.7575 10.0075 3.7575 9 P 0 ;1
L 10.0075 3.8075 10.0075 3.8075 9 P 0 ;1
L 10.0075 3.8575 10.0075 3.8575 9 P 0 ;1
L 10.0075 3.9075 10.0075 3.9075 9 P 0 ;1
L 10.0075 3.9575 10.0075 3.9575 9 P 0 ;1
L 10.0075 4.0075 10.0075 4.0075 9 P 0 ;1
L 10.0075 4.0575 10.0075 4.0575 9 P 0 ;1
L 10.0075 4.1075 10.0075 4.1075 9 P 0 ;1
L 10.0075 4.1575 10.0075 4.1575 9 P 0 ;1
L 10.0075 4.2075 10.0075 4.2075 9 P 0 ;1
L 10.0075 4.2575 10.0075 4.2575 9 P 0 ;1
L 10.0075 4.3075 10.0075 4.3075 9 P 0 ;1
L 10.0075 4.3575 10.0075 4.3575 9 P 0 ;1
L 10.0075 4.4075 10.0075 4.4075 9 P 0 ;1
L 10.0075 4.7575 10.0075 4.7575 9 P 0 ;1
L 10.0075 4.8075 10.0075 4.8075 9 P 0 ;1
L 10.0075 4.8575 10.0075 4.8575 9 P 0 ;1
L 10.0075 4.9075 10.0075 4.9075 9 P 0 ;1
L 10.0075 4.9575 10.0075 4.9575 9 P 0 ;1
L 10.0075 5.0075 10.0075 5.0075 9 P 0 ;1
L 10.0075 5.0575 10.0075 5.0575 9 P 0 ;1
L 10.0075 5.1075 10.0075 5.1075 9 P 0 ;1
L 10.0075 5.1575 10.0075 5.1575 9 P 0 ;1
L 10.0075 5.2075 10.0075 5.2075 9 P 0 ;1
L 10.0075 5.2575 10.0075 5.2575 9 P 0 ;1
L 10.0075 5.6575 10.0075 5.6575 9 P 0 ;1
L 10.0075 5.7075 10.0075 5.7075 9 P 0 ;1
L 10.0075 5.7575 10.0075 5.7575 9 P 0 ;1
L 10.0075 5.8075 10.0075 5.8075 9 P 0 ;1
L 10.0075 5.8575 10.0075 5.8575 9 P 0 ;1
L 10.0075 5.9075 10.0075 5.9075 9 P 0 ;1
L 10.0575 0.1575 10.0575 0.1575 9 P 0 ;1
L 10.0575 0.2075 10.0575 0.2075 9 P 0 ;1
L 10.0575 0.2575 10.0575 0.2575 9 P 0 ;1
L 10.0575 0.3075 10.0575 0.3075 9 P 0 ;1
L 10.0575 0.3575 10.0575 0.3575 9 P 0 ;1
L 10.0575 0.4075 10.0575 0.4075 9 P 0 ;1
L 10.0575 0.4575 10.0575 0.4575 9 P 0 ;1
L 10.0575 0.5075 10.0575 0.5075 9 P 0 ;1
L 10.0575 0.5575 10.0575 0.5575 9 P 0 ;1
L 10.0575 0.6075 10.0575 0.6075 9 P 0 ;1
L 10.0575 0.6575 10.0575 0.6575 9 P 0 ;1
L 10.0575 0.7075 10.0575 0.7075 9 P 0 ;1
L 10.0575 0.7575 10.0575 0.7575 9 P 0 ;1
L 10.0575 0.8075 10.0575 0.8075 9 P 0 ;1
L 10.0575 0.8575 10.0575 0.8575 9 P 0 ;1
L 10.0575 0.9075 10.0575 0.9075 9 P 0 ;1
L 10.0575 0.9575 10.0575 0.9575 9 P 0 ;1
L 10.0575 1.0075 10.0575 1.0075 9 P 0 ;1
L 10.0575 1.0575 10.0575 1.0575 9 P 0 ;1
L 10.0575 1.1075 10.0575 1.1075 9 P 0 ;1
L 10.0575 1.1575 10.0575 1.1575 9 P 0 ;1
L 10.0575 1.2075 10.0575 1.2075 9 P 0 ;1
L 10.0575 1.2575 10.0575 1.2575 9 P 0 ;1
L 10.0575 1.3075 10.0575 1.3075 9 P 0 ;1
L 10.0575 1.3575 10.0575 1.3575 9 P 0 ;1
L 10.0575 1.4075 10.0575 1.4075 9 P 0 ;1
L 10.0575 1.4575 10.0575 1.4575 9 P 0 ;1
L 10.0575 1.5075 10.0575 1.5075 9 P 0 ;1
L 10.0575 1.5575 10.0575 1.5575 9 P 0 ;1
L 10.0575 1.6075 10.0575 1.6075 9 P 0 ;1
L 10.0575 1.6575 10.0575 1.6575 9 P 0 ;1
L 10.0575 1.7075 10.0575 1.7075 9 P 0 ;1
L 10.0575 1.7575 10.0575 1.7575 9 P 0 ;1
L 10.0575 1.8075 10.0575 1.8075 9 P 0 ;1
L 10.0575 1.8575 10.0575 1.8575 9 P 0 ;1
L 10.0575 1.9075 10.0575 1.9075 9 P 0 ;1
L 10.0575 3.0075 10.0575 3.0075 9 P 0 ;1
L 10.0575 3.0575 10.0575 3.0575 9 P 0 ;1
L 10.0575 3.1075 10.0575 3.1075 9 P 0 ;1
L 10.0575 3.1575 10.0575 3.1575 9 P 0 ;1
L 10.0575 3.2075 10.0575 3.2075 9 P 0 ;1
L 10.0575 3.2575 10.0575 3.2575 9 P 0 ;1
L 10.0575 3.3075 10.0575 3.3075 9 P 0 ;1
L 10.0575 3.3575 10.0575 3.3575 9 P 0 ;1
L 10.0575 3.4075 10.0575 3.4075 9 P 0 ;1
L 10.0575 3.4575 10.0575 3.4575 9 P 0 ;1
L 10.0575 3.5075 10.0575 3.5075 9 P 0 ;1
L 10.0575 3.5575 10.0575 3.5575 9 P 0 ;1
L 10.0575 3.6075 10.0575 3.6075 9 P 0 ;1
L 10.0575 3.6575 10.0575 3.6575 9 P 0 ;1
L 10.0575 3.7075 10.0575 3.7075 9 P 0 ;1
L 10.0575 3.7575 10.0575 3.7575 9 P 0 ;1
L 10.0575 3.8075 10.0575 3.8075 9 P 0 ;1
L 10.0575 3.8575 10.0575 3.8575 9 P 0 ;1
L 10.0575 3.9075 10.0575 3.9075 9 P 0 ;1
L 10.0575 3.9575 10.0575 3.9575 9 P 0 ;1
L 10.0575 4.0075 10.0575 4.0075 9 P 0 ;1
L 10.0575 4.0575 10.0575 4.0575 9 P 0 ;1
L 10.0575 4.1075 10.0575 4.1075 9 P 0 ;1
L 10.0575 4.1575 10.0575 4.1575 9 P 0 ;1
L 10.0575 4.2075 10.0575 4.2075 9 P 0 ;1
L 10.0575 4.2575 10.0575 4.2575 9 P 0 ;1
L 10.0575 4.3075 10.0575 4.3075 9 P 0 ;1
L 10.0575 4.3575 10.0575 4.3575 9 P 0 ;1
L 10.0575 4.4075 10.0575 4.4075 9 P 0 ;1
L 10.0575 4.7075 10.0575 4.7075 9 P 0 ;1
L 10.0575 4.7575 10.0575 4.7575 9 P 0 ;1
L 10.0575 4.8075 10.0575 4.8075 9 P 0 ;1
L 10.0575 4.8575 10.0575 4.8575 9 P 0 ;1
L 10.0575 4.9075 10.0575 4.9075 9 P 0 ;1
L 10.0575 4.9575 10.0575 4.9575 9 P 0 ;1
L 10.0575 5.0075 10.0575 5.0075 9 P 0 ;1
L 10.0575 5.0575 10.0575 5.0575 9 P 0 ;1
L 10.0575 5.1075 10.0575 5.1075 9 P 0 ;1
L 10.0575 5.1575 10.0575 5.1575 9 P 0 ;1
L 10.0575 5.2075 10.0575 5.2075 9 P 0 ;1
L 10.0575 5.7075 10.0575 5.7075 9 P 0 ;1
L 10.0575 5.7575 10.0575 5.7575 9 P 0 ;1
L 10.0575 5.8075 10.0575 5.8075 9 P 0 ;1
L 10.0575 5.8575 10.0575 5.8575 9 P 0 ;1
L 10.0575 5.9075 10.0575 5.9075 9 P 0 ;1
L 10.1075 0.1575 10.1075 0.1575 9 P 0 ;1
L 10.1075 0.2075 10.1075 0.2075 9 P 0 ;1
L 10.1075 0.2575 10.1075 0.2575 9 P 0 ;1
L 10.1075 0.3075 10.1075 0.3075 9 P 0 ;1
L 10.1075 0.3575 10.1075 0.3575 9 P 0 ;1
L 10.1075 0.4075 10.1075 0.4075 9 P 0 ;1
L 10.1075 0.4575 10.1075 0.4575 9 P 0 ;1
L 10.1075 0.5075 10.1075 0.5075 9 P 0 ;1
L 10.1075 0.5575 10.1075 0.5575 9 P 0 ;1
L 10.1075 0.6075 10.1075 0.6075 9 P 0 ;1
L 10.1075 0.6575 10.1075 0.6575 9 P 0 ;1
L 10.1075 0.7075 10.1075 0.7075 9 P 0 ;1
L 10.1075 0.7575 10.1075 0.7575 9 P 0 ;1
L 10.1075 0.8075 10.1075 0.8075 9 P 0 ;1
L 10.1075 0.8575 10.1075 0.8575 9 P 0 ;1
L 10.1075 0.9075 10.1075 0.9075 9 P 0 ;1
L 10.1075 0.9575 10.1075 0.9575 9 P 0 ;1
L 10.1075 1.0075 10.1075 1.0075 9 P 0 ;1
L 10.1075 1.0575 10.1075 1.0575 9 P 0 ;1
L 10.1075 1.1075 10.1075 1.1075 9 P 0 ;1
L 10.1075 1.1575 10.1075 1.1575 9 P 0 ;1
L 10.1075 1.2075 10.1075 1.2075 9 P 0 ;1
L 10.1075 1.2575 10.1075 1.2575 9 P 0 ;1
L 10.1075 1.3075 10.1075 1.3075 9 P 0 ;1
L 10.1075 1.3575 10.1075 1.3575 9 P 0 ;1
L 10.1075 1.4075 10.1075 1.4075 9 P 0 ;1
L 10.1075 1.4575 10.1075 1.4575 9 P 0 ;1
L 10.1075 1.5075 10.1075 1.5075 9 P 0 ;1
L 10.1075 1.5575 10.1075 1.5575 9 P 0 ;1
L 10.1075 1.6075 10.1075 1.6075 9 P 0 ;1
L 10.1075 1.6575 10.1075 1.6575 9 P 0 ;1
L 10.1075 1.7075 10.1075 1.7075 9 P 0 ;1
L 10.1075 1.7575 10.1075 1.7575 9 P 0 ;1
L 10.1075 1.8075 10.1075 1.8075 9 P 0 ;1
L 10.1075 1.8575 10.1075 1.8575 9 P 0 ;1
L 10.1075 1.9075 10.1075 1.9075 9 P 0 ;1
L 10.1075 3.0075 10.1075 3.0075 9 P 0 ;1
L 10.1075 3.0575 10.1075 3.0575 9 P 0 ;1
L 10.1075 3.1075 10.1075 3.1075 9 P 0 ;1
L 10.1075 3.1575 10.1075 3.1575 9 P 0 ;1
L 10.1075 3.2075 10.1075 3.2075 9 P 0 ;1
L 10.1075 3.2575 10.1075 3.2575 9 P 0 ;1
L 10.1075 3.3075 10.1075 3.3075 9 P 0 ;1
L 10.1075 3.3575 10.1075 3.3575 9 P 0 ;1
L 10.1075 3.4075 10.1075 3.4075 9 P 0 ;1
L 10.1075 3.4575 10.1075 3.4575 9 P 0 ;1
L 10.1075 3.5075 10.1075 3.5075 9 P 0 ;1
L 10.1075 3.5575 10.1075 3.5575 9 P 0 ;1
L 10.1075 3.6075 10.1075 3.6075 9 P 0 ;1
L 10.1075 3.6575 10.1075 3.6575 9 P 0 ;1
L 10.1075 3.7075 10.1075 3.7075 9 P 0 ;1
L 10.1075 3.7575 10.1075 3.7575 9 P 0 ;1
L 10.1075 3.8075 10.1075 3.8075 9 P 0 ;1
L 10.1075 3.8575 10.1075 3.8575 9 P 0 ;1
L 10.1075 3.9075 10.1075 3.9075 9 P 0 ;1
L 10.1075 3.9575 10.1075 3.9575 9 P 0 ;1
L 10.1075 4.0075 10.1075 4.0075 9 P 0 ;1
L 10.1075 4.0575 10.1075 4.0575 9 P 0 ;1
L 10.1075 4.1075 10.1075 4.1075 9 P 0 ;1
L 10.1075 4.1575 10.1075 4.1575 9 P 0 ;1
L 10.1075 4.2075 10.1075 4.2075 9 P 0 ;1
L 10.1075 4.2575 10.1075 4.2575 9 P 0 ;1
L 10.1075 4.3075 10.1075 4.3075 9 P 0 ;1
L 10.1075 4.3575 10.1075 4.3575 9 P 0 ;1
L 10.1075 4.4075 10.1075 4.4075 9 P 0 ;1
L 10.1075 4.4575 10.1075 4.4575 9 P 0 ;1
L 10.1075 4.5575 10.1075 4.5575 9 P 0 ;1
L 10.1075 4.6575 10.1075 4.6575 9 P 0 ;1
L 10.1075 4.7075 10.1075 4.7075 9 P 0 ;1
L 10.1075 4.7575 10.1075 4.7575 9 P 0 ;1
L 10.1075 4.8075 10.1075 4.8075 9 P 0 ;1
L 10.1075 4.8575 10.1075 4.8575 9 P 0 ;1
L 10.1075 4.9075 10.1075 4.9075 9 P 0 ;1
L 10.1075 4.9575 10.1075 4.9575 9 P 0 ;1
L 10.1075 5.0075 10.1075 5.0075 9 P 0 ;1
L 10.1075 5.0575 10.1075 5.0575 9 P 0 ;1
L 10.1075 5.1075 10.1075 5.1075 9 P 0 ;1
L 10.1075 5.1575 10.1075 5.1575 9 P 0 ;1
L 10.1075 5.7075 10.1075 5.7075 9 P 0 ;1
L 10.1075 5.7575 10.1075 5.7575 9 P 0 ;1
L 10.1075 5.8075 10.1075 5.8075 9 P 0 ;1
L 10.1075 5.8575 10.1075 5.8575 9 P 0 ;1
L 10.1075 5.9075 10.1075 5.9075 9 P 0 ;1
L 10.1575 0.1575 10.1575 0.1575 9 P 0 ;1
L 10.1575 0.2075 10.1575 0.2075 9 P 0 ;1
L 10.1575 0.2575 10.1575 0.2575 9 P 0 ;1
L 10.1575 0.3075 10.1575 0.3075 9 P 0 ;1
L 10.1575 0.3575 10.1575 0.3575 9 P 0 ;1
L 10.1575 0.4075 10.1575 0.4075 9 P 0 ;1
L 10.1575 0.4575 10.1575 0.4575 9 P 0 ;1
L 10.1575 0.5075 10.1575 0.5075 9 P 0 ;1
L 10.1575 0.5575 10.1575 0.5575 9 P 0 ;1
L 10.1575 0.6075 10.1575 0.6075 9 P 0 ;1
L 10.1575 0.6575 10.1575 0.6575 9 P 0 ;1
L 10.1575 0.7075 10.1575 0.7075 9 P 0 ;1
L 10.1575 0.7575 10.1575 0.7575 9 P 0 ;1
L 10.1575 0.8075 10.1575 0.8075 9 P 0 ;1
L 10.1575 0.8575 10.1575 0.8575 9 P 0 ;1
L 10.1575 0.9075 10.1575 0.9075 9 P 0 ;1
L 10.1575 0.9575 10.1575 0.9575 9 P 0 ;1
L 10.1575 1.0075 10.1575 1.0075 9 P 0 ;1
L 10.1575 1.0575 10.1575 1.0575 9 P 0 ;1
L 10.1575 1.1075 10.1575 1.1075 9 P 0 ;1
L 10.1575 1.1575 10.1575 1.1575 9 P 0 ;1
L 10.1575 1.2075 10.1575 1.2075 9 P 0 ;1
L 10.1575 1.2575 10.1575 1.2575 9 P 0 ;1
L 10.1575 1.3075 10.1575 1.3075 9 P 0 ;1
L 10.1575 1.3575 10.1575 1.3575 9 P 0 ;1
L 10.1575 1.4075 10.1575 1.4075 9 P 0 ;1
L 10.1575 1.4575 10.1575 1.4575 9 P 0 ;1
L 10.1575 1.5075 10.1575 1.5075 9 P 0 ;1
L 10.1575 1.5575 10.1575 1.5575 9 P 0 ;1
L 10.1575 1.6075 10.1575 1.6075 9 P 0 ;1
L 10.1575 1.6575 10.1575 1.6575 9 P 0 ;1
L 10.1575 1.7075 10.1575 1.7075 9 P 0 ;1
L 10.1575 1.7575 10.1575 1.7575 9 P 0 ;1
L 10.1575 1.8075 10.1575 1.8075 9 P 0 ;1
L 10.1575 1.8575 10.1575 1.8575 9 P 0 ;1
L 10.1575 3.0075 10.1575 3.0075 9 P 0 ;1
L 10.1575 3.0575 10.1575 3.0575 9 P 0 ;1
L 10.1575 3.1075 10.1575 3.1075 9 P 0 ;1
L 10.1575 3.1575 10.1575 3.1575 9 P 0 ;1
L 10.1575 3.2075 10.1575 3.2075 9 P 0 ;1
L 10.1575 3.2575 10.1575 3.2575 9 P 0 ;1
L 10.1575 3.3075 10.1575 3.3075 9 P 0 ;1
L 10.1575 3.3575 10.1575 3.3575 9 P 0 ;1
L 10.1575 3.4075 10.1575 3.4075 9 P 0 ;1
L 10.1575 3.4575 10.1575 3.4575 9 P 0 ;1
L 10.1575 3.5075 10.1575 3.5075 9 P 0 ;1
L 10.1575 3.5575 10.1575 3.5575 9 P 0 ;1
L 10.1575 3.6075 10.1575 3.6075 9 P 0 ;1
L 10.1575 3.6575 10.1575 3.6575 9 P 0 ;1
L 10.1575 3.7075 10.1575 3.7075 9 P 0 ;1
L 10.1575 3.7575 10.1575 3.7575 9 P 0 ;1
L 10.1575 3.8075 10.1575 3.8075 9 P 0 ;1
L 10.1575 3.8575 10.1575 3.8575 9 P 0 ;1
L 10.1575 3.9075 10.1575 3.9075 9 P 0 ;1
L 10.1575 3.9575 10.1575 3.9575 9 P 0 ;1
L 10.1575 4.0075 10.1575 4.0075 9 P 0 ;1
L 10.1575 4.0575 10.1575 4.0575 9 P 0 ;1
L 10.1575 4.1075 10.1575 4.1075 9 P 0 ;1
L 10.1575 4.1575 10.1575 4.1575 9 P 0 ;1
L 10.1575 4.2075 10.1575 4.2075 9 P 0 ;1
L 10.1575 4.2575 10.1575 4.2575 9 P 0 ;1
L 10.1575 4.3075 10.1575 4.3075 9 P 0 ;1
L 10.1575 4.3575 10.1575 4.3575 9 P 0 ;1
L 10.1575 4.4075 10.1575 4.4075 9 P 0 ;1
L 10.1575 4.4575 10.1575 4.4575 9 P 0 ;1
L 10.1575 4.5075 10.1575 4.5075 9 P 0 ;1
L 10.1575 4.5575 10.1575 4.5575 9 P 0 ;1
L 10.1575 4.6075 10.1575 4.6075 9 P 0 ;1
L 10.1575 4.6575 10.1575 4.6575 9 P 0 ;1
L 10.1575 4.7075 10.1575 4.7075 9 P 0 ;1
L 10.1575 4.7575 10.1575 4.7575 9 P 0 ;1
L 10.1575 4.8075 10.1575 4.8075 9 P 0 ;1
L 10.1575 4.8575 10.1575 4.8575 9 P 0 ;1
L 10.1575 4.9075 10.1575 4.9075 9 P 0 ;1
L 10.1575 4.9575 10.1575 4.9575 9 P 0 ;1
L 10.1575 5.0075 10.1575 5.0075 9 P 0 ;1
L 10.1575 5.0575 10.1575 5.0575 9 P 0 ;1
L 10.1575 5.1075 10.1575 5.1075 9 P 0 ;1
L 10.1575 5.1575 10.1575 5.1575 9 P 0 ;1
L 10.1575 5.7575 10.1575 5.7575 9 P 0 ;1
L 10.1575 5.8075 10.1575 5.8075 9 P 0 ;1
L 10.1575 5.8575 10.1575 5.8575 9 P 0 ;1
L 10.1575 5.9075 10.1575 5.9075 9 P 0 ;1
L 10.2075 0.1575 10.2075 0.1575 9 P 0 ;1
L 10.2075 0.2075 10.2075 0.2075 9 P 0 ;1
L 10.2075 0.2575 10.2075 0.2575 9 P 0 ;1
L 10.2075 0.3075 10.2075 0.3075 9 P 0 ;1
L 10.2075 0.3575 10.2075 0.3575 9 P 0 ;1
L 10.2075 0.4075 10.2075 0.4075 9 P 0 ;1
L 10.2075 0.4575 10.2075 0.4575 9 P 0 ;1
L 10.2075 0.5075 10.2075 0.5075 9 P 0 ;1
L 10.2075 0.5575 10.2075 0.5575 9 P 0 ;1
L 10.2075 0.6075 10.2075 0.6075 9 P 0 ;1
L 10.2075 0.6575 10.2075 0.6575 9 P 0 ;1
L 10.2075 0.7075 10.2075 0.7075 9 P 0 ;1
L 10.2075 0.7575 10.2075 0.7575 9 P 0 ;1
L 10.2075 0.8075 10.2075 0.8075 9 P 0 ;1
L 10.2075 0.8575 10.2075 0.8575 9 P 0 ;1
L 10.2075 0.9075 10.2075 0.9075 9 P 0 ;1
L 10.2075 0.9575 10.2075 0.9575 9 P 0 ;1
L 10.2075 1.0075 10.2075 1.0075 9 P 0 ;1
L 10.2075 1.0575 10.2075 1.0575 9 P 0 ;1
L 10.2075 1.1075 10.2075 1.1075 9 P 0 ;1
L 10.2075 1.1575 10.2075 1.1575 9 P 0 ;1
L 10.2075 1.2075 10.2075 1.2075 9 P 0 ;1
L 10.2075 1.2575 10.2075 1.2575 9 P 0 ;1
L 10.2075 1.3075 10.2075 1.3075 9 P 0 ;1
L 10.2075 1.3575 10.2075 1.3575 9 P 0 ;1
L 10.2075 1.4075 10.2075 1.4075 9 P 0 ;1
L 10.2075 1.4575 10.2075 1.4575 9 P 0 ;1
L 10.2075 1.5075 10.2075 1.5075 9 P 0 ;1
L 10.2075 1.5575 10.2075 1.5575 9 P 0 ;1
L 10.2075 2.3575 10.2075 2.3575 9 P 0 ;1
L 10.2075 3.3075 10.2075 3.3075 9 P 0 ;1
L 10.2075 3.3575 10.2075 3.3575 9 P 0 ;1
L 10.2075 3.4075 10.2075 3.4075 9 P 0 ;1
L 10.2075 3.4575 10.2075 3.4575 9 P 0 ;1
L 10.2075 3.5075 10.2075 3.5075 9 P 0 ;1
L 10.2075 3.5575 10.2075 3.5575 9 P 0 ;1
L 10.2075 3.6075 10.2075 3.6075 9 P 0 ;1
L 10.2075 3.6575 10.2075 3.6575 9 P 0 ;1
L 10.2075 3.7075 10.2075 3.7075 9 P 0 ;1
L 10.2075 3.7575 10.2075 3.7575 9 P 0 ;1
L 10.2075 3.8075 10.2075 3.8075 9 P 0 ;1
L 10.2075 3.8575 10.2075 3.8575 9 P 0 ;1
L 10.2075 3.9075 10.2075 3.9075 9 P 0 ;1
L 10.2075 3.9575 10.2075 3.9575 9 P 0 ;1
L 10.2075 4.0075 10.2075 4.0075 9 P 0 ;1
L 10.2075 4.0575 10.2075 4.0575 9 P 0 ;1
L 10.2075 4.1075 10.2075 4.1075 9 P 0 ;1
L 10.2075 4.1575 10.2075 4.1575 9 P 0 ;1
L 10.2075 4.2075 10.2075 4.2075 9 P 0 ;1
L 10.2075 4.2575 10.2075 4.2575 9 P 0 ;1
L 10.2075 4.3075 10.2075 4.3075 9 P 0 ;1
L 10.2075 4.3575 10.2075 4.3575 9 P 0 ;1
L 10.2075 4.4075 10.2075 4.4075 9 P 0 ;1
L 10.2075 4.4575 10.2075 4.4575 9 P 0 ;1
L 10.2075 4.5075 10.2075 4.5075 9 P 0 ;1
L 10.2075 4.5575 10.2075 4.5575 9 P 0 ;1
L 10.2075 4.6075 10.2075 4.6075 9 P 0 ;1
L 10.2075 5.7575 10.2075 5.7575 9 P 0 ;1
L 10.2075 5.8075 10.2075 5.8075 9 P 0 ;1
L 10.2075 5.8575 10.2075 5.8575 9 P 0 ;1
L 10.2075 5.9075 10.2075 5.9075 9 P 0 ;1
L 10.2575 0.1575 10.2575 0.1575 9 P 0 ;1
L 10.2575 0.2075 10.2575 0.2075 9 P 0 ;1
L 10.2575 0.2575 10.2575 0.2575 9 P 0 ;1
L 10.2575 0.3075 10.2575 0.3075 9 P 0 ;1
L 10.2575 0.3575 10.2575 0.3575 9 P 0 ;1
L 10.2575 0.4075 10.2575 0.4075 9 P 0 ;1
L 10.2575 0.4575 10.2575 0.4575 9 P 0 ;1
L 10.2575 0.5075 10.2575 0.5075 9 P 0 ;1
L 10.2575 0.5575 10.2575 0.5575 9 P 0 ;1
L 10.2575 0.6075 10.2575 0.6075 9 P 0 ;1
L 10.2575 0.6575 10.2575 0.6575 9 P 0 ;1
L 10.2575 0.7075 10.2575 0.7075 9 P 0 ;1
L 10.2575 0.7575 10.2575 0.7575 9 P 0 ;1
L 10.2575 0.8075 10.2575 0.8075 9 P 0 ;1
L 10.2575 0.8575 10.2575 0.8575 9 P 0 ;1
L 10.2575 0.9075 10.2575 0.9075 9 P 0 ;1
L 10.2575 0.9575 10.2575 0.9575 9 P 0 ;1
L 10.2575 1.0075 10.2575 1.0075 9 P 0 ;1
L 10.2575 1.0575 10.2575 1.0575 9 P 0 ;1
L 10.2575 1.1075 10.2575 1.1075 9 P 0 ;1
L 10.2575 1.1575 10.2575 1.1575 9 P 0 ;1
L 10.2575 1.2075 10.2575 1.2075 9 P 0 ;1
L 10.2575 1.2575 10.2575 1.2575 9 P 0 ;1
L 10.2575 1.3075 10.2575 1.3075 9 P 0 ;1
L 10.2575 1.3575 10.2575 1.3575 9 P 0 ;1
L 10.2575 1.4075 10.2575 1.4075 9 P 0 ;1
L 10.2575 1.4575 10.2575 1.4575 9 P 0 ;1
L 10.2575 1.5075 10.2575 1.5075 9 P 0 ;1
L 10.2575 1.5575 10.2575 1.5575 9 P 0 ;1
L 10.2575 2.3575 10.2575 2.3575 9 P 0 ;1
L 10.2575 2.4075 10.2575 2.4075 9 P 0 ;1
L 10.2575 3.6075 10.2575 3.6075 9 P 0 ;1
L 10.2575 3.6575 10.2575 3.6575 9 P 0 ;1
L 10.2575 3.7075 10.2575 3.7075 9 P 0 ;1
L 10.2575 3.7575 10.2575 3.7575 9 P 0 ;1
L 10.2575 3.8075 10.2575 3.8075 9 P 0 ;1
L 10.2575 3.8575 10.2575 3.8575 9 P 0 ;1
L 10.2575 3.9075 10.2575 3.9075 9 P 0 ;1
L 10.2575 3.9575 10.2575 3.9575 9 P 0 ;1
L 10.2575 4.0075 10.2575 4.0075 9 P 0 ;1
L 10.2575 4.0575 10.2575 4.0575 9 P 0 ;1
L 10.2575 4.1075 10.2575 4.1075 9 P 0 ;1
L 10.2575 4.1575 10.2575 4.1575 9 P 0 ;1
L 10.2575 4.2075 10.2575 4.2075 9 P 0 ;1
L 10.2575 4.2575 10.2575 4.2575 9 P 0 ;1
L 10.2575 4.3075 10.2575 4.3075 9 P 0 ;1
L 10.2575 4.3575 10.2575 4.3575 9 P 0 ;1
L 10.2575 4.4075 10.2575 4.4075 9 P 0 ;1
L 10.2575 4.4575 10.2575 4.4575 9 P 0 ;1
L 10.2575 4.5075 10.2575 4.5075 9 P 0 ;1
L 10.2575 4.5575 10.2575 4.5575 9 P 0 ;1
L 10.2575 5.7575 10.2575 5.7575 9 P 0 ;1
L 10.2575 5.8075 10.2575 5.8075 9 P 0 ;1
L 10.2575 5.8575 10.2575 5.8575 9 P 0 ;1
L 10.2575 5.9075 10.2575 5.9075 9 P 0 ;1
L 10.3075 0.1575 10.3075 0.1575 9 P 0 ;1
L 10.3075 0.2075 10.3075 0.2075 9 P 0 ;1
L 10.3075 0.2575 10.3075 0.2575 9 P 0 ;1
L 10.3075 0.3075 10.3075 0.3075 9 P 0 ;1
L 10.3075 0.3575 10.3075 0.3575 9 P 0 ;1
L 10.3075 0.4075 10.3075 0.4075 9 P 0 ;1
L 10.3075 0.4575 10.3075 0.4575 9 P 0 ;1
L 10.3075 0.5075 10.3075 0.5075 9 P 0 ;1
L 10.3075 0.5575 10.3075 0.5575 9 P 0 ;1
L 10.3075 0.6075 10.3075 0.6075 9 P 0 ;1
L 10.3075 0.6575 10.3075 0.6575 9 P 0 ;1
L 10.3075 0.7075 10.3075 0.7075 9 P 0 ;1
L 10.3075 0.7575 10.3075 0.7575 9 P 0 ;1
L 10.3075 0.8075 10.3075 0.8075 9 P 0 ;1
L 10.3075 0.8575 10.3075 0.8575 9 P 0 ;1
L 10.3075 0.9075 10.3075 0.9075 9 P 0 ;1
L 10.3075 0.9575 10.3075 0.9575 9 P 0 ;1
L 10.3075 1.0075 10.3075 1.0075 9 P 0 ;1
L 10.3075 1.0575 10.3075 1.0575 9 P 0 ;1
L 10.3075 1.1075 10.3075 1.1075 9 P 0 ;1
L 10.3075 1.1575 10.3075 1.1575 9 P 0 ;1
L 10.3075 1.2075 10.3075 1.2075 9 P 0 ;1
L 10.3075 1.2575 10.3075 1.2575 9 P 0 ;1
L 10.3075 1.3075 10.3075 1.3075 9 P 0 ;1
L 10.3075 1.3575 10.3075 1.3575 9 P 0 ;1
L 10.3075 1.4075 10.3075 1.4075 9 P 0 ;1
L 10.3075 2.3075 10.3075 2.3075 9 P 0 ;1
L 10.3075 2.3575 10.3075 2.3575 9 P 0 ;1
L 10.3075 2.4075 10.3075 2.4075 9 P 0 ;1
L 10.3075 2.4575 10.3075 2.4575 9 P 0 ;1
L 10.3075 3.8575 10.3075 3.8575 9 P 0 ;1
L 10.3075 3.9075 10.3075 3.9075 9 P 0 ;1
L 10.3075 3.9575 10.3075 3.9575 9 P 0 ;1
L 10.3075 4.0075 10.3075 4.0075 9 P 0 ;1
L 10.3075 4.0575 10.3075 4.0575 9 P 0 ;1
L 10.3075 4.1075 10.3075 4.1075 9 P 0 ;1
L 10.3075 4.1575 10.3075 4.1575 9 P 0 ;1
L 10.3075 4.2075 10.3075 4.2075 9 P 0 ;1
L 10.3075 4.2575 10.3075 4.2575 9 P 0 ;1
L 10.3075 4.3075 10.3075 4.3075 9 P 0 ;1
L 10.3075 4.3575 10.3075 4.3575 9 P 0 ;1
L 10.3075 4.4075 10.3075 4.4075 9 P 0 ;1
L 10.3075 4.4575 10.3075 4.4575 9 P 0 ;1
L 10.3075 4.5075 10.3075 4.5075 9 P 0 ;1
L 10.3075 4.5575 10.3075 4.5575 9 P 0 ;1
L 10.3075 5.7075 10.3075 5.7075 9 P 0 ;1
L 10.3075 5.7575 10.3075 5.7575 9 P 0 ;1
L 10.3075 5.8075 10.3075 5.8075 9 P 0 ;1
L 10.3075 5.8575 10.3075 5.8575 9 P 0 ;1
L 10.3075 5.9075 10.3075 5.9075 9 P 0 ;1
L 10.3575 0.1575 10.3575 0.1575 9 P 0 ;1
L 10.3575 0.2075 10.3575 0.2075 9 P 0 ;1
L 10.3575 0.2575 10.3575 0.2575 9 P 0 ;1
L 10.3575 0.3075 10.3575 0.3075 9 P 0 ;1
L 10.3575 0.3575 10.3575 0.3575 9 P 0 ;1
L 10.3575 0.4075 10.3575 0.4075 9 P 0 ;1
L 10.3575 0.4575 10.3575 0.4575 9 P 0 ;1
L 10.3575 0.5075 10.3575 0.5075 9 P 0 ;1
L 10.3575 0.5575 10.3575 0.5575 9 P 0 ;1
L 10.3575 0.6075 10.3575 0.6075 9 P 0 ;1
L 10.3575 0.6575 10.3575 0.6575 9 P 0 ;1
L 10.3575 0.7075 10.3575 0.7075 9 P 0 ;1
L 10.3575 0.7575 10.3575 0.7575 9 P 0 ;1
L 10.3575 0.8075 10.3575 0.8075 9 P 0 ;1
L 10.3575 0.8575 10.3575 0.8575 9 P 0 ;1
L 10.3575 0.9075 10.3575 0.9075 9 P 0 ;1
L 10.3575 0.9575 10.3575 0.9575 9 P 0 ;1
L 10.3575 1.0075 10.3575 1.0075 9 P 0 ;1
L 10.3575 1.0575 10.3575 1.0575 9 P 0 ;1
L 10.3575 1.1075 10.3575 1.1075 9 P 0 ;1
L 10.3575 1.1575 10.3575 1.1575 9 P 0 ;1
L 10.3575 1.2075 10.3575 1.2075 9 P 0 ;1
L 10.3575 2.2575 10.3575 2.2575 9 P 0 ;1
L 10.3575 2.3075 10.3575 2.3075 9 P 0 ;1
L 10.3575 2.3575 10.3575 2.3575 9 P 0 ;1
L 10.3575 2.4075 10.3575 2.4075 9 P 0 ;1
L 10.3575 2.4575 10.3575 2.4575 9 P 0 ;1
L 10.3575 2.5075 10.3575 2.5075 9 P 0 ;1
L 10.3575 2.5575 10.3575 2.5575 9 P 0 ;1
L 10.3575 2.6075 10.3575 2.6075 9 P 0 ;1
L 10.3575 2.6575 10.3575 2.6575 9 P 0 ;1
L 10.3575 4.0075 10.3575 4.0075 9 P 0 ;1
L 10.3575 4.0575 10.3575 4.0575 9 P 0 ;1
L 10.3575 4.1075 10.3575 4.1075 9 P 0 ;1
L 10.3575 4.1575 10.3575 4.1575 9 P 0 ;1
L 10.3575 4.2075 10.3575 4.2075 9 P 0 ;1
L 10.3575 4.2575 10.3575 4.2575 9 P 0 ;1
L 10.3575 4.3075 10.3575 4.3075 9 P 0 ;1
L 10.3575 4.3575 10.3575 4.3575 9 P 0 ;1
L 10.3575 4.4075 10.3575 4.4075 9 P 0 ;1
L 10.3575 4.4575 10.3575 4.4575 9 P 0 ;1
L 10.3575 4.5075 10.3575 4.5075 9 P 0 ;1
L 10.3575 4.5575 10.3575 4.5575 9 P 0 ;1
L 10.3575 5.2075 10.3575 5.2075 9 P 0 ;1
L 10.3575 5.7075 10.3575 5.7075 9 P 0 ;1
L 10.3575 5.7575 10.3575 5.7575 9 P 0 ;1
L 10.3575 5.8075 10.3575 5.8075 9 P 0 ;1
L 10.3575 5.8575 10.3575 5.8575 9 P 0 ;1
L 10.3575 5.9075 10.3575 5.9075 9 P 0 ;1
L 10.4075 0.1575 10.4075 0.1575 9 P 0 ;1
L 10.4075 0.2075 10.4075 0.2075 9 P 0 ;1
L 10.4075 0.2575 10.4075 0.2575 9 P 0 ;1
L 10.4075 0.3075 10.4075 0.3075 9 P 0 ;1
L 10.4075 0.3575 10.4075 0.3575 9 P 0 ;1
L 10.4075 0.4075 10.4075 0.4075 9 P 0 ;1
L 10.4075 0.4575 10.4075 0.4575 9 P 0 ;1
L 10.4075 0.5075 10.4075 0.5075 9 P 0 ;1
L 10.4075 0.5575 10.4075 0.5575 9 P 0 ;1
L 10.4075 0.6075 10.4075 0.6075 9 P 0 ;1
L 10.4075 0.6575 10.4075 0.6575 9 P 0 ;1
L 10.4075 0.7075 10.4075 0.7075 9 P 0 ;1
L 10.4075 0.7575 10.4075 0.7575 9 P 0 ;1
L 10.4075 0.8075 10.4075 0.8075 9 P 0 ;1
L 10.4075 0.8575 10.4075 0.8575 9 P 0 ;1
L 10.4075 0.9075 10.4075 0.9075 9 P 0 ;1
L 10.4075 0.9575 10.4075 0.9575 9 P 0 ;1
L 10.4075 1.0075 10.4075 1.0075 9 P 0 ;1
L 10.4075 1.0575 10.4075 1.0575 9 P 0 ;1
L 10.4075 1.1075 10.4075 1.1075 9 P 0 ;1
L 10.4075 1.1575 10.4075 1.1575 9 P 0 ;1
L 10.4075 2.1575 10.4075 2.1575 9 P 0 ;1
L 10.4075 2.2075 10.4075 2.2075 9 P 0 ;1
L 10.4075 2.2575 10.4075 2.2575 9 P 0 ;1
L 10.4075 2.3075 10.4075 2.3075 9 P 0 ;1
L 10.4075 2.3575 10.4075 2.3575 9 P 0 ;1
L 10.4075 2.4075 10.4075 2.4075 9 P 0 ;1
L 10.4075 2.4575 10.4075 2.4575 9 P 0 ;1
L 10.4075 2.5075 10.4075 2.5075 9 P 0 ;1
L 10.4075 2.5575 10.4075 2.5575 9 P 0 ;1
L 10.4075 2.6075 10.4075 2.6075 9 P 0 ;1
L 10.4075 2.6575 10.4075 2.6575 9 P 0 ;1
L 10.4075 2.7075 10.4075 2.7075 9 P 0 ;1
L 10.4075 2.7575 10.4075 2.7575 9 P 0 ;1
L 10.4075 2.8075 10.4075 2.8075 9 P 0 ;1
L 10.4075 2.8575 10.4075 2.8575 9 P 0 ;1
L 10.4075 2.9075 10.4075 2.9075 9 P 0 ;1
L 10.4075 4.0575 10.4075 4.0575 9 P 0 ;1
L 10.4075 4.1075 10.4075 4.1075 9 P 0 ;1
L 10.4075 4.1575 10.4075 4.1575 9 P 0 ;1
L 10.4075 4.2075 10.4075 4.2075 9 P 0 ;1
L 10.4075 4.2575 10.4075 4.2575 9 P 0 ;1
L 10.4075 4.3075 10.4075 4.3075 9 P 0 ;1
L 10.4075 4.3575 10.4075 4.3575 9 P 0 ;1
L 10.4075 4.4075 10.4075 4.4075 9 P 0 ;1
L 10.4075 4.4575 10.4075 4.4575 9 P 0 ;1
L 10.4075 4.5075 10.4075 4.5075 9 P 0 ;1
L 10.4075 4.5575 10.4075 4.5575 9 P 0 ;1
L 10.4075 5.6575 10.4075 5.6575 9 P 0 ;1
L 10.4075 5.7075 10.4075 5.7075 9 P 0 ;1
L 10.4075 5.7575 10.4075 5.7575 9 P 0 ;1
L 10.4075 5.8075 10.4075 5.8075 9 P 0 ;1
L 10.4075 5.8575 10.4075 5.8575 9 P 0 ;1
L 10.4075 5.9075 10.4075 5.9075 9 P 0 ;1
L 10.4575 0.1575 10.4575 0.1575 9 P 0 ;1
L 10.4575 0.2075 10.4575 0.2075 9 P 0 ;1
L 10.4575 0.2575 10.4575 0.2575 9 P 0 ;1
L 10.4575 0.3075 10.4575 0.3075 9 P 0 ;1
L 10.4575 0.3575 10.4575 0.3575 9 P 0 ;1
L 10.4575 0.4075 10.4575 0.4075 9 P 0 ;1
L 10.4575 0.4575 10.4575 0.4575 9 P 0 ;1
L 10.4575 0.5075 10.4575 0.5075 9 P 0 ;1
L 10.4575 0.5575 10.4575 0.5575 9 P 0 ;1
L 10.4575 0.6075 10.4575 0.6075 9 P 0 ;1
L 10.4575 0.6575 10.4575 0.6575 9 P 0 ;1
L 10.4575 0.7075 10.4575 0.7075 9 P 0 ;1
L 10.4575 0.7575 10.4575 0.7575 9 P 0 ;1
L 10.4575 0.8075 10.4575 0.8075 9 P 0 ;1
L 10.4575 0.8575 10.4575 0.8575 9 P 0 ;1
L 10.4575 0.9075 10.4575 0.9075 9 P 0 ;1
L 10.4575 0.9575 10.4575 0.9575 9 P 0 ;1
L 10.4575 1.0075 10.4575 1.0075 9 P 0 ;1
L 10.4575 1.0575 10.4575 1.0575 9 P 0 ;1
L 10.4575 1.1075 10.4575 1.1075 9 P 0 ;1
L 10.4575 1.1575 10.4575 1.1575 9 P 0 ;1
L 10.4575 2.1075 10.4575 2.1075 9 P 0 ;1
L 10.4575 2.1575 10.4575 2.1575 9 P 0 ;1
L 10.4575 2.2075 10.4575 2.2075 9 P 0 ;1
L 10.4575 2.2575 10.4575 2.2575 9 P 0 ;1
L 10.4575 2.3075 10.4575 2.3075 9 P 0 ;1
L 10.4575 2.3575 10.4575 2.3575 9 P 0 ;1
L 10.4575 2.4075 10.4575 2.4075 9 P 0 ;1
L 10.4575 2.4575 10.4575 2.4575 9 P 0 ;1
L 10.4575 2.5075 10.4575 2.5075 9 P 0 ;1
L 10.4575 2.5575 10.4575 2.5575 9 P 0 ;1
L 10.4575 2.6075 10.4575 2.6075 9 P 0 ;1
L 10.4575 2.6575 10.4575 2.6575 9 P 0 ;1
L 10.4575 2.7075 10.4575 2.7075 9 P 0 ;1
L 10.4575 2.7575 10.4575 2.7575 9 P 0 ;1
L 10.4575 2.8075 10.4575 2.8075 9 P 0 ;1
L 10.4575 2.8575 10.4575 2.8575 9 P 0 ;1
L 10.4575 2.9075 10.4575 2.9075 9 P 0 ;1
L 10.4575 2.9575 10.4575 2.9575 9 P 0 ;1
L 10.4575 3.0075 10.4575 3.0075 9 P 0 ;1
L 10.4575 3.0575 10.4575 3.0575 9 P 0 ;1
L 10.4575 3.1075 10.4575 3.1075 9 P 0 ;1
L 10.4575 3.1575 10.4575 3.1575 9 P 0 ;1
L 10.4575 3.2075 10.4575 3.2075 9 P 0 ;1
L 10.4575 4.0575 10.4575 4.0575 9 P 0 ;1
L 10.4575 4.1075 10.4575 4.1075 9 P 0 ;1
L 10.4575 4.1575 10.4575 4.1575 9 P 0 ;1
L 10.4575 4.2075 10.4575 4.2075 9 P 0 ;1
L 10.4575 4.2575 10.4575 4.2575 9 P 0 ;1
L 10.4575 4.3075 10.4575 4.3075 9 P 0 ;1
L 10.4575 4.3575 10.4575 4.3575 9 P 0 ;1
L 10.4575 4.4075 10.4575 4.4075 9 P 0 ;1
L 10.4575 4.4575 10.4575 4.4575 9 P 0 ;1
L 10.4575 4.5075 10.4575 4.5075 9 P 0 ;1
L 10.4575 4.5575 10.4575 4.5575 9 P 0 ;1
L 10.4575 5.5575 10.4575 5.5575 9 P 0 ;1
L 10.4575 5.6075 10.4575 5.6075 9 P 0 ;1
L 10.4575 5.6575 10.4575 5.6575 9 P 0 ;1
L 10.4575 5.7075 10.4575 5.7075 9 P 0 ;1
L 10.4575 5.7575 10.4575 5.7575 9 P 0 ;1
L 10.4575 5.8075 10.4575 5.8075 9 P 0 ;1
L 10.4575 5.8575 10.4575 5.8575 9 P 0 ;1
L 10.4575 5.9075 10.4575 5.9075 9 P 0 ;1
L 10.5075 0.1575 10.5075 0.1575 9 P 0 ;1
L 10.5075 0.2075 10.5075 0.2075 9 P 0 ;1
L 10.5075 0.2575 10.5075 0.2575 9 P 0 ;1
L 10.5075 0.3075 10.5075 0.3075 9 P 0 ;1
L 10.5075 0.3575 10.5075 0.3575 9 P 0 ;1
L 10.5075 0.4075 10.5075 0.4075 9 P 0 ;1
L 10.5075 0.4575 10.5075 0.4575 9 P 0 ;1
L 10.5075 0.5075 10.5075 0.5075 9 P 0 ;1
L 10.5075 0.5575 10.5075 0.5575 9 P 0 ;1
L 10.5075 0.6075 10.5075 0.6075 9 P 0 ;1
L 10.5075 0.6575 10.5075 0.6575 9 P 0 ;1
L 10.5075 0.7075 10.5075 0.7075 9 P 0 ;1
L 10.5075 0.7575 10.5075 0.7575 9 P 0 ;1
L 10.5075 0.8075 10.5075 0.8075 9 P 0 ;1
L 10.5075 0.8575 10.5075 0.8575 9 P 0 ;1
L 10.5075 0.9075 10.5075 0.9075 9 P 0 ;1
L 10.5075 0.9575 10.5075 0.9575 9 P 0 ;1
L 10.5075 1.0075 10.5075 1.0075 9 P 0 ;1
L 10.5075 1.0575 10.5075 1.0575 9 P 0 ;1
L 10.5075 1.1075 10.5075 1.1075 9 P 0 ;1
L 10.5075 1.1575 10.5075 1.1575 9 P 0 ;1
L 10.5075 2.0075 10.5075 2.0075 9 P 0 ;1
L 10.5075 2.0575 10.5075 2.0575 9 P 0 ;1
L 10.5075 2.1075 10.5075 2.1075 9 P 0 ;1
L 10.5075 2.1575 10.5075 2.1575 9 P 0 ;1
L 10.5075 2.2075 10.5075 2.2075 9 P 0 ;1
L 10.5075 2.2575 10.5075 2.2575 9 P 0 ;1
L 10.5075 2.3075 10.5075 2.3075 9 P 0 ;1
L 10.5075 2.3575 10.5075 2.3575 9 P 0 ;1
L 10.5075 2.4075 10.5075 2.4075 9 P 0 ;1
L 10.5075 2.4575 10.5075 2.4575 9 P 0 ;1
L 10.5075 2.5075 10.5075 2.5075 9 P 0 ;1
L 10.5075 2.5575 10.5075 2.5575 9 P 0 ;1
L 10.5075 2.6075 10.5075 2.6075 9 P 0 ;1
L 10.5075 2.6575 10.5075 2.6575 9 P 0 ;1
L 10.5075 2.7075 10.5075 2.7075 9 P 0 ;1
L 10.5075 2.7575 10.5075 2.7575 9 P 0 ;1
L 10.5075 2.8075 10.5075 2.8075 9 P 0 ;1
L 10.5075 2.8575 10.5075 2.8575 9 P 0 ;1
L 10.5075 2.9075 10.5075 2.9075 9 P 0 ;1
L 10.5075 2.9575 10.5075 2.9575 9 P 0 ;1
L 10.5075 3.0075 10.5075 3.0075 9 P 0 ;1
L 10.5075 3.0575 10.5075 3.0575 9 P 0 ;1
L 10.5075 3.1075 10.5075 3.1075 9 P 0 ;1
L 10.5075 3.1575 10.5075 3.1575 9 P 0 ;1
L 10.5075 3.2075 10.5075 3.2075 9 P 0 ;1
L 10.5075 3.2575 10.5075 3.2575 9 P 0 ;1
L 10.5075 3.3075 10.5075 3.3075 9 P 0 ;1
L 10.5075 3.3575 10.5075 3.3575 9 P 0 ;1
L 10.5075 3.4075 10.5075 3.4075 9 P 0 ;1
L 10.5075 3.4575 10.5075 3.4575 9 P 0 ;1
L 10.5075 3.5075 10.5075 3.5075 9 P 0 ;1
L 10.5075 4.1075 10.5075 4.1075 9 P 0 ;1
L 10.5075 4.1575 10.5075 4.1575 9 P 0 ;1
L 10.5075 4.2075 10.5075 4.2075 9 P 0 ;1
L 10.5075 4.2575 10.5075 4.2575 9 P 0 ;1
L 10.5075 4.3075 10.5075 4.3075 9 P 0 ;1
L 10.5075 4.3575 10.5075 4.3575 9 P 0 ;1
L 10.5075 4.4075 10.5075 4.4075 9 P 0 ;1
L 10.5075 4.4575 10.5075 4.4575 9 P 0 ;1
L 10.5075 4.5075 10.5075 4.5075 9 P 0 ;1
L 10.5075 4.5575 10.5075 4.5575 9 P 0 ;1
L 10.5075 5.9075 10.5075 5.9075 9 P 0 ;1
L 10.5575 0.1575 10.5575 0.1575 9 P 0 ;1
L 10.5575 0.2075 10.5575 0.2075 9 P 0 ;1
L 10.5575 0.2575 10.5575 0.2575 9 P 0 ;1
L 10.5575 0.3075 10.5575 0.3075 9 P 0 ;1
L 10.5575 0.3575 10.5575 0.3575 9 P 0 ;1
L 10.5575 0.4075 10.5575 0.4075 9 P 0 ;1
L 10.5575 0.4575 10.5575 0.4575 9 P 0 ;1
L 10.5575 0.5075 10.5575 0.5075 9 P 0 ;1
L 10.5575 0.5575 10.5575 0.5575 9 P 0 ;1
L 10.5575 0.6075 10.5575 0.6075 9 P 0 ;1
L 10.5575 0.6575 10.5575 0.6575 9 P 0 ;1
L 10.5575 0.7075 10.5575 0.7075 9 P 0 ;1
L 10.5575 0.7575 10.5575 0.7575 9 P 0 ;1
L 10.5575 0.8075 10.5575 0.8075 9 P 0 ;1
L 10.5575 0.8575 10.5575 0.8575 9 P 0 ;1
L 10.5575 0.9075 10.5575 0.9075 9 P 0 ;1
L 10.5575 0.9575 10.5575 0.9575 9 P 0 ;1
L 10.5575 1.0075 10.5575 1.0075 9 P 0 ;1
L 10.5575 1.0575 10.5575 1.0575 9 P 0 ;1
L 10.5575 1.1075 10.5575 1.1075 9 P 0 ;1
L 10.5575 4.1075 10.5575 4.1075 9 P 0 ;1
L 10.5575 4.1575 10.5575 4.1575 9 P 0 ;1
L 10.5575 4.2075 10.5575 4.2075 9 P 0 ;1
L 10.5575 4.2575 10.5575 4.2575 9 P 0 ;1
L 10.5575 4.3075 10.5575 4.3075 9 P 0 ;1
L 10.5575 4.3575 10.5575 4.3575 9 P 0 ;1
L 10.5575 4.4075 10.5575 4.4075 9 P 0 ;1
L 10.5575 4.4575 10.5575 4.4575 9 P 0 ;1
L 10.5575 4.5075 10.5575 4.5075 9 P 0 ;1
L 10.5575 4.5575 10.5575 4.5575 9 P 0 ;1
L 10.5575 4.6075 10.5575 4.6075 9 P 0 ;1
L 10.5575 4.6575 10.5575 4.6575 9 P 0 ;1
L 10.5575 4.7075 10.5575 4.7075 9 P 0 ;1
L 10.5575 4.7575 10.5575 4.7575 9 P 0 ;1
L 10.5575 4.8075 10.5575 4.8075 9 P 0 ;1
L 10.5575 4.8575 10.5575 4.8575 9 P 0 ;1
L 10.5575 4.9075 10.5575 4.9075 9 P 0 ;1
L 10.5575 4.9575 10.5575 4.9575 9 P 0 ;1
L 10.5575 5.0075 10.5575 5.0075 9 P 0 ;1
L 10.5575 5.0575 10.5575 5.0575 9 P 0 ;1
L 10.6075 0.1575 10.6075 0.1575 9 P 0 ;1
L 10.6075 0.2075 10.6075 0.2075 9 P 0 ;1
L 10.6075 0.2575 10.6075 0.2575 9 P 0 ;1
L 10.6075 0.3075 10.6075 0.3075 9 P 0 ;1
L 10.6075 0.3575 10.6075 0.3575 9 P 0 ;1
L 10.6075 0.4075 10.6075 0.4075 9 P 0 ;1
L 10.6075 0.4575 10.6075 0.4575 9 P 0 ;1
L 10.6075 0.5075 10.6075 0.5075 9 P 0 ;1
L 10.6075 0.5575 10.6075 0.5575 9 P 0 ;1
L 10.6075 0.6075 10.6075 0.6075 9 P 0 ;1
L 10.6075 0.6575 10.6075 0.6575 9 P 0 ;1
L 10.6075 0.7075 10.6075 0.7075 9 P 0 ;1
L 10.6075 0.7575 10.6075 0.7575 9 P 0 ;1
L 10.6075 0.8075 10.6075 0.8075 9 P 0 ;1
L 10.6075 0.8575 10.6075 0.8575 9 P 0 ;1
L 10.6075 0.9075 10.6075 0.9075 9 P 0 ;1
L 10.6075 0.9575 10.6075 0.9575 9 P 0 ;1
L 10.6075 1.0075 10.6075 1.0075 9 P 0 ;1
L 10.6075 1.0575 10.6075 1.0575 9 P 0 ;1
L 10.6075 4.1075 10.6075 4.1075 9 P 0 ;1
L 10.6075 4.1575 10.6075 4.1575 9 P 0 ;1
L 10.6075 4.2075 10.6075 4.2075 9 P 0 ;1
L 10.6075 4.2575 10.6075 4.2575 9 P 0 ;1
L 10.6075 4.3075 10.6075 4.3075 9 P 0 ;1
L 10.6075 4.3575 10.6075 4.3575 9 P 0 ;1
L 10.6075 4.4075 10.6075 4.4075 9 P 0 ;1
L 10.6075 4.4575 10.6075 4.4575 9 P 0 ;1
L 10.6075 4.5075 10.6075 4.5075 9 P 0 ;1
L 10.6075 4.5575 10.6075 4.5575 9 P 0 ;1
L 10.6575 0.1575 10.6575 0.1575 9 P 0 ;1
L 10.6575 0.2075 10.6575 0.2075 9 P 0 ;1
L 10.6575 0.2575 10.6575 0.2575 9 P 0 ;1
L 10.6575 0.3075 10.6575 0.3075 9 P 0 ;1
L 10.6575 0.3575 10.6575 0.3575 9 P 0 ;1
L 10.6575 0.4075 10.6575 0.4075 9 P 0 ;1
L 10.6575 0.4575 10.6575 0.4575 9 P 0 ;1
L 10.6575 0.5075 10.6575 0.5075 9 P 0 ;1
L 10.6575 0.5575 10.6575 0.5575 9 P 0 ;1
L 10.6575 0.6075 10.6575 0.6075 9 P 0 ;1
L 10.6575 0.6575 10.6575 0.6575 9 P 0 ;1
L 10.6575 0.7075 10.6575 0.7075 9 P 0 ;1
L 10.6575 0.7575 10.6575 0.7575 9 P 0 ;1
L 10.6575 0.8075 10.6575 0.8075 9 P 0 ;1
L 10.6575 0.8575 10.6575 0.8575 9 P 0 ;1
L 10.6575 0.9075 10.6575 0.9075 9 P 0 ;1
L 10.6575 0.9575 10.6575 0.9575 9 P 0 ;1
L 10.6575 1.0075 10.6575 1.0075 9 P 0 ;1
L 10.6575 1.0575 10.6575 1.0575 9 P 0 ;1
L 10.6575 1.6075 10.6575 1.6075 9 P 0 ;1
L 10.6575 4.1075 10.6575 4.1075 9 P 0 ;1
L 10.6575 4.1575 10.6575 4.1575 9 P 0 ;1
L 10.6575 4.3075 10.6575 4.3075 9 P 0 ;1
L 10.6575 4.3575 10.6575 4.3575 9 P 0 ;1
L 10.6575 4.4075 10.6575 4.4075 9 P 0 ;1
L 10.6575 4.4575 10.6575 4.4575 9 P 0 ;1
L 10.6575 4.5075 10.6575 4.5075 9 P 0 ;1
L 10.6575 4.5575 10.6575 4.5575 9 P 0 ;1
L 10.7075 0.1575 10.7075 0.1575 9 P 0 ;1
L 10.7075 0.2075 10.7075 0.2075 9 P 0 ;1
L 10.7075 0.2575 10.7075 0.2575 9 P 0 ;1
L 10.7075 0.3075 10.7075 0.3075 9 P 0 ;1
L 10.7075 0.3575 10.7075 0.3575 9 P 0 ;1
L 10.7075 0.4075 10.7075 0.4075 9 P 0 ;1
L 10.7075 0.4575 10.7075 0.4575 9 P 0 ;1
L 10.7075 0.5075 10.7075 0.5075 9 P 0 ;1
L 10.7075 0.5575 10.7075 0.5575 9 P 0 ;1
L 10.7075 0.6075 10.7075 0.6075 9 P 0 ;1
L 10.7075 0.6575 10.7075 0.6575 9 P 0 ;1
L 10.7075 0.7075 10.7075 0.7075 9 P 0 ;1
L 10.7075 0.7575 10.7075 0.7575 9 P 0 ;1
L 10.7075 0.8075 10.7075 0.8075 9 P 0 ;1
L 10.7075 0.8575 10.7075 0.8575 9 P 0 ;1
L 10.7075 0.9075 10.7075 0.9075 9 P 0 ;1
L 10.7075 0.9575 10.7075 0.9575 9 P 0 ;1
L 10.7075 1.0075 10.7075 1.0075 9 P 0 ;1
L 10.7075 1.0575 10.7075 1.0575 9 P 0 ;1
L 10.7075 4.4075 10.7075 4.4075 9 P 0 ;1
L 10.7075 4.4575 10.7075 4.4575 9 P 0 ;1
L 10.7075 4.5075 10.7075 4.5075 9 P 0 ;1
L 10.7075 4.5575 10.7075 4.5575 9 P 0 ;1
L 10.7575 0.1575 10.7575 0.1575 9 P 0 ;1
L 10.7575 0.2075 10.7575 0.2075 9 P 0 ;1
L 10.7575 0.2575 10.7575 0.2575 9 P 0 ;1
L 10.7575 0.3075 10.7575 0.3075 9 P 0 ;1
L 10.7575 0.3575 10.7575 0.3575 9 P 0 ;1
L 10.7575 0.4075 10.7575 0.4075 9 P 0 ;1
L 10.7575 0.4575 10.7575 0.4575 9 P 0 ;1
L 10.7575 0.5075 10.7575 0.5075 9 P 0 ;1
L 10.7575 0.5575 10.7575 0.5575 9 P 0 ;1
L 10.7575 0.6075 10.7575 0.6075 9 P 0 ;1
L 10.7575 0.6575 10.7575 0.6575 9 P 0 ;1
L 10.7575 0.7075 10.7575 0.7075 9 P 0 ;1
L 10.7575 0.7575 10.7575 0.7575 9 P 0 ;1
L 10.7575 0.8075 10.7575 0.8075 9 P 0 ;1
L 10.7575 0.8575 10.7575 0.8575 9 P 0 ;1
L 10.7575 0.9075 10.7575 0.9075 9 P 0 ;1
L 10.7575 0.9575 10.7575 0.9575 9 P 0 ;1
L 10.7575 1.0075 10.7575 1.0075 9 P 0 ;1
L 10.7575 1.0575 10.7575 1.0575 9 P 0 ;1
L 10.7575 4.4075 10.7575 4.4075 9 P 0 ;1
L 10.7575 4.4575 10.7575 4.4575 9 P 0 ;1
L 10.7575 4.5075 10.7575 4.5075 9 P 0 ;1
L 10.7575 4.5575 10.7575 4.5575 9 P 0 ;1
L 10.8075 0.1575 10.8075 0.1575 9 P 0 ;1
L 10.8075 0.2075 10.8075 0.2075 9 P 0 ;1
L 10.8075 0.2575 10.8075 0.2575 9 P 0 ;1
L 10.8075 0.3075 10.8075 0.3075 9 P 0 ;1
L 10.8075 0.3575 10.8075 0.3575 9 P 0 ;1
L 10.8075 0.4075 10.8075 0.4075 9 P 0 ;1
L 10.8075 0.4575 10.8075 0.4575 9 P 0 ;1
L 10.8075 0.5075 10.8075 0.5075 9 P 0 ;1
L 10.8075 0.5575 10.8075 0.5575 9 P 0 ;1
L 10.8075 0.6075 10.8075 0.6075 9 P 0 ;1
L 10.8075 0.6575 10.8075 0.6575 9 P 0 ;1
L 10.8075 0.7075 10.8075 0.7075 9 P 0 ;1
L 10.8075 0.7575 10.8075 0.7575 9 P 0 ;1
L 10.8075 0.8075 10.8075 0.8075 9 P 0 ;1
L 10.8075 0.8575 10.8075 0.8575 9 P 0 ;1
L 10.8075 0.9075 10.8075 0.9075 9 P 0 ;1
L 10.8075 0.9575 10.8075 0.9575 9 P 0 ;1
L 10.8075 1.0075 10.8075 1.0075 9 P 0 ;1
L 10.8075 4.4575 10.8075 4.4575 9 P 0 ;1
L 10.8075 4.5075 10.8075 4.5075 9 P 0 ;1
L 10.8075 4.5575 10.8075 4.5575 9 P 0 ;1
L 10.8575 0.1575 10.8575 0.1575 9 P 0 ;1
L 10.8575 0.2075 10.8575 0.2075 9 P 0 ;1
L 10.8575 0.2575 10.8575 0.2575 9 P 0 ;1
L 10.8575 0.3075 10.8575 0.3075 9 P 0 ;1
L 10.8575 0.3575 10.8575 0.3575 9 P 0 ;1
L 10.8575 0.4075 10.8575 0.4075 9 P 0 ;1
L 10.8575 0.4575 10.8575 0.4575 9 P 0 ;1
L 10.8575 0.5075 10.8575 0.5075 9 P 0 ;1
L 10.8575 0.5575 10.8575 0.5575 9 P 0 ;1
L 10.8575 0.6075 10.8575 0.6075 9 P 0 ;1
L 10.8575 0.6575 10.8575 0.6575 9 P 0 ;1
L 10.8575 0.7075 10.8575 0.7075 9 P 0 ;1
L 10.8575 0.7575 10.8575 0.7575 9 P 0 ;1
L 10.8575 0.8075 10.8575 0.8075 9 P 0 ;1
L 10.8575 0.8575 10.8575 0.8575 9 P 0 ;1
L 10.8575 0.9075 10.8575 0.9075 9 P 0 ;1
L 10.8575 0.9575 10.8575 0.9575 9 P 0 ;1
L 10.8575 1.0075 10.8575 1.0075 9 P 0 ;1
L 10.8575 4.4575 10.8575 4.4575 9 P 0 ;1
L 10.8575 4.5075 10.8575 4.5075 9 P 0 ;1
L 10.8575 4.5575 10.8575 4.5575 9 P 0 ;1
L 10.9075 0.1575 10.9075 0.1575 9 P 0 ;1
L 10.9075 0.2075 10.9075 0.2075 9 P 0 ;1
L 10.9075 0.2575 10.9075 0.2575 9 P 0 ;1
L 10.9075 0.3075 10.9075 0.3075 9 P 0 ;1
L 10.9075 0.3575 10.9075 0.3575 9 P 0 ;1
L 10.9075 0.4075 10.9075 0.4075 9 P 0 ;1
L 10.9075 0.4575 10.9075 0.4575 9 P 0 ;1
L 10.9075 0.5075 10.9075 0.5075 9 P 0 ;1
L 10.9075 0.5575 10.9075 0.5575 9 P 0 ;1
L 10.9075 0.6075 10.9075 0.6075 9 P 0 ;1
L 10.9075 0.6575 10.9075 0.6575 9 P 0 ;1
L 10.9075 0.7075 10.9075 0.7075 9 P 0 ;1
L 10.9075 0.7575 10.9075 0.7575 9 P 0 ;1
L 10.9075 0.8075 10.9075 0.8075 9 P 0 ;1
L 10.9075 0.8575 10.9075 0.8575 9 P 0 ;1
L 10.9075 0.9075 10.9075 0.9075 9 P 0 ;1
L 10.9075 0.9575 10.9075 0.9575 9 P 0 ;1
L 10.9075 1.0075 10.9075 1.0075 9 P 0 ;1
L 10.9075 4.4075 10.9075 4.4075 9 P 0 ;1
L 10.9075 4.4575 10.9075 4.4575 9 P 0 ;1
L 10.9075 4.5075 10.9075 4.5075 9 P 0 ;1
L 10.9075 4.5575 10.9075 4.5575 9 P 0 ;1
L 10.9575 0.1575 10.9575 0.1575 9 P 0 ;1
L 10.9575 0.2075 10.9575 0.2075 9 P 0 ;1
L 10.9575 0.2575 10.9575 0.2575 9 P 0 ;1
L 10.9575 0.3075 10.9575 0.3075 9 P 0 ;1
L 10.9575 0.3575 10.9575 0.3575 9 P 0 ;1
L 10.9575 0.4075 10.9575 0.4075 9 P 0 ;1
L 10.9575 0.4575 10.9575 0.4575 9 P 0 ;1
L 10.9575 0.5075 10.9575 0.5075 9 P 0 ;1
L 10.9575 0.5575 10.9575 0.5575 9 P 0 ;1
L 10.9575 0.6075 10.9575 0.6075 9 P 0 ;1
L 10.9575 0.6575 10.9575 0.6575 9 P 0 ;1
L 10.9575 0.7075 10.9575 0.7075 9 P 0 ;1
L 10.9575 0.7575 10.9575 0.7575 9 P 0 ;1
L 10.9575 0.8075 10.9575 0.8075 9 P 0 ;1
L 10.9575 0.8575 10.9575 0.8575 9 P 0 ;1
L 10.9575 0.9075 10.9575 0.9075 9 P 0 ;1
L 10.9575 0.9575 10.9575 0.9575 9 P 0 ;1
L 10.9575 1.0075 10.9575 1.0075 9 P 0 ;1
L 10.9575 1.0575 10.9575 1.0575 9 P 0 ;1
L 10.9575 4.4075 10.9575 4.4075 9 P 0 ;1
L 10.9575 4.4575 10.9575 4.4575 9 P 0 ;1
L 10.9575 4.5075 10.9575 4.5075 9 P 0 ;1
L 10.9575 4.5575 10.9575 4.5575 9 P 0 ;1
L 10.9575 4.6075 10.9575 4.6075 9 P 0 ;1
L 10.9575 4.6575 10.9575 4.6575 9 P 0 ;1
L 10.9575 4.7075 10.9575 4.7075 9 P 0 ;1
L 10.9575 4.7575 10.9575 4.7575 9 P 0 ;1
L 10.9575 4.8075 10.9575 4.8075 9 P 0 ;1
L 11.0075 0.1575 11.0075 0.1575 9 P 0 ;1
L 11.0075 0.2075 11.0075 0.2075 9 P 0 ;1
L 11.0075 0.2575 11.0075 0.2575 9 P 0 ;1
L 11.0075 0.3075 11.0075 0.3075 9 P 0 ;1
L 11.0075 0.3575 11.0075 0.3575 9 P 0 ;1
L 11.0075 0.4075 11.0075 0.4075 9 P 0 ;1
L 11.0075 0.4575 11.0075 0.4575 9 P 0 ;1
L 11.0075 0.5075 11.0075 0.5075 9 P 0 ;1
L 11.0075 0.5575 11.0075 0.5575 9 P 0 ;1
L 11.0075 0.6075 11.0075 0.6075 9 P 0 ;1
L 11.0075 0.6575 11.0075 0.6575 9 P 0 ;1
L 11.0075 0.7075 11.0075 0.7075 9 P 0 ;1
L 11.0075 0.7575 11.0075 0.7575 9 P 0 ;1
L 11.0075 0.8075 11.0075 0.8075 9 P 0 ;1
L 11.0075 0.8575 11.0075 0.8575 9 P 0 ;1
L 11.0075 0.9075 11.0075 0.9075 9 P 0 ;1
L 11.0075 0.9575 11.0075 0.9575 9 P 0 ;1
L 11.0075 1.0075 11.0075 1.0075 9 P 0 ;1
L 11.0075 1.0575 11.0075 1.0575 9 P 0 ;1
L 11.0075 1.6075 11.0075 1.6075 9 P 0 ;1
L 11.0075 4.3075 11.0075 4.3075 9 P 0 ;1
L 11.0075 4.3575 11.0075 4.3575 9 P 0 ;1
L 11.0075 4.4075 11.0075 4.4075 9 P 0 ;1
L 11.0075 4.4575 11.0075 4.4575 9 P 0 ;1
L 11.0075 4.5075 11.0075 4.5075 9 P 0 ;1
L 11.0075 4.5575 11.0075 4.5575 9 P 0 ;1
L 11.0575 0.1575 11.0575 0.1575 9 P 0 ;1
L 11.0575 0.2075 11.0575 0.2075 9 P 0 ;1
L 11.0575 0.2575 11.0575 0.2575 9 P 0 ;1
L 11.0575 0.3075 11.0575 0.3075 9 P 0 ;1
L 11.0575 0.3575 11.0575 0.3575 9 P 0 ;1
L 11.0575 0.4075 11.0575 0.4075 9 P 0 ;1
L 11.0575 0.4575 11.0575 0.4575 9 P 0 ;1
L 11.0575 0.5075 11.0575 0.5075 9 P 0 ;1
L 11.0575 0.5575 11.0575 0.5575 9 P 0 ;1
L 11.0575 0.6075 11.0575 0.6075 9 P 0 ;1
L 11.0575 0.6575 11.0575 0.6575 9 P 0 ;1
L 11.0575 0.7075 11.0575 0.7075 9 P 0 ;1
L 11.0575 0.7575 11.0575 0.7575 9 P 0 ;1
L 11.0575 0.8075 11.0575 0.8075 9 P 0 ;1
L 11.0575 0.8575 11.0575 0.8575 9 P 0 ;1
L 11.0575 0.9075 11.0575 0.9075 9 P 0 ;1
L 11.0575 0.9575 11.0575 0.9575 9 P 0 ;1
L 11.0575 1.0075 11.0575 1.0075 9 P 0 ;1
L 11.0575 1.0575 11.0575 1.0575 9 P 0 ;1
L 11.0575 1.5075 11.0575 1.5075 9 P 0 ;1
L 11.0575 1.5575 11.0575 1.5575 9 P 0 ;1
L 11.0575 1.6075 11.0575 1.6075 9 P 0 ;1
L 11.0575 4.1575 11.0575 4.1575 9 P 0 ;1
L 11.0575 4.2075 11.0575 4.2075 9 P 0 ;1
L 11.0575 4.2575 11.0575 4.2575 9 P 0 ;1
L 11.0575 4.3075 11.0575 4.3075 9 P 0 ;1
L 11.0575 4.3575 11.0575 4.3575 9 P 0 ;1
L 11.0575 4.4075 11.0575 4.4075 9 P 0 ;1
L 11.0575 4.4575 11.0575 4.4575 9 P 0 ;1
L 11.0575 4.5075 11.0575 4.5075 9 P 0 ;1
L 11.0575 4.5575 11.0575 4.5575 9 P 0 ;1
L 11.1075 0.1575 11.1075 0.1575 9 P 0 ;1
L 11.1075 0.2075 11.1075 0.2075 9 P 0 ;1
L 11.1075 0.2575 11.1075 0.2575 9 P 0 ;1
L 11.1075 0.3075 11.1075 0.3075 9 P 0 ;1
L 11.1075 0.3575 11.1075 0.3575 9 P 0 ;1
L 11.1075 0.4075 11.1075 0.4075 9 P 0 ;1
L 11.1075 0.4575 11.1075 0.4575 9 P 0 ;1
L 11.1075 0.5075 11.1075 0.5075 9 P 0 ;1
L 11.1075 0.5575 11.1075 0.5575 9 P 0 ;1
L 11.1075 0.6075 11.1075 0.6075 9 P 0 ;1
L 11.1075 0.6575 11.1075 0.6575 9 P 0 ;1
L 11.1075 0.7075 11.1075 0.7075 9 P 0 ;1
L 11.1075 0.7575 11.1075 0.7575 9 P 0 ;1
L 11.1075 0.8075 11.1075 0.8075 9 P 0 ;1
L 11.1075 0.8575 11.1075 0.8575 9 P 0 ;1
L 11.1075 0.9075 11.1075 0.9075 9 P 0 ;1
L 11.1075 0.9575 11.1075 0.9575 9 P 0 ;1
L 11.1075 1.0075 11.1075 1.0075 9 P 0 ;1
L 11.1075 1.0575 11.1075 1.0575 9 P 0 ;1
L 11.1075 1.5075 11.1075 1.5075 9 P 0 ;1
L 11.1075 1.5575 11.1075 1.5575 9 P 0 ;1
L 11.1075 1.6075 11.1075 1.6075 9 P 0 ;1
L 11.1075 4.1575 11.1075 4.1575 9 P 0 ;1
L 11.1075 4.2075 11.1075 4.2075 9 P 0 ;1
L 11.1075 4.2575 11.1075 4.2575 9 P 0 ;1
L 11.1075 4.3075 11.1075 4.3075 9 P 0 ;1
L 11.1075 4.3575 11.1075 4.3575 9 P 0 ;1
L 11.1075 4.4075 11.1075 4.4075 9 P 0 ;1
L 11.1075 4.4575 11.1075 4.4575 9 P 0 ;1
L 11.1075 4.5075 11.1075 4.5075 9 P 0 ;1
L 11.1075 4.5575 11.1075 4.5575 9 P 0 ;1
L 11.1575 0.1575 11.1575 0.1575 9 P 0 ;1
L 11.1575 0.2075 11.1575 0.2075 9 P 0 ;1
L 11.1575 0.2575 11.1575 0.2575 9 P 0 ;1
L 11.1575 0.3075 11.1575 0.3075 9 P 0 ;1
L 11.1575 0.3575 11.1575 0.3575 9 P 0 ;1
L 11.1575 0.4075 11.1575 0.4075 9 P 0 ;1
L 11.1575 0.4575 11.1575 0.4575 9 P 0 ;1
L 11.1575 0.5075 11.1575 0.5075 9 P 0 ;1
L 11.1575 0.5575 11.1575 0.5575 9 P 0 ;1
L 11.1575 0.6075 11.1575 0.6075 9 P 0 ;1
L 11.1575 0.6575 11.1575 0.6575 9 P 0 ;1
L 11.1575 0.7075 11.1575 0.7075 9 P 0 ;1
L 11.1575 0.7575 11.1575 0.7575 9 P 0 ;1
L 11.1575 0.8075 11.1575 0.8075 9 P 0 ;1
L 11.1575 0.8575 11.1575 0.8575 9 P 0 ;1
L 11.1575 0.9075 11.1575 0.9075 9 P 0 ;1
L 11.1575 0.9575 11.1575 0.9575 9 P 0 ;1
L 11.1575 1.0075 11.1575 1.0075 9 P 0 ;1
L 11.1575 1.0575 11.1575 1.0575 9 P 0 ;1
L 11.1575 1.5575 11.1575 1.5575 9 P 0 ;1
L 11.1575 1.6075 11.1575 1.6075 9 P 0 ;1
L 11.1575 4.1575 11.1575 4.1575 9 P 0 ;1
L 11.1575 4.2075 11.1575 4.2075 9 P 0 ;1
L 11.1575 4.2575 11.1575 4.2575 9 P 0 ;1
L 11.1575 4.3075 11.1575 4.3075 9 P 0 ;1
L 11.1575 4.3575 11.1575 4.3575 9 P 0 ;1
L 11.1575 4.4075 11.1575 4.4075 9 P 0 ;1
L 11.1575 4.4575 11.1575 4.4575 9 P 0 ;1
L 11.1575 4.5075 11.1575 4.5075 9 P 0 ;1
L 11.1575 4.5575 11.1575 4.5575 9 P 0 ;1
L 11.2075 0.1575 11.2075 0.1575 9 P 0 ;1
L 11.2075 0.2075 11.2075 0.2075 9 P 0 ;1
L 11.2075 0.2575 11.2075 0.2575 9 P 0 ;1
L 11.2075 0.3075 11.2075 0.3075 9 P 0 ;1
L 11.2075 0.3575 11.2075 0.3575 9 P 0 ;1
L 11.2075 0.4075 11.2075 0.4075 9 P 0 ;1
L 11.2075 0.4575 11.2075 0.4575 9 P 0 ;1
L 11.2075 0.5075 11.2075 0.5075 9 P 0 ;1
L 11.2075 0.5575 11.2075 0.5575 9 P 0 ;1
L 11.2075 0.6075 11.2075 0.6075 9 P 0 ;1
L 11.2075 0.6575 11.2075 0.6575 9 P 0 ;1
L 11.2075 0.7075 11.2075 0.7075 9 P 0 ;1
L 11.2075 0.7575 11.2075 0.7575 9 P 0 ;1
L 11.2075 0.8075 11.2075 0.8075 9 P 0 ;1
L 11.2075 0.8575 11.2075 0.8575 9 P 0 ;1
L 11.2075 0.9075 11.2075 0.9075 9 P 0 ;1
L 11.2075 0.9575 11.2075 0.9575 9 P 0 ;1
L 11.2075 1.0075 11.2075 1.0075 9 P 0 ;1
L 11.2075 1.0575 11.2075 1.0575 9 P 0 ;1
L 11.2075 1.6075 11.2075 1.6075 9 P 0 ;1
L 11.2075 1.6575 11.2075 1.6575 9 P 0 ;1
L 11.2075 2.0075 11.2075 2.0075 9 P 0 ;1
L 11.2075 2.0575 11.2075 2.0575 9 P 0 ;1
L 11.2075 2.1075 11.2075 2.1075 9 P 0 ;1
L 11.2075 2.1575 11.2075 2.1575 9 P 0 ;1
L 11.2075 2.2075 11.2075 2.2075 9 P 0 ;1
L 11.2075 2.2575 11.2075 2.2575 9 P 0 ;1
L 11.2075 2.3075 11.2075 2.3075 9 P 0 ;1
L 11.2075 2.3575 11.2075 2.3575 9 P 0 ;1
L 11.2075 2.4075 11.2075 2.4075 9 P 0 ;1
L 11.2075 2.4575 11.2075 2.4575 9 P 0 ;1
L 11.2075 2.5075 11.2075 2.5075 9 P 0 ;1
L 11.2075 2.5575 11.2075 2.5575 9 P 0 ;1
L 11.2075 2.6075 11.2075 2.6075 9 P 0 ;1
L 11.2075 2.6575 11.2075 2.6575 9 P 0 ;1
L 11.2075 2.7075 11.2075 2.7075 9 P 0 ;1
L 11.2075 2.7575 11.2075 2.7575 9 P 0 ;1
L 11.2075 3.8075 11.2075 3.8075 9 P 0 ;1
L 11.2075 3.8575 11.2075 3.8575 9 P 0 ;1
L 11.2075 4.1575 11.2075 4.1575 9 P 0 ;1
L 11.2075 4.2075 11.2075 4.2075 9 P 0 ;1
L 11.2075 4.2575 11.2075 4.2575 9 P 0 ;1
L 11.2075 4.3075 11.2075 4.3075 9 P 0 ;1
L 11.2075 4.3575 11.2075 4.3575 9 P 0 ;1
L 11.2075 4.4075 11.2075 4.4075 9 P 0 ;1
L 11.2075 4.4575 11.2075 4.4575 9 P 0 ;1
L 11.2075 4.5075 11.2075 4.5075 9 P 0 ;1
L 11.2075 4.5575 11.2075 4.5575 9 P 0 ;1
L 11.2575 0.1575 11.2575 0.1575 9 P 0 ;1
L 11.2575 0.2075 11.2575 0.2075 9 P 0 ;1
L 11.2575 0.2575 11.2575 0.2575 9 P 0 ;1
L 11.2575 0.3075 11.2575 0.3075 9 P 0 ;1
L 11.2575 0.3575 11.2575 0.3575 9 P 0 ;1
L 11.2575 0.4075 11.2575 0.4075 9 P 0 ;1
L 11.2575 0.4575 11.2575 0.4575 9 P 0 ;1
L 11.2575 0.5075 11.2575 0.5075 9 P 0 ;1
L 11.2575 0.5575 11.2575 0.5575 9 P 0 ;1
L 11.2575 0.6075 11.2575 0.6075 9 P 0 ;1
L 11.2575 0.6575 11.2575 0.6575 9 P 0 ;1
L 11.2575 0.7075 11.2575 0.7075 9 P 0 ;1
L 11.2575 0.7575 11.2575 0.7575 9 P 0 ;1
L 11.2575 0.8075 11.2575 0.8075 9 P 0 ;1
L 11.2575 0.8575 11.2575 0.8575 9 P 0 ;1
L 11.2575 0.9075 11.2575 0.9075 9 P 0 ;1
L 11.2575 0.9575 11.2575 0.9575 9 P 0 ;1
L 11.2575 1.0075 11.2575 1.0075 9 P 0 ;1
L 11.2575 1.0575 11.2575 1.0575 9 P 0 ;1
L 11.2575 1.1075 11.2575 1.1075 9 P 0 ;1
L 11.2575 1.6075 11.2575 1.6075 9 P 0 ;1
L 11.2575 1.6575 11.2575 1.6575 9 P 0 ;1
L 11.2575 1.7075 11.2575 1.7075 9 P 0 ;1
L 11.2575 2.1075 11.2575 2.1075 9 P 0 ;1
L 11.2575 2.1575 11.2575 2.1575 9 P 0 ;1
L 11.2575 2.2075 11.2575 2.2075 9 P 0 ;1
L 11.2575 2.2575 11.2575 2.2575 9 P 0 ;1
L 11.2575 2.3075 11.2575 2.3075 9 P 0 ;1
L 11.2575 2.3575 11.2575 2.3575 9 P 0 ;1
L 11.2575 2.4075 11.2575 2.4075 9 P 0 ;1
L 11.2575 2.4575 11.2575 2.4575 9 P 0 ;1
L 11.2575 2.5075 11.2575 2.5075 9 P 0 ;1
L 11.2575 2.5575 11.2575 2.5575 9 P 0 ;1
L 11.2575 2.6075 11.2575 2.6075 9 P 0 ;1
L 11.2575 2.6575 11.2575 2.6575 9 P 0 ;1
L 11.2575 2.7075 11.2575 2.7075 9 P 0 ;1
L 11.2575 2.7575 11.2575 2.7575 9 P 0 ;1
L 11.2575 2.8075 11.2575 2.8075 9 P 0 ;1
L 11.2575 2.8575 11.2575 2.8575 9 P 0 ;1
L 11.2575 3.4075 11.2575 3.4075 9 P 0 ;1
L 11.2575 3.4575 11.2575 3.4575 9 P 0 ;1
L 11.2575 3.5075 11.2575 3.5075 9 P 0 ;1
L 11.2575 3.5575 11.2575 3.5575 9 P 0 ;1
L 11.2575 3.6075 11.2575 3.6075 9 P 0 ;1
L 11.2575 3.6575 11.2575 3.6575 9 P 0 ;1
L 11.2575 3.7075 11.2575 3.7075 9 P 0 ;1
L 11.2575 3.7575 11.2575 3.7575 9 P 0 ;1
L 11.2575 3.8075 11.2575 3.8075 9 P 0 ;1
L 11.2575 3.8575 11.2575 3.8575 9 P 0 ;1
L 11.2575 3.9075 11.2575 3.9075 9 P 0 ;1
L 11.2575 4.2075 11.2575 4.2075 9 P 0 ;1
L 11.2575 4.2575 11.2575 4.2575 9 P 0 ;1
L 11.2575 4.3075 11.2575 4.3075 9 P 0 ;1
L 11.2575 4.3575 11.2575 4.3575 9 P 0 ;1
L 11.2575 4.4075 11.2575 4.4075 9 P 0 ;1
L 11.2575 4.4575 11.2575 4.4575 9 P 0 ;1
L 11.2575 4.5075 11.2575 4.5075 9 P 0 ;1
L 11.2575 4.5575 11.2575 4.5575 9 P 0 ;1
L 11.2575 4.6075 11.2575 4.6075 9 P 0 ;1
L 11.2575 4.6575 11.2575 4.6575 9 P 0 ;1
L 11.2575 4.7075 11.2575 4.7075 9 P 0 ;1
L 11.3075 0.1575 11.3075 0.1575 9 P 0 ;1
L 11.3075 0.2075 11.3075 0.2075 9 P 0 ;1
L 11.3075 0.2575 11.3075 0.2575 9 P 0 ;1
L 11.3075 0.3075 11.3075 0.3075 9 P 0 ;1
L 11.3075 0.3575 11.3075 0.3575 9 P 0 ;1
L 11.3075 0.4075 11.3075 0.4075 9 P 0 ;1
L 11.3075 0.4575 11.3075 0.4575 9 P 0 ;1
L 11.3075 0.5075 11.3075 0.5075 9 P 0 ;1
L 11.3075 0.5575 11.3075 0.5575 9 P 0 ;1
L 11.3075 0.6075 11.3075 0.6075 9 P 0 ;1
L 11.3075 0.6575 11.3075 0.6575 9 P 0 ;1
L 11.3075 0.7075 11.3075 0.7075 9 P 0 ;1
L 11.3075 0.7575 11.3075 0.7575 9 P 0 ;1
L 11.3075 0.8075 11.3075 0.8075 9 P 0 ;1
L 11.3075 0.8575 11.3075 0.8575 9 P 0 ;1
L 11.3075 0.9075 11.3075 0.9075 9 P 0 ;1
L 11.3075 0.9575 11.3075 0.9575 9 P 0 ;1
L 11.3075 1.0075 11.3075 1.0075 9 P 0 ;1
L 11.3075 1.0575 11.3075 1.0575 9 P 0 ;1
L 11.3075 1.1075 11.3075 1.1075 9 P 0 ;1
L 11.3075 1.6575 11.3075 1.6575 9 P 0 ;1
L 11.3075 1.7075 11.3075 1.7075 9 P 0 ;1
L 11.3075 2.1575 11.3075 2.1575 9 P 0 ;1
L 11.3075 2.2075 11.3075 2.2075 9 P 0 ;1
L 11.3075 2.2575 11.3075 2.2575 9 P 0 ;1
L 11.3075 2.3075 11.3075 2.3075 9 P 0 ;1
L 11.3075 2.3575 11.3075 2.3575 9 P 0 ;1
L 11.3075 2.4075 11.3075 2.4075 9 P 0 ;1
L 11.3075 2.4575 11.3075 2.4575 9 P 0 ;1
L 11.3075 2.5075 11.3075 2.5075 9 P 0 ;1
L 11.3075 2.5575 11.3075 2.5575 9 P 0 ;1
L 11.3075 2.6075 11.3075 2.6075 9 P 0 ;1
L 11.3075 2.6575 11.3075 2.6575 9 P 0 ;1
L 11.3075 2.7075 11.3075 2.7075 9 P 0 ;1
L 11.3075 2.7575 11.3075 2.7575 9 P 0 ;1
L 11.3075 2.8075 11.3075 2.8075 9 P 0 ;1
L 11.3075 2.8575 11.3075 2.8575 9 P 0 ;1
L 11.3075 3.4075 11.3075 3.4075 9 P 0 ;1
L 11.3075 3.4575 11.3075 3.4575 9 P 0 ;1
L 11.3075 3.5075 11.3075 3.5075 9 P 0 ;1
L 11.3075 3.5575 11.3075 3.5575 9 P 0 ;1
L 11.3075 3.6075 11.3075 3.6075 9 P 0 ;1
L 11.3075 3.6575 11.3075 3.6575 9 P 0 ;1
L 11.3075 3.7075 11.3075 3.7075 9 P 0 ;1
L 11.3075 3.7575 11.3075 3.7575 9 P 0 ;1
L 11.3075 3.8075 11.3075 3.8075 9 P 0 ;1
L 11.3075 3.8575 11.3075 3.8575 9 P 0 ;1
L 11.3075 4.2075 11.3075 4.2075 9 P 0 ;1
L 11.3075 4.2575 11.3075 4.2575 9 P 0 ;1
L 11.3075 4.3075 11.3075 4.3075 9 P 0 ;1
L 11.3075 4.3575 11.3075 4.3575 9 P 0 ;1
L 11.3075 4.4075 11.3075 4.4075 9 P 0 ;1
L 11.3075 4.4575 11.3075 4.4575 9 P 0 ;1
L 11.3075 4.5075 11.3075 4.5075 9 P 0 ;1
L 11.3075 4.5575 11.3075 4.5575 9 P 0 ;1
L 11.3075 4.6075 11.3075 4.6075 9 P 0 ;1
L 11.3075 4.6575 11.3075 4.6575 9 P 0 ;1
L 11.3075 4.7075 11.3075 4.7075 9 P 0 ;1
L 11.3575 0.1575 11.3575 0.1575 9 P 0 ;1
L 11.3575 0.2075 11.3575 0.2075 9 P 0 ;1
L 11.3575 0.2575 11.3575 0.2575 9 P 0 ;1
L 11.3575 0.3075 11.3575 0.3075 9 P 0 ;1
L 11.3575 0.3575 11.3575 0.3575 9 P 0 ;1
L 11.3575 0.4075 11.3575 0.4075 9 P 0 ;1
L 11.3575 0.4575 11.3575 0.4575 9 P 0 ;1
L 11.3575 0.5075 11.3575 0.5075 9 P 0 ;1
L 11.3575 0.5575 11.3575 0.5575 9 P 0 ;1
L 11.3575 0.6075 11.3575 0.6075 9 P 0 ;1
L 11.3575 0.6575 11.3575 0.6575 9 P 0 ;1
L 11.3575 0.7075 11.3575 0.7075 9 P 0 ;1
L 11.3575 0.7575 11.3575 0.7575 9 P 0 ;1
L 11.3575 0.8075 11.3575 0.8075 9 P 0 ;1
L 11.3575 0.8575 11.3575 0.8575 9 P 0 ;1
L 11.3575 0.9075 11.3575 0.9075 9 P 0 ;1
L 11.3575 0.9575 11.3575 0.9575 9 P 0 ;1
L 11.3575 1.0075 11.3575 1.0075 9 P 0 ;1
L 11.3575 1.0575 11.3575 1.0575 9 P 0 ;1
L 11.3575 1.1075 11.3575 1.1075 9 P 0 ;1
L 11.3575 1.7075 11.3575 1.7075 9 P 0 ;1
L 11.3575 2.2575 11.3575 2.2575 9 P 0 ;1
L 11.3575 2.3075 11.3575 2.3075 9 P 0 ;1
L 11.3575 2.3575 11.3575 2.3575 9 P 0 ;1
L 11.3575 2.4075 11.3575 2.4075 9 P 0 ;1
L 11.3575 2.4575 11.3575 2.4575 9 P 0 ;1
L 11.3575 2.5075 11.3575 2.5075 9 P 0 ;1
L 11.3575 2.5575 11.3575 2.5575 9 P 0 ;1
L 11.3575 2.6075 11.3575 2.6075 9 P 0 ;1
L 11.3575 2.9075 11.3575 2.9075 9 P 0 ;1
L 11.3575 3.3575 11.3575 3.3575 9 P 0 ;1
L 11.3575 3.4075 11.3575 3.4075 9 P 0 ;1
L 11.3575 3.4575 11.3575 3.4575 9 P 0 ;1
L 11.3575 3.5075 11.3575 3.5075 9 P 0 ;1
L 11.3575 3.5575 11.3575 3.5575 9 P 0 ;1
L 11.3575 3.6075 11.3575 3.6075 9 P 0 ;1
L 11.3575 3.6575 11.3575 3.6575 9 P 0 ;1
L 11.3575 3.7075 11.3575 3.7075 9 P 0 ;1
L 11.3575 3.7575 11.3575 3.7575 9 P 0 ;1
L 11.3575 3.8075 11.3575 3.8075 9 P 0 ;1
L 11.3575 3.8575 11.3575 3.8575 9 P 0 ;1
L 11.3575 4.2075 11.3575 4.2075 9 P 0 ;1
L 11.3575 4.2575 11.3575 4.2575 9 P 0 ;1
L 11.3575 4.3075 11.3575 4.3075 9 P 0 ;1
L 11.3575 4.3575 11.3575 4.3575 9 P 0 ;1
L 11.3575 4.4075 11.3575 4.4075 9 P 0 ;1
L 11.3575 4.4575 11.3575 4.4575 9 P 0 ;1
L 11.3575 4.5075 11.3575 4.5075 9 P 0 ;1
L 11.3575 4.5575 11.3575 4.5575 9 P 0 ;1
L 11.3575 4.6075 11.3575 4.6075 9 P 0 ;1
L 11.3575 4.6575 11.3575 4.6575 9 P 0 ;1
L 11.3575 4.7075 11.3575 4.7075 9 P 0 ;1
L 11.4075 0.1575 11.4075 0.1575 9 P 0 ;1
L 11.4075 0.2075 11.4075 0.2075 9 P 0 ;1
L 11.4075 0.2575 11.4075 0.2575 9 P 0 ;1
L 11.4075 0.3075 11.4075 0.3075 9 P 0 ;1
L 11.4075 0.3575 11.4075 0.3575 9 P 0 ;1
L 11.4075 0.4075 11.4075 0.4075 9 P 0 ;1
L 11.4075 0.4575 11.4075 0.4575 9 P 0 ;1
L 11.4075 0.5075 11.4075 0.5075 9 P 0 ;1
L 11.4075 0.5575 11.4075 0.5575 9 P 0 ;1
L 11.4075 0.6075 11.4075 0.6075 9 P 0 ;1
L 11.4075 0.6575 11.4075 0.6575 9 P 0 ;1
L 11.4075 0.7075 11.4075 0.7075 9 P 0 ;1
L 11.4075 0.7575 11.4075 0.7575 9 P 0 ;1
L 11.4075 0.8075 11.4075 0.8075 9 P 0 ;1
L 11.4075 0.8575 11.4075 0.8575 9 P 0 ;1
L 11.4075 0.9075 11.4075 0.9075 9 P 0 ;1
L 11.4075 0.9575 11.4075 0.9575 9 P 0 ;1
L 11.4075 1.0075 11.4075 1.0075 9 P 0 ;1
L 11.4075 1.0575 11.4075 1.0575 9 P 0 ;1
L 11.4075 1.1075 11.4075 1.1075 9 P 0 ;1
L 11.4075 1.7075 11.4075 1.7075 9 P 0 ;1
L 11.4075 2.3075 11.4075 2.3075 9 P 0 ;1
L 11.4075 2.3575 11.4075 2.3575 9 P 0 ;1
L 11.4075 2.4075 11.4075 2.4075 9 P 0 ;1
L 11.4075 2.4575 11.4075 2.4575 9 P 0 ;1
L 11.4075 2.5075 11.4075 2.5075 9 P 0 ;1
L 11.4075 2.5575 11.4075 2.5575 9 P 0 ;1
L 11.4075 2.6075 11.4075 2.6075 9 P 0 ;1
L 11.4075 3.4075 11.4075 3.4075 9 P 0 ;1
L 11.4075 3.4575 11.4075 3.4575 9 P 0 ;1
L 11.4075 3.5075 11.4075 3.5075 9 P 0 ;1
L 11.4075 3.5575 11.4075 3.5575 9 P 0 ;1
L 11.4075 3.6075 11.4075 3.6075 9 P 0 ;1
L 11.4075 3.6575 11.4075 3.6575 9 P 0 ;1
L 11.4075 3.7075 11.4075 3.7075 9 P 0 ;1
L 11.4075 3.7575 11.4075 3.7575 9 P 0 ;1
L 11.4075 3.8075 11.4075 3.8075 9 P 0 ;1
L 11.4075 3.8575 11.4075 3.8575 9 P 0 ;1
L 11.4075 4.2075 11.4075 4.2075 9 P 0 ;1
L 11.4075 4.2575 11.4075 4.2575 9 P 0 ;1
L 11.4075 4.3075 11.4075 4.3075 9 P 0 ;1
L 11.4075 4.3575 11.4075 4.3575 9 P 0 ;1
L 11.4075 4.4075 11.4075 4.4075 9 P 0 ;1
L 11.4075 4.4575 11.4075 4.4575 9 P 0 ;1
L 11.4075 4.5075 11.4075 4.5075 9 P 0 ;1
L 11.4075 4.5575 11.4075 4.5575 9 P 0 ;1
L 11.4075 4.6075 11.4075 4.6075 9 P 0 ;1
L 11.4075 4.6575 11.4075 4.6575 9 P 0 ;1
L 11.4075 4.7075 11.4075 4.7075 9 P 0 ;1
L 11.4575 0.1575 11.4575 0.1575 9 P 0 ;1
L 11.4575 0.2075 11.4575 0.2075 9 P 0 ;1
L 11.4575 0.2575 11.4575 0.2575 9 P 0 ;1
L 11.4575 0.3075 11.4575 0.3075 9 P 0 ;1
L 11.4575 0.3575 11.4575 0.3575 9 P 0 ;1
L 11.4575 0.4075 11.4575 0.4075 9 P 0 ;1
L 11.4575 0.4575 11.4575 0.4575 9 P 0 ;1
L 11.4575 0.5075 11.4575 0.5075 9 P 0 ;1
L 11.4575 0.5575 11.4575 0.5575 9 P 0 ;1
L 11.4575 0.6075 11.4575 0.6075 9 P 0 ;1
L 11.4575 0.6575 11.4575 0.6575 9 P 0 ;1
L 11.4575 0.7075 11.4575 0.7075 9 P 0 ;1
L 11.4575 0.7575 11.4575 0.7575 9 P 0 ;1
L 11.4575 0.8075 11.4575 0.8075 9 P 0 ;1
L 11.4575 0.8575 11.4575 0.8575 9 P 0 ;1
L 11.4575 0.9075 11.4575 0.9075 9 P 0 ;1
L 11.4575 0.9575 11.4575 0.9575 9 P 0 ;1
L 11.4575 1.0075 11.4575 1.0075 9 P 0 ;1
L 11.4575 1.0575 11.4575 1.0575 9 P 0 ;1
L 11.4575 1.1075 11.4575 1.1075 9 P 0 ;1
L 11.4575 2.6575 11.4575 2.6575 9 P 0 ;1
L 11.4575 3.4075 11.4575 3.4075 9 P 0 ;1
L 11.4575 3.4575 11.4575 3.4575 9 P 0 ;1
L 11.4575 3.5075 11.4575 3.5075 9 P 0 ;1
L 11.4575 3.5575 11.4575 3.5575 9 P 0 ;1
L 11.4575 3.6075 11.4575 3.6075 9 P 0 ;1
L 11.4575 3.6575 11.4575 3.6575 9 P 0 ;1
L 11.4575 3.7075 11.4575 3.7075 9 P 0 ;1
L 11.4575 3.7575 11.4575 3.7575 9 P 0 ;1
L 11.4575 3.8075 11.4575 3.8075 9 P 0 ;1
L 11.4575 3.8575 11.4575 3.8575 9 P 0 ;1
L 11.4575 4.2075 11.4575 4.2075 9 P 0 ;1
L 11.4575 4.2575 11.4575 4.2575 9 P 0 ;1
L 11.4575 4.3075 11.4575 4.3075 9 P 0 ;1
L 11.4575 4.3575 11.4575 4.3575 9 P 0 ;1
L 11.4575 4.4075 11.4575 4.4075 9 P 0 ;1
L 11.4575 4.4575 11.4575 4.4575 9 P 0 ;1
L 11.4575 4.5075 11.4575 4.5075 9 P 0 ;1
L 11.4575 4.5575 11.4575 4.5575 9 P 0 ;1
L 11.4575 4.6075 11.4575 4.6075 9 P 0 ;1
L 11.4575 4.6575 11.4575 4.6575 9 P 0 ;1
L 11.4575 4.7075 11.4575 4.7075 9 P 0 ;1
L 11.5075 0.1575 11.5075 0.1575 9 P 0 ;1
L 11.5075 0.2075 11.5075 0.2075 9 P 0 ;1
L 11.5075 0.2575 11.5075 0.2575 9 P 0 ;1
L 11.5075 0.3075 11.5075 0.3075 9 P 0 ;1
L 11.5075 0.3575 11.5075 0.3575 9 P 0 ;1
L 11.5075 0.4075 11.5075 0.4075 9 P 0 ;1
L 11.5075 0.4575 11.5075 0.4575 9 P 0 ;1
L 11.5075 0.5075 11.5075 0.5075 9 P 0 ;1
L 11.5075 0.5575 11.5075 0.5575 9 P 0 ;1
L 11.5075 0.6075 11.5075 0.6075 9 P 0 ;1
L 11.5075 0.6575 11.5075 0.6575 9 P 0 ;1
L 11.5075 0.7075 11.5075 0.7075 9 P 0 ;1
L 11.5075 0.7575 11.5075 0.7575 9 P 0 ;1
L 11.5075 0.8075 11.5075 0.8075 9 P 0 ;1
L 11.5075 0.8575 11.5075 0.8575 9 P 0 ;1
L 11.5075 0.9075 11.5075 0.9075 9 P 0 ;1
L 11.5075 0.9575 11.5075 0.9575 9 P 0 ;1
L 11.5075 1.0075 11.5075 1.0075 9 P 0 ;1
L 11.5075 1.0575 11.5075 1.0575 9 P 0 ;1
L 11.5075 1.1075 11.5075 1.1075 9 P 0 ;1
L 11.5075 3.3575 11.5075 3.3575 9 P 0 ;1
L 11.5075 3.4075 11.5075 3.4075 9 P 0 ;1
L 11.5075 3.4575 11.5075 3.4575 9 P 0 ;1
L 11.5075 3.5075 11.5075 3.5075 9 P 0 ;1
L 11.5075 3.5575 11.5075 3.5575 9 P 0 ;1
L 11.5075 3.6075 11.5075 3.6075 9 P 0 ;1
L 11.5075 3.6575 11.5075 3.6575 9 P 0 ;1
L 11.5075 3.7075 11.5075 3.7075 9 P 0 ;1
L 11.5075 3.7575 11.5075 3.7575 9 P 0 ;1
L 11.5075 3.8075 11.5075 3.8075 9 P 0 ;1
L 11.5075 3.8575 11.5075 3.8575 9 P 0 ;1
L 11.5075 4.2575 11.5075 4.2575 9 P 0 ;1
L 11.5075 4.3075 11.5075 4.3075 9 P 0 ;1
L 11.5075 4.3575 11.5075 4.3575 9 P 0 ;1
L 11.5075 4.4075 11.5075 4.4075 9 P 0 ;1
L 11.5075 4.4575 11.5075 4.4575 9 P 0 ;1
L 11.5075 4.5075 11.5075 4.5075 9 P 0 ;1
L 11.5075 4.5575 11.5075 4.5575 9 P 0 ;1
L 11.5075 4.6075 11.5075 4.6075 9 P 0 ;1
L 11.5075 4.6575 11.5075 4.6575 9 P 0 ;1
L 11.5075 4.7075 11.5075 4.7075 9 P 0 ;1
L 11.5575 0.1575 11.5575 0.1575 9 P 0 ;1
L 11.5575 0.2075 11.5575 0.2075 9 P 0 ;1
L 11.5575 0.2575 11.5575 0.2575 9 P 0 ;1
L 11.5575 0.3075 11.5575 0.3075 9 P 0 ;1
L 11.5575 0.3575 11.5575 0.3575 9 P 0 ;1
L 11.5575 0.4075 11.5575 0.4075 9 P 0 ;1
L 11.5575 0.4575 11.5575 0.4575 9 P 0 ;1
L 11.5575 0.5075 11.5575 0.5075 9 P 0 ;1
L 11.5575 0.5575 11.5575 0.5575 9 P 0 ;1
L 11.5575 0.6075 11.5575 0.6075 9 P 0 ;1
L 11.5575 0.6575 11.5575 0.6575 9 P 0 ;1
L 11.5575 0.7075 11.5575 0.7075 9 P 0 ;1
L 11.5575 0.7575 11.5575 0.7575 9 P 0 ;1
L 11.5575 0.8075 11.5575 0.8075 9 P 0 ;1
L 11.5575 0.8575 11.5575 0.8575 9 P 0 ;1
L 11.5575 0.9075 11.5575 0.9075 9 P 0 ;1
L 11.5575 0.9575 11.5575 0.9575 9 P 0 ;1
L 11.5575 1.0075 11.5575 1.0075 9 P 0 ;1
L 11.5575 1.0575 11.5575 1.0575 9 P 0 ;1
L 11.5575 1.1075 11.5575 1.1075 9 P 0 ;1
L 11.5575 2.6575 11.5575 2.6575 9 P 0 ;1
L 11.5575 3.0075 11.5575 3.0075 9 P 0 ;1
L 11.5575 3.0575 11.5575 3.0575 9 P 0 ;1
L 11.5575 3.1075 11.5575 3.1075 9 P 0 ;1
L 11.5575 3.1575 11.5575 3.1575 9 P 0 ;1
L 11.5575 3.2075 11.5575 3.2075 9 P 0 ;1
L 11.5575 3.2575 11.5575 3.2575 9 P 0 ;1
L 11.5575 3.3075 11.5575 3.3075 9 P 0 ;1
L 11.5575 3.3575 11.5575 3.3575 9 P 0 ;1
L 11.5575 3.4075 11.5575 3.4075 9 P 0 ;1
L 11.5575 3.4575 11.5575 3.4575 9 P 0 ;1
L 11.5575 3.5075 11.5575 3.5075 9 P 0 ;1
L 11.5575 3.5575 11.5575 3.5575 9 P 0 ;1
L 11.5575 3.6075 11.5575 3.6075 9 P 0 ;1
L 11.5575 3.6575 11.5575 3.6575 9 P 0 ;1
L 11.5575 3.7075 11.5575 3.7075 9 P 0 ;1
L 11.5575 3.7575 11.5575 3.7575 9 P 0 ;1
L 11.5575 3.8075 11.5575 3.8075 9 P 0 ;1
L 11.5575 3.8575 11.5575 3.8575 9 P 0 ;1
L 11.5575 4.3075 11.5575 4.3075 9 P 0 ;1
L 11.5575 4.3575 11.5575 4.3575 9 P 0 ;1
L 11.5575 4.4075 11.5575 4.4075 9 P 0 ;1
L 11.5575 4.4575 11.5575 4.4575 9 P 0 ;1
L 11.5575 4.5075 11.5575 4.5075 9 P 0 ;1
L 11.5575 4.5575 11.5575 4.5575 9 P 0 ;1
L 11.5575 4.6075 11.5575 4.6075 9 P 0 ;1
L 11.5575 4.6575 11.5575 4.6575 9 P 0 ;1
L 11.5575 4.7075 11.5575 4.7075 9 P 0 ;1
L 11.6075 0.1575 11.6075 0.1575 9 P 0 ;1
L 11.6075 0.2075 11.6075 0.2075 9 P 0 ;1
L 11.6075 0.2575 11.6075 0.2575 9 P 0 ;1
L 11.6075 0.3075 11.6075 0.3075 9 P 0 ;1
L 11.6075 0.3575 11.6075 0.3575 9 P 0 ;1
L 11.6075 0.4075 11.6075 0.4075 9 P 0 ;1
L 11.6075 0.4575 11.6075 0.4575 9 P 0 ;1
L 11.6075 0.5075 11.6075 0.5075 9 P 0 ;1
L 11.6075 0.5575 11.6075 0.5575 9 P 0 ;1
L 11.6075 0.6075 11.6075 0.6075 9 P 0 ;1
L 11.6075 0.6575 11.6075 0.6575 9 P 0 ;1
L 11.6075 0.7075 11.6075 0.7075 9 P 0 ;1
L 11.6075 0.7575 11.6075 0.7575 9 P 0 ;1
L 11.6075 0.8075 11.6075 0.8075 9 P 0 ;1
L 11.6075 0.8575 11.6075 0.8575 9 P 0 ;1
L 11.6075 0.9075 11.6075 0.9075 9 P 0 ;1
L 11.6075 0.9575 11.6075 0.9575 9 P 0 ;1
L 11.6075 1.0075 11.6075 1.0075 9 P 0 ;1
L 11.6075 1.0575 11.6075 1.0575 9 P 0 ;1
L 11.6075 1.1075 11.6075 1.1075 9 P 0 ;1
L 11.6075 2.1575 11.6075 2.1575 9 P 0 ;1
L 11.6075 3.0075 11.6075 3.0075 9 P 0 ;1
L 11.6075 3.0575 11.6075 3.0575 9 P 0 ;1
L 11.6075 3.1075 11.6075 3.1075 9 P 0 ;1
L 11.6075 3.1575 11.6075 3.1575 9 P 0 ;1
L 11.6075 3.2075 11.6075 3.2075 9 P 0 ;1
L 11.6075 3.2575 11.6075 3.2575 9 P 0 ;1
L 11.6075 3.3075 11.6075 3.3075 9 P 0 ;1
L 11.6075 3.3575 11.6075 3.3575 9 P 0 ;1
L 11.6075 3.4075 11.6075 3.4075 9 P 0 ;1
L 11.6075 3.4575 11.6075 3.4575 9 P 0 ;1
L 11.6075 3.5075 11.6075 3.5075 9 P 0 ;1
L 11.6075 3.5575 11.6075 3.5575 9 P 0 ;1
L 11.6075 3.6075 11.6075 3.6075 9 P 0 ;1
L 11.6075 3.6575 11.6075 3.6575 9 P 0 ;1
L 11.6075 3.7075 11.6075 3.7075 9 P 0 ;1
L 11.6075 3.7575 11.6075 3.7575 9 P 0 ;1
L 11.6075 3.8075 11.6075 3.8075 9 P 0 ;1
L 11.6075 4.3075 11.6075 4.3075 9 P 0 ;1
L 11.6075 4.3575 11.6075 4.3575 9 P 0 ;1
L 11.6075 4.4075 11.6075 4.4075 9 P 0 ;1
L 11.6075 4.4575 11.6075 4.4575 9 P 0 ;1
L 11.6075 4.5075 11.6075 4.5075 9 P 0 ;1
L 11.6075 4.5575 11.6075 4.5575 9 P 0 ;1
L 11.6075 4.6075 11.6075 4.6075 9 P 0 ;1
L 11.6075 4.6575 11.6075 4.6575 9 P 0 ;1
L 11.6075 4.7075 11.6075 4.7075 9 P 0 ;1
L 11.6575 0.1575 11.6575 0.1575 9 P 0 ;1
L 11.6575 0.2075 11.6575 0.2075 9 P 0 ;1
L 11.6575 0.2575 11.6575 0.2575 9 P 0 ;1
L 11.6575 0.3075 11.6575 0.3075 9 P 0 ;1
L 11.6575 0.3575 11.6575 0.3575 9 P 0 ;1
L 11.6575 0.4075 11.6575 0.4075 9 P 0 ;1
L 11.6575 0.4575 11.6575 0.4575 9 P 0 ;1
L 11.6575 0.5075 11.6575 0.5075 9 P 0 ;1
L 11.6575 0.5575 11.6575 0.5575 9 P 0 ;1
L 11.6575 0.6075 11.6575 0.6075 9 P 0 ;1
L 11.6575 0.6575 11.6575 0.6575 9 P 0 ;1
L 11.6575 0.7075 11.6575 0.7075 9 P 0 ;1
L 11.6575 0.7575 11.6575 0.7575 9 P 0 ;1
L 11.6575 0.8075 11.6575 0.8075 9 P 0 ;1
L 11.6575 0.8575 11.6575 0.8575 9 P 0 ;1
L 11.6575 0.9075 11.6575 0.9075 9 P 0 ;1
L 11.6575 0.9575 11.6575 0.9575 9 P 0 ;1
L 11.6575 1.0075 11.6575 1.0075 9 P 0 ;1
L 11.6575 1.0575 11.6575 1.0575 9 P 0 ;1
L 11.6575 1.1075 11.6575 1.1075 9 P 0 ;1
L 11.6575 2.9575 11.6575 2.9575 9 P 0 ;1
L 11.6575 3.0075 11.6575 3.0075 9 P 0 ;1
L 11.6575 3.0575 11.6575 3.0575 9 P 0 ;1
L 11.6575 3.1075 11.6575 3.1075 9 P 0 ;1
L 11.6575 3.1575 11.6575 3.1575 9 P 0 ;1
L 11.6575 3.2075 11.6575 3.2075 9 P 0 ;1
L 11.6575 3.2575 11.6575 3.2575 9 P 0 ;1
L 11.6575 3.3075 11.6575 3.3075 9 P 0 ;1
L 11.6575 3.3575 11.6575 3.3575 9 P 0 ;1
L 11.6575 3.4075 11.6575 3.4075 9 P 0 ;1
L 11.6575 3.4575 11.6575 3.4575 9 P 0 ;1
L 11.6575 3.5075 11.6575 3.5075 9 P 0 ;1
L 11.6575 3.5575 11.6575 3.5575 9 P 0 ;1
L 11.6575 3.6075 11.6575 3.6075 9 P 0 ;1
L 11.6575 3.6575 11.6575 3.6575 9 P 0 ;1
L 11.6575 3.7075 11.6575 3.7075 9 P 0 ;1
L 11.6575 3.7575 11.6575 3.7575 9 P 0 ;1
L 11.6575 3.8075 11.6575 3.8075 9 P 0 ;1
L 11.6575 4.3575 11.6575 4.3575 9 P 0 ;1
L 11.6575 4.4075 11.6575 4.4075 9 P 0 ;1
L 11.6575 4.4575 11.6575 4.4575 9 P 0 ;1
L 11.6575 4.5075 11.6575 4.5075 9 P 0 ;1
L 11.6575 4.5575 11.6575 4.5575 9 P 0 ;1
L 11.6575 4.6075 11.6575 4.6075 9 P 0 ;1
L 11.6575 4.6575 11.6575 4.6575 9 P 0 ;1
L 11.6575 4.7075 11.6575 4.7075 9 P 0 ;1
L 11.7075 0.1575 11.7075 0.1575 9 P 0 ;1
L 11.7075 0.2075 11.7075 0.2075 9 P 0 ;1
L 11.7075 0.2575 11.7075 0.2575 9 P 0 ;1
L 11.7075 0.3075 11.7075 0.3075 9 P 0 ;1
L 11.7075 0.3575 11.7075 0.3575 9 P 0 ;1
L 11.7075 0.4075 11.7075 0.4075 9 P 0 ;1
L 11.7075 0.4575 11.7075 0.4575 9 P 0 ;1
L 11.7075 0.5075 11.7075 0.5075 9 P 0 ;1
L 11.7075 0.5575 11.7075 0.5575 9 P 0 ;1
L 11.7075 0.6075 11.7075 0.6075 9 P 0 ;1
L 11.7075 0.6575 11.7075 0.6575 9 P 0 ;1
L 11.7075 0.7075 11.7075 0.7075 9 P 0 ;1
L 11.7075 0.7575 11.7075 0.7575 9 P 0 ;1
L 11.7075 0.8075 11.7075 0.8075 9 P 0 ;1
L 11.7075 0.8575 11.7075 0.8575 9 P 0 ;1
L 11.7075 0.9075 11.7075 0.9075 9 P 0 ;1
L 11.7075 0.9575 11.7075 0.9575 9 P 0 ;1
L 11.7075 1.0075 11.7075 1.0075 9 P 0 ;1
L 11.7075 1.0575 11.7075 1.0575 9 P 0 ;1
L 11.7075 1.1075 11.7075 1.1075 9 P 0 ;1
L 11.7075 2.9575 11.7075 2.9575 9 P 0 ;1
L 11.7075 3.0075 11.7075 3.0075 9 P 0 ;1
L 11.7075 3.0575 11.7075 3.0575 9 P 0 ;1
L 11.7075 3.1075 11.7075 3.1075 9 P 0 ;1
L 11.7075 3.1575 11.7075 3.1575 9 P 0 ;1
L 11.7075 3.2075 11.7075 3.2075 9 P 0 ;1
L 11.7075 3.2575 11.7075 3.2575 9 P 0 ;1
L 11.7075 3.3075 11.7075 3.3075 9 P 0 ;1
L 11.7075 3.3575 11.7075 3.3575 9 P 0 ;1
L 11.7075 3.4075 11.7075 3.4075 9 P 0 ;1
L 11.7075 3.4575 11.7075 3.4575 9 P 0 ;1
L 11.7075 3.5075 11.7075 3.5075 9 P 0 ;1
L 11.7075 3.5575 11.7075 3.5575 9 P 0 ;1
L 11.7075 3.6075 11.7075 3.6075 9 P 0 ;1
L 11.7075 3.6575 11.7075 3.6575 9 P 0 ;1
L 11.7075 3.7075 11.7075 3.7075 9 P 0 ;1
L 11.7075 3.7575 11.7075 3.7575 9 P 0 ;1
L 11.7075 3.8075 11.7075 3.8075 9 P 0 ;1
L 11.7075 4.0575 11.7075 4.0575 9 P 0 ;1
L 11.7075 4.1075 11.7075 4.1075 9 P 0 ;1
L 11.7075 4.4075 11.7075 4.4075 9 P 0 ;1
L 11.7075 4.4575 11.7075 4.4575 9 P 0 ;1
L 11.7075 4.5075 11.7075 4.5075 9 P 0 ;1
L 11.7075 4.5575 11.7075 4.5575 9 P 0 ;1
L 11.7075 4.6075 11.7075 4.6075 9 P 0 ;1
L 11.7075 4.6575 11.7075 4.6575 9 P 0 ;1
L 11.7075 4.7075 11.7075 4.7075 9 P 0 ;1
L 11.7575 0.1575 11.7575 0.1575 9 P 0 ;1
L 11.7575 0.2075 11.7575 0.2075 9 P 0 ;1
L 11.7575 0.2575 11.7575 0.2575 9 P 0 ;1
L 11.7575 0.3075 11.7575 0.3075 9 P 0 ;1
L 11.7575 0.3575 11.7575 0.3575 9 P 0 ;1
L 11.7575 0.4075 11.7575 0.4075 9 P 0 ;1
L 11.7575 0.4575 11.7575 0.4575 9 P 0 ;1
L 11.7575 0.5075 11.7575 0.5075 9 P 0 ;1
L 11.7575 0.5575 11.7575 0.5575 9 P 0 ;1
L 11.7575 0.6075 11.7575 0.6075 9 P 0 ;1
L 11.7575 0.6575 11.7575 0.6575 9 P 0 ;1
L 11.7575 0.7075 11.7575 0.7075 9 P 0 ;1
L 11.7575 0.7575 11.7575 0.7575 9 P 0 ;1
L 11.7575 0.8075 11.7575 0.8075 9 P 0 ;1
L 11.7575 0.8575 11.7575 0.8575 9 P 0 ;1
L 11.7575 0.9075 11.7575 0.9075 9 P 0 ;1
L 11.7575 0.9575 11.7575 0.9575 9 P 0 ;1
L 11.7575 1.0075 11.7575 1.0075 9 P 0 ;1
L 11.7575 1.0575 11.7575 1.0575 9 P 0 ;1
L 11.7575 1.3075 11.7575 1.3075 9 P 0 ;1
L 11.7575 2.8575 11.7575 2.8575 9 P 0 ;1
L 11.7575 2.9075 11.7575 2.9075 9 P 0 ;1
L 11.7575 2.9575 11.7575 2.9575 9 P 0 ;1
L 11.7575 3.0075 11.7575 3.0075 9 P 0 ;1
L 11.7575 3.0575 11.7575 3.0575 9 P 0 ;1
L 11.7575 3.1075 11.7575 3.1075 9 P 0 ;1
L 11.7575 3.1575 11.7575 3.1575 9 P 0 ;1
L 11.7575 3.2075 11.7575 3.2075 9 P 0 ;1
L 11.7575 3.2575 11.7575 3.2575 9 P 0 ;1
L 11.7575 3.3075 11.7575 3.3075 9 P 0 ;1
L 11.7575 3.3575 11.7575 3.3575 9 P 0 ;1
L 11.7575 3.4075 11.7575 3.4075 9 P 0 ;1
L 11.7575 3.4575 11.7575 3.4575 9 P 0 ;1
L 11.7575 3.5075 11.7575 3.5075 9 P 0 ;1
L 11.7575 3.5575 11.7575 3.5575 9 P 0 ;1
L 11.7575 3.6075 11.7575 3.6075 9 P 0 ;1
L 11.7575 3.6575 11.7575 3.6575 9 P 0 ;1
L 11.7575 3.7075 11.7575 3.7075 9 P 0 ;1
L 11.7575 3.7575 11.7575 3.7575 9 P 0 ;1
L 11.7575 3.8075 11.7575 3.8075 9 P 0 ;1
L 11.7575 4.0575 11.7575 4.0575 9 P 0 ;1
L 11.7575 4.1075 11.7575 4.1075 9 P 0 ;1
L 11.7575 4.1575 11.7575 4.1575 9 P 0 ;1
L 11.7575 4.4075 11.7575 4.4075 9 P 0 ;1
L 11.7575 4.4575 11.7575 4.4575 9 P 0 ;1
L 11.7575 4.5075 11.7575 4.5075 9 P 0 ;1
L 11.7575 4.5575 11.7575 4.5575 9 P 0 ;1
L 11.7575 4.6075 11.7575 4.6075 9 P 0 ;1
L 11.7575 4.6575 11.7575 4.6575 9 P 0 ;1
L 11.7575 4.7075 11.7575 4.7075 9 P 0 ;1
L 11.8075 0.1575 11.8075 0.1575 9 P 0 ;1
L 11.8075 0.2075 11.8075 0.2075 9 P 0 ;1
L 11.8075 0.2575 11.8075 0.2575 9 P 0 ;1
L 11.8075 0.3075 11.8075 0.3075 9 P 0 ;1
L 11.8075 0.3575 11.8075 0.3575 9 P 0 ;1
L 11.8075 0.4075 11.8075 0.4075 9 P 0 ;1
L 11.8075 0.4575 11.8075 0.4575 9 P 0 ;1
L 11.8075 0.5075 11.8075 0.5075 9 P 0 ;1
L 11.8075 0.5575 11.8075 0.5575 9 P 0 ;1
L 11.8075 0.6075 11.8075 0.6075 9 P 0 ;1
L 11.8075 0.6575 11.8075 0.6575 9 P 0 ;1
L 11.8075 0.7075 11.8075 0.7075 9 P 0 ;1
L 11.8075 0.7575 11.8075 0.7575 9 P 0 ;1
L 11.8075 0.8075 11.8075 0.8075 9 P 0 ;1
L 11.8075 0.8575 11.8075 0.8575 9 P 0 ;1
L 11.8075 0.9075 11.8075 0.9075 9 P 0 ;1
L 11.8075 0.9575 11.8075 0.9575 9 P 0 ;1
L 11.8075 1.0075 11.8075 1.0075 9 P 0 ;1
L 11.8075 1.0575 11.8075 1.0575 9 P 0 ;1
L 11.8075 1.3075 11.8075 1.3075 9 P 0 ;1
L 11.8075 2.9575 11.8075 2.9575 9 P 0 ;1
L 11.8075 3.0075 11.8075 3.0075 9 P 0 ;1
L 11.8075 3.0575 11.8075 3.0575 9 P 0 ;1
L 11.8075 3.1075 11.8075 3.1075 9 P 0 ;1
L 11.8075 3.1575 11.8075 3.1575 9 P 0 ;1
L 11.8075 3.2075 11.8075 3.2075 9 P 0 ;1
L 11.8075 3.2575 11.8075 3.2575 9 P 0 ;1
L 11.8075 3.3075 11.8075 3.3075 9 P 0 ;1
L 11.8075 3.3575 11.8075 3.3575 9 P 0 ;1
L 11.8075 3.4075 11.8075 3.4075 9 P 0 ;1
L 11.8075 3.4575 11.8075 3.4575 9 P 0 ;1
L 11.8075 3.5075 11.8075 3.5075 9 P 0 ;1
L 11.8075 3.5575 11.8075 3.5575 9 P 0 ;1
L 11.8075 3.6075 11.8075 3.6075 9 P 0 ;1
L 11.8075 3.6575 11.8075 3.6575 9 P 0 ;1
L 11.8075 3.7075 11.8075 3.7075 9 P 0 ;1
L 11.8075 3.7575 11.8075 3.7575 9 P 0 ;1
L 11.8075 3.8075 11.8075 3.8075 9 P 0 ;1
L 11.8075 4.0575 11.8075 4.0575 9 P 0 ;1
L 11.8075 4.1075 11.8075 4.1075 9 P 0 ;1
L 11.8075 4.1575 11.8075 4.1575 9 P 0 ;1
L 11.8075 4.5575 11.8075 4.5575 9 P 0 ;1
L 11.8075 4.6075 11.8075 4.6075 9 P 0 ;1
L 11.8075 4.6575 11.8075 4.6575 9 P 0 ;1
L 11.8075 4.7075 11.8075 4.7075 9 P 0 ;1
L 11.8575 0.1575 11.8575 0.1575 9 P 0 ;1
L 11.8575 0.2075 11.8575 0.2075 9 P 0 ;1
L 11.8575 0.2575 11.8575 0.2575 9 P 0 ;1
L 11.8575 0.3075 11.8575 0.3075 9 P 0 ;1
L 11.8575 0.3575 11.8575 0.3575 9 P 0 ;1
L 11.8575 0.4075 11.8575 0.4075 9 P 0 ;1
L 11.8575 0.4575 11.8575 0.4575 9 P 0 ;1
L 11.8575 0.5075 11.8575 0.5075 9 P 0 ;1
L 11.8575 0.5575 11.8575 0.5575 9 P 0 ;1
L 11.8575 0.6075 11.8575 0.6075 9 P 0 ;1
L 11.8575 0.6575 11.8575 0.6575 9 P 0 ;1
L 11.8575 0.7075 11.8575 0.7075 9 P 0 ;1
L 11.8575 0.7575 11.8575 0.7575 9 P 0 ;1
L 11.8575 0.8075 11.8575 0.8075 9 P 0 ;1
L 11.8575 0.8575 11.8575 0.8575 9 P 0 ;1
L 11.8575 0.9075 11.8575 0.9075 9 P 0 ;1
L 11.8575 0.9575 11.8575 0.9575 9 P 0 ;1
L 11.8575 1.0075 11.8575 1.0075 9 P 0 ;1
L 11.8575 1.0575 11.8575 1.0575 9 P 0 ;1
L 11.8575 1.3075 11.8575 1.3075 9 P 0 ;1
L 11.8575 1.3575 11.8575 1.3575 9 P 0 ;1
L 11.8575 2.3575 11.8575 2.3575 9 P 0 ;1
L 11.8575 2.9575 11.8575 2.9575 9 P 0 ;1
L 11.8575 3.0075 11.8575 3.0075 9 P 0 ;1
L 11.8575 3.0575 11.8575 3.0575 9 P 0 ;1
L 11.8575 3.1075 11.8575 3.1075 9 P 0 ;1
L 11.8575 3.1575 11.8575 3.1575 9 P 0 ;1
L 11.8575 3.2075 11.8575 3.2075 9 P 0 ;1
L 11.8575 3.2575 11.8575 3.2575 9 P 0 ;1
L 11.8575 3.3075 11.8575 3.3075 9 P 0 ;1
L 11.8575 3.3575 11.8575 3.3575 9 P 0 ;1
L 11.8575 3.4075 11.8575 3.4075 9 P 0 ;1
L 11.8575 3.4575 11.8575 3.4575 9 P 0 ;1
L 11.8575 3.5075 11.8575 3.5075 9 P 0 ;1
L 11.8575 3.5575 11.8575 3.5575 9 P 0 ;1
L 11.8575 3.6075 11.8575 3.6075 9 P 0 ;1
L 11.8575 3.6575 11.8575 3.6575 9 P 0 ;1
L 11.8575 3.7075 11.8575 3.7075 9 P 0 ;1
L 11.8575 3.7575 11.8575 3.7575 9 P 0 ;1
L 11.8575 4.0575 11.8575 4.0575 9 P 0 ;1
L 11.8575 4.1075 11.8575 4.1075 9 P 0 ;1
L 11.8575 4.1575 11.8575 4.1575 9 P 0 ;1
L 11.8575 4.2075 11.8575 4.2075 9 P 0 ;1
L 11.8575 4.5575 11.8575 4.5575 9 P 0 ;1
L 11.8575 4.6075 11.8575 4.6075 9 P 0 ;1
L 11.8575 4.6575 11.8575 4.6575 9 P 0 ;1
L 11.8575 4.7075 11.8575 4.7075 9 P 0 ;1
L 11.9075 0.1575 11.9075 0.1575 9 P 0 ;1
L 11.9075 0.2075 11.9075 0.2075 9 P 0 ;1
L 11.9075 0.2575 11.9075 0.2575 9 P 0 ;1
L 11.9075 0.3075 11.9075 0.3075 9 P 0 ;1
L 11.9075 0.3575 11.9075 0.3575 9 P 0 ;1
L 11.9075 0.4075 11.9075 0.4075 9 P 0 ;1
L 11.9075 0.4575 11.9075 0.4575 9 P 0 ;1
L 11.9075 0.5075 11.9075 0.5075 9 P 0 ;1
L 11.9075 0.5575 11.9075 0.5575 9 P 0 ;1
L 11.9075 0.6075 11.9075 0.6075 9 P 0 ;1
L 11.9075 0.6575 11.9075 0.6575 9 P 0 ;1
L 11.9075 0.7075 11.9075 0.7075 9 P 0 ;1
L 11.9075 0.7575 11.9075 0.7575 9 P 0 ;1
L 11.9075 0.8075 11.9075 0.8075 9 P 0 ;1
L 11.9075 0.8575 11.9075 0.8575 9 P 0 ;1
L 11.9075 0.9075 11.9075 0.9075 9 P 0 ;1
L 11.9075 0.9575 11.9075 0.9575 9 P 0 ;1
L 11.9075 1.0075 11.9075 1.0075 9 P 0 ;1
L 11.9075 1.0575 11.9075 1.0575 9 P 0 ;1
L 11.9075 1.1075 11.9075 1.1075 9 P 0 ;1
L 11.9075 1.3075 11.9075 1.3075 9 P 0 ;1
L 11.9075 1.3575 11.9075 1.3575 9 P 0 ;1
L 11.9075 1.4075 11.9075 1.4075 9 P 0 ;1
L 11.9075 1.4575 11.9075 1.4575 9 P 0 ;1
L 11.9075 2.3075 11.9075 2.3075 9 P 0 ;1
L 11.9075 2.3575 11.9075 2.3575 9 P 0 ;1
L 11.9075 2.4075 11.9075 2.4075 9 P 0 ;1
L 11.9075 2.4575 11.9075 2.4575 9 P 0 ;1
L 11.9075 3.0575 11.9075 3.0575 9 P 0 ;1
L 11.9075 3.1075 11.9075 3.1075 9 P 0 ;1
L 11.9075 3.1575 11.9075 3.1575 9 P 0 ;1
L 11.9075 3.2075 11.9075 3.2075 9 P 0 ;1
L 11.9075 3.2575 11.9075 3.2575 9 P 0 ;1
L 11.9075 3.3075 11.9075 3.3075 9 P 0 ;1
L 11.9075 3.3575 11.9075 3.3575 9 P 0 ;1
L 11.9075 3.4075 11.9075 3.4075 9 P 0 ;1
L 11.9075 3.4575 11.9075 3.4575 9 P 0 ;1
L 11.9075 3.5075 11.9075 3.5075 9 P 0 ;1
L 11.9075 3.5575 11.9075 3.5575 9 P 0 ;1
L 11.9075 3.6075 11.9075 3.6075 9 P 0 ;1
L 11.9075 3.6575 11.9075 3.6575 9 P 0 ;1
L 11.9075 3.7075 11.9075 3.7075 9 P 0 ;1
L 11.9075 3.7575 11.9075 3.7575 9 P 0 ;1
L 11.9075 4.0575 11.9075 4.0575 9 P 0 ;1
L 11.9075 4.1075 11.9075 4.1075 9 P 0 ;1
L 11.9075 4.1575 11.9075 4.1575 9 P 0 ;1
L 11.9075 4.2075 11.9075 4.2075 9 P 0 ;1
L 11.9075 4.2575 11.9075 4.2575 9 P 0 ;1
L 11.9075 4.5575 11.9075 4.5575 9 P 0 ;1
L 11.9075 4.6075 11.9075 4.6075 9 P 0 ;1
L 11.9075 4.6575 11.9075 4.6575 9 P 0 ;1
L 11.9075 4.7075 11.9075 4.7075 9 P 0 ;1
L 11.9575 0.1575 11.9575 0.1575 9 P 0 ;1
L 11.9575 0.2075 11.9575 0.2075 9 P 0 ;1
L 11.9575 0.2575 11.9575 0.2575 9 P 0 ;1
L 11.9575 0.3075 11.9575 0.3075 9 P 0 ;1
L 11.9575 0.3575 11.9575 0.3575 9 P 0 ;1
L 11.9575 0.4075 11.9575 0.4075 9 P 0 ;1
L 11.9575 0.4575 11.9575 0.4575 9 P 0 ;1
L 11.9575 0.5075 11.9575 0.5075 9 P 0 ;1
L 11.9575 0.5575 11.9575 0.5575 9 P 0 ;1
L 11.9575 0.6075 11.9575 0.6075 9 P 0 ;1
L 11.9575 0.6575 11.9575 0.6575 9 P 0 ;1
L 11.9575 0.7075 11.9575 0.7075 9 P 0 ;1
L 11.9575 0.7575 11.9575 0.7575 9 P 0 ;1
L 11.9575 0.8075 11.9575 0.8075 9 P 0 ;1
L 11.9575 0.8575 11.9575 0.8575 9 P 0 ;1
L 11.9575 0.9075 11.9575 0.9075 9 P 0 ;1
L 11.9575 0.9575 11.9575 0.9575 9 P 0 ;1
L 11.9575 1.0075 11.9575 1.0075 9 P 0 ;1
L 11.9575 1.0575 11.9575 1.0575 9 P 0 ;1
L 11.9575 1.1075 11.9575 1.1075 9 P 0 ;1
L 11.9575 1.3075 11.9575 1.3075 9 P 0 ;1
L 11.9575 1.3575 11.9575 1.3575 9 P 0 ;1
L 11.9575 1.4075 11.9575 1.4075 9 P 0 ;1
L 11.9575 2.3575 11.9575 2.3575 9 P 0 ;1
L 11.9575 2.4075 11.9575 2.4075 9 P 0 ;1
L 11.9575 2.4575 11.9575 2.4575 9 P 0 ;1
L 11.9575 3.1075 11.9575 3.1075 9 P 0 ;1
L 11.9575 3.1575 11.9575 3.1575 9 P 0 ;1
L 11.9575 3.2075 11.9575 3.2075 9 P 0 ;1
L 11.9575 3.2575 11.9575 3.2575 9 P 0 ;1
L 11.9575 3.3075 11.9575 3.3075 9 P 0 ;1
L 11.9575 3.3575 11.9575 3.3575 9 P 0 ;1
L 11.9575 3.4075 11.9575 3.4075 9 P 0 ;1
L 11.9575 3.4575 11.9575 3.4575 9 P 0 ;1
L 11.9575 3.5075 11.9575 3.5075 9 P 0 ;1
L 11.9575 3.5575 11.9575 3.5575 9 P 0 ;1
L 11.9575 3.6075 11.9575 3.6075 9 P 0 ;1
L 11.9575 3.6575 11.9575 3.6575 9 P 0 ;1
L 11.9575 3.7075 11.9575 3.7075 9 P 0 ;1
L 11.9575 3.7575 11.9575 3.7575 9 P 0 ;1
L 11.9575 4.0575 11.9575 4.0575 9 P 0 ;1
L 11.9575 4.5575 11.9575 4.5575 9 P 0 ;1
L 11.9575 4.6075 11.9575 4.6075 9 P 0 ;1
L 11.9575 4.6575 11.9575 4.6575 9 P 0 ;1
L 11.9575 4.7075 11.9575 4.7075 9 P 0 ;1
L 12.0075 0.1575 12.0075 0.1575 9 P 0 ;1
L 12.0075 0.2075 12.0075 0.2075 9 P 0 ;1
L 12.0075 0.2575 12.0075 0.2575 9 P 0 ;1
L 12.0075 0.3075 12.0075 0.3075 9 P 0 ;1
L 12.0075 0.3575 12.0075 0.3575 9 P 0 ;1
L 12.0075 0.4075 12.0075 0.4075 9 P 0 ;1
L 12.0075 0.4575 12.0075 0.4575 9 P 0 ;1
L 12.0075 0.5075 12.0075 0.5075 9 P 0 ;1
L 12.0075 0.5575 12.0075 0.5575 9 P 0 ;1
L 12.0075 0.6075 12.0075 0.6075 9 P 0 ;1
L 12.0075 0.6575 12.0075 0.6575 9 P 0 ;1
L 12.0075 0.7075 12.0075 0.7075 9 P 0 ;1
L 12.0075 0.7575 12.0075 0.7575 9 P 0 ;1
L 12.0075 0.8075 12.0075 0.8075 9 P 0 ;1
L 12.0075 0.8575 12.0075 0.8575 9 P 0 ;1
L 12.0075 0.9075 12.0075 0.9075 9 P 0 ;1
L 12.0075 0.9575 12.0075 0.9575 9 P 0 ;1
L 12.0075 1.0075 12.0075 1.0075 9 P 0 ;1
L 12.0075 1.0575 12.0075 1.0575 9 P 0 ;1
L 12.0075 1.1075 12.0075 1.1075 9 P 0 ;1
L 12.0075 1.3575 12.0075 1.3575 9 P 0 ;1
L 12.0075 2.4075 12.0075 2.4075 9 P 0 ;1
L 12.0075 3.1575 12.0075 3.1575 9 P 0 ;1
L 12.0075 3.2075 12.0075 3.2075 9 P 0 ;1
L 12.0075 3.2575 12.0075 3.2575 9 P 0 ;1
L 12.0075 3.3075 12.0075 3.3075 9 P 0 ;1
L 12.0075 3.3575 12.0075 3.3575 9 P 0 ;1
L 12.0075 3.4075 12.0075 3.4075 9 P 0 ;1
L 12.0075 3.4575 12.0075 3.4575 9 P 0 ;1
L 12.0075 3.5075 12.0075 3.5075 9 P 0 ;1
L 12.0075 3.5575 12.0075 3.5575 9 P 0 ;1
L 12.0075 3.6075 12.0075 3.6075 9 P 0 ;1
L 12.0075 3.6575 12.0075 3.6575 9 P 0 ;1
L 12.0075 3.7075 12.0075 3.7075 9 P 0 ;1
L 12.0075 3.7575 12.0075 3.7575 9 P 0 ;1
L 12.0075 4.5575 12.0075 4.5575 9 P 0 ;1
L 12.0075 4.6075 12.0075 4.6075 9 P 0 ;1
L 12.0075 4.6575 12.0075 4.6575 9 P 0 ;1
L 12.0075 4.7075 12.0075 4.7075 9 P 0 ;1
L 12.0575 0.1575 12.0575 0.1575 9 P 0 ;1
L 12.0575 0.2075 12.0575 0.2075 9 P 0 ;1
L 12.0575 0.2575 12.0575 0.2575 9 P 0 ;1
L 12.0575 0.3075 12.0575 0.3075 9 P 0 ;1
L 12.0575 0.3575 12.0575 0.3575 9 P 0 ;1
L 12.0575 0.4075 12.0575 0.4075 9 P 0 ;1
L 12.0575 0.4575 12.0575 0.4575 9 P 0 ;1
L 12.0575 0.5075 12.0575 0.5075 9 P 0 ;1
L 12.0575 0.5575 12.0575 0.5575 9 P 0 ;1
L 12.0575 0.6075 12.0575 0.6075 9 P 0 ;1
L 12.0575 0.6575 12.0575 0.6575 9 P 0 ;1
L 12.0575 0.7075 12.0575 0.7075 9 P 0 ;1
L 12.0575 0.7575 12.0575 0.7575 9 P 0 ;1
L 12.0575 0.8075 12.0575 0.8075 9 P 0 ;1
L 12.0575 0.8575 12.0575 0.8575 9 P 0 ;1
L 12.0575 0.9075 12.0575 0.9075 9 P 0 ;1
L 12.0575 0.9575 12.0575 0.9575 9 P 0 ;1
L 12.0575 1.0075 12.0575 1.0075 9 P 0 ;1
L 12.0575 1.0575 12.0575 1.0575 9 P 0 ;1
L 12.0575 1.1075 12.0575 1.1075 9 P 0 ;1
L 12.0575 3.2575 12.0575 3.2575 9 P 0 ;1
L 12.0575 3.3075 12.0575 3.3075 9 P 0 ;1
L 12.0575 3.3575 12.0575 3.3575 9 P 0 ;1
L 12.0575 3.4075 12.0575 3.4075 9 P 0 ;1
L 12.0575 3.4575 12.0575 3.4575 9 P 0 ;1
L 12.0575 3.5075 12.0575 3.5075 9 P 0 ;1
L 12.0575 3.5575 12.0575 3.5575 9 P 0 ;1
L 12.0575 3.6075 12.0575 3.6075 9 P 0 ;1
L 12.0575 3.6575 12.0575 3.6575 9 P 0 ;1
L 12.0575 3.7075 12.0575 3.7075 9 P 0 ;1
L 12.0575 3.7575 12.0575 3.7575 9 P 0 ;1
L 12.0575 4.5575 12.0575 4.5575 9 P 0 ;1
L 12.0575 4.6075 12.0575 4.6075 9 P 0 ;1
L 12.0575 4.6575 12.0575 4.6575 9 P 0 ;1
L 12.0575 4.7075 12.0575 4.7075 9 P 0 ;1
L 12.0575 4.7575 12.0575 4.7575 9 P 0 ;1
L 12.0575 4.8075 12.0575 4.8075 9 P 0 ;1
L 12.1075 0.1575 12.1075 0.1575 9 P 0 ;1
L 12.1075 0.2075 12.1075 0.2075 9 P 0 ;1
L 12.1075 0.2575 12.1075 0.2575 9 P 0 ;1
L 12.1075 0.3075 12.1075 0.3075 9 P 0 ;1
L 12.1075 0.3575 12.1075 0.3575 9 P 0 ;1
L 12.1075 0.4075 12.1075 0.4075 9 P 0 ;1
L 12.1075 0.4575 12.1075 0.4575 9 P 0 ;1
L 12.1075 0.5075 12.1075 0.5075 9 P 0 ;1
L 12.1075 0.5575 12.1075 0.5575 9 P 0 ;1
L 12.1075 0.6075 12.1075 0.6075 9 P 0 ;1
L 12.1075 0.6575 12.1075 0.6575 9 P 0 ;1
L 12.1075 0.7075 12.1075 0.7075 9 P 0 ;1
L 12.1075 0.7575 12.1075 0.7575 9 P 0 ;1
L 12.1075 0.8075 12.1075 0.8075 9 P 0 ;1
L 12.1075 0.8575 12.1075 0.8575 9 P 0 ;1
L 12.1075 0.9075 12.1075 0.9075 9 P 0 ;1
L 12.1075 0.9575 12.1075 0.9575 9 P 0 ;1
L 12.1075 1.0075 12.1075 1.0075 9 P 0 ;1
L 12.1075 1.0575 12.1075 1.0575 9 P 0 ;1
L 12.1075 1.1075 12.1075 1.1075 9 P 0 ;1
L 12.1075 3.3075 12.1075 3.3075 9 P 0 ;1
L 12.1075 3.3575 12.1075 3.3575 9 P 0 ;1
L 12.1075 3.4075 12.1075 3.4075 9 P 0 ;1
L 12.1075 3.4575 12.1075 3.4575 9 P 0 ;1
L 12.1075 3.5075 12.1075 3.5075 9 P 0 ;1
L 12.1075 3.5575 12.1075 3.5575 9 P 0 ;1
L 12.1075 3.6075 12.1075 3.6075 9 P 0 ;1
L 12.1075 3.6575 12.1075 3.6575 9 P 0 ;1
L 12.1075 3.7075 12.1075 3.7075 9 P 0 ;1
L 12.1075 3.7575 12.1075 3.7575 9 P 0 ;1
L 12.1075 4.5575 12.1075 4.5575 9 P 0 ;1
L 12.1075 4.6075 12.1075 4.6075 9 P 0 ;1
L 12.1075 4.6575 12.1075 4.6575 9 P 0 ;1
L 12.1075 4.7075 12.1075 4.7075 9 P 0 ;1
L 12.1075 4.7575 12.1075 4.7575 9 P 0 ;1
L 12.1075 4.8075 12.1075 4.8075 9 P 0 ;1
L 12.1575 0.1575 12.1575 0.1575 9 P 0 ;1
L 12.1575 0.2075 12.1575 0.2075 9 P 0 ;1
L 12.1575 0.4075 12.1575 0.4075 9 P 0 ;1
L 12.1575 0.4575 12.1575 0.4575 9 P 0 ;1
L 12.1575 0.5075 12.1575 0.5075 9 P 0 ;1
L 12.1575 0.5575 12.1575 0.5575 9 P 0 ;1
L 12.1575 0.6075 12.1575 0.6075 9 P 0 ;1
L 12.1575 0.6575 12.1575 0.6575 9 P 0 ;1
L 12.1575 0.7075 12.1575 0.7075 9 P 0 ;1
L 12.1575 0.7575 12.1575 0.7575 9 P 0 ;1
L 12.1575 0.8075 12.1575 0.8075 9 P 0 ;1
L 12.1575 0.8575 12.1575 0.8575 9 P 0 ;1
L 12.1575 0.9075 12.1575 0.9075 9 P 0 ;1
L 12.1575 0.9575 12.1575 0.9575 9 P 0 ;1
L 12.1575 1.0075 12.1575 1.0075 9 P 0 ;1
L 12.1575 1.0575 12.1575 1.0575 9 P 0 ;1
L 12.1575 1.1075 12.1575 1.1075 9 P 0 ;1
L 12.1575 1.7575 12.1575 1.7575 9 P 0 ;1
L 12.1575 1.8075 12.1575 1.8075 9 P 0 ;1
L 12.1575 2.7075 12.1575 2.7075 9 P 0 ;1
L 12.1575 2.7575 12.1575 2.7575 9 P 0 ;1
L 12.1575 2.8075 12.1575 2.8075 9 P 0 ;1
L 12.1575 3.4075 12.1575 3.4075 9 P 0 ;1
L 12.1575 3.4575 12.1575 3.4575 9 P 0 ;1
L 12.1575 3.5075 12.1575 3.5075 9 P 0 ;1
L 12.1575 3.5575 12.1575 3.5575 9 P 0 ;1
L 12.1575 3.6075 12.1575 3.6075 9 P 0 ;1
L 12.1575 3.6575 12.1575 3.6575 9 P 0 ;1
L 12.1575 3.7075 12.1575 3.7075 9 P 0 ;1
L 12.1575 4.5575 12.1575 4.5575 9 P 0 ;1
L 12.1575 4.6075 12.1575 4.6075 9 P 0 ;1
L 12.1575 4.6575 12.1575 4.6575 9 P 0 ;1
L 12.1575 4.7075 12.1575 4.7075 9 P 0 ;1
L 12.1575 4.7575 12.1575 4.7575 9 P 0 ;1
L 12.1575 4.8075 12.1575 4.8075 9 P 0 ;1
L 12.2075 0.1575 12.2075 0.1575 9 P 0 ;1
L 12.2075 0.4575 12.2075 0.4575 9 P 0 ;1
L 12.2075 0.5075 12.2075 0.5075 9 P 0 ;1
L 12.2075 0.5575 12.2075 0.5575 9 P 0 ;1
L 12.2075 0.6075 12.2075 0.6075 9 P 0 ;1
L 12.2075 0.6575 12.2075 0.6575 9 P 0 ;1
L 12.2075 0.7075 12.2075 0.7075 9 P 0 ;1
L 12.2075 0.7575 12.2075 0.7575 9 P 0 ;1
L 12.2075 0.8075 12.2075 0.8075 9 P 0 ;1
L 12.2075 0.8575 12.2075 0.8575 9 P 0 ;1
L 12.2075 0.9075 12.2075 0.9075 9 P 0 ;1
L 12.2075 0.9575 12.2075 0.9575 9 P 0 ;1
L 12.2075 1.0075 12.2075 1.0075 9 P 0 ;1
L 12.2075 1.0575 12.2075 1.0575 9 P 0 ;1
L 12.2075 1.1075 12.2075 1.1075 9 P 0 ;1
L 12.2075 1.1575 12.2075 1.1575 9 P 0 ;1
L 12.2075 1.7075 12.2075 1.7075 9 P 0 ;1
L 12.2075 1.7575 12.2075 1.7575 9 P 0 ;1
L 12.2075 1.8075 12.2075 1.8075 9 P 0 ;1
L 12.2075 1.8575 12.2075 1.8575 9 P 0 ;1
L 12.2075 1.9075 12.2075 1.9075 9 P 0 ;1
L 12.2075 1.9575 12.2075 1.9575 9 P 0 ;1
L 12.2075 2.0075 12.2075 2.0075 9 P 0 ;1
L 12.2075 3.4575 12.2075 3.4575 9 P 0 ;1
L 12.2075 3.5075 12.2075 3.5075 9 P 0 ;1
L 12.2075 3.5575 12.2075 3.5575 9 P 0 ;1
L 12.2075 3.6075 12.2075 3.6075 9 P 0 ;1
L 12.2075 3.6575 12.2075 3.6575 9 P 0 ;1
L 12.2075 3.7075 12.2075 3.7075 9 P 0 ;1
L 12.2075 4.5575 12.2075 4.5575 9 P 0 ;1
L 12.2075 4.6075 12.2075 4.6075 9 P 0 ;1
L 12.2075 4.6575 12.2075 4.6575 9 P 0 ;1
L 12.2075 4.7075 12.2075 4.7075 9 P 0 ;1
L 12.2075 4.7575 12.2075 4.7575 9 P 0 ;1
L 12.2075 4.8075 12.2075 4.8075 9 P 0 ;1
L 12.2575 0.4575 12.2575 0.4575 9 P 0 ;1
L 12.2575 0.5075 12.2575 0.5075 9 P 0 ;1
L 12.2575 0.5575 12.2575 0.5575 9 P 0 ;1
L 12.2575 0.6075 12.2575 0.6075 9 P 0 ;1
L 12.2575 0.6575 12.2575 0.6575 9 P 0 ;1
L 12.2575 0.7075 12.2575 0.7075 9 P 0 ;1
L 12.2575 0.7575 12.2575 0.7575 9 P 0 ;1
L 12.2575 0.8075 12.2575 0.8075 9 P 0 ;1
L 12.2575 0.8575 12.2575 0.8575 9 P 0 ;1
L 12.2575 0.9075 12.2575 0.9075 9 P 0 ;1
L 12.2575 0.9575 12.2575 0.9575 9 P 0 ;1
L 12.2575 1.0075 12.2575 1.0075 9 P 0 ;1
L 12.2575 1.0575 12.2575 1.0575 9 P 0 ;1
L 12.2575 1.1075 12.2575 1.1075 9 P 0 ;1
L 12.2575 1.1575 12.2575 1.1575 9 P 0 ;1
L 12.2575 1.7075 12.2575 1.7075 9 P 0 ;1
L 12.2575 1.7575 12.2575 1.7575 9 P 0 ;1
L 12.2575 1.8075 12.2575 1.8075 9 P 0 ;1
L 12.2575 1.8575 12.2575 1.8575 9 P 0 ;1
L 12.2575 1.9075 12.2575 1.9075 9 P 0 ;1
L 12.2575 1.9575 12.2575 1.9575 9 P 0 ;1
L 12.2575 2.0075 12.2575 2.0075 9 P 0 ;1
L 12.2575 2.0575 12.2575 2.0575 9 P 0 ;1
L 12.2575 2.1075 12.2575 2.1075 9 P 0 ;1
L 12.2575 3.5575 12.2575 3.5575 9 P 0 ;1
L 12.2575 3.6075 12.2575 3.6075 9 P 0 ;1
L 12.2575 3.6575 12.2575 3.6575 9 P 0 ;1
L 12.2575 3.7075 12.2575 3.7075 9 P 0 ;1
L 12.2575 4.6075 12.2575 4.6075 9 P 0 ;1
L 12.2575 4.6575 12.2575 4.6575 9 P 0 ;1
L 12.2575 4.7075 12.2575 4.7075 9 P 0 ;1
L 12.2575 4.7575 12.2575 4.7575 9 P 0 ;1
L 12.2575 4.8075 12.2575 4.8075 9 P 0 ;1
L 12.3075 0.1575 12.3075 0.1575 9 P 0 ;1
L 12.3075 0.4575 12.3075 0.4575 9 P 0 ;1
L 12.3075 0.5075 12.3075 0.5075 9 P 0 ;1
L 12.3075 0.5575 12.3075 0.5575 9 P 0 ;1
L 12.3075 0.6075 12.3075 0.6075 9 P 0 ;1
L 12.3075 0.6575 12.3075 0.6575 9 P 0 ;1
L 12.3075 0.7075 12.3075 0.7075 9 P 0 ;1
L 12.3075 0.7575 12.3075 0.7575 9 P 0 ;1
L 12.3075 0.8075 12.3075 0.8075 9 P 0 ;1
L 12.3075 0.8575 12.3075 0.8575 9 P 0 ;1
L 12.3075 0.9075 12.3075 0.9075 9 P 0 ;1
L 12.3075 0.9575 12.3075 0.9575 9 P 0 ;1
L 12.3075 1.0075 12.3075 1.0075 9 P 0 ;1
L 12.3075 1.0575 12.3075 1.0575 9 P 0 ;1
L 12.3075 1.1075 12.3075 1.1075 9 P 0 ;1
L 12.3075 1.1575 12.3075 1.1575 9 P 0 ;1
L 12.3075 1.2075 12.3075 1.2075 9 P 0 ;1
L 12.3075 1.8075 12.3075 1.8075 9 P 0 ;1
L 12.3075 1.8575 12.3075 1.8575 9 P 0 ;1
L 12.3075 1.9075 12.3075 1.9075 9 P 0 ;1
L 12.3075 1.9575 12.3075 1.9575 9 P 0 ;1
L 12.3075 2.0075 12.3075 2.0075 9 P 0 ;1
L 12.3075 2.0575 12.3075 2.0575 9 P 0 ;1
L 12.3075 2.1075 12.3075 2.1075 9 P 0 ;1
L 12.3075 3.6075 12.3075 3.6075 9 P 0 ;1
L 12.3075 3.6575 12.3075 3.6575 9 P 0 ;1
L 12.3075 3.7075 12.3075 3.7075 9 P 0 ;1
L 12.3075 4.1075 12.3075 4.1075 9 P 0 ;1
L 12.3075 4.6075 12.3075 4.6075 9 P 0 ;1
L 12.3075 4.6575 12.3075 4.6575 9 P 0 ;1
L 12.3075 4.7075 12.3075 4.7075 9 P 0 ;1
L 12.3075 4.7575 12.3075 4.7575 9 P 0 ;1
L 12.3075 4.8075 12.3075 4.8075 9 P 0 ;1
L 12.3075 4.8575 12.3075 4.8575 9 P 0 ;1
L 12.3075 4.9075 12.3075 4.9075 9 P 0 ;1
L 12.3075 4.9575 12.3075 4.9575 9 P 0 ;1
L 12.3575 0.1575 12.3575 0.1575 9 P 0 ;1
L 12.3575 0.4075 12.3575 0.4075 9 P 0 ;1
L 12.3575 0.4575 12.3575 0.4575 9 P 0 ;1
L 12.3575 0.5075 12.3575 0.5075 9 P 0 ;1
L 12.3575 0.5575 12.3575 0.5575 9 P 0 ;1
L 12.3575 0.6075 12.3575 0.6075 9 P 0 ;1
L 12.3575 0.6575 12.3575 0.6575 9 P 0 ;1
L 12.3575 0.7075 12.3575 0.7075 9 P 0 ;1
L 12.3575 0.7575 12.3575 0.7575 9 P 0 ;1
L 12.3575 0.8075 12.3575 0.8075 9 P 0 ;1
L 12.3575 0.8575 12.3575 0.8575 9 P 0 ;1
L 12.3575 0.9075 12.3575 0.9075 9 P 0 ;1
L 12.3575 0.9575 12.3575 0.9575 9 P 0 ;1
L 12.3575 1.0075 12.3575 1.0075 9 P 0 ;1
L 12.3575 1.0575 12.3575 1.0575 9 P 0 ;1
L 12.3575 1.1075 12.3575 1.1075 9 P 0 ;1
L 12.3575 1.1575 12.3575 1.1575 9 P 0 ;1
L 12.3575 1.2075 12.3575 1.2075 9 P 0 ;1
L 12.3575 1.2575 12.3575 1.2575 9 P 0 ;1
L 12.3575 2.0575 12.3575 2.0575 9 P 0 ;1
L 12.3575 2.1075 12.3575 2.1075 9 P 0 ;1
L 12.3575 3.6575 12.3575 3.6575 9 P 0 ;1
L 12.3575 3.7075 12.3575 3.7075 9 P 0 ;1
L 12.3575 4.1575 12.3575 4.1575 9 P 0 ;1
L 12.3575 4.2075 12.3575 4.2075 9 P 0 ;1
L 12.3575 4.2575 12.3575 4.2575 9 P 0 ;1
L 12.3575 4.6075 12.3575 4.6075 9 P 0 ;1
L 12.3575 4.6575 12.3575 4.6575 9 P 0 ;1
L 12.3575 4.7075 12.3575 4.7075 9 P 0 ;1
L 12.3575 4.7575 12.3575 4.7575 9 P 0 ;1
L 12.3575 4.8075 12.3575 4.8075 9 P 0 ;1
L 12.3575 4.8575 12.3575 4.8575 9 P 0 ;1
L 12.3575 4.9075 12.3575 4.9075 9 P 0 ;1
L 12.3575 4.9575 12.3575 4.9575 9 P 0 ;1
L 12.3575 5.0075 12.3575 5.0075 9 P 0 ;1
L 12.4075 0.1575 12.4075 0.1575 9 P 0 ;1
L 12.4075 0.2075 12.4075 0.2075 9 P 0 ;1
L 12.4075 0.2575 12.4075 0.2575 9 P 0 ;1
L 12.4075 0.3075 12.4075 0.3075 9 P 0 ;1
L 12.4075 0.3575 12.4075 0.3575 9 P 0 ;1
L 12.4075 0.4075 12.4075 0.4075 9 P 0 ;1
L 12.4075 0.4575 12.4075 0.4575 9 P 0 ;1
L 12.4075 0.5075 12.4075 0.5075 9 P 0 ;1
L 12.4075 0.5575 12.4075 0.5575 9 P 0 ;1
L 12.4075 0.6075 12.4075 0.6075 9 P 0 ;1
L 12.4075 0.6575 12.4075 0.6575 9 P 0 ;1
L 12.4075 0.7075 12.4075 0.7075 9 P 0 ;1
L 12.4075 0.7575 12.4075 0.7575 9 P 0 ;1
L 12.4075 0.8075 12.4075 0.8075 9 P 0 ;1
L 12.4075 0.8575 12.4075 0.8575 9 P 0 ;1
L 12.4075 0.9075 12.4075 0.9075 9 P 0 ;1
L 12.4075 0.9575 12.4075 0.9575 9 P 0 ;1
L 12.4075 1.0075 12.4075 1.0075 9 P 0 ;1
L 12.4075 1.0575 12.4075 1.0575 9 P 0 ;1
L 12.4075 1.1075 12.4075 1.1075 9 P 0 ;1
L 12.4075 1.1575 12.4075 1.1575 9 P 0 ;1
L 12.4075 1.2075 12.4075 1.2075 9 P 0 ;1
L 12.4075 1.2575 12.4075 1.2575 9 P 0 ;1
L 12.4075 1.3075 12.4075 1.3075 9 P 0 ;1
L 12.4075 2.2575 12.4075 2.2575 9 P 0 ;1
L 12.4075 2.3075 12.4075 2.3075 9 P 0 ;1
L 12.4075 4.2075 12.4075 4.2075 9 P 0 ;1
L 12.4075 4.6075 12.4075 4.6075 9 P 0 ;1
L 12.4075 4.6575 12.4075 4.6575 9 P 0 ;1
L 12.4075 4.7075 12.4075 4.7075 9 P 0 ;1
L 12.4075 4.7575 12.4075 4.7575 9 P 0 ;1
L 12.4075 4.8075 12.4075 4.8075 9 P 0 ;1
L 12.4075 4.8575 12.4075 4.8575 9 P 0 ;1
L 12.4075 4.9075 12.4075 4.9075 9 P 0 ;1
L 12.4075 4.9575 12.4075 4.9575 9 P 0 ;1
L 12.4075 5.0075 12.4075 5.0075 9 P 0 ;1
L 12.4075 5.0575 12.4075 5.0575 9 P 0 ;1
L 12.4575 0.1575 12.4575 0.1575 9 P 0 ;1
L 12.4575 0.2075 12.4575 0.2075 9 P 0 ;1
L 12.4575 0.2575 12.4575 0.2575 9 P 0 ;1
L 12.4575 0.3075 12.4575 0.3075 9 P 0 ;1
L 12.4575 0.3575 12.4575 0.3575 9 P 0 ;1
L 12.4575 0.4075 12.4575 0.4075 9 P 0 ;1
L 12.4575 0.4575 12.4575 0.4575 9 P 0 ;1
L 12.4575 0.5075 12.4575 0.5075 9 P 0 ;1
L 12.4575 0.5575 12.4575 0.5575 9 P 0 ;1
L 12.4575 0.6075 12.4575 0.6075 9 P 0 ;1
L 12.4575 0.6575 12.4575 0.6575 9 P 0 ;1
L 12.4575 0.7075 12.4575 0.7075 9 P 0 ;1
L 12.4575 0.7575 12.4575 0.7575 9 P 0 ;1
L 12.4575 0.8075 12.4575 0.8075 9 P 0 ;1
L 12.4575 0.8575 12.4575 0.8575 9 P 0 ;1
L 12.4575 0.9075 12.4575 0.9075 9 P 0 ;1
L 12.4575 0.9575 12.4575 0.9575 9 P 0 ;1
L 12.4575 1.0075 12.4575 1.0075 9 P 0 ;1
L 12.4575 1.0575 12.4575 1.0575 9 P 0 ;1
L 12.4575 1.1075 12.4575 1.1075 9 P 0 ;1
L 12.4575 1.1575 12.4575 1.1575 9 P 0 ;1
L 12.4575 1.2075 12.4575 1.2075 9 P 0 ;1
L 12.4575 1.2575 12.4575 1.2575 9 P 0 ;1
L 12.4575 1.3075 12.4575 1.3075 9 P 0 ;1
L 12.4575 1.3575 12.4575 1.3575 9 P 0 ;1
L 12.4575 1.4075 12.4575 1.4075 9 P 0 ;1
L 12.4575 1.4575 12.4575 1.4575 9 P 0 ;1
L 12.4575 1.5075 12.4575 1.5075 9 P 0 ;1
L 12.4575 1.5575 12.4575 1.5575 9 P 0 ;1
L 12.4575 2.2575 12.4575 2.2575 9 P 0 ;1
L 12.4575 3.9075 12.4575 3.9075 9 P 0 ;1
L 12.4575 4.4075 12.4575 4.4075 9 P 0 ;1
L 12.4575 4.6075 12.4575 4.6075 9 P 0 ;1
L 12.4575 4.6575 12.4575 4.6575 9 P 0 ;1
L 12.4575 4.7075 12.4575 4.7075 9 P 0 ;1
L 12.4575 4.7575 12.4575 4.7575 9 P 0 ;1
L 12.4575 4.8075 12.4575 4.8075 9 P 0 ;1
L 12.4575 4.8575 12.4575 4.8575 9 P 0 ;1
L 12.4575 4.9075 12.4575 4.9075 9 P 0 ;1
L 12.4575 4.9575 12.4575 4.9575 9 P 0 ;1
L 12.4575 5.0075 12.4575 5.0075 9 P 0 ;1
L 12.4575 5.0575 12.4575 5.0575 9 P 0 ;1
L 12.4575 5.1075 12.4575 5.1075 9 P 0 ;1
L 12.5075 0.1575 12.5075 0.1575 9 P 0 ;1
L 12.5075 0.2075 12.5075 0.2075 9 P 0 ;1
L 12.5075 0.2575 12.5075 0.2575 9 P 0 ;1
L 12.5075 0.3075 12.5075 0.3075 9 P 0 ;1
L 12.5075 0.3575 12.5075 0.3575 9 P 0 ;1
L 12.5075 0.4075 12.5075 0.4075 9 P 0 ;1
L 12.5075 0.4575 12.5075 0.4575 9 P 0 ;1
L 12.5075 0.5075 12.5075 0.5075 9 P 0 ;1
L 12.5075 0.5575 12.5075 0.5575 9 P 0 ;1
L 12.5075 0.6075 12.5075 0.6075 9 P 0 ;1
L 12.5075 0.6575 12.5075 0.6575 9 P 0 ;1
L 12.5075 0.8075 12.5075 0.8075 9 P 0 ;1
L 12.5075 0.8575 12.5075 0.8575 9 P 0 ;1
L 12.5075 0.9075 12.5075 0.9075 9 P 0 ;1
L 12.5075 0.9575 12.5075 0.9575 9 P 0 ;1
L 12.5075 1.0075 12.5075 1.0075 9 P 0 ;1
L 12.5075 1.0575 12.5075 1.0575 9 P 0 ;1
L 12.5075 1.1075 12.5075 1.1075 9 P 0 ;1
L 12.5075 1.1575 12.5075 1.1575 9 P 0 ;1
L 12.5075 1.2075 12.5075 1.2075 9 P 0 ;1
L 12.5075 1.2575 12.5075 1.2575 9 P 0 ;1
L 12.5075 1.3075 12.5075 1.3075 9 P 0 ;1
L 12.5075 1.8075 12.5075 1.8075 9 P 0 ;1
L 12.5075 4.7575 12.5075 4.7575 9 P 0 ;1
L 12.5075 4.8075 12.5075 4.8075 9 P 0 ;1
L 12.5075 4.8575 12.5075 4.8575 9 P 0 ;1
L 12.5075 4.9075 12.5075 4.9075 9 P 0 ;1
L 12.5075 4.9575 12.5075 4.9575 9 P 0 ;1
L 12.5075 5.0075 12.5075 5.0075 9 P 0 ;1
L 12.5075 5.0575 12.5075 5.0575 9 P 0 ;1
L 12.5575 0.1575 12.5575 0.1575 9 P 0 ;1
L 12.5575 0.2075 12.5575 0.2075 9 P 0 ;1
L 12.5575 0.2575 12.5575 0.2575 9 P 0 ;1
L 12.5575 0.3075 12.5575 0.3075 9 P 0 ;1
L 12.5575 0.3575 12.5575 0.3575 9 P 0 ;1
L 12.5575 0.4075 12.5575 0.4075 9 P 0 ;1
L 12.5575 0.5575 12.5575 0.5575 9 P 0 ;1
L 12.5575 0.9075 12.5575 0.9075 9 P 0 ;1
L 12.5575 0.9575 12.5575 0.9575 9 P 0 ;1
L 12.5575 1.0075 12.5575 1.0075 9 P 0 ;1
L 12.5575 1.0575 12.5575 1.0575 9 P 0 ;1
L 12.5575 1.1075 12.5575 1.1075 9 P 0 ;1
L 12.5575 1.1575 12.5575 1.1575 9 P 0 ;1
L 12.5575 1.2075 12.5575 1.2075 9 P 0 ;1
L 12.5575 1.2575 12.5575 1.2575 9 P 0 ;1
L 12.5575 1.3075 12.5575 1.3075 9 P 0 ;1
L 12.5575 4.7575 12.5575 4.7575 9 P 0 ;1
L 12.5575 4.8075 12.5575 4.8075 9 P 0 ;1
L 12.5575 4.8575 12.5575 4.8575 9 P 0 ;1
L 12.5575 4.9075 12.5575 4.9075 9 P 0 ;1
L 12.5575 4.9575 12.5575 4.9575 9 P 0 ;1
L 12.6075 0.1575 12.6075 0.1575 9 P 0 ;1
L 12.6075 0.2075 12.6075 0.2075 9 P 0 ;1
L 12.6075 0.2575 12.6075 0.2575 9 P 0 ;1
L 12.6075 0.3075 12.6075 0.3075 9 P 0 ;1
L 12.6075 1.1075 12.6075 1.1075 9 P 0 ;1
L 12.6075 1.1575 12.6075 1.1575 9 P 0 ;1
L 12.6075 1.2075 12.6075 1.2075 9 P 0 ;1
L 12.6075 1.2575 12.6075 1.2575 9 P 0 ;1
L 12.6075 4.8075 12.6075 4.8075 9 P 0 ;1
L 12.6075 5.5575 12.6075 5.5575 9 P 0 ;1
L 12.6075 5.6075 12.6075 5.6075 9 P 0 ;1
L 12.6075 5.6575 12.6075 5.6575 9 P 0 ;1
L 12.6075 5.7075 12.6075 5.7075 9 P 0 ;1
L 12.6075 5.7575 12.6075 5.7575 9 P 0 ;1
L 12.6075 5.8075 12.6075 5.8075 9 P 0 ;1
L 12.6075 5.8575 12.6075 5.8575 9 P 0 ;1
L 12.6075 5.9075 12.6075 5.9075 9 P 0 ;1
L 12.6575 0.1575 12.6575 0.1575 9 P 0 ;1
L 12.6575 0.2075 12.6575 0.2075 9 P 0 ;1
L 12.6575 0.2575 12.6575 0.2575 9 P 0 ;1
L 12.6575 0.3075 12.6575 0.3075 9 P 0 ;1
L 12.6575 1.1075 12.6575 1.1075 9 P 0 ;1
L 12.6575 1.1575 12.6575 1.1575 9 P 0 ;1
L 12.6575 1.2075 12.6575 1.2075 9 P 0 ;1
L 12.6575 1.2575 12.6575 1.2575 9 P 0 ;1
L 12.6575 5.6075 12.6575 5.6075 9 P 0 ;1
L 12.6575 5.6575 12.6575 5.6575 9 P 0 ;1
L 12.6575 5.7075 12.6575 5.7075 9 P 0 ;1
L 12.6575 5.7575 12.6575 5.7575 9 P 0 ;1
L 12.6575 5.8075 12.6575 5.8075 9 P 0 ;1
L 12.6575 5.8575 12.6575 5.8575 9 P 0 ;1
L 12.6575 5.9075 12.6575 5.9075 9 P 0 ;1
L 12.7075 0.1575 12.7075 0.1575 9 P 0 ;1
L 12.7075 0.2075 12.7075 0.2075 9 P 0 ;1
L 12.7075 0.2575 12.7075 0.2575 9 P 0 ;1
L 12.7075 0.3075 12.7075 0.3075 9 P 0 ;1
L 12.7075 1.1075 12.7075 1.1075 9 P 0 ;1
L 12.7075 1.1575 12.7075 1.1575 9 P 0 ;1
L 12.7075 1.2075 12.7075 1.2075 9 P 0 ;1
L 12.7075 1.2575 12.7075 1.2575 9 P 0 ;1
L 12.7075 5.6075 12.7075 5.6075 9 P 0 ;1
L 12.7075 5.6575 12.7075 5.6575 9 P 0 ;1
L 12.7075 5.7075 12.7075 5.7075 9 P 0 ;1
L 12.7075 5.7575 12.7075 5.7575 9 P 0 ;1
L 12.7075 5.8075 12.7075 5.8075 9 P 0 ;1
L 12.7075 5.8575 12.7075 5.8575 9 P 0 ;1
L 12.7075 5.9075 12.7075 5.9075 9 P 0 ;1
L 12.7575 0.1575 12.7575 0.1575 9 P 0 ;1
L 12.7575 0.2075 12.7575 0.2075 9 P 0 ;1
L 12.7575 0.2575 12.7575 0.2575 9 P 0 ;1
L 12.7575 0.3075 12.7575 0.3075 9 P 0 ;1
L 12.7575 1.1075 12.7575 1.1075 9 P 0 ;1
L 12.7575 1.1575 12.7575 1.1575 9 P 0 ;1
L 12.7575 1.2075 12.7575 1.2075 9 P 0 ;1
L 12.7575 1.2575 12.7575 1.2575 9 P 0 ;1
L 12.7575 5.5575 12.7575 5.5575 9 P 0 ;1
L 12.7575 5.6075 12.7575 5.6075 9 P 0 ;1
L 12.7575 5.6575 12.7575 5.6575 9 P 0 ;1
L 12.7575 5.7075 12.7575 5.7075 9 P 0 ;1
L 12.7575 5.7575 12.7575 5.7575 9 P 0 ;1
L 12.7575 5.8075 12.7575 5.8075 9 P 0 ;1
L 12.7575 5.8575 12.7575 5.8575 9 P 0 ;1
L 12.7575 5.9075 12.7575 5.9075 9 P 0 ;1
L 12.8075 0.1575 12.8075 0.1575 9 P 0 ;1
L 12.8075 0.2075 12.8075 0.2075 9 P 0 ;1
L 12.8075 0.2575 12.8075 0.2575 9 P 0 ;1
L 12.8075 0.3075 12.8075 0.3075 9 P 0 ;1
L 12.8075 0.3575 12.8075 0.3575 9 P 0 ;1
L 12.8075 0.5575 12.8075 0.5575 9 P 0 ;1
L 12.8075 0.9075 12.8075 0.9075 9 P 0 ;1
L 12.8075 1.0075 12.8075 1.0075 9 P 0 ;1
L 12.8075 1.0575 12.8075 1.0575 9 P 0 ;1
L 12.8075 1.1075 12.8075 1.1075 9 P 0 ;1
L 12.8075 1.1575 12.8075 1.1575 9 P 0 ;1
L 12.8075 1.2075 12.8075 1.2075 9 P 0 ;1
L 12.8075 1.2575 12.8075 1.2575 9 P 0 ;1
L 12.8075 1.3075 12.8075 1.3075 9 P 0 ;1
L 12.8075 4.7575 12.8075 4.7575 9 P 0 ;1
L 12.8075 4.8075 12.8075 4.8075 9 P 0 ;1
L 12.8075 4.8575 12.8075 4.8575 9 P 0 ;1
L 12.8075 4.9575 12.8075 4.9575 9 P 0 ;1
L 12.8075 5.5075 12.8075 5.5075 9 P 0 ;1
L 12.8075 5.5575 12.8075 5.5575 9 P 0 ;1
L 12.8075 5.6075 12.8075 5.6075 9 P 0 ;1
L 12.8075 5.6575 12.8075 5.6575 9 P 0 ;1
L 12.8075 5.7075 12.8075 5.7075 9 P 0 ;1
L 12.8075 5.7575 12.8075 5.7575 9 P 0 ;1
L 12.8075 5.8075 12.8075 5.8075 9 P 0 ;1
L 12.8075 5.8575 12.8075 5.8575 9 P 0 ;1
L 12.8075 5.9075 12.8075 5.9075 9 P 0 ;1

### steps/drc/layers/l6/features
#
#Feature symbol names
#
$0 r2
$1 r6
$2 r15
$3 r20
$4 r28
$5 r30
$6 r32
$7 r33
$8 r40
$9 r50
$10 r57.09
$11 r78.74
$12 r86.61
$13 r90.55
$14 r100
$15 r131.89
$16 r137.8
$17 r161.42
$18 r168.31
$19 r173.23
$20 r181.1
$21 r204.72
$22 r224.41
$23 r440.94
$24 null
$25 oval236.22x177.17
$26 thr61.02x49.21x45x4x15.75
$27 thr96.46x76.77x45x4x19.69

#
#Feature attribute names
#
@0 .nomenclature
@1 .geometry

#
#Feature attribute text strings
#
&0 TPB30V20D10AT28BPM
&1 C1_11P0_7
&2 C1_11P0_7TP
&3 V17D8AT30SM11
&4 V20D10AT28SM14
&5 C2_5N
&6 S1_11P0_7TP
&7 S1_11P0_7
&8 V20D10AT28PG
&9 C1_17P0_76TPM
&10 C1_9P1_4
&11 S1_9P1_4
&12 SP-8C5_2P0_254
&13 SP-9C5_7P0_254
&14 C3_175N-A
&15 C10N
&16 C3_3N
&17 C4_5N-B
&18 C4N-B
&19 C3_5N
&20 O5X3_5N
&21 C3N
&22 C1_3N
&23 C2_35N
&24 C1N

#
#Layer features
#
P 7.785 4.45 4 P 0 0;1=0
P 7.835 4.45 4 P 0 0;1=0
P 1.8 4.485 4 P 0 0;1=0
P 1.86 4.485 4 P 0 0;1=0
P 0.27165 1.72835 10 P 0 0;1=1
P 0.17323002 2.12205 10 P 0 0;1=1
P 12.73621004 1.76771998 10 P 0 0;1=1
P 12.81495 2.59448996 10 P 0 0;1=1
P 12.63778996 2.16141998 10 P 0 0;1=1
P 0.725 -0.25 10 P 0 0;1=2
P 0.875 -0.25 10 P 0 0;1=2
P 1.065 6.26 10 P 0 0;1=2
P 1.065 6.36 10 P 0 0;1=2
P 1.29 6.26 10 P 0 0;1=2
P 1.29 6.36 10 P 0 0;1=2
P 1.515 6.26 10 P 0 0;1=2
P 1.515 6.36 10 P 0 0;1=2
P 0.84 6.26 10 P 0 0;1=2
P 0.84 6.36 10 P 0 0;1=2
P 1.74 6.26 10 P 0 0;1=2
P 1.74 6.36 10 P 0 0;1=2
P 2.09606004 3.56615 5 P 0 0;1=3
P 8.1 3.56615 5 P 0 0;1=3
P 12.55905 3.38188996 10 P 0 0;1=1
P 12.81495 4.64173996 10 P 0 0;1=1
P 12.81495 1.88583002 10 P 0 0;1=1
P 0.35038996 4.60236998 10 P 0 0;1=1
P 0.35038996 2.55511998 10 P 0 0;1=1
P 0.35038996 1.84646004 10 P 0 0;1=1
P 0.09448996 3.34251998 10 P 0 0;1=1
P 6.385 5.03 4 P 0 0;1=4
P 12.68701998 0.97243996 16 P 0 0;1=5
P 0.22245 0.93306998 16 P 0 0;1=5
P 12.68701004 4.91338002 16 P 0 0;1=5
P 3.94 4.545 4 P 0 0;1=0
P 4.91 5.375 4 P 0 0;1=4
P 1.08 5.85 4 P 0 0;1=0
P 3.6817 5.74 4 P 0 0;1=4
P 10.07 2.928 4 P 0 0;1=4
P 4.105 4.985 4 P 0 0;1=0
P 4.125 2.725 4 P 0 0;1=4
P 4.02 4.355 4 P 0 0;1=0
P 1.16 5.85 4 P 0 0;1=0
P 3.815 5.815 4 P 0 0;1=4
P 1.19 6.36 26 P 0 3;1=6
P 1.19 6.26 26 P 0 3;1=6
P 1.415 6.36 26 P 0 3;1=6
P 1.415 6.26 26 P 0 3;1=6
P 1.64 6.36 26 P 0 3;1=6
P 1.64 6.26 26 P 0 3;1=6
P 0.965 6.26 26 P 0 3;1=6
P 0.965 6.36 26 P 0 3;1=6
P 0.74 6.26 26 P 0 3;1=6
P 0.74 6.36 26 P 0 3;1=6
P 12.63778996 1.37401998 10 P 0 0;1=7
P 0.17323002 1.33465 10 P 0 0;1=7
P 6.501 5.017 4 P 0 0;1=0
P 7.425 3.43 4 P 0 0;1=0
P 7.445 1.705 4 P 0 0;1=4
P 11.03661004 3.81615 5 P 0 0;1=3
P 11.135 2.845 4 P 0 0;1=4
P 11.03661004 2.16615 5 P 0 0;1=3
P 3.8899 4.765 4 P 0 0;1=0
P 4.93268002 2.41615 5 P 0 0;1=3
P 4.93268002 2.46615 5 P 0 0;1=3
P 7.2926 5.04351004 4 P 0 0;1=0
P 7.2426 5.04351004 4 P 0 0;1=0
P 3.45646004 5.3 4 P 0 0;1=0
P 1.28906004 5.04351004 4 P 0 0;1=0
P 1.23906004 5.04351004 4 P 0 0;1=0
P 9.46 5.3 4 P 0 0;1=0
P 4.68268002 2.36615 5 P 0 0;1=3
P 0.27165 4.01181004 10 P 0 0;1=1
P 4.58268002 2.36615 5 P 0 0;1=3
P 0.27165 4.16928996 10 P 0 0;1=1
P 4.63268002 2.41615 5 P 0 0;1=3
P 0.27165 4.32676998 10 P 0 0;1=1
P 4.73268002 2.26615 5 P 0 0;1=3
P 0.27165 3.38188996 10 P 0 0;1=1
P 4.73268002 2.41615 5 P 0 0;1=3
P 0.27165 4.48425 10 P 0 0;1=1
P 4.68268002 2.21615 5 P 0 0;1=3
P 0.27165 3.53936998 10 P 0 0;1=1
P 4.63268002 2.26615 5 P 0 0;1=3
P 0.27165 3.85433002 10 P 0 0;1=1
P 4.58268002 2.06615 5 P 0 0;1=3
P 0.35038996 3.02756004 10 P 0 0;1=1
P 4.58268002 2.11615 5 P 0 0;1=3
P 0.27165 2.98818996 10 P 0 0;1=1
P 4.63268002 1.86615 5 P 0 0;1=3
P 0.35038996 2.3189 10 P 0 0;1=1
P 4.58268002 1.96615 5 P 0 0;1=3
P 0.27165 2.43701004 10 P 0 0;1=1
P 4.68268002 2.06615 5 P 0 0;1=3
P 0.35038996 3.18503996 10 P 0 0;1=1
P 4.58268002 1.91615 5 P 0 0;1=3
P 0.35038996 2.47638002 10 P 0 0;1=1
P 0.27165 2.27953002 10 P 0 0;1=1
P 4.63268002 1.91615 5 P 0 0;1=3
P 5.42048002 1.7396 5 P 0 0;1=3
P 0.09448996 2.55511998 10 P 0 0;1=1
P 4.68268002 2.11615 5 P 0 0;1=3
P 0.27165 3.14566998 10 P 0 0;1=1
P 5.42048002 1.7796 5 P 0 0;1=3
P 0.17323002 2.51575 10 P 0 0;1=1
P 4.68268002 1.91615 5 P 0 0;1=3
P 0.35038996 2.16141998 10 P 0 0;1=1
P 4.68268002 1.96615 5 P 0 0;1=3
P 0.27165 2.12205 10 P 0 0;1=1
P 5.57531004 2.0878 5 P 0 0;1=3
P 0.09448996 3.1063 10 P 0 0;1=1
P 5.57531004 2.1278 5 P 0 0;1=3
P 0.17323002 3.06693002 10 P 0 0;1=1
P 5.57531004 2.2232 5 P 0 0;1=3
P 0.17323002 3.46063002 10 P 0 0;1=1
P 5.57531004 2.2632 5 P 0 0;1=3
P 0.09448996 3.42126004 10 P 0 0;1=1
P 5.42048002 2.4662 5 P 0 0;1=3
P 0.09448996 4.05118002 10 P 0 0;1=1
P 5.57531004 2.3986 5 P 0 0;1=3
P 0.09448996 3.8937 10 P 0 0;1=1
P 5.57531004 2.673 5 P 0 0;1=3
P 0.09448996 4.36613996 10 P 0 0;1=1
P 5.57531004 1.9869 5 P 0 0;1=3
P 0.17323002 2.75196998 10 P 0 0;1=1
P 5.57531004 2.4978 5 P 0 0;1=3
P 0.17323002 4.24803002 10 P 0 0;1=1
P 5.57531004 1.6718 5 P 0 0;1=3
P 0.17323002 2.20078996 10 P 0 0;1=1
P 5.57531004 2.633 5 P 0 0;1=3
P 0.17323002 4.40551004 10 P 0 0;1=1
P 5.57531004 1.7118 5 P 0 0;1=3
P 0.09448996 2.24016004 10 P 0 0;1=1
P 5.57531004 2.5378 5 P 0 0;1=3
P 0.09448996 4.20866004 10 P 0 0;1=1
P 5.42048002 1.6433 5 P 0 0;1=3
P 0.09448996 2.39763996 10 P 0 0;1=1
P 5.42048002 2.6054 5 P 0 0;1=3
P 0.09448996 4.52361998 10 P 0 0;1=1
P 5.42048002 1.87835 5 P 0 0;1=3
P 0.09448996 2.94881998 10 P 0 0;1=1
P 5.57531004 2.3586 5 P 0 0;1=3
P 0.17323002 3.93306998 10 P 0 0;1=1
P 5.42048002 1.6033 5 P 0 0;1=3
P 0.17323002 2.35826998 10 P 0 0;1=1
P 5.42048002 2.4262 5 P 0 0;1=3
P 0.17323002 4.09055 10 P 0 0;1=1
P 5.42048002 1.91835 5 P 0 0;1=3
P 0.17323002 2.90945 10 P 0 0;1=1
P 5.42048002 2.0547 5 P 0 0;1=3
P 0.17323002 3.22441004 10 P 0 0;1=1
P 5.57531004 1.9469 5 P 0 0;1=3
P 0.09448996 2.79133996 10 P 0 0;1=1
P 5.42048002 2.0147 5 P 0 0;1=3
P 0.09448996 3.26378002 10 P 0 0;1=1
P 5.57531004 1.8508 5 P 0 0;1=3
P 0.09448996 2.00393996 10 P 0 0;1=1
P 5.57531004 1.8108 5 P 0 0;1=3
P 0.17323002 2.04331004 10 P 0 0;1=1
P 0.35038996 3.97243996 10 P 0 0;1=1
P 4.68268002 2.41615 5 P 0 0;1=3
P 4.73268002 2.46615 5 P 0 0;1=3
P 0.35038996 4.44488002 10 P 0 0;1=1
P 4.63268002 2.46615 5 P 0 0;1=3
P 0.35038996 4.2874 10 P 0 0;1=1
P 0.35038996 4.12991998 10 P 0 0;1=1
P 4.58268002 2.41615 5 P 0 0;1=3
P 4.68268002 2.26615 5 P 0 0;1=3
P 0.35038996 3.5 10 P 0 0;1=1
P 5.42048002 2.1554 5 P 0 0;1=3
P 0.17323002 3.77558996 10 P 0 0;1=1
P 4.73268002 2.31615 5 P 0 0;1=3
P 0.35038996 3.34251998 10 P 0 0;1=1
P 4.63268002 2.31615 5 P 0 0;1=3
P 0.35038996 3.81496004 10 P 0 0;1=1
P 4.58268002 2.26615 5 P 0 0;1=3
P 0.35038996 3.65748002 10 P 0 0;1=1
P 5.42048002 2.5654 5 P 0 0;1=3
P 0.17323002 4.563 10 P 0 0;1=1
P 5.42048002 2.1954 5 P 0 0;1=3
P 0.09448996 3.73621998 10 P 0 0;1=1
P 0.09448996 3.57873996 10 P 0 0;1=1
P 5.42048002 2.3308 5 P 0 0;1=3
P 0.17323002 3.61811004 10 P 0 0;1=1
P 5.42048002 2.2908 5 P 0 0;1=3
P 0.35038996 1.9252 10 P 0 0;1=1
P 4.73268002 1.91615 5 P 0 0;1=3
P 4.73268002 1.86615 5 P 0 0;1=3
P 0.27165 1.96456998 10 P 0 0;1=1
P 4.58268002 2.21615 5 P 0 0;1=3
P 0.27165 3.69685 10 P 0 0;1=1
P 4.73268002 2.06615 5 P 0 0;1=3
P 0.27165 2.67323002 10 P 0 0;1=1
P 4.73268002 2.01615 5 P 0 0;1=3
P 0.35038996 2.7126 10 P 0 0;1=1
P 4.63268002 2.01615 5 P 0 0;1=3
P 0.35038996 2.87008002 10 P 0 0;1=1
P 4.63268002 2.06615 5 P 0 0;1=3
P 0.27165 2.83071004 10 P 0 0;1=1
P 6.785 4.725 4 P 0 0;1=4
P 6.785 4.685 4 P 0 0;1=4
P 6.74018996 4.765 4 P 0 0;1=4
P 6.74 4.805 4 P 0 0;1=0
P 6.785 4.845 4 P 0 0;1=4
P 6.785 4.805 4 P 0 0;1=4
P 6.785 4.765 4 P 0 0;1=4
P 6.74 4.845 4 P 0 0;1=4
P 6.65 5.055 4 P 0 0;1=0
P 6.49205 5.09705 4 P 0 0;1=0
P 6.495 4.9328 4 P 0 0;1=0
P 6.55118996 5.04705 4 P 0 0;1=0
P 6.78 4.94705 4 P 0 0;1=0
P 6.755 4.89705 4 P 0 0;1=0
P 6.74 4.987 4 P 0 0;1=0
P 12.73621004 2.08268002 10 P 0 0;1=1
P 12.73621004 2.63386004 10 P 0 0;1=1
P 12.81495 3.30315 10 P 0 0;1=1
P 12.73621004 4.60236998 10 P 0 0;1=1
P 12.55905 1.96456998 10 P 0 0;1=1
P 12.63778996 1.9252 10 P 0 0;1=1
P 0.09448996 1.9252 10 P 0 0;1=1
P 0.17323002 1.88583002 10 P 0 0;1=1
P 0.27165 2.04331004 10 P 0 0;1=1
P 0.27165 4.563 10 P 0 0;1=1
P 0.35038996 3.26378002 10 P 0 0;1=1
P 0.27165 2.59448996 10 P 0 0;1=1
P 0.17323002 1.72835 10 P 0 0;1=1
P 5.03268002 1.91615 5 P 0 0;1=3
P 1.025 -0.25 10 P 0 0;1=2
P 1.175 -0.25 10 P 0 0;1=2
P 1.325 -0.25 10 P 0 0;1=2
P 5.03268002 2.06615 5 P 0 0;1=3
P 12.63778996 4.12991998 10 P 0 0;1=1
P 11.53316004 2.372 5 P 0 0;1=3
P 5.08268002 2.26615 5 P 0 0;1=3
P 11.53316004 1.892 5 P 0 0;1=3
P 12.55905 3.30315 10 P 0 0;1=1
P 12.81495 2.51575 10 P 0 0;1=1
P 10.58661004 1.91615 5 P 0 0;1=3
P 10.26 1.66445 5 P 0 0;1=3
P 11.03998996 4.8431 4 P 0 0;1=4
P 11.08498996 4.8431 4 P 0 0;1=4
P 11.13498996 4.8431 4 P 0 0;1=4
P 11.17998996 4.8431 4 P 0 0;1=4
P 11.17998996 4.8031 4 P 0 0;1=4
P 11.17998996 4.7581 4 P 0 0;1=4
P 11.17998996 4.7131 4 P 0 0;1=4
P 11.17998996 4.6731 4 P 0 0;1=4
P 11.03998996 4.6731 4 P 0 0;1=4
P 11.08498996 4.6731 4 P 0 0;1=4
P 11.13498996 4.6731 4 P 0 0;1=4
P 11.03998996 4.7131 4 P 0 0;1=4
P 11.03998996 4.8031 4 P 0 0;1=4
P 11.03998996 4.7581 4 P 0 0;1=4
P 10.81998996 4.6631 4 P 0 0;1=4
P 10.85998996 4.6631 4 P 0 0;1=4
P 10.65998996 4.6631 4 P 0 0;1=4
P 10.69998996 4.6631 4 P 0 0;1=4
P 10.81998996 4.7031 4 P 0 0;1=4
P 10.81998996 4.8381 4 P 0 0;1=4
P 10.81998996 4.7931 4 P 0 0;1=4
P 10.81998996 4.7481 4 P 0 0;1=4
P 10.85998996 4.7031 4 P 0 0;1=4
P 10.85998996 4.8381 4 P 0 0;1=4
P 10.85998996 4.7931 4 P 0 0;1=4
P 10.85998996 4.7481 4 P 0 0;1=4
P 10.65998996 4.7031 4 P 0 0;1=4
P 10.65998996 4.8381 4 P 0 0;1=4
P 10.65998996 4.7931 4 P 0 0;1=4
P 10.65998996 4.7481 4 P 0 0;1=4
P 10.69998996 4.7031 4 P 0 0;1=4
P 10.69998996 4.8381 4 P 0 0;1=4
P 10.69998996 4.7931 4 P 0 0;1=4
P 10.69998996 4.7481 4 P 0 0;1=4
P 10.77998996 4.6431 4 P 0 0;1=4
P 10.73498996 4.6431 4 P 0 0;1=4
P 10.73998996 4.8381 4 P 0 0;1=4
P 10.77998996 4.8381 4 P 0 0;1=4
P 10.30998996 4.6631 4 P 0 0;1=4
P 10.26998996 4.6631 4 P 0 0;1=4
P 10.34498996 4.6431 4 P 0 0;1=4
P 10.38998996 4.6431 4 P 0 0;1=4
P 10.42998996 4.6631 4 P 0 0;1=4
P 10.46998996 4.6631 4 P 0 0;1=4
P 10.30998996 4.7481 4 P 0 0;1=4
P 10.30998996 4.7931 4 P 0 0;1=4
P 10.30998996 4.7031 4 P 0 0;1=4
P 10.26998996 4.7481 4 P 0 0;1=4
P 10.26998996 4.7931 4 P 0 0;1=4
P 10.26998996 4.7031 4 P 0 0;1=4
P 10.26998996 4.8381 4 P 0 0;1=4
P 10.30998996 4.8381 4 P 0 0;1=4
P 10.38998996 4.8381 4 P 0 0;1=4
P 10.34998996 4.8381 4 P 0 0;1=4
P 10.46998996 4.8381 4 P 0 0;1=4
P 10.42998996 4.8381 4 P 0 0;1=4
P 10.42998996 4.7031 4 P 0 0;1=4
P 10.42998996 4.7931 4 P 0 0;1=4
P 10.42998996 4.7481 4 P 0 0;1=4
P 10.46998996 4.7031 4 P 0 0;1=4
P 10.46998996 4.7931 4 P 0 0;1=4
P 10.46998996 4.7481 4 P 0 0;1=4
P 10.58661004 3.16615 5 P 0 0;1=3
P 10.63661004 3.01615 5 P 0 0;1=3
P 10.58661004 3.11615 5 P 0 0;1=3
P 10.58661004 3.01615 5 P 0 0;1=3
P 10.63661004 3.11615 5 P 0 0;1=3
P 10.63661004 2.96615 5 P 0 0;1=3
P 10.58661004 2.96615 5 P 0 0;1=3
P 10.58661004 3.41615 5 P 0 0;1=3
P 10.63661004 3.16615 5 P 0 0;1=3
P 10.63661004 3.26615 5 P 0 0;1=3
P 10.58661004 3.31615 5 P 0 0;1=3
P 10.58661004 3.26615 5 P 0 0;1=3
P 10.63661004 3.31615 5 P 0 0;1=3
P 10.63661004 3.56615 5 P 0 0;1=3
P 10.63661004 3.61615 5 P 0 0;1=3
P 10.58661004 3.56615 5 P 0 0;1=3
P 10.58661004 3.61615 5 P 0 0;1=3
P 10.63661004 3.46615 5 P 0 0;1=3
P 10.63661004 3.41615 5 P 0 0;1=3
P 10.58661004 3.46615 5 P 0 0;1=3
P 10.63661004 3.86615 5 P 0 0;1=3
P 10.63661004 3.76615 5 P 0 0;1=3
P 10.58661004 3.86615 5 P 0 0;1=3
P 10.58661004 3.76615 5 P 0 0;1=3
P 10.63661004 3.71615 5 P 0 0;1=3
P 10.58661004 3.71615 5 P 0 0;1=3
P 10.88661004 2.96615 5 P 0 0;1=3
P 10.83661004 2.96615 5 P 0 0;1=3
P 10.88661004 3.01615 5 P 0 0;1=3
P 10.83661004 3.01615 5 P 0 0;1=3
P 10.88661004 3.11615 5 P 0 0;1=3
P 10.83661004 3.11615 5 P 0 0;1=3
P 10.83661004 3.16615 5 P 0 0;1=3
P 10.78661004 3.16615 5 P 0 0;1=3
P 10.68661004 3.16615 5 P 0 0;1=3
P 10.73661004 3.16615 5 P 0 0;1=3
P 10.78661004 3.01615 5 P 0 0;1=3
P 10.78661004 3.11615 5 P 0 0;1=3
P 10.73661004 3.01615 5 P 0 0;1=3
P 10.73661004 3.11615 5 P 0 0;1=3
P 10.68661004 3.01615 5 P 0 0;1=3
P 10.68661004 3.11615 5 P 0 0;1=3
P 10.78661004 2.96615 5 P 0 0;1=3
P 10.73661004 2.96615 5 P 0 0;1=3
P 10.68661004 2.96615 5 P 0 0;1=3
P 10.88661004 3.16615 5 P 0 0;1=3
P 10.88661004 3.26615 5 P 0 0;1=3
P 10.83661004 3.26615 5 P 0 0;1=3
P 10.83661004 3.31615 5 P 0 0;1=3
P 10.88661004 3.31615 5 P 0 0;1=3
P 10.83661004 3.41615 5 P 0 0;1=3
P 10.78661004 3.41615 5 P 0 0;1=3
P 10.68661004 3.41615 5 P 0 0;1=3
P 10.73661004 3.41615 5 P 0 0;1=3
P 10.78661004 3.31615 5 P 0 0;1=3
P 10.78661004 3.26615 5 P 0 0;1=3
P 10.68661004 3.31615 5 P 0 0;1=3
P 10.68661004 3.26615 5 P 0 0;1=3
P 10.73661004 3.26615 5 P 0 0;1=3
P 10.73661004 3.31615 5 P 0 0;1=3
P 10.88661004 3.41615 5 P 0 0;1=3
P 10.83661004 3.46615 5 P 0 0;1=3
P 10.88661004 3.46615 5 P 0 0;1=3
P 10.83661004 3.56615 5 P 0 0;1=3
P 10.88661004 3.56615 5 P 0 0;1=3
P 10.83661004 3.61615 5 P 0 0;1=3
P 10.88661004 3.61615 5 P 0 0;1=3
P 10.78661004 3.56615 5 P 0 0;1=3
P 10.78661004 3.61615 5 P 0 0;1=3
P 10.68661004 3.61615 5 P 0 0;1=3
P 10.68661004 3.56615 5 P 0 0;1=3
P 10.73661004 3.61615 5 P 0 0;1=3
P 10.73661004 3.56615 5 P 0 0;1=3
P 10.78661004 3.46615 5 P 0 0;1=3
P 10.73661004 3.46615 5 P 0 0;1=3
P 10.68661004 3.46615 5 P 0 0;1=3
P 10.83661004 3.71615 5 P 0 0;1=3
P 10.88661004 3.71615 5 P 0 0;1=3
P 10.83661004 3.76615 5 P 0 0;1=3
P 10.88661004 3.76615 5 P 0 0;1=3
P 10.83661004 3.86615 5 P 0 0;1=3
P 10.88661004 3.86615 5 P 0 0;1=3
P 10.78661004 3.86615 5 P 0 0;1=3
P 10.78661004 3.76615 5 P 0 0;1=3
P 10.68661004 3.86615 5 P 0 0;1=3
P 10.68661004 3.76615 5 P 0 0;1=3
P 10.73661004 3.86615 5 P 0 0;1=3
P 10.73661004 3.76615 5 P 0 0;1=3
P 10.78661004 3.71615 5 P 0 0;1=3
P 10.68661004 3.71615 5 P 0 0;1=3
P 10.73661004 3.71615 5 P 0 0;1=3
P 11.03661004 2.96615 5 P 0 0;1=3
P 10.93661004 2.96615 5 P 0 0;1=3
P 10.98661004 2.96615 5 P 0 0;1=3
P 11.03661004 3.01615 5 P 0 0;1=3
P 10.93661004 3.01615 5 P 0 0;1=3
P 10.98661004 3.01615 5 P 0 0;1=3
P 11.03661004 3.11615 5 P 0 0;1=3
P 10.93661004 3.11615 5 P 0 0;1=3
P 10.98661004 3.11615 5 P 0 0;1=3
P 11.03661004 3.16615 5 P 0 0;1=3
P 10.93661004 3.16615 5 P 0 0;1=3
P 10.98661004 3.16615 5 P 0 0;1=3
P 11.03661004 3.26615 5 P 0 0;1=3
P 10.93661004 3.26615 5 P 0 0;1=3
P 10.98661004 3.26615 5 P 0 0;1=3
P 10.98661004 3.31615 5 P 0 0;1=3
P 10.93661004 3.31615 5 P 0 0;1=3
P 11.03661004 3.31615 5 P 0 0;1=3
P 10.98661004 3.41615 5 P 0 0;1=3
P 10.93661004 3.41615 5 P 0 0;1=3
P 11.03661004 3.41615 5 P 0 0;1=3
P 10.98661004 3.46615 5 P 0 0;1=3
P 10.93661004 3.46615 5 P 0 0;1=3
P 11.03661004 3.46615 5 P 0 0;1=3
P 10.98661004 3.56615 5 P 0 0;1=3
P 10.93661004 3.56615 5 P 0 0;1=3
P 11.03661004 3.56615 5 P 0 0;1=3
P 10.98661004 3.61615 5 P 0 0;1=3
P 10.93661004 3.61615 5 P 0 0;1=3
P 11.03661004 3.61615 5 P 0 0;1=3
P 10.98661004 3.71615 5 P 0 0;1=3
P 10.93661004 3.71615 5 P 0 0;1=3
P 11.03661004 3.71615 5 P 0 0;1=3
P 10.98661004 3.76615 5 P 0 0;1=3
P 10.93661004 3.76615 5 P 0 0;1=3
P 11.03661004 3.76615 5 P 0 0;1=3
P 10.98661004 3.86615 5 P 0 0;1=3
P 10.93661004 3.86615 5 P 0 0;1=3
P 11.03661004 3.86615 5 P 0 0;1=3
P 5.08268002 2.06615 5 P 0 0;1=3
P 10.58661004 2.36615 5 P 0 0;1=3
P 9.975 2.4709 5 P 0 0;1=3
P 12.73621004 4.20866004 10 P 0 0;1=1
P 11.08661004 2.36615 5 P 0 0;1=3
P 5.08268002 2.11615 5 P 0 0;1=3
P 11.08661004 2.41615 5 P 0 0;1=3
P 12.73621004 2.47638002 10 P 0 0;1=1
P 10.58661004 1.96615 5 P 0 0;1=3
P 10.26 1.70445 5 P 0 0;1=3
P 10.98661004 2.41615 5 P 0 0;1=3
P 8.5 3.76615 5 P 0 0;1=3
P 9.35271004 5.1035 5 P 0 0;1=3
P 4.98268002 2.06615 5 P 0 0;1=3
P 8.5 3.81615 5 P 0 0;1=3
P 9.31271004 5.1035 5 P 0 0;1=3
P 12.55905 2.59448996 10 P 0 0;1=1
P 11.53316004 1.572 5 P 0 0;1=3
P 4.98268002 2.11615 5 P 0 0;1=3
P 10.98661004 2.36615 5 P 0 0;1=3
P 8.5 3.61615 5 P 0 0;1=3
P 9.56531004 5.14 5 P 0 0;1=3
P 4.93268002 2.01615 5 P 0 0;1=3
P 11.53316004 1.412 5 P 0 0;1=3
P 12.63778996 2.39763996 10 P 0 0;1=1
P 8.5 3.66615 5 P 0 0;1=3
P 9.52531004 5.14 5 P 0 0;1=3
P 12.73621004 2.87008002 10 P 0 0;1=1
P 10.63661004 2.06615 5 P 0 0;1=3
P 10.225 1.96645 5 P 0 0;1=3
P 11.53316004 1.452 5 P 0 0;1=3
P 12.55905 2.43701004 10 P 0 0;1=1
P 8.35 3.66615 5 P 0 0;1=3
P 9.56531004 4.71973002 5 P 0 0;1=3
P 4.93268002 2.06615 5 P 0 0;1=3
P 8.35 3.71615 5 P 0 0;1=3
P 9.52531004 4.71973002 5 P 0 0;1=3
P 11.83316004 2.212 5 P 0 0;1=3
P 12.63778996 3.65748002 10 P 0 0;1=1
P 12.73621004 3.02756004 10 P 0 0;1=1
P 10.58661004 2.11615 5 P 0 0;1=3
P 10.09 2.05655 5 P 0 0;1=3
P 11.53316004 1.932 5 P 0 0;1=3
P 12.63778996 3.26378002 10 P 0 0;1=1
P 8.74578996 5.14 5 P 0 0;1=3
P 8.05 3.61615 5 P 0 0;1=3
P 12.81495 4.01181004 10 P 0 0;1=1
P 10.09 2.57845 5 P 0 0;1=3
P 10.68661004 2.41615 5 P 0 0;1=3
P 11.73316004 1.492 5 P 0 0;1=3
P 12.63778996 2.24016004 10 P 0 0;1=1
P 8.78578996 5.14 5 P 0 0;1=3
P 8.05 3.66615 5 P 0 0;1=3
P 12.73621004 2.7126 10 P 0 0;1=1
P 10.73661004 2.06615 5 P 0 0;1=3
P 10.26025 1.86845 5 P 0 0;1=3
P 11.03661004 2.46615 5 P 0 0;1=3
P 8.15 3.61615 5 P 0 0;1=3
P 8.88441004 5.17001998 5 P 0 0;1=3
P 12.55905 4.09055 10 P 0 0;1=1
P 11.53316004 2.412 5 P 0 0;1=3
P 11.03661004 2.51615 5 P 0 0;1=3
P 8.15 3.66615 5 P 0 0;1=3
P 8.92441004 5.17001998 5 P 0 0;1=3
P 1.057 5.027 4 P 0 0;1=0
P 12.73621004 3.18503996 10 P 0 0;1=1
P 10.68661004 2.11615 5 P 0 0;1=3
P 10.09 2.17095 5 P 0 0;1=3
P 11.78316004 1.692 5 P 0 0;1=3
P 12.55905 2.04331004 10 P 0 0;1=1
P 12.81495 2.90945 10 P 0 0;1=1
P 10.63661004 2.01615 5 P 0 0;1=3
P 10.225 1.92645 5 P 0 0;1=3
P 11.78316004 1.652 5 P 0 0;1=3
P 12.63778996 2.08268002 10 P 0 0;1=1
P 1.122 5.417 4 P 0 0;1=4
P 5.855 0.925 4 P 0 0;1=4
P 3.88 4.545 4 P 0 0;1=0
P 0.96555 5.78055 4 P 0 0;1=0
P 4.07 4.625 4 P 0 0;1=4
P 10.58661004 2.71615 5 P 0 0;1=3
P 9.91 4.433 4 P 0 0;1=0
P 9.995 2.936 4 P 0 0;1=4
P 11.83316004 2.252 5 P 0 0;1=3
P 12.55905 3.61811004 10 P 0 0;1=1
P 12.81495 3.06693002 10 P 0 0;1=1
P 10.58661004 2.06615 5 P 0 0;1=3
P 10.09 2.01655 5 P 0 0;1=3
P 8.1 3.81615 5 P 0 0;1=3
P 9.10011004 5.0535 5 P 0 0;1=3
P 8.1 3.86615 5 P 0 0;1=3
P 9.14011004 5.0535 5 P 0 0;1=3
P 3.9599 5.395 4 P 0 0;1=0
P 0.88681004 5.78181004 4 P 0 0;1=4
P 12.73621004 2.3189 10 P 0 0;1=1
P 10.63661004 1.91615 5 P 0 0;1=3
P 10.38371998 1.49328002 5 P 0 0;1=3
P 8.35 3.81615 5 P 0 0;1=3
P 9.28185 5.22001998 5 P 0 0;1=3
P 0.72933002 5.463 4 P 0 0;1=0
P 11.53316004 2.572 5 P 0 0;1=3
P 12.55905 4.56298996 10 P 0 0;1=1
P 8.35 3.86615 5 P 0 0;1=3
P 9.24185 5.22001998 5 P 0 0;1=3
P 4.125 2.682 4 P 0 0;1=4
P 3.94 4.42 4 P 0 0;1=0
P 5.03 5.4 4 P 0 0;1=4
P 4.58268002 2.71615 5 P 0 0;1=3
P 8.45 3.81615 5 P 0 0;1=3
P 9.21098002 4.78291998 5 P 0 0;1=3
P 8.45 3.86615 5 P 0 0;1=3
P 9.17098002 4.78291998 5 P 0 0;1=3
P 3.75998996 0.24001004 4 P 0 0;1=0
P 9.55795 0.26133996 4 P 0 0;1=0
P 3.71203002 0.77535 4 P 0 0;1=4
P 3.70998996 0.7 4 P 0 0;1=4
P 9.50795 0.72133002 4 P 0 0;1=4
P 9.46795 0.82631998 4 P 0 0;1=4
P 4.02893002 2.59336998 4 P 0 0;1=4
P 11.395 2.725 4 P 0 0;1=0
P 11.395 2.8 4 P 0 0;1=4
P 11.58613002 2.905 4 P 0 0;1=4
P 11.58613002 2.785 4 P 0 0;1=4
P 1.33906004 4.60351004 4 P 0 0;1=0
P 3.67 4.45 4 P 0 0;1=4
P 3.72 4.545 4 P 0 0;1=4
P 5.37968996 2.8 4 P 0 0;1=4
P 5.387 2.725 4 P 0 0;1=0
P 5.5822 2.785 4 P 0 0;1=4
P 5.5822 2.905 4 P 0 0;1=4
P 7.2426 4.69351004 4 P 0 0;1=4
P 7.2926 4.60351004 4 P 0 0;1=4
P 9.98 4.51 4 P 0 0;1=4
P 10.07286004 2.82336998 4 P 0 0;1=4
P 10.03 4.61 4 P 0 0;1=4
P 1.23906004 4.69351004 4 P 0 0;1=4
P 3.89 4.655 4 P 0 0;1=4
P 3.9899 4.765 4 P 0 0;1=4
P 4.1049 4.86 4 P 0 0;1=4
P 4.0599 5.395 4 P 0 0;1=4
P 3.91 5.51 4 P 0 0;1=4
P 5.125 5.4 4 P 0 0;1=4
P 1.37925 5.78 4 P 0 0;1=4
P 1.45798996 5.78 4 P 0 0;1=4
P 1.42 5.78 4 P 0 0;1=4
P 1.335 5.78 4 P 0 0;1=4
P 12.63778996 2.55511998 10 P 0 0;1=1
P 11.53316004 1.612 5 P 0 0;1=3
P 8.4 3.76615 5 P 0 0;1=3
P 9.28185 4.642 5 P 0 0;1=3
P 12.73621004 4.36613996 10 P 0 0;1=1
P 10.63661004 2.41615 5 P 0 0;1=3
P 9.975 2.66445 5 P 0 0;1=3
P 8.4 3.81615 5 P 0 0;1=3
P 9.24185 4.642 5 P 0 0;1=3
P 11.53316004 2.532 5 P 0 0;1=3
P 12.63778996 4.60236998 10 P 0 0;1=1
P 8.45 3.66615 5 P 0 0;1=3
P 9.42358002 4.78291998 5 P 0 0;1=3
P 0.95951004 5.4595 4 P 0 0;1=0
P 8.45 3.71615 5 P 0 0;1=3
P 9.38358002 4.78291998 5 P 0 0;1=3
P 8.4 3.61615 5 P 0 0;1=3
P 9.49445 4.587 5 P 0 0;1=3
P 8.4 3.66615 5 P 0 0;1=3
P 9.45445 4.587 5 P 0 0;1=3
P 9.07353996 4.42 4 P 0 0;1=4
P 7.1926 5.15351004 4 P 0 0;1=0
P 8.1 3.66615 5 P 0 0;1=3
P 8.74578996 4.667 5 P 0 0;1=3
P 8.1 3.71615 5 P 0 0;1=3
P 8.78578996 4.667 5 P 0 0;1=3
P 8.2 3.66615 5 P 0 0;1=3
P 8.81665 4.78291998 5 P 0 0;1=3
P 8.2 3.71615 5 P 0 0;1=3
P 8.85665 4.78291998 5 P 0 0;1=3
P 8.05 3.76615 5 P 0 0;1=3
P 8.89061998 4.667 5 P 0 0;1=3
P 8.05 3.81615 5 P 0 0;1=3
P 8.93061998 4.667 5 P 0 0;1=3
P 9.02925 4.667 5 P 0 0;1=3
P 8.2 3.81615 5 P 0 0;1=3
P 9.06925 4.667 5 P 0 0;1=3
P 8.2 3.86615 5 P 0 0;1=3
P 4.68268002 2.71615 5 P 0 0;1=3
P 4.98268002 2.71615 5 P 0 0;1=3
P 2.14606004 2.51615 5 P 0 0;1=3
P 8.45 3.41615 5 P 0 0;1=3
P 8.18811004 5.0535 5 P 0 0;1=3
P 5.03268002 3.81615 5 P 0 0;1=3
P 4.07408002 4.01978996 4 P 0 0;1=0
P 8.45 3.46615 5 P 0 0;1=3
P 8.14811004 5.0535 5 P 0 0;1=3
P 5.03268002 2.16615 5 P 0 0;1=3
P 3.9099 5.395 4 P 0 0;1=0
P 8.45 3.26615 5 P 0 0;1=3
P 8.40071004 5.115 5 P 0 0;1=3
P 8.45 3.31615 5 P 0 0;1=3
P 8.36071004 5.115 5 P 0 0;1=3
P 8.35 3.26615 5 P 0 0;1=3
P 8.40071004 4.742 5 P 0 0;1=3
P 8.35 3.31615 5 P 0 0;1=3
P 8.36071004 4.742 5 P 0 0;1=3
P 8.3 3.56615 5 P 0 0;1=3
P 8.05 3.31615 5 P 0 0;1=3
P 7.58118996 5.169 5 P 0 0;1=3
P 8.25 3.56615 5 P 0 0;1=3
P 8.05 3.36615 5 P 0 0;1=3
P 7.62118996 5.169 5 P 0 0;1=3
P 2.24606004 2.86615 5 P 0 0;1=3
P 8.05 2.61615 24 P 0 0;1=3
P 8.05 2.66615 24 P 0 0;1=3
P 8.1 2.46615 24 P 0 0;1=3
P 8.1 2.41615 24 P 0 0;1=3
P 8.2 2.46615 24 P 0 0;1=3
P 8.2 2.41615 24 P 0 0;1=3
P 8.15 2.41615 24 P 0 0;1=3
P 8.15 2.36615 24 P 0 0;1=3
P 8.05 2.41615 24 P 0 0;1=3
P 8.05 2.36615 24 P 0 0;1=3
P 8.2 2.31615 24 P 0 0;1=3
P 8.2 2.26615 24 P 0 0;1=3
P 8.15 2.26615 24 P 0 0;1=3
P 8.15 2.21615 24 P 0 0;1=3
P 8.1 2.31615 24 P 0 0;1=3
P 8.1 2.26615 24 P 0 0;1=3
P 8.05 2.26615 24 P 0 0;1=3
P 8.05 2.21615 24 P 0 0;1=3
P 8.1 2.11615 24 P 0 0;1=3
P 8.1 2.06615 24 P 0 0;1=3
P 8.2 2.11615 24 P 0 0;1=3
P 8.2 2.06615 24 P 0 0;1=3
P 8.15 2.06615 24 P 0 0;1=3
P 8.15 2.01615 24 P 0 0;1=3
P 8.05 2.06615 24 P 0 0;1=3
P 8.05 2.01615 24 P 0 0;1=3
P 8.2 1.96615 24 P 0 0;1=3
P 8.2 1.91615 24 P 0 0;1=3
P 8.15 1.91615 24 P 0 0;1=3
P 8.15 1.86615 24 P 0 0;1=3
P 8.1 1.96615 24 P 0 0;1=3
P 8.1 1.91615 24 P 0 0;1=3
P 8.05 1.91615 24 P 0 0;1=3
P 8.05 1.86615 24 P 0 0;1=3
P 8.1 3.16615 24 P 0 0;1=3
P 8.1 3.11615 24 P 0 0;1=3
P 8.2 3.16615 24 P 0 0;1=3
P 8.2 3.11615 24 P 0 0;1=3
P 8.15 3.11615 24 P 0 0;1=3
P 8.15 3.06615 24 P 0 0;1=3
P 8.05 3.11615 24 P 0 0;1=3
P 8.05 3.06615 24 P 0 0;1=3
P 8.2 3.01615 24 P 0 0;1=3
P 8.2 2.96615 24 P 0 0;1=3
P 8.15 2.96615 24 P 0 0;1=3
P 8.15 2.91615 24 P 0 0;1=3
P 8.1 3.01615 24 P 0 0;1=3
P 8.1 2.96615 24 P 0 0;1=3
P 8.05 2.96615 24 P 0 0;1=3
P 8.05 2.91615 24 P 0 0;1=3
P 8 2.81615 24 P 0 0;1=3
P 8 2.76615 24 P 0 0;1=3
P 8.15 2.81615 24 P 0 0;1=3
P 8.15 2.76615 24 P 0 0;1=3
P 8.2 2.76615 24 P 0 0;1=3
P 8.2 2.71615 24 P 0 0;1=3
P 8.1 2.76615 24 P 0 0;1=3
P 8.1 2.71615 24 P 0 0;1=3
P 8.15 2.66615 24 P 0 0;1=3
P 8.15 2.61615 24 P 0 0;1=3
P 8.2 2.61615 24 P 0 0;1=3
P 8.2 2.56615 24 P 0 0;1=3
P 8.1 2.61615 24 P 0 0;1=3
P 8.1 2.56615 24 P 0 0;1=3
P 8.35 2.56615 24 P 0 0;1=3
P 8.35 2.61615 24 P 0 0;1=3
P 8.35 2.46615 24 P 0 0;1=3
P 8.35 2.41615 24 P 0 0;1=3
P 8.45 2.46615 24 P 0 0;1=3
P 8.45 2.41615 24 P 0 0;1=3
P 8.5 2.41615 24 P 0 0;1=3
P 8.5 2.36615 24 P 0 0;1=3
P 8.4 2.41615 24 P 0 0;1=3
P 8.4 2.36615 24 P 0 0;1=3
P 8.45 2.31615 24 P 0 0;1=3
P 8.45 2.26615 24 P 0 0;1=3
P 8.5 2.26615 24 P 0 0;1=3
P 8.5 2.21615 24 P 0 0;1=3
P 8.4 2.26615 24 P 0 0;1=3
P 8.4 2.21615 24 P 0 0;1=3
P 8.35 2.31615 24 P 0 0;1=3
P 8.35 2.26615 24 P 0 0;1=3
P 8.35 2.11615 24 P 0 0;1=3
P 8.35 2.06615 24 P 0 0;1=3
P 8.45 2.11615 24 P 0 0;1=3
P 8.45 2.06615 24 P 0 0;1=3
P 8.5 2.06615 24 P 0 0;1=3
P 8.5 2.01615 24 P 0 0;1=3
P 8.4 2.06615 24 P 0 0;1=3
P 8.4 2.01615 24 P 0 0;1=3
P 8.45 1.96615 24 P 0 0;1=3
P 8.45 1.91615 24 P 0 0;1=3
P 8.5 1.91615 24 P 0 0;1=3
P 8.5 1.86615 24 P 0 0;1=3
P 8.4 1.91615 24 P 0 0;1=3
P 8.4 1.86615 24 P 0 0;1=3
P 8.35 1.96615 24 P 0 0;1=3
P 8.35 1.91615 24 P 0 0;1=3
P 8.35 3.16615 24 P 0 0;1=3
P 8.35 3.11615 24 P 0 0;1=3
P 8.45 3.16615 24 P 0 0;1=3
P 8.45 3.11615 24 P 0 0;1=3
P 8.5 3.11615 24 P 0 0;1=3
P 8.5 3.06615 24 P 0 0;1=3
P 8.4 3.11615 24 P 0 0;1=3
P 8.4 3.06615 24 P 0 0;1=3
P 8.45 3.01615 24 P 0 0;1=3
P 8.45 2.96615 24 P 0 0;1=3
P 8.5 2.96615 24 P 0 0;1=3
P 8.5 2.91615 24 P 0 0;1=3
P 8.4 2.96615 24 P 0 0;1=3
P 8.4 2.91615 24 P 0 0;1=3
P 8.35 3.01615 24 P 0 0;1=3
P 8.35 2.96615 24 P 0 0;1=3
P 8.4 2.81615 24 P 0 0;1=3
P 8.4 2.76615 24 P 0 0;1=3
P 8.5 2.81615 24 P 0 0;1=3
P 8.5 2.76615 24 P 0 0;1=3
P 8.45 2.76615 24 P 0 0;1=3
P 8.45 2.71615 24 P 0 0;1=3
P 8.35 2.76615 24 P 0 0;1=3
P 8.35 2.71615 24 P 0 0;1=3
P 8.5 2.66615 24 P 0 0;1=3
P 8.5 2.61615 24 P 0 0;1=3
P 8.45 2.61615 24 P 0 0;1=3
P 8.45 2.56615 24 P 0 0;1=3
P 8.4 2.66615 24 P 0 0;1=3
P 8.4 2.61615 24 P 0 0;1=3
P 2.04606024 2.61615 24 P 0 0;1=3
P 2.04606024 2.66615 24 P 0 0;1=3
P 2.09606024 2.46615 24 P 0 0;1=3
P 2.09606024 2.41615 24 P 0 0;1=3
P 2.19606024 2.46615 24 P 0 0;1=3
P 2.19606024 2.41615 24 P 0 0;1=3
P 2.14606024 2.41615 24 P 0 0;1=3
P 2.14606024 2.36615 24 P 0 0;1=3
P 2.04606024 2.41615 24 P 0 0;1=3
P 2.04606024 2.36615 24 P 0 0;1=3
P 2.19606024 2.31615 24 P 0 0;1=3
P 2.19606024 2.26615 24 P 0 0;1=3
P 2.14606024 2.26615 24 P 0 0;1=3
P 2.14606024 2.21615 24 P 0 0;1=3
P 2.09606024 2.31615 24 P 0 0;1=3
P 2.09606024 2.26615 24 P 0 0;1=3
P 2.04606024 2.26615 24 P 0 0;1=3
P 2.04606024 2.21615 24 P 0 0;1=3
P 2.09606024 2.11615 24 P 0 0;1=3
P 2.09606024 2.06615 24 P 0 0;1=3
P 2.19606024 2.11615 24 P 0 0;1=3
P 2.19606024 2.06615 24 P 0 0;1=3
P 2.14606024 2.06615 24 P 0 0;1=3
P 2.14606024 2.01615 24 P 0 0;1=3
P 2.04606024 2.06615 24 P 0 0;1=3
P 2.04606024 2.01615 24 P 0 0;1=3
P 2.19606024 1.96615 24 P 0 0;1=3
P 2.19606024 1.91615 24 P 0 0;1=3
P 2.14606024 1.91615 24 P 0 0;1=3
P 2.14606024 1.86615 24 P 0 0;1=3
P 2.09606024 1.96615 24 P 0 0;1=3
P 2.09606024 1.91615 24 P 0 0;1=3
P 2.04606024 1.91615 24 P 0 0;1=3
P 2.04606024 1.86615 24 P 0 0;1=3
P 2.09606024 3.16615 24 P 0 0;1=3
P 2.09606024 3.11615 24 P 0 0;1=3
P 2.19606024 3.16615 24 P 0 0;1=3
P 2.19606024 3.11615 24 P 0 0;1=3
P 2.14606024 3.11615 24 P 0 0;1=3
P 2.14606024 3.06615 24 P 0 0;1=3
P 2.04606024 3.11615 24 P 0 0;1=3
P 2.04606024 3.06615 24 P 0 0;1=3
P 2.19606024 3.01615 24 P 0 0;1=3
P 2.19606024 2.96615 24 P 0 0;1=3
P 2.14606024 2.96615 24 P 0 0;1=3
P 2.14606024 2.91615 24 P 0 0;1=3
P 2.09606024 3.01615 24 P 0 0;1=3
P 2.09606024 2.96615 24 P 0 0;1=3
P 2.04606024 2.96615 24 P 0 0;1=3
P 2.04606024 2.91615 24 P 0 0;1=3
P 1.99605974 2.81615 24 P 0 0;1=3
P 1.99605974 2.76615 24 P 0 0;1=3
P 2.14606024 2.81615 24 P 0 0;1=3
P 2.14606024 2.76615 24 P 0 0;1=3
P 2.19606024 2.76615 24 P 0 0;1=3
P 2.19606024 2.71615 24 P 0 0;1=3
P 2.09606024 2.76615 24 P 0 0;1=3
P 2.09606024 2.71615 24 P 0 0;1=3
P 2.14606024 2.66615 24 P 0 0;1=3
P 2.14606024 2.61615 24 P 0 0;1=3
P 2.19606024 2.61615 24 P 0 0;1=3
P 2.19606024 2.56615 24 P 0 0;1=3
P 2.09606024 2.61615 24 P 0 0;1=3
P 2.09606024 2.56615 24 P 0 0;1=3
P 2.34606024 2.56615 24 P 0 0;1=3
P 2.34606024 2.61615 24 P 0 0;1=3
P 2.34606024 2.46615 24 P 0 0;1=3
P 2.34606024 2.41615 24 P 0 0;1=3
P 2.44606024 2.46615 24 P 0 0;1=3
P 2.44606024 2.41615 24 P 0 0;1=3
P 2.49606024 2.41615 24 P 0 0;1=3
P 2.49606024 2.36615 24 P 0 0;1=3
P 2.39606024 2.41615 24 P 0 0;1=3
P 2.39606024 2.36615 24 P 0 0;1=3
P 2.44606024 2.31615 24 P 0 0;1=3
P 2.44606024 2.26615 24 P 0 0;1=3
P 2.49606024 2.26615 24 P 0 0;1=3
P 2.49606024 2.21615 24 P 0 0;1=3
P 2.39606024 2.26615 24 P 0 0;1=3
P 2.39606024 2.21615 24 P 0 0;1=3
P 2.34606024 2.31615 24 P 0 0;1=3
P 2.34606024 2.26615 24 P 0 0;1=3
P 2.34606024 2.11615 24 P 0 0;1=3
P 2.34606024 2.06615 24 P 0 0;1=3
P 2.44606024 2.11615 24 P 0 0;1=3
P 2.44606024 2.06615 24 P 0 0;1=3
P 2.49606024 2.06615 24 P 0 0;1=3
P 2.49606024 2.01615 24 P 0 0;1=3
P 2.39606024 2.06615 24 P 0 0;1=3
P 2.39606024 2.01615 24 P 0 0;1=3
P 2.44606024 1.96615 24 P 0 0;1=3
P 2.44606024 1.91615 24 P 0 0;1=3
P 2.49606024 1.91615 24 P 0 0;1=3
P 2.49606024 1.86615 24 P 0 0;1=3
P 2.39606024 1.91615 24 P 0 0;1=3
P 2.39606024 1.86615 24 P 0 0;1=3
P 2.34606024 1.96615 24 P 0 0;1=3
P 2.34606024 1.91615 24 P 0 0;1=3
P 2.34606024 3.16615 24 P 0 0;1=3
P 2.34606024 3.11615 24 P 0 0;1=3
P 2.44606024 3.16615 24 P 0 0;1=3
P 2.44606024 3.11615 24 P 0 0;1=3
P 2.49606024 3.11615 24 P 0 0;1=3
P 2.49606024 3.06615 24 P 0 0;1=3
P 2.39606024 3.11615 24 P 0 0;1=3
P 2.39606024 3.06615 24 P 0 0;1=3
P 2.44606024 3.01615 24 P 0 0;1=3
P 2.44606024 2.96615 24 P 0 0;1=3
P 2.49606024 2.96615 24 P 0 0;1=3
P 2.49606024 2.91615 24 P 0 0;1=3
P 2.39606024 2.96615 24 P 0 0;1=3
P 2.39606024 2.91615 24 P 0 0;1=3
P 2.34606024 3.01615 24 P 0 0;1=3
P 2.34606024 2.96615 24 P 0 0;1=3
P 2.39606024 2.81615 24 P 0 0;1=3
P 2.39606024 2.76615 24 P 0 0;1=3
P 2.49606024 2.81615 24 P 0 0;1=3
P 2.49606024 2.76615 24 P 0 0;1=3
P 2.44606024 2.76615 24 P 0 0;1=3
P 2.44606024 2.71615 24 P 0 0;1=3
P 2.34606024 2.76615 24 P 0 0;1=3
P 2.34606024 2.71615 24 P 0 0;1=3
P 2.49606024 2.66615 24 P 0 0;1=3
P 2.49606024 2.61615 24 P 0 0;1=3
P 2.44606024 2.61615 24 P 0 0;1=3
P 2.44606024 2.56615 24 P 0 0;1=3
P 2.39606024 2.66615 24 P 0 0;1=3
P 2.39606024 2.61615 24 P 0 0;1=3
P 8.94061998 4.70574026 24 P 0 0;1=4
P 9.01925 4.70574026 24 P 0 0;1=4
P 9.07925 4.70574026 24 P 0 0;1=4
P 8.73579006 4.70573996 24 P 0 0;1=4
P 8.79579006 4.70573996 24 P 0 0;1=4
P 8.86665 4.74417972 24 P 0 0;1=4
P 8.80665 4.74417972 24 P 0 0;1=4
P 9.43358002 4.74417972 24 P 0 0;1=4
P 9.51531004 4.68098996 24 P 0 0;1=4
P 9.57531004 4.68098996 24 P 0 0;1=4
P 9.44445 4.62574026 24 P 0 0;1=4
P 9.50445 4.62574026 24 P 0 0;1=4
P 9.23185 4.68074026 24 P 0 0;1=4
P 9.29185 4.68074026 24 P 0 0;1=4
P 9.16098002 4.74417972 24 P 0 0;1=4
P 9.37358002 4.74417972 24 P 0 0;1=4
P 9.22098002 4.74417972 24 P 0 0;1=4
P 9.51531004 5.17873996 24 P 0 0;1=4
P 9.57531004 5.17873996 24 P 0 0;1=4
P 9.43358002 5.18127972 24 P 0 0;1=4
P 9.23185 5.18127972 24 P 0 0;1=4
P 9.29185 5.18127972 24 P 0 0;1=4
P 9.37358002 5.18127972 24 P 0 0;1=4
P 9.36271004 5.14223996 24 P 0 0;1=4
P 9.30271004 5.14223996 24 P 0 0;1=4
P 9.15011004 5.09223996 24 P 0 0;1=4
P 9.09011004 5.09223996 24 P 0 0;1=4
P 9.07925 5.20374026 24 P 0 0;1=4
P 9.01925 5.20374026 24 P 0 0;1=4
P 8.93440994 5.20876004 24 P 0 0;1=4
P 8.73579006 5.17873996 24 P 0 0;1=4
P 8.79579006 5.17873996 24 P 0 0;1=4
P 8.87440994 5.20876004 24 P 0 0;1=4
P 7.64205 4.74417972 24 P 0 0;1=4
P 7.70205 4.74417972 24 P 0 0;1=4
P 7.63118996 4.66826004 24 P 0 0;1=4
P 7.57118996 4.66826004 24 P 0 0;1=4
P 7.91465 4.61825974 24 P 0 0;1=4
P 7.78378996 4.74418002 24 P 0 0;1=4
P 7.84378996 4.74418002 24 P 0 0;1=4
P 7.85465 4.61825974 24 P 0 0;1=4
P 8.06725 4.74417972 24 P 0 0;1=4
P 8.12725 4.74417972 24 P 0 0;1=4
P 8.02207028 4.62815 24 P 0 0;1=4
P 8.08207028 4.62815 24 P 0 0;1=4
P 8.41070994 4.70326004 24 P 0 0;1=4
P 8.35070994 4.70326004 24 P 0 0;1=4
P 8.20898002 4.74417972 24 P 0 0;1=4
P 8.26898002 4.74417972 24 P 0 0;1=4
P 8.21208996 4.62826004 24 P 0 0;1=4
P 8.27208996 4.62826004 24 P 0 0;1=4
P 8.19811004 5.09223996 24 P 0 0;1=4
P 8.12725 5.13025974 24 P 0 0;1=4
P 8.06725 5.13025974 24 P 0 0;1=4
P 7.91465 5.13025974 24 P 0 0;1=4
P 7.92551004 5.09223996 24 P 0 0;1=4
P 7.98551004 5.09223996 24 P 0 0;1=4
P 7.85465 5.13025974 24 P 0 0;1=4
P 7.64204006 5.09223996 24 P 0 0;1=4
P 7.70204006 5.09223996 24 P 0 0;1=4
P 7.57118996 5.13026004 24 P 0 0;1=4
P 7.63118996 5.13026004 24 P 0 0;1=4
P 2.73225 4.70574026 24 P 0 0;1=4
P 2.79225 4.70574026 24 P 0 0;1=4
P 3.22830994 5.18128002 24 P 0 0;1=4
P 3.28830994 5.18128002 24 P 0 0;1=4
P 3.01571004 5.20373996 24 P 0 0;1=4
P 3.07571004 5.20373996 24 P 0 0;1=4
P 2.73225 5.17874026 24 P 0 0;1=4
P 2.79225 5.17874026 24 P 0 0;1=4
P 1.56765 4.66825974 24 P 0 0;1=4
P 1.62765 4.66825974 24 P 0 0;1=4
P 1.56765 5.13025974 24 P 0 0;1=4
P 1.62765 5.13025974 24 P 0 0;1=4
P 1.91110994 5.13026004 24 P 0 0;1=4
P 1.85110994 5.13026004 24 P 0 0;1=4
P 5.08267972 2.76615 24 P 0 0;1=3
P 5.03267972 2.76615 24 P 0 0;1=3
P 5.03267972 2.71615 24 P 0 0;1=3
P 4.93267972 2.76615 24 P 0 0;1=3
P 4.98267972 2.76615 24 P 0 0;1=3
P 4.93267972 2.71615 24 P 0 0;1=3
P 5.08267972 2.66615 24 P 0 0;1=3
P 4.98267972 2.66615 24 P 0 0;1=3
P 5.03267972 2.56615 24 P 0 0;1=3
P 4.93267972 2.56615 24 P 0 0;1=3
P 4.98267972 2.46615 24 P 0 0;1=3
P 4.98267972 2.51615 24 P 0 0;1=3
P 4.93267972 2.51615 24 P 0 0;1=3
P 5.08267972 2.51615 24 P 0 0;1=3
P 5.08267972 2.46615 24 P 0 0;1=3
P 5.03267972 2.21615 24 P 0 0;1=3
P 4.93267972 2.21615 24 P 0 0;1=3
P 4.98267972 2.31615 24 P 0 0;1=3
P 4.93267972 2.36615 24 P 0 0;1=3
P 5.08267972 2.31615 24 P 0 0;1=3
P 5.08267972 2.16615 24 P 0 0;1=3
P 4.93267972 2.16615 24 P 0 0;1=3
P 4.98267972 2.16615 24 P 0 0;1=3
P 4.93267972 1.96615 24 P 0 0;1=3
P 5.03267972 1.96615 24 P 0 0;1=3
P 5.03267972 2.11615 24 P 0 0;1=3
P 4.93267972 2.11615 24 P 0 0;1=3
P 4.98267972 2.01615 24 P 0 0;1=3
P 5.08267972 2.01615 24 P 0 0;1=3
P 4.98267972 1.86615 24 P 0 0;1=3
P 5.08267972 1.86615 24 P 0 0;1=3
P 4.78267972 3.81615 24 P 0 0;1=3
P 4.78267972 3.66615 24 P 0 0;1=3
P 4.73267972 3.81615 24 P 0 0;1=3
P 4.73267972 3.66615 24 P 0 0;1=3
P 4.68267972 3.81615 24 P 0 0;1=3
P 4.68267972 3.66615 24 P 0 0;1=3
P 4.78267972 3.51615 24 P 0 0;1=3
P 4.73267972 3.51615 24 P 0 0;1=3
P 4.68267972 3.51615 24 P 0 0;1=3
P 4.78267972 3.36615 24 P 0 0;1=3
P 4.73267972 3.36615 24 P 0 0;1=3
P 4.78267972 3.21615 24 P 0 0;1=3
P 4.73267972 3.21615 24 P 0 0;1=3
P 4.68267972 3.36615 24 P 0 0;1=3
P 4.68267972 3.21615 24 P 0 0;1=3
P 4.78267972 3.06615 24 P 0 0;1=3
P 4.73267972 3.06615 24 P 0 0;1=3
P 4.68267972 3.06615 24 P 0 0;1=3
P 4.78267972 2.91615 24 P 0 0;1=3
P 4.73267972 2.91615 24 P 0 0;1=3
P 4.68267972 2.91615 24 P 0 0;1=3
P 4.88267972 2.76615 24 P 0 0;1=3
P 4.88267972 2.66615 24 P 0 0;1=3
P 4.78267972 2.46615 24 P 0 0;1=3
P 4.88267972 2.56615 24 P 0 0;1=3
P 4.88267972 2.61615 24 P 0 0;1=3
P 4.68267972 2.46615 24 P 0 0;1=3
P 4.88267972 2.46615 24 P 0 0;1=3
P 4.88267972 2.51615 24 P 0 0;1=3
P 4.78267972 2.41615 24 P 0 0;1=3
P 4.88267972 2.41615 24 P 0 0;1=3
P 4.78267972 2.36615 24 P 0 0;1=3
P 4.78267972 2.31615 24 P 0 0;1=3
P 4.78267972 2.26615 24 P 0 0;1=3
P 4.78267972 2.21615 24 P 0 0;1=3
P 4.73267972 2.36615 24 P 0 0;1=3
P 4.68267972 2.31615 24 P 0 0;1=3
P 4.73267972 2.21615 24 P 0 0;1=3
P 4.88267972 2.21615 24 P 0 0;1=3
P 4.88267972 2.26615 24 P 0 0;1=3
P 4.88267972 2.31615 24 P 0 0;1=3
P 4.88267972 2.36615 24 P 0 0;1=3
P 4.73267972 2.16615 24 P 0 0;1=3
P 4.68267972 2.16615 24 P 0 0;1=3
P 4.78267972 1.96615 24 P 0 0;1=3
P 4.78267972 2.06615 24 P 0 0;1=3
P 4.78267972 2.01615 24 P 0 0;1=3
P 4.88267972 1.96615 24 P 0 0;1=3
P 4.88267972 2.06615 24 P 0 0;1=3
P 4.88267972 2.01615 24 P 0 0;1=3
P 4.78267972 2.11615 24 P 0 0;1=3
P 4.88267972 2.11615 24 P 0 0;1=3
P 4.73267972 2.11615 24 P 0 0;1=3
P 4.68267972 2.01615 24 P 0 0;1=3
P 4.73267972 1.96615 24 P 0 0;1=3
P 4.78267972 1.86615 24 P 0 0;1=3
P 4.88267972 1.86615 24 P 0 0;1=3
P 4.68267972 1.86615 24 P 0 0;1=3
P 4.63267972 3.81615 24 P 0 0;1=3
P 4.63267972 3.66615 24 P 0 0;1=3
P 4.58267972 3.81615 24 P 0 0;1=3
P 4.58267972 3.66615 24 P 0 0;1=3
P 4.63267972 3.51615 24 P 0 0;1=3
P 4.58267972 3.51615 24 P 0 0;1=3
P 4.63267972 3.36615 24 P 0 0;1=3
P 4.58267972 3.36615 24 P 0 0;1=3
P 4.63267972 3.21615 24 P 0 0;1=3
P 4.58267972 3.21615 24 P 0 0;1=3
P 4.63267972 3.06615 24 P 0 0;1=3
P 4.58267972 3.06615 24 P 0 0;1=3
P 4.63267972 2.91615 24 P 0 0;1=3
P 4.58267972 2.91615 24 P 0 0;1=3
P 4.58267972 2.46615 24 P 0 0;1=3
P 4.63267972 2.21615 24 P 0 0;1=3
P 4.58267972 2.31615 24 P 0 0;1=3
P 4.63267972 2.36615 24 P 0 0;1=3
P 4.58267972 2.01615 24 P 0 0;1=3
P 4.63267972 2.11615 24 P 0 0;1=3
P 4.63267972 1.96615 24 P 0 0;1=3
P 4.58267972 1.86615 24 P 0 0;1=3
P 2.04606024 3.41615 24 P 0 0;1=3
P 2.09606024 3.51615 24 P 0 0;1=3
P 3.37003996 5.18128002 24 P 0 0;1=4
P 3.43003996 5.18128002 24 P 0 0;1=4
P 3.29916998 5.14224026 24 P 0 0;1=4
P 3.35916998 5.14224026 24 P 0 0;1=4
P 2.93708002 4.70573996 24 P 0 0;1=4
P 3.07571004 4.70573996 24 P 0 0;1=4
P 3.01571004 4.70573996 24 P 0 0;1=4
P 2.87708002 4.70573996 24 P 0 0;1=4
P 2.93086998 5.20876024 24 P 0 0;1=4
P 2.87086998 5.20876024 24 P 0 0;1=4
P 2.80310994 4.74418002 24 P 0 0;1=4
P 2.86310994 4.74418002 24 P 0 0;1=4
P 3.08656998 5.09224026 24 P 0 0;1=4
P 3.14656998 5.09224026 24 P 0 0;1=4
P 2.26855 4.62825974 24 P 0 0;1=4
P 2.20855 4.62825974 24 P 0 0;1=4
P 2.26543996 4.74418002 24 P 0 0;1=4
P 2.20543996 4.74418002 24 P 0 0;1=4
P 2.34716998 4.70326004 24 P 0 0;1=4
P 2.07853002 4.62815 24 P 0 0;1=4
P 2.01853002 4.62815 24 P 0 0;1=4
P 2.12370994 4.74418002 24 P 0 0;1=4
P 2.06370994 4.74418002 24 P 0 0;1=4
P 2.19456998 5.09224026 24 P 0 0;1=4
P 2.13456998 5.09224026 24 P 0 0;1=4
P 2.12370994 5.13026004 24 P 0 0;1=4
P 2.06370994 5.13026004 24 P 0 0;1=4
P 1.6985 5.09224026 24 P 0 0;1=4
P 1.6385 5.09224026 24 P 0 0;1=4
P 1.85110994 4.61826004 24 P 0 0;1=4
P 1.63850994 4.74418002 24 P 0 0;1=4
P 1.69850994 4.74418002 24 P 0 0;1=4
P 1.98196998 5.09224026 24 P 0 0;1=4
P 1.92196998 5.09224026 24 P 0 0;1=4
P 1.84025 4.74417972 24 P 0 0;1=4
P 1.78025 4.74417972 24 P 0 0;1=4
P 11.03660974 2.71615 24 P 0 0;1=3
P 10.93660974 2.71615 24 P 0 0;1=3
P 11.03660974 2.76615 24 P 0 0;1=3
P 10.98660974 2.76615 24 P 0 0;1=3
P 10.93660974 2.76615 24 P 0 0;1=3
P 11.08660974 2.76615 24 P 0 0;1=3
P 11.03660974 2.56615 24 P 0 0;1=3
P 10.93660974 2.56615 24 P 0 0;1=3
P 10.98660974 2.66615 24 P 0 0;1=3
P 10.98660974 2.51615 24 P 0 0;1=3
P 10.93660974 2.51615 24 P 0 0;1=3
P 11.08660974 2.66615 24 P 0 0;1=3
P 11.08660974 2.51615 24 P 0 0;1=3
P 11.08660974 2.46615 24 P 0 0;1=3
P 10.98660974 2.46615 24 P 0 0;1=3
P 11.08660974 2.31615 24 P 0 0;1=3
P 10.93660974 2.36615 24 P 0 0;1=3
P 10.98660974 2.31615 24 P 0 0;1=3
P 10.93660974 2.21615 24 P 0 0;1=3
P 11.03660974 2.21615 24 P 0 0;1=3
P 11.03660974 2.11615 24 P 0 0;1=3
P 10.93660974 2.11615 24 P 0 0;1=3
P 10.98660974 2.01615 24 P 0 0;1=3
P 10.93660974 1.96615 24 P 0 0;1=3
P 11.03660974 1.96615 24 P 0 0;1=3
P 11.08660974 2.01615 24 P 0 0;1=3
P 10.98660974 2.16615 24 P 0 0;1=3
P 10.93660974 2.16615 24 P 0 0;1=3
P 11.08660974 2.16615 24 P 0 0;1=3
P 10.98660974 1.86615 24 P 0 0;1=3
P 11.08660974 1.86615 24 P 0 0;1=3
P 10.73660974 2.71615 24 P 0 0;1=3
P 10.73660974 2.76615 24 P 0 0;1=3
P 10.88660974 2.76615 24 P 0 0;1=3
P 10.78660974 2.76615 24 P 0 0;1=3
P 10.73660974 2.56615 24 P 0 0;1=3
P 10.68660974 2.66615 24 P 0 0;1=3
P 10.73660974 2.51615 24 P 0 0;1=3
P 10.68660974 2.51615 24 P 0 0;1=3
P 10.88660974 2.61615 24 P 0 0;1=3
P 10.88660974 2.56615 24 P 0 0;1=3
P 10.88660974 2.51615 24 P 0 0;1=3
P 10.78660974 2.56615 24 P 0 0;1=3
P 10.78660974 2.61615 24 P 0 0;1=3
P 10.78660974 2.66615 24 P 0 0;1=3
P 10.78660974 2.51615 24 P 0 0;1=3
P 10.78660974 2.46615 24 P 0 0;1=3
P 10.68660974 2.46615 24 P 0 0;1=3
P 10.88660974 2.46615 24 P 0 0;1=3
P 10.78660974 2.21615 24 P 0 0;1=3
P 10.78660974 2.26615 24 P 0 0;1=3
P 10.78660974 2.31615 24 P 0 0;1=3
P 10.78660974 2.36615 24 P 0 0;1=3
P 10.68660974 2.31615 24 P 0 0;1=3
P 10.73660974 2.36615 24 P 0 0;1=3
P 10.73660974 2.21615 24 P 0 0;1=3
P 10.78660974 2.41615 24 P 0 0;1=3
P 10.88660974 2.36615 24 P 0 0;1=3
P 10.88660974 2.31615 24 P 0 0;1=3
P 10.88660974 2.26615 24 P 0 0;1=3
P 10.88660974 2.21615 24 P 0 0;1=3
P 10.73660974 1.96615 24 P 0 0;1=3
P 10.68660974 2.01615 24 P 0 0;1=3
P 10.73660974 2.11615 24 P 0 0;1=3
P 10.78660974 2.11615 24 P 0 0;1=3
P 10.78660974 2.01615 24 P 0 0;1=3
P 10.78660974 1.96615 24 P 0 0;1=3
P 10.78660974 2.06615 24 P 0 0;1=3
P 10.68660974 2.16615 24 P 0 0;1=3
P 10.73660974 2.16615 24 P 0 0;1=3
P 10.88660974 2.01615 24 P 0 0;1=3
P 10.88660974 2.06615 24 P 0 0;1=3
P 10.88660974 2.11615 24 P 0 0;1=3
P 10.88660974 1.96615 24 P 0 0;1=3
P 10.78660974 1.91615 24 P 0 0;1=3
P 10.68660974 1.86615 24 P 0 0;1=3
P 10.78660974 1.86615 24 P 0 0;1=3
P 10.88660974 1.86615 24 P 0 0;1=3
P 10.63660974 2.71615 24 P 0 0;1=3
P 10.63660974 2.76615 24 P 0 0;1=3
P 10.63660974 2.56615 24 P 0 0;1=3
P 10.58660974 2.66615 24 P 0 0;1=3
P 10.63660974 2.51615 24 P 0 0;1=3
P 10.58660974 2.51615 24 P 0 0;1=3
P 10.58660974 2.46615 24 P 0 0;1=3
P 10.63660974 2.36615 24 P 0 0;1=3
P 10.58660974 2.31615 24 P 0 0;1=3
P 10.58660974 2.01615 24 P 0 0;1=3
P 10.63660974 1.96615 24 P 0 0;1=3
P 10.63660974 2.11615 24 P 0 0;1=3
P 10.58660974 1.86615 24 P 0 0;1=3
P 1.92345974 5.377 24 P 0 0;1=4
P 2.14345974 5.377 24 P 0 0;1=4
P 7.927 5.377 24 P 0 0;1=4
P 8.147 5.377 24 P 0 0;1=4
P 3.43003996 4.74418002 24 P 0 0;1=4
P 3.51177008 4.68098996 24 P 0 0;1=4
P 3.57177008 4.68098996 24 P 0 0;1=4
P 3.21743996 4.74418002 24 P 0 0;1=4
P 3.37003996 4.74418002 24 P 0 0;1=4
P 3.41 5.332 24 P 0 0;1=4
P 5.38047972 1.5957 24 P 0 0;1=4
P 5.38047972 1.7891 24 P 0 0;1=4
P 5.38047972 1.732 24 P 0 0;1=4
P 5.38047972 1.6528 24 P 0 0;1=4
P 5.53530974 1.8603 24 P 0 0;1=4
P 5.53530974 1.8032 24 P 0 0;1=4
P 5.53530974 2.2727 24 P 0 0;1=4
P 5.53530974 2.1373 24 P 0 0;1=4
P 5.53530974 1.9964 24 P 0 0;1=4
P 5.38047972 2.3403 24 P 0 0;1=4
P 5.38047972 2.2832 24 P 0 0;1=4
P 5.38047972 2.2049 24 P 0 0;1=4
P 5.38047972 2.1478 24 P 0 0;1=4
P 5.38047972 2.0642 24 P 0 0;1=4
P 5.38047972 2.0071 24 P 0 0;1=4
P 5.38047972 1.9288 24 P 0 0;1=4
P 5.38047972 1.8717 24 P 0 0;1=4
P 5.53530974 2.351 24 P 0 0;1=4
P 5.38047972 2.4757 24 P 0 0;1=4
P 5.38047972 2.4186 24 P 0 0;1=4
P 5.53530974 2.4902 24 P 0 0;1=4
P 5.53530974 2.6825 24 P 0 0;1=4
P 5.53530974 2.6254 24 P 0 0;1=4
P 5.38047972 2.5578 24 P 0 0;1=4
P 5.38047972 2.6149 24 P 0 0;1=4
P 10.43 1.3341 24 P 0 0;1=4
P 10.43 1.277 24 P 0 0;1=4
P 10.4159 1.43 24 P 0 0;1=4
P 10.473 1.43 24 P 0 0;1=4
P 10.37313996 1.55333474 24 P 0 0;1=4
P 10.41451004 1.51195472 24 P 0 0;1=4
P 10.295 1.713 24 P 0 0;1=4
P 10.295 1.6559 24 P 0 0;1=4
P 10.26 1.9179 24 P 0 0;1=4
P 10.29525 1.877 24 P 0 0;1=4
P 10.29525 1.8199 24 P 0 0;1=4
P 10.26 1.975 24 P 0 0;1=4
P 10.125 2.0651 24 P 0 0;1=4
P 10.125 2.1224 24 P 0 0;1=4
P 10.125 2.1795 24 P 0 0;1=4
P 10.01 2.2481 24 P 0 0;1=4
P 10.01 2.191 24 P 0 0;1=4
P 10.01 2.38435 24 P 0 0;1=4
P 10.01 2.32725 24 P 0 0;1=4
P 10.125 2.3168 24 P 0 0;1=4
P 10.125 2.2597 24 P 0 0;1=4
P 10.125 2.4519 24 P 0 0;1=4
P 10.125 2.3948 24 P 0 0;1=4
P 10.01 2.51945 24 P 0 0;1=4
P 10.01 2.46235 24 P 0 0;1=4
P 10.125 2.587 24 P 0 0;1=4
P 10.125 2.5299 24 P 0 0;1=4
P 10.01 2.673 24 P 0 0;1=4
P 10.01 2.6159 24 P 0 0;1=4
P 11.74315974 1.7035 24 P 0 0;1=4
P 11.74315974 1.6405 24 P 0 0;1=4
P 11.69315974 1.4805 24 P 0 0;1=4
P 11.69315974 1.5435 24 P 0 0;1=4
P 11.49315974 1.5605 24 P 0 0;1=4
P 11.49315974 1.6235 24 P 0 0;1=4
P 11.49315974 1.4635 24 P 0 0;1=4
P 11.49365974 1.401 24 P 0 0;1=4
P 11.69315974 2.6005 24 P 0 0;1=4
P 11.69315974 2.5035 24 P 0 0;1=4
P 11.69315974 2.4405 24 P 0 0;1=4
P 11.69315974 2.3435 24 P 0 0;1=4
P 11.69315974 2.2805 24 P 0 0;1=4
P 11.69315974 2.1835 24 P 0 0;1=4
P 11.69315974 1.9605 24 P 0 0;1=4
P 11.69315974 2.0235 24 P 0 0;1=4
P 11.69315974 2.1205 24 P 0 0;1=4
P 11.69315974 1.8005 24 P 0 0;1=4
P 11.69315974 1.8635 24 P 0 0;1=4
P 11.49315974 2.5205 24 P 0 0;1=4
P 11.49315974 2.5835 24 P 0 0;1=4
P 11.49315974 2.4235 24 P 0 0;1=4
P 11.49315974 2.3605 24 P 0 0;1=4
P 11.79315974 2.2635 24 P 0 0;1=4
P 11.79315974 2.2005 24 P 0 0;1=4
P 11.49315974 1.9435 24 P 0 0;1=4
P 11.49315974 2.1035 24 P 0 0;1=4
P 11.49315974 2.0405 24 P 0 0;1=4
P 11.49315974 1.8805 24 P 0 0;1=4
P 11.49365974 1.721 24 P 0 0;1=4
P 11.49315974 1.7835 24 P 0 0;1=4
P 10.125 2.7451 24 P 0 0;1=4
P 10.125 2.688 24 P 0 0;1=4
P 12.34 2.19 24 P 0 0;1=4
P 9.415 5.332 24 P 0 0;1=4
P 9.265 5.332 24 P 0 0;1=4
P 9.07 5.332 24 P 0 0;1=4
P 4.7 5.54929026 24 P 0 0;1=4
P 4.81 5.375 24 P 0 0;1=4
P 4.96 5.375 24 P 0 0;1=4
P 5.16 5.645 24 P 0 0;1=4
P 5.04440974 5.605 24 P 0 0;1=4
P 4.92 5.7 24 P 0 0;1=4
P 9.91 4.7 24 P 0 0;1=4
P 3.57 4.45 24 P 0 0;1=4
P 10.465 5.195 24 P 0 0;1=4
P 10.515 5.32 24 P 0 0;1=4
P 10.465 5.275 24 P 0 0;1=4
P 12.025 4.915 24 P 0 0;1=4
P 12.12 4.965 24 P 0 0;1=4
P 12.185 4.915 24 P 0 0;1=4
P 3.72 4.45 24 P 0 0;1=4
P 3.66 4.63 24 P 0 0;1=4
P 3.77 4.86 24 P 0 0;1=4
P 9.96 4.69 24 P 0 0;1=4
P 10.03 4.51 24 P 0 0;1=4
P 3.835 4.6 24 P 0 0;1=4
P 3.9865 4.635 24 P 0 0;1=4
P 4.14 4.655 24 P 0 0;1=4
P 4.1049 4.7649 24 P 0 0;1=4
P 1.28050974 5.78 24 P 0 0;1=4
P 3.87 5.125 24 P 0 0;1=4
P 0.4826 5.8976 24 P 0 0;1=4
P 0.84952972 5.17 24 P 0 0;1=4
P 0.955 5.325 24 P 0 0;1=4
P 1.31 5.355 24 P 0 0;1=4
P 1.20176998 5.78 24 P 0 0;1=4
P 6.31295 4.99705 24 P 0 0;1=4
P 6.87 5 24 P 0 0;1=4
P 9.64795974 0.79643002 24 P 0 0;1=4
P 9.40795 0.26133002 24 P 0 0;1=4
P 3.60998976 0.24 24 P 0 0;1=4
P 3.65998976 0.345 24 P 0 0;1=4
P 3.86 0.7751 24 P 0 0;1=0
P 6.905 4.94705 24 P 0 0;1=4
P 6.905 4.88705 24 P 0 0;1=4
P 6.955 4.8 24 P 0 0;1=4
P 6.955 4.84 24 P 0 0;1=4
P 6.955 4.72 24 P 0 0;1=4
P 6.955 4.76 24 P 0 0;1=4
P 6.59708976 5.0502 24 P 0 0;1=4
P 6.65218976 4.77 24 P 0 0;1=4
P 6.62119006 4.95641998 24 P 0 0;1=8
P 6.6015 4.93674026 24 P 0 0;1=8
P 6.64088002 4.93673996 24 P 0 0;1=8
P 6.62118976 4.91705 24 P 0 0;1=8
P 6.62118976 4.87768002 24 P 0 0;1=8
P 6.6015 4.89736024 24 P 0 0;1=8
P 6.64087992 4.89736004 24 P 0 0;1=8
P 6.62 4.69 24 P 0 0;1=4
P 6.62 4.725 24 P 0 0;1=4
P 6.385 5.07 24 P 0 0;1=4
P 5.53594026 4.55505 24 P 0 0;1=4
P 6.05708976 4.5102 24 P 0 0;1=4
P 6.01708976 4.5102 24 P 0 0;1=4
P 5.97708976 4.5102 24 P 0 0;1=4
P 5.93708976 4.5102 24 P 0 0;1=4
P 5.89708976 4.5102 24 P 0 0;1=4
P 6.09708976 4.5102 24 P 0 0;1=4
P 5.61708976 4.5102 24 P 0 0;1=4
P 5.65708976 4.5102 24 P 0 0;1=4
P 5.85708976 4.5102 24 P 0 0;1=4
P 5.81708976 4.5102 24 P 0 0;1=4
P 5.77708976 4.5102 24 P 0 0;1=4
P 5.73708976 4.5102 24 P 0 0;1=4
P 5.69708976 4.5102 24 P 0 0;1=4
P 5.57708976 4.5102 24 P 0 0;1=4
P 0.036 0.10868002 24 P 0 0;1=4
P 0.036 0.15868002 24 P 0 0;1=4
P 0.036 0.20868002 24 P 0 0;1=4
P 0.22873976 0.036 24 P 0 0;1=4
P 0.17873976 0.036 24 P 0 0;1=4
P 0.12873976 0.036 24 P 0 0;1=4
P 0.07873976 0.036 24 P 0 0;1=4
P 0.47873976 0.036 24 P 0 0;1=4
P 0.42873976 0.036 24 P 0 0;1=4
P 0.37873976 0.036 24 P 0 0;1=4
P 0.32873976 0.036 24 P 0 0;1=4
P 0.27873976 0.036 24 P 0 0;1=4
P 0.77873976 0.036 24 P 0 0;1=4
P 0.72873976 0.036 24 P 0 0;1=4
P 0.67873976 0.036 24 P 0 0;1=4
P 0.62873976 0.036 24 P 0 0;1=4
P 0.57873976 0.036 24 P 0 0;1=4
P 0.52873976 0.036 24 P 0 0;1=4
P 1.02873976 0.036 24 P 0 0;1=4
P 0.97873976 0.036 24 P 0 0;1=4
P 0.92873976 0.036 24 P 0 0;1=4
P 0.87873976 0.036 24 P 0 0;1=4
P 0.82873976 0.036 24 P 0 0;1=4
P 1.27873976 0.036 24 P 0 0;1=4
P 1.22873976 0.036 24 P 0 0;1=4
P 1.17873976 0.036 24 P 0 0;1=4
P 1.12873976 0.036 24 P 0 0;1=4
P 1.07873976 0.036 24 P 0 0;1=4
P 1.52873976 0.036 24 P 0 0;1=4
P 1.47873976 0.036 24 P 0 0;1=4
P 1.42873976 0.036 24 P 0 0;1=4
P 1.37873976 0.036 24 P 0 0;1=4
P 1.32873976 0.036 24 P 0 0;1=4
P 1.82873976 0.036 24 P 0 0;1=4
P 1.77873976 0.036 24 P 0 0;1=4
P 1.72873976 0.036 24 P 0 0;1=4
P 1.67873976 0.036 24 P 0 0;1=4
P 1.62873976 0.036 24 P 0 0;1=4
P 1.57873976 0.036 24 P 0 0;1=4
P 2.07873976 0.036 24 P 0 0;1=4
P 2.02873976 0.036 24 P 0 0;1=4
P 1.97873976 0.036 24 P 0 0;1=4
P 1.92873976 0.036 24 P 0 0;1=4
P 1.87873976 0.036 24 P 0 0;1=4
P 2.32873976 0.036 24 P 0 0;1=4
P 2.27873976 0.036 24 P 0 0;1=4
P 2.22873976 0.036 24 P 0 0;1=4
P 2.17873976 0.036 24 P 0 0;1=4
P 2.12873976 0.036 24 P 0 0;1=4
P 2.62873976 0.036 24 P 0 0;1=4
P 2.57873976 0.036 24 P 0 0;1=4
P 2.52873976 0.036 24 P 0 0;1=4
P 2.47873976 0.036 24 P 0 0;1=4
P 2.42873976 0.036 24 P 0 0;1=4
P 2.37873976 0.036 24 P 0 0;1=4
P 2.87873976 0.036 24 P 0 0;1=4
P 2.82873976 0.036 24 P 0 0;1=4
P 2.77873976 0.036 24 P 0 0;1=4
P 2.72873976 0.036 24 P 0 0;1=4
P 2.67873976 0.036 24 P 0 0;1=4
P 3.12873976 0.036 24 P 0 0;1=4
P 3.07873976 0.036 24 P 0 0;1=4
P 3.02873976 0.036 24 P 0 0;1=4
P 2.97873976 0.036 24 P 0 0;1=4
P 2.92873976 0.036 24 P 0 0;1=4
P 3.37873976 0.036 24 P 0 0;1=4
P 3.32873976 0.036 24 P 0 0;1=4
P 3.27873976 0.036 24 P 0 0;1=4
P 3.22873976 0.036 24 P 0 0;1=4
P 3.17873976 0.036 24 P 0 0;1=4
P 3.67873976 0.036 24 P 0 0;1=4
P 3.62873976 0.036 24 P 0 0;1=4
P 3.57873976 0.036 24 P 0 0;1=4
P 3.52873976 0.036 24 P 0 0;1=4
P 3.47873976 0.036 24 P 0 0;1=4
P 3.42873976 0.036 24 P 0 0;1=4
P 3.92873976 0.036 24 P 0 0;1=4
P 3.87873976 0.036 24 P 0 0;1=4
P 3.82873976 0.036 24 P 0 0;1=4
P 3.77873976 0.036 24 P 0 0;1=4
P 3.72873976 0.036 24 P 0 0;1=4
P 4.17873976 0.036 24 P 0 0;1=4
P 4.12873976 0.036 24 P 0 0;1=4
P 4.07873976 0.036 24 P 0 0;1=4
P 4.02873976 0.036 24 P 0 0;1=4
P 3.97873976 0.036 24 P 0 0;1=4
P 4.42873976 0.036 24 P 0 0;1=4
P 4.37873976 0.036 24 P 0 0;1=4
P 4.32873976 0.036 24 P 0 0;1=4
P 4.27873976 0.036 24 P 0 0;1=4
P 4.22873976 0.036 24 P 0 0;1=4
P 4.72873976 0.036 24 P 0 0;1=4
P 4.67873976 0.036 24 P 0 0;1=4
P 4.62873976 0.036 24 P 0 0;1=4
P 4.57873976 0.036 24 P 0 0;1=4
P 4.52873976 0.036 24 P 0 0;1=4
P 4.47873976 0.036 24 P 0 0;1=4
P 4.81833976 0.21825 24 P 0 0;1=4
P 4.81833976 0.16825 24 P 0 0;1=4
P 4.81833976 0.11825 24 P 0 0;1=4
P 4.81703888 0.06825906 24 P 0 0;1=4
P 4.77873809 0.03612175 24 P 0 0;1=4
P 6.80730974 0.036 24 P 0 0;1=4
P 6.75730974 0.036 24 P 0 0;1=4
P 6.70730974 0.036 24 P 0 0;1=4
P 6.65730955 0.03676043 24 P 0 0;1=4
P 6.62298947 0.07311939 24 P 0 0;1=4
P 6.62261998 0.12311998 24 P 0 0;1=4
P 6.62261998 0.17311998 24 P 0 0;1=4
P 6.62261998 0.22311998 24 P 0 0;1=4
P 7.00730974 0.036 24 P 0 0;1=4
P 6.95730974 0.036 24 P 0 0;1=4
P 6.90730974 0.036 24 P 0 0;1=4
P 6.85730974 0.036 24 P 0 0;1=4
P 0.036 0.25868002 24 P 0 0;1=4
P 0.036 0.30868002 24 P 0 0;1=4
P 0.036 0.35868002 24 P 0 0;1=4
P 0.036 0.40868002 24 P 0 0;1=4
P 0.036 0.45868002 24 P 0 0;1=4
P 4.96804006 0.46906998 24 P 0 0;1=4
P 4.91804941 0.46808051 24 P 0 0;1=4
P 4.87108927 0.45089055 24 P 0 0;1=4
P 4.83591132 0.41536132 24 P 0 0;1=4
P 4.81919035 0.36823996 24 P 0 0;1=4
P 4.81833976 0.31825 24 P 0 0;1=4
P 4.81833976 0.26825 24 P 0 0;1=4
P 5.21804006 0.46906998 24 P 0 0;1=4
P 5.16804006 0.46906998 24 P 0 0;1=4
P 5.11804006 0.46906998 24 P 0 0;1=4
P 5.06804006 0.46906998 24 P 0 0;1=4
P 5.01804006 0.46906998 24 P 0 0;1=4
P 5.51804006 0.46906998 24 P 0 0;1=4
P 5.46804006 0.46906998 24 P 0 0;1=4
P 5.41804006 0.46906998 24 P 0 0;1=4
P 5.36804006 0.46906998 24 P 0 0;1=4
P 5.31804006 0.46906998 24 P 0 0;1=4
P 5.26804006 0.46906998 24 P 0 0;1=4
P 5.76804006 0.46906998 24 P 0 0;1=4
P 5.71804006 0.46906998 24 P 0 0;1=4
P 5.66804006 0.46906998 24 P 0 0;1=4
P 5.61804006 0.46906998 24 P 0 0;1=4
P 5.56804006 0.46906998 24 P 0 0;1=4
P 6.01804006 0.46906998 24 P 0 0;1=4
P 5.96804006 0.46906998 24 P 0 0;1=4
P 5.91804006 0.46906998 24 P 0 0;1=4
P 5.86804006 0.46906998 24 P 0 0;1=4
P 5.81804006 0.46906998 24 P 0 0;1=4
P 6.31804006 0.46906998 24 P 0 0;1=4
P 6.26804006 0.46906998 24 P 0 0;1=4
P 6.21804006 0.46906998 24 P 0 0;1=4
P 6.16804006 0.46906998 24 P 0 0;1=4
P 6.11804006 0.46906998 24 P 0 0;1=4
P 6.06804006 0.46906998 24 P 0 0;1=4
P 6.56567894 0.45345098 24 P 0 0;1=4
P 6.5180314 0.46861841 24 P 0 0;1=4
P 6.46804006 0.46906998 24 P 0 0;1=4
P 6.41804006 0.46906998 24 P 0 0;1=4
P 6.36804006 0.46906998 24 P 0 0;1=4
P 6.62261998 0.27311998 24 P 0 0;1=4
P 6.62261998 0.32311998 24 P 0 0;1=4
P 6.62106949 0.37309951 24 P 0 0;1=4
P 6.60234085 0.41946063 24 P 0 0;1=4
P 0.036 0.50868002 24 P 0 0;1=4
P 0.036 0.55868002 24 P 0 0;1=4
P 11.845 2.85 24 P 0 0;1=4
P 8.98115 2.7861 24 P 0 0;1=4
P 8.98115 2.8989 24 P 0 0;1=4
P 11.58612972 2.855 24 P 0 0;1=4
P 11.50361998 2.8 24 P 0 0;1=4
P 11.50361998 2.73 24 P 0 0;1=4
P 5.5722 3 24 P 0 0;1=4
P 5.75779006 3.02558996 24 P 0 0;1=4
P 5.9192 2.943 24 P 0 0;1=4
P 4.07385974 2.55 24 P 0 0;1=4
P 3.86826998 2.64559026 24 P 0 0;1=4
P 9.995 2.87559026 24 P 0 0;1=4
P 10.11778976 2.78 24 P 0 0;1=4
P 7.2426 4.60351024 24 P 0 0;1=4
P 7.3401 4.85601024 24 P 0 0;1=4
P 7.1926 5.04351024 24 P 0 0;1=4
P 0.66 2.045 24 P 0 0;1=0
P 1.792 2.4781 24 P 0 0;1=4
P 2.97720974 2.8989 24 P 0 0;1=4
P 2.97720974 2.7861 24 P 0 0;1=4
P 2.9422 2.925 24 P 0 0;1=4
P 8.94278976 2.925 24 P 0 0;1=4
P 5.5822 2.855 24 P 0 0;1=4
P 5.84969026 2.85 24 P 0 0;1=4
P 0.65348996 1.85608996 24 P 0 0;1=4
P 0.65348996 1.91628996 24 P 0 0;1=4
P 0.09448996 4.60236998 26 P 0 3;1=1
P 0.35038996 4.20865994 26 P 0 3;1=1
P 0.09448996 4.2874 26 P 0 3;1=1
P 0.09448996 4.12991998 26 P 0 3;1=1
P 0.17322992 4.16928996 26 P 0 3;1=1
P 0.27165 4.09055 26 P 0 3;1=1
P 0.27165 3.93306998 26 P 0 3;1=1
P 0.35038996 4.05117992 26 P 0 3;1=1
P 0.35038996 3.8937 26 P 0 3;1=1
P 0.09448996 3.97243996 26 P 0 3;1=1
P 0.09448996 3.81495994 26 P 0 3;1=1
P 0.17322992 4.01180994 26 P 0 3;1=1
P 0.17322992 3.85432992 26 P 0 3;1=1
P 0.27165 3.77558996 26 P 0 3;1=1
P 0.27165 3.61810994 26 P 0 3;1=1
P 0.35038996 3.73621998 26 P 0 3;1=1
P 0.35038996 3.57873996 26 P 0 3;1=1
P 0.09448996 3.65747992 26 P 0 3;1=1
P 0.09448996 3.5 26 P 0 3;1=1
P 0.17322992 3.69685 26 P 0 3;1=1
P 0.17322992 3.53936998 26 P 0 3;1=1
P 0.27165 3.46062992 26 P 0 3;1=1
P 0.35038996 3.42125994 26 P 0 3;1=1
P 0.27165 3.30315 26 P 0 3;1=1
P 0.27165 3.22440994 26 P 0 3;1=1
P 0.17322992 3.38188996 26 P 0 3;1=1
P 0.17322992 3.30315 26 P 0 3;1=1
P 0.35038996 3.1063 26 P 0 3;1=1
P 0.35038996 2.94881998 26 P 0 3;1=1
P 0.27165 3.06692992 26 P 0 3;1=1
P 0.27165 2.90945 26 P 0 3;1=1
P 0.17322992 3.14566998 26 P 0 3;1=1
P 0.17322992 2.98818996 26 P 0 3;1=1
P 0.09448996 3.18503996 26 P 0 3;1=1
P 0.09448996 3.02755994 26 P 0 3;1=1
P 0.35038996 2.79133996 26 P 0 3;1=1
P 0.27165 2.75196998 26 P 0 3;1=1
P 0.35038996 2.63385994 26 P 0 3;1=1
P 0.17322992 2.83070994 26 P 0 3;1=1
P 0.09448996 2.87007992 26 P 0 3;1=1
P 0.09448996 2.7126 26 P 0 3;1=1
P 0.35038996 2.39763996 26 P 0 3;1=1
P 0.27165 2.51575 26 P 0 3;1=1
P 0.27165 2.35826998 26 P 0 3;1=1
P 0.17322992 2.59448996 26 P 0 3;1=1
P 0.17322992 2.43700994 26 P 0 3;1=1
P 0.09448996 2.47637992 26 P 0 3;1=1
P 0.09448996 2.3189 26 P 0 3;1=1
P 0.35038996 2.24015994 26 P 0 3;1=1
P 0.35038996 2.08267992 26 P 0 3;1=1
P 0.35038996 2.00393996 26 P 0 3;1=1
P 0.27165 2.20078996 26 P 0 3;1=1
P 0.17322992 2.27952992 26 P 0 3;1=1
P 0.09448996 2.16141998 26 P 0 3;1=1
P 0.09448996 2.08267992 26 P 0 3;1=1
P 0.17322992 1.96456998 26 P 0 3;1=1
P 0.09448996 1.84645994 26 P 0 3;1=1
P 0.09448996 4.44487992 26 P 0 3;1=1
P 12.63778996 2.00393996 26 P 0 3;1=1
P 12.55905 2.12205 26 P 0 3;1=1
P 12.55905 1.88582992 26 P 0 3;1=1
P 12.81495 2.12205 26 P 0 3;1=1
P 12.81495 2.04330994 26 P 0 3;1=1
P 12.73620994 2.39763996 26 P 0 3;1=1
P 12.73620994 2.24015994 26 P 0 3;1=1
P 12.63778996 2.3189 26 P 0 3;1=1
P 12.55905 2.35826998 26 P 0 3;1=1
P 12.55905 2.20078996 26 P 0 3;1=1
P 12.81495 2.43700994 26 P 0 3;1=1
P 12.81495 2.27952992 26 P 0 3;1=1
P 12.73620994 2.55511998 26 P 0 3;1=1
P 12.63778996 2.63385994 26 P 0 3;1=1
P 12.63778996 2.47637992 26 P 0 3;1=1
P 12.55905 2.51575 26 P 0 3;1=1
P 12.81495 2.67322992 26 P 0 3;1=1
P 12.73620994 2.94881998 26 P 0 3;1=1
P 12.73620994 2.79133996 26 P 0 3;1=1
P 12.63778996 3.02755994 26 P 0 3;1=1
P 12.63778996 2.87007992 26 P 0 3;1=1
P 12.55905 2.90945 26 P 0 3;1=1
P 12.55905 2.75196998 26 P 0 3;1=1
P 12.81495 2.98818996 26 P 0 3;1=1
P 12.81495 2.83070994 26 P 0 3;1=1
P 12.73620994 3.26377992 26 P 0 3;1=1
P 12.73620994 3.1063 26 P 0 3;1=1
P 12.63778996 3.18503996 26 P 0 3;1=1
P 12.55905 3.22440994 26 P 0 3;1=1
P 12.55905 3.06692992 26 P 0 3;1=1
P 12.81495 3.14566998 26 P 0 3;1=1
P 12.55905 3.53936998 26 P 0 3;1=1
P 12.63778996 3.57873996 26 P 0 3;1=1
P 12.63778996 3.42125994 26 P 0 3;1=1
P 12.73620994 3.5 26 P 0 3;1=1
P 12.73620994 3.34251998 26 P 0 3;1=1
P 12.63778996 3.34251998 26 P 0 3;1=1
P 12.81495 3.61810994 26 P 0 3;1=1
P 12.81495 3.46062992 26 P 0 3;1=1
P 12.55905 3.85432992 26 P 0 3;1=1
P 12.55905 3.69685 26 P 0 3;1=1
P 12.63778996 3.8937 26 P 0 3;1=1
P 12.63778996 3.73621998 26 P 0 3;1=1
P 12.73620994 3.81495994 26 P 0 3;1=1
P 12.73620994 3.65747992 26 P 0 3;1=1
P 12.81495 3.93306998 26 P 0 3;1=1
P 12.81495 3.77558996 26 P 0 3;1=1
P 12.55905 4.16928996 26 P 0 3;1=1
P 12.55905 4.01180994 26 P 0 3;1=1
P 12.63778996 4.20865994 26 P 0 3;1=1
P 12.63778996 4.05117992 26 P 0 3;1=1
P 12.73620994 4.12991998 26 P 0 3;1=1
P 12.73620994 3.97243996 26 P 0 3;1=1
P 12.81495 4.09055 26 P 0 3;1=1
P 12.55905 4.48425 26 P 0 3;1=1
P 12.55905 4.32676998 26 P 0 3;1=1
P 12.63778996 4.52361998 26 P 0 3;1=1
P 12.63778996 4.36613996 26 P 0 3;1=1
P 12.73620994 4.44487992 26 P 0 3;1=1
P 12.73620994 4.2874 26 P 0 3;1=1
P 12.81495 4.40550994 26 P 0 3;1=1
P 12.81495 4.24802992 26 P 0 3;1=1
P 12.55905 4.64173996 26 P 0 3;1=1
P 12.81495 4.56298996 26 P 0 3;1=1
P 0.27165 4.40550994 26 P 0 3;1=1
P 0.35038996 4.52361998 26 P 0 3;1=1
P 0.17322992 4.48425 26 P 0 3;1=1
P 0.27165 4.24802992 26 P 0 3;1=1
P 0.35038996 4.36613996 26 P 0 3;1=1
P 0.17322992 4.32676998 26 P 0 3;1=1
P 5.49220974 2.73 24 P 0 0;1=4
P 5.44885974 2.9414 24 P 0 0;1=4
P 5.44885974 3.0214 24 P 0 0;1=4
P 5.44885974 3.0564 24 P 0 0;1=4
P 5.44885974 3.1014 24 P 0 0;1=4
P 5.44885974 3.1364 24 P 0 0;1=4
P 5.44885974 3.2164 24 P 0 0;1=4
P 5.44885974 3.1814 24 P 0 0;1=4
P 5.44885974 2.9764 24 P 0 0;1=4
P 5.44885974 3.2614 24 P 0 0;1=4
P 5.44885974 3.2964 24 P 0 0;1=4
P 10.33998976 4.9231 24 P 0 0;1=4
P 10.38498976 4.9231 24 P 0 0;1=0
P 10.77498976 4.9231 24 P 0 0;1=4
P 10.72998976 4.9231 24 P 0 0;1=4
P 10.30498976 4.9431 24 P 0 0;1=4
P 10.26498976 4.9431 24 P 0 0;1=4
P 10.30498976 5.0281 24 P 0 0;1=4
P 10.30498976 5.0731 24 P 0 0;1=4
P 10.30498976 4.9831 24 P 0 0;1=4
P 10.26498976 5.0281 24 P 0 0;1=4
P 10.26498976 5.0731 24 P 0 0;1=4
P 10.26498976 4.9831 24 P 0 0;1=4
P 10.26498976 5.1181 24 P 0 0;1=4
P 10.30498976 5.1181 24 P 0 0;1=4
P 10.34498976 5.1181 24 P 0 0;1=4
P 10.42498976 4.9431 24 P 0 0;1=4
P 10.46498976 4.9431 24 P 0 0;1=4
P 10.38498976 5.1181 24 P 0 0;1=4
P 10.46498976 5.1181 24 P 0 0;1=4
P 10.42498976 5.1181 24 P 0 0;1=4
P 10.42498976 4.9831 24 P 0 0;1=4
P 10.42498976 5.0731 24 P 0 0;1=4
P 10.42498976 5.0281 24 P 0 0;1=4
P 10.46498976 4.9831 24 P 0 0;1=4
P 10.46498976 5.0731 24 P 0 0;1=4
P 10.46498976 5.0281 24 P 0 0;1=4
P 10.85498976 4.9431 24 P 0 0;1=4
P 10.81498976 4.9431 24 P 0 0;1=4
P 10.65498976 4.9431 24 P 0 0;1=4
P 10.69498976 4.9431 24 P 0 0;1=4
P 10.85498976 5.0281 24 P 0 0;1=4
P 10.85498976 5.0731 24 P 0 0;1=4
P 10.85498976 4.9831 24 P 0 0;1=4
P 10.81498976 5.0281 24 P 0 0;1=4
P 10.81498976 5.0731 24 P 0 0;1=4
P 10.81498976 4.9831 24 P 0 0;1=4
P 10.81498976 5.1181 24 P 0 0;1=4
P 10.85498976 5.1181 24 P 0 0;1=4
P 10.73498976 5.1181 24 P 0 0;1=4
P 10.69498976 5.1181 24 P 0 0;1=4
P 10.65498976 5.1181 24 P 0 0;1=4
P 10.77498976 5.1181 24 P 0 0;1=4
P 10.65498976 4.9831 24 P 0 0;1=4
P 10.65498976 5.0731 24 P 0 0;1=4
P 10.65498976 5.0281 24 P 0 0;1=4
P 10.69498976 4.9831 24 P 0 0;1=4
P 10.69498976 5.0731 24 P 0 0;1=4
P 10.69498976 5.0281 24 P 0 0;1=4
P 1.23905994 4.60351004 24 P 0 0;1=4
P 1.18905994 5.04351004 24 P 0 0;1=4
P 1.33655994 4.85601004 24 P 0 0;1=4
P 10.16606998 2.81 24 P 0 0;1=4
P 4.15220974 2.9281 24 P 0 0;1=4
P 11.45278976 2.9414 24 P 0 0;1=4
P 11.45278976 3.0214 24 P 0 0;1=4
P 11.45278976 3.0564 24 P 0 0;1=4
P 11.45278976 3.1014 24 P 0 0;1=4
P 11.45278976 3.1364 24 P 0 0;1=4
P 11.45278976 3.2164 24 P 0 0;1=4
P 11.45278976 3.1814 24 P 0 0;1=4
P 11.45278976 2.9764 24 P 0 0;1=4
P 11.45278976 3.2614 24 P 0 0;1=4
P 11.45278976 3.2964 24 P 0 0;1=4
P 0.09448996 1.45275994 26 P 0 3;1=1
P 0.27165 1.57086998 26 P 0 3;1=1
P 0.35038996 1.45275994 26 P 0 3;1=1
P 12.81495 1.49212992 26 P 0 3;1=1
P 12.73620994 1.61023996 26 P 0 3;1=1
P 12.55905 1.49212992 26 P 0 3;1=1
P 0.27165 1.88582992 26 P 0 3;1=1
P 12.73620994 1.9252 26 P 0 3;1=1
P 7.35730974 0.036 24 P 0 0;1=4
P 7.60730974 0.036 24 P 0 0;1=4
P 7.55730974 0.036 24 P 0 0;1=4
P 7.50730974 0.036 24 P 0 0;1=4
P 7.45730974 0.036 24 P 0 0;1=4
P 7.40730974 0.036 24 P 0 0;1=4
P 7.85730974 0.036 24 P 0 0;1=4
P 7.80730974 0.036 24 P 0 0;1=4
P 7.75730974 0.036 24 P 0 0;1=4
P 7.70730974 0.036 24 P 0 0;1=4
P 7.65730974 0.036 24 P 0 0;1=4
P 8.15730974 0.036 24 P 0 0;1=4
P 8.10730974 0.036 24 P 0 0;1=4
P 8.05730974 0.036 24 P 0 0;1=4
P 8.00730974 0.036 24 P 0 0;1=4
P 7.95730974 0.036 24 P 0 0;1=4
P 7.90730974 0.036 24 P 0 0;1=4
P 8.40730974 0.036 24 P 0 0;1=4
P 8.35730974 0.036 24 P 0 0;1=4
P 8.30730974 0.036 24 P 0 0;1=4
P 8.25730974 0.036 24 P 0 0;1=4
P 8.20730974 0.036 24 P 0 0;1=4
P 8.65730974 0.036 24 P 0 0;1=4
P 8.60730974 0.036 24 P 0 0;1=4
P 8.55730974 0.036 24 P 0 0;1=4
P 8.50730974 0.036 24 P 0 0;1=4
P 8.45730974 0.036 24 P 0 0;1=4
P 8.90730974 0.036 24 P 0 0;1=4
P 8.85730974 0.036 24 P 0 0;1=4
P 8.80730974 0.036 24 P 0 0;1=4
P 8.75730974 0.036 24 P 0 0;1=4
P 8.70730974 0.036 24 P 0 0;1=4
P 9.20730974 0.036 24 P 0 0;1=4
P 9.15730974 0.036 24 P 0 0;1=4
P 9.10730974 0.036 24 P 0 0;1=4
P 9.05730974 0.036 24 P 0 0;1=4
P 9.00730974 0.036 24 P 0 0;1=4
P 8.95730974 0.036 24 P 0 0;1=4
P 9.45730974 0.036 24 P 0 0;1=4
P 9.40730974 0.036 24 P 0 0;1=4
P 9.35730974 0.036 24 P 0 0;1=4
P 9.30730974 0.036 24 P 0 0;1=4
P 9.25730974 0.036 24 P 0 0;1=4
P 9.70730974 0.036 24 P 0 0;1=4
P 9.65730974 0.036 24 P 0 0;1=4
P 9.60730974 0.036 24 P 0 0;1=4
P 9.55730974 0.036 24 P 0 0;1=4
P 9.50730974 0.036 24 P 0 0;1=4
P 10.00730974 0.036 24 P 0 0;1=4
P 9.95730974 0.036 24 P 0 0;1=4
P 9.90730974 0.036 24 P 0 0;1=4
P 9.85730974 0.036 24 P 0 0;1=4
P 9.80730974 0.036 24 P 0 0;1=4
P 9.75730974 0.036 24 P 0 0;1=4
P 10.25730974 0.036 24 P 0 0;1=4
P 10.20730974 0.036 24 P 0 0;1=4
P 10.15730974 0.036 24 P 0 0;1=4
P 10.10730974 0.036 24 P 0 0;1=4
P 10.05730974 0.036 24 P 0 0;1=4
P 10.50730974 0.036 24 P 0 0;1=4
P 10.45730974 0.036 24 P 0 0;1=4
P 10.40730974 0.036 24 P 0 0;1=4
P 10.35730974 0.036 24 P 0 0;1=4
P 10.30730974 0.036 24 P 0 0;1=4
P 10.75730974 0.036 24 P 0 0;1=4
P 10.70730974 0.036 24 P 0 0;1=4
P 10.65730974 0.036 24 P 0 0;1=4
P 10.60730974 0.036 24 P 0 0;1=4
P 10.55730974 0.036 24 P 0 0;1=4
P 11.05730974 0.036 24 P 0 0;1=4
P 11.00730974 0.036 24 P 0 0;1=4
P 10.95730974 0.036 24 P 0 0;1=4
P 10.90730974 0.036 24 P 0 0;1=4
P 10.85730974 0.036 24 P 0 0;1=4
P 10.80730974 0.036 24 P 0 0;1=4
P 11.30730974 0.036 24 P 0 0;1=4
P 11.25730974 0.036 24 P 0 0;1=4
P 11.20730974 0.036 24 P 0 0;1=4
P 11.15730974 0.036 24 P 0 0;1=4
P 11.10730974 0.036 24 P 0 0;1=4
P 11.55730974 0.036 24 P 0 0;1=4
P 11.50730974 0.036 24 P 0 0;1=4
P 11.45730974 0.036 24 P 0 0;1=4
P 11.40730974 0.036 24 P 0 0;1=4
P 11.35730974 0.036 24 P 0 0;1=4
P 11.80730974 0.036 24 P 0 0;1=4
P 11.75730974 0.036 24 P 0 0;1=4
P 11.70730974 0.036 24 P 0 0;1=4
P 11.65730974 0.036 24 P 0 0;1=4
P 11.60730974 0.036 24 P 0 0;1=4
P 12.10730974 0.036 24 P 0 0;1=4
P 12.05730974 0.036 24 P 0 0;1=4
P 12.00730974 0.036 24 P 0 0;1=4
P 11.95730974 0.036 24 P 0 0;1=4
P 11.90730974 0.036 24 P 0 0;1=4
P 11.85730974 0.036 24 P 0 0;1=4
P 12.35730974 0.036 24 P 0 0;1=4
P 12.30730974 0.036 24 P 0 0;1=4
P 12.25730974 0.036 24 P 0 0;1=4
P 12.20730974 0.036 24 P 0 0;1=4
P 12.15730974 0.036 24 P 0 0;1=4
P 12.60730974 0.036 24 P 0 0;1=4
P 12.55730974 0.036 24 P 0 0;1=4
P 12.50730974 0.036 24 P 0 0;1=4
P 12.45730974 0.036 24 P 0 0;1=4
P 12.40730974 0.036 24 P 0 0;1=4
P 12.8892 0.22595974 24 P 0 0;1=4
P 12.8892 0.17595974 24 P 0 0;1=4
P 12.8892 0.12595974 24 P 0 0;1=4
P 12.88911073 0.07596083 24 P 0 0;1=4
P 12.85728868 0.03739114 24 P 0 0;1=4
P 12.80730974 0.036 24 P 0 0;1=4
P 12.75730974 0.036 24 P 0 0;1=4
P 12.70730974 0.036 24 P 0 0;1=4
P 12.65730974 0.036 24 P 0 0;1=4
P 12.8892 0.47595974 24 P 0 0;1=4
P 12.8892 0.42595974 24 P 0 0;1=4
P 12.8892 0.37595974 24 P 0 0;1=4
P 12.8892 0.32595974 24 P 0 0;1=4
P 12.8892 0.27595974 24 P 0 0;1=4
P 12.8892 0.62595974 24 P 0 0;1=4
P 12.8892 0.57595974 24 P 0 0;1=4
P 12.8892 0.52595974 24 P 0 0;1=4
P 0.036 1.00868002 24 P 0 0;1=4
P 0.036 1.05868002 24 P 0 0;1=4
P 0.036 1.10868002 24 P 0 0;1=4
P 0.036 1.15868002 24 P 0 0;1=4
P 0.036 1.20868002 24 P 0 0;1=4
P 0.036 1.25868002 24 P 0 0;1=4
P 0.036 1.30868002 24 P 0 0;1=4
P 0.036 1.35868002 24 P 0 0;1=4
P 0.036 1.40868002 24 P 0 0;1=4
P 0.036 1.45868002 24 P 0 0;1=4
P 0.036 1.50868002 24 P 0 0;1=4
P 0.036 1.55868002 24 P 0 0;1=4
P 0.036 1.60868002 24 P 0 0;1=4
P 0.036 1.65868002 24 P 0 0;1=4
P 0.036 1.70868002 24 P 0 0;1=4
P 0.036 1.75868002 24 P 0 0;1=4
P 0.036 1.80868002 24 P 0 0;1=4
P 0.036 1.85868002 24 P 0 0;1=4
P 0.036 1.90868002 24 P 0 0;1=4
P 0.036 1.95868002 24 P 0 0;1=4
P 0.036 2.00868002 24 P 0 0;1=4
P 0.036 2.05868002 24 P 0 0;1=4
P 0.036 2.10868002 24 P 0 0;1=4
P 0.036 2.15868002 24 P 0 0;1=4
P 0.036 2.20868002 24 P 0 0;1=4
P 0.036 2.25868002 24 P 0 0;1=4
P 0.036 2.30868002 24 P 0 0;1=4
P 0.036 2.35868002 24 P 0 0;1=4
P 0.036 2.40868002 24 P 0 0;1=4
P 0.036 2.45868002 24 P 0 0;1=4
P 0.036 2.50868002 24 P 0 0;1=4
P 0.036 2.55868002 24 P 0 0;1=4
P 0.036 2.60868002 24 P 0 0;1=4
P 0.036 2.65868002 24 P 0 0;1=4
P 0.036 2.70868002 24 P 0 0;1=4
P 0.036 2.75868002 24 P 0 0;1=4
P 0.036 2.80868002 24 P 0 0;1=4
P 0.036 2.85868002 24 P 0 0;1=4
P 0.036 2.90868002 24 P 0 0;1=4
P 0.036 2.95868002 24 P 0 0;1=4
P 0.036 3.00868002 24 P 0 0;1=4
P 0.036 3.05868002 24 P 0 0;1=4
P 0.036 3.10868002 24 P 0 0;1=4
P 0.036 3.15868002 24 P 0 0;1=4
P 0.036 3.20868002 24 P 0 0;1=4
P 0.036 3.25868002 24 P 0 0;1=4
P 0.036 3.30868002 24 P 0 0;1=4
P 0.036 3.35868002 24 P 0 0;1=4
P 0.036 3.40868002 24 P 0 0;1=4
P 0.036 3.45868002 24 P 0 0;1=4
P 0.036 3.50868002 24 P 0 0;1=4
P 0.036 3.55868002 24 P 0 0;1=4
P 0.036 3.60868002 24 P 0 0;1=4
P 0.036 3.65868002 24 P 0 0;1=4
P 0.036 3.70868002 24 P 0 0;1=4
P 0.036 3.75868002 24 P 0 0;1=4
P 0.036 3.80868002 24 P 0 0;1=4
P 0.036 3.85868002 24 P 0 0;1=4
P 0.036 3.90868002 24 P 0 0;1=4
P 0.036 3.95868002 24 P 0 0;1=4
P 0.036 4.00868002 24 P 0 0;1=4
P 0.036 4.05868002 24 P 0 0;1=4
P 0.036 4.10868002 24 P 0 0;1=4
P 0.036 4.15868002 24 P 0 0;1=4
P 0.036 4.20868002 24 P 0 0;1=4
P 0.036 4.25868002 24 P 0 0;1=4
P 0.036 4.30868002 24 P 0 0;1=4
P 0.036 4.35868002 24 P 0 0;1=4
P 0.036 4.40868002 24 P 0 0;1=4
P 0.036 4.45868002 24 P 0 0;1=4
P 0.036 4.50868002 24 P 0 0;1=4
P 0.036 4.55868002 24 P 0 0;1=4
P 0.036 4.60868002 24 P 0 0;1=4
P 0.036 4.65868002 24 P 0 0;1=4
P 0.036 4.70868002 24 P 0 0;1=4
P 0.036 4.75868002 24 P 0 0;1=4
P 12.8892 1.02595974 24 P 0 0;1=4
P 12.8892 1.27595974 24 P 0 0;1=4
P 12.8892 1.22595974 24 P 0 0;1=4
P 12.8892 1.17595974 24 P 0 0;1=4
P 12.8892 1.12595974 24 P 0 0;1=4
P 12.8892 1.07595974 24 P 0 0;1=4
P 12.8892 1.52595974 24 P 0 0;1=4
P 12.8892 1.47595974 24 P 0 0;1=4
P 12.8892 1.42595974 24 P 0 0;1=4
P 12.8892 1.37595974 24 P 0 0;1=4
P 12.8892 1.32595974 24 P 0 0;1=4
P 12.8892 1.77595974 24 P 0 0;1=4
P 12.8892 1.72595974 24 P 0 0;1=4
P 12.8892 1.67595974 24 P 0 0;1=4
P 12.8892 1.62595974 24 P 0 0;1=4
P 12.8892 1.57595974 24 P 0 0;1=4
P 12.8892 2.07595974 24 P 0 0;1=4
P 12.8892 2.02595974 24 P 0 0;1=4
P 12.8892 1.97595974 24 P 0 0;1=4
P 12.8892 1.92595974 24 P 0 0;1=4
P 12.8892 1.87595974 24 P 0 0;1=4
P 12.8892 1.82595974 24 P 0 0;1=4
P 12.8892 2.32595974 24 P 0 0;1=4
P 12.8892 2.27595974 24 P 0 0;1=4
P 12.8892 2.22595974 24 P 0 0;1=4
P 12.8892 2.17595974 24 P 0 0;1=4
P 12.8892 2.57595974 24 P 0 0;1=4
P 12.8892 2.52595974 24 P 0 0;1=4
P 12.8892 2.47595974 24 P 0 0;1=4
P 12.8892 2.42595974 24 P 0 0;1=4
P 12.8892 2.37595974 24 P 0 0;1=4
P 12.8892 2.82595974 24 P 0 0;1=4
P 12.8892 2.77595974 24 P 0 0;1=4
P 12.8892 2.72595974 24 P 0 0;1=4
P 12.8892 2.67595974 24 P 0 0;1=4
P 12.8892 2.62595974 24 P 0 0;1=4
P 12.8892 3.12595974 24 P 0 0;1=4
P 12.8892 3.07595974 24 P 0 0;1=4
P 12.8892 3.02595974 24 P 0 0;1=4
P 12.8892 2.97595974 24 P 0 0;1=4
P 12.8892 2.92595974 24 P 0 0;1=4
P 12.8892 2.87595974 24 P 0 0;1=4
P 12.8892 3.37595974 24 P 0 0;1=4
P 12.8892 3.32595974 24 P 0 0;1=4
P 12.8892 3.27595974 24 P 0 0;1=4
P 12.8892 3.22595974 24 P 0 0;1=4
P 12.8892 3.17595974 24 P 0 0;1=4
P 12.8892 3.62595974 24 P 0 0;1=4
P 12.8892 3.57595974 24 P 0 0;1=4
P 12.8892 3.52595974 24 P 0 0;1=4
P 12.8892 3.47595974 24 P 0 0;1=4
P 12.8892 3.42595974 24 P 0 0;1=4
P 12.8892 3.92595974 24 P 0 0;1=4
P 12.8892 3.87595974 24 P 0 0;1=4
P 12.8892 3.82595974 24 P 0 0;1=4
P 12.8892 3.77595974 24 P 0 0;1=4
P 12.8892 3.72595974 24 P 0 0;1=4
P 12.8892 3.67595974 24 P 0 0;1=4
P 12.8892 4.17595974 24 P 0 0;1=4
P 12.8892 4.12595974 24 P 0 0;1=4
P 12.8892 4.07595974 24 P 0 0;1=4
P 12.8892 4.02595974 24 P 0 0;1=4
P 12.8892 3.97595974 24 P 0 0;1=4
P 12.8892 4.42595974 24 P 0 0;1=4
P 12.8892 4.37595974 24 P 0 0;1=4
P 12.8892 4.32595974 24 P 0 0;1=4
P 12.8892 4.27595974 24 P 0 0;1=4
P 12.8892 4.22595974 24 P 0 0;1=4
P 12.8892 4.67595974 24 P 0 0;1=4
P 12.8892 4.62595974 24 P 0 0;1=4
P 12.8892 4.57595974 24 P 0 0;1=4
P 12.8892 4.52595974 24 P 0 0;1=4
P 12.8892 4.47595974 24 P 0 0;1=4
P 12.8892 4.82595974 24 P 0 0;1=4
P 12.8892 4.77595974 24 P 0 0;1=4
P 12.8892 4.72595974 24 P 0 0;1=4
P 0.036 5.25868002 24 P 0 0;1=4
P 0.036 5.30868002 24 P 0 0;1=4
P 0.036 5.35868002 24 P 0 0;1=4
P 0.036 5.40868002 24 P 0 0;1=4
P 0.036 5.45868002 24 P 0 0;1=4
P 0.036 5.50868002 24 P 0 0;1=4
P 0.036 5.55868002 24 P 0 0;1=4
P 0.036 5.60868002 24 P 0 0;1=4
P 0.036 5.65868002 24 P 0 0;1=4
P 0.036 5.70868002 24 P 0 0;1=4
P 0.036 5.75868002 24 P 0 0;1=4
P 0.036 5.80868002 24 P 0 0;1=4
P 0.036 5.85868002 24 P 0 0;1=4
P 0.036 5.90868002 24 P 0 0;1=4
P 0.03826998 5.95863002 24 P 0 0;1=4
P 0.07901024 5.98761998 24 P 0 0;1=4
P 0.12901024 5.98761998 24 P 0 0;1=4
P 0.17901024 5.98761998 24 P 0 0;1=4
P 0.22901024 5.98761998 24 P 0 0;1=4
P 0.27901024 5.98761998 24 P 0 0;1=4
P 0.32901024 5.98761998 24 P 0 0;1=4
P 0.37901024 5.98761998 24 P 0 0;1=4
P 0.42901024 5.98761998 24 P 0 0;1=4
P 0.47901024 5.98761998 24 P 0 0;1=4
P 0.52901024 5.98761998 24 P 0 0;1=4
P 0.57901024 5.98761998 24 P 0 0;1=4
P 0.62901024 5.98761998 24 P 0 0;1=4
P 0.67901024 5.98761998 24 P 0 0;1=4
P 0.72901024 5.98761998 24 P 0 0;1=4
P 0.77901024 5.98761998 24 P 0 0;1=4
P 0.82901024 5.98761998 24 P 0 0;1=4
P 0.87901024 5.98761998 24 P 0 0;1=4
P 0.92901024 5.98761998 24 P 0 0;1=4
P 0.97901024 5.98761998 24 P 0 0;1=4
P 1.02901024 5.98761998 24 P 0 0;1=4
P 1.07901024 5.98761998 24 P 0 0;1=4
P 1.12901024 5.98761998 24 P 0 0;1=4
P 1.17901024 5.98761998 24 P 0 0;1=4
P 1.22901024 5.98761998 24 P 0 0;1=4
P 1.27901024 5.98761998 24 P 0 0;1=4
P 1.32901024 5.98761998 24 P 0 0;1=4
P 1.37901024 5.98761998 24 P 0 0;1=4
P 1.42901024 5.98761998 24 P 0 0;1=4
P 1.47901024 5.98761998 24 P 0 0;1=4
P 1.52901024 5.98761998 24 P 0 0;1=4
P 1.57901024 5.98761998 24 P 0 0;1=4
P 1.62901024 5.98761998 24 P 0 0;1=4
P 1.67901024 5.98761998 24 P 0 0;1=4
P 1.72901024 5.98761998 24 P 0 0;1=4
P 1.77901024 5.98761998 24 P 0 0;1=4
P 1.82901024 5.98761998 24 P 0 0;1=4
P 1.87901024 5.98761998 24 P 0 0;1=4
P 1.92901024 5.98761998 24 P 0 0;1=4
P 1.97901024 5.98761998 24 P 0 0;1=4
P 2.02901024 5.98761998 24 P 0 0;1=4
P 2.07901024 5.98761998 24 P 0 0;1=4
P 2.12901024 5.98761998 24 P 0 0;1=4
P 2.17901024 5.98761998 24 P 0 0;1=4
P 2.22901024 5.98761998 24 P 0 0;1=4
P 2.27901024 5.98761998 24 P 0 0;1=4
P 2.32901024 5.98761998 24 P 0 0;1=4
P 2.37901024 5.98761998 24 P 0 0;1=4
P 2.42901024 5.98761998 24 P 0 0;1=4
P 2.47901024 5.98761998 24 P 0 0;1=4
P 2.52901024 5.98761998 24 P 0 0;1=4
P 2.57901024 5.98761998 24 P 0 0;1=4
P 2.62901024 5.98761998 24 P 0 0;1=4
P 2.67901024 5.98761998 24 P 0 0;1=4
P 2.72901024 5.98761998 24 P 0 0;1=4
P 2.77901024 5.98761998 24 P 0 0;1=4
P 2.82901024 5.98761998 24 P 0 0;1=4
P 2.87901024 5.98761998 24 P 0 0;1=4
P 2.92901024 5.98761998 24 P 0 0;1=4
P 2.97901024 5.98761998 24 P 0 0;1=4
P 3.02901024 5.98761998 24 P 0 0;1=4
P 3.07901024 5.98761998 24 P 0 0;1=4
P 3.12901024 5.98761998 24 P 0 0;1=4
P 3.17901024 5.98761998 24 P 0 0;1=4
P 3.22901024 5.98761998 24 P 0 0;1=4
P 3.27901024 5.98761998 24 P 0 0;1=4
P 3.32901024 5.98761998 24 P 0 0;1=4
P 3.37901024 5.98761998 24 P 0 0;1=4
P 3.42901024 5.98761998 24 P 0 0;1=4
P 3.47901024 5.98761998 24 P 0 0;1=4
P 3.52901024 5.98761998 24 P 0 0;1=4
P 3.57901024 5.98761998 24 P 0 0;1=4
P 3.62901024 5.98761998 24 P 0 0;1=4
P 3.67901024 5.98761998 24 P 0 0;1=4
P 3.72901024 5.98761998 24 P 0 0;1=4
P 3.77901024 5.98761998 24 P 0 0;1=4
P 3.82901024 5.98761998 24 P 0 0;1=4
P 3.87901024 5.98761998 24 P 0 0;1=4
P 3.92901024 5.98761998 24 P 0 0;1=4
P 3.97901024 5.98761998 24 P 0 0;1=4
P 4.02901024 5.98761998 24 P 0 0;1=4
P 4.07901024 5.98761998 24 P 0 0;1=4
P 4.12901024 5.98761998 24 P 0 0;1=4
P 4.17901024 5.98761998 24 P 0 0;1=4
P 4.22901024 5.98761998 24 P 0 0;1=4
P 4.27901024 5.98761998 24 P 0 0;1=4
P 4.32901024 5.98761998 24 P 0 0;1=4
P 4.37901024 5.98761998 24 P 0 0;1=4
P 4.42901024 5.98761998 24 P 0 0;1=4
P 4.47901024 5.98761998 24 P 0 0;1=4
P 4.52901024 5.98761998 24 P 0 0;1=4
P 4.57901024 5.98761998 24 P 0 0;1=4
P 4.62901024 5.98761998 24 P 0 0;1=4
P 4.67901024 5.98761998 24 P 0 0;1=4
P 4.72901024 5.98761998 24 P 0 0;1=4
P 4.77901024 5.98761998 24 P 0 0;1=4
P 4.82901024 5.98761998 24 P 0 0;1=4
P 4.87901024 5.98761998 24 P 0 0;1=4
P 4.92901024 5.98761998 24 P 0 0;1=4
P 4.97901024 5.98761998 24 P 0 0;1=4
P 5.02901024 5.98761998 24 P 0 0;1=4
P 5.07901024 5.98761998 24 P 0 0;1=4
P 5.12901024 5.98761998 24 P 0 0;1=4
P 5.17901024 5.98761998 24 P 0 0;1=4
P 5.22901024 5.98761998 24 P 0 0;1=4
P 5.27901024 5.98761998 24 P 0 0;1=4
P 5.32901024 5.98761998 24 P 0 0;1=4
P 5.37901024 5.98761998 24 P 0 0;1=4
P 5.42901024 5.98761998 24 P 0 0;1=4
P 5.47901024 5.98761998 24 P 0 0;1=4
P 5.52901024 5.98761998 24 P 0 0;1=4
P 5.57901024 5.98761998 24 P 0 0;1=4
P 5.62901024 5.98761998 24 P 0 0;1=4
P 5.67901024 5.98761998 24 P 0 0;1=4
P 5.72901024 5.98761998 24 P 0 0;1=4
P 5.77901024 5.98761998 24 P 0 0;1=4
P 5.82901024 5.98761998 24 P 0 0;1=4
P 5.87901024 5.98761998 24 P 0 0;1=4
P 5.92901024 5.98761998 24 P 0 0;1=4
P 5.97901024 5.98761998 24 P 0 0;1=4
P 6.02901024 5.98761998 24 P 0 0;1=4
P 6.07901024 5.98761998 24 P 0 0;1=4
P 6.12901024 5.98761998 24 P 0 0;1=4
P 6.17901024 5.98761998 24 P 0 0;1=4
P 6.22901024 5.98761998 24 P 0 0;1=4
P 6.27901024 5.98761998 24 P 0 0;1=4
P 6.32901024 5.98761998 24 P 0 0;1=4
P 6.37901024 5.98761998 24 P 0 0;1=4
P 6.42901024 5.98761998 24 P 0 0;1=4
P 6.47901024 5.98761998 24 P 0 0;1=4
P 6.52901024 5.98761998 24 P 0 0;1=4
P 6.57901024 5.98761998 24 P 0 0;1=4
P 6.62901024 5.98761998 24 P 0 0;1=4
P 6.67901024 5.98761998 24 P 0 0;1=4
P 6.72901024 5.98761998 24 P 0 0;1=4
P 6.77901024 5.98761998 24 P 0 0;1=4
P 6.82901024 5.98761998 24 P 0 0;1=4
P 6.87901024 5.98761998 24 P 0 0;1=4
P 6.92901024 5.98761998 24 P 0 0;1=4
P 6.97901024 5.98761998 24 P 0 0;1=4
P 12.8892 5.47595974 24 P 0 0;1=4
P 12.8892 5.42595974 24 P 0 0;1=4
P 12.8892 5.37595974 24 P 0 0;1=4
P 12.8892 5.32595974 24 P 0 0;1=4
P 12.8892 5.27595974 24 P 0 0;1=4
P 12.8892 5.72595974 24 P 0 0;1=4
P 12.8892 5.67595974 24 P 0 0;1=4
P 12.8892 5.62595974 24 P 0 0;1=4
P 12.8892 5.57595974 24 P 0 0;1=4
P 12.8892 5.52595974 24 P 0 0;1=4
P 7.37901024 5.98761998 24 P 0 0;1=4
P 7.42901024 5.98761998 24 P 0 0;1=4
P 7.47901024 5.98761998 24 P 0 0;1=4
P 7.52901024 5.98761998 24 P 0 0;1=4
P 7.57901024 5.98761998 24 P 0 0;1=4
P 7.62901024 5.98761998 24 P 0 0;1=4
P 7.67901024 5.98761998 24 P 0 0;1=4
P 7.72901024 5.98761998 24 P 0 0;1=4
P 7.77901024 5.98761998 24 P 0 0;1=4
P 7.82901024 5.98761998 24 P 0 0;1=4
P 7.87901024 5.98761998 24 P 0 0;1=4
P 7.92901024 5.98761998 24 P 0 0;1=4
P 7.97901024 5.98761998 24 P 0 0;1=4
P 8.02901024 5.98761998 24 P 0 0;1=4
P 8.07901024 5.98761998 24 P 0 0;1=4
P 8.12901024 5.98761998 24 P 0 0;1=4
P 8.17901024 5.98761998 24 P 0 0;1=4
P 8.22901024 5.98761998 24 P 0 0;1=4
P 8.27901024 5.98761998 24 P 0 0;1=4
P 8.32901024 5.98761998 24 P 0 0;1=4
P 8.37901024 5.98761998 24 P 0 0;1=4
P 8.42901024 5.98761998 24 P 0 0;1=4
P 8.47901024 5.98761998 24 P 0 0;1=4
P 8.52901024 5.98761998 24 P 0 0;1=4
P 8.57901024 5.98761998 24 P 0 0;1=4
P 8.62901024 5.98761998 24 P 0 0;1=4
P 8.67901024 5.98761998 24 P 0 0;1=4
P 8.72901024 5.98761998 24 P 0 0;1=4
P 8.77901024 5.98761998 24 P 0 0;1=4
P 8.82901024 5.98761998 24 P 0 0;1=4
P 8.87901024 5.98761998 24 P 0 0;1=4
P 8.92901024 5.98761998 24 P 0 0;1=4
P 8.97901024 5.98761998 24 P 0 0;1=4
P 9.02901024 5.98761998 24 P 0 0;1=4
P 9.07901024 5.98761998 24 P 0 0;1=4
P 9.12901024 5.98761998 24 P 0 0;1=4
P 9.17901024 5.98761998 24 P 0 0;1=4
P 9.22901024 5.98761998 24 P 0 0;1=4
P 9.27901024 5.98761998 24 P 0 0;1=4
P 9.32901024 5.98761998 24 P 0 0;1=4
P 9.37901024 5.98761998 24 P 0 0;1=4
P 9.42901024 5.98761998 24 P 0 0;1=4
P 9.47901024 5.98761998 24 P 0 0;1=4
P 9.52901024 5.98761998 24 P 0 0;1=4
P 9.57901024 5.98761998 24 P 0 0;1=4
P 9.62901024 5.98761998 24 P 0 0;1=4
P 9.67901024 5.98761998 24 P 0 0;1=4
P 9.72901024 5.98761998 24 P 0 0;1=4
P 9.77901024 5.98761998 24 P 0 0;1=4
P 9.82901024 5.98761998 24 P 0 0;1=4
P 9.87901024 5.98761998 24 P 0 0;1=4
P 9.92901024 5.98761998 24 P 0 0;1=4
P 9.97901024 5.98761998 24 P 0 0;1=4
P 10.02901024 5.98761998 24 P 0 0;1=4
P 10.07901024 5.98761998 24 P 0 0;1=4
P 10.12901024 5.98761998 24 P 0 0;1=4
P 10.17901024 5.98761998 24 P 0 0;1=4
P 10.22901024 5.98761998 24 P 0 0;1=4
P 10.27901024 5.98761998 24 P 0 0;1=4
P 10.32901024 5.98761998 24 P 0 0;1=4
P 10.37901024 5.98761998 24 P 0 0;1=4
P 10.42901024 5.98761998 24 P 0 0;1=4
P 10.47901024 5.98761998 24 P 0 0;1=4
P 10.52901024 5.98761998 24 P 0 0;1=4
P 10.57901024 5.98761998 24 P 0 0;1=4
P 10.62901024 5.98761998 24 P 0 0;1=4
P 10.67901024 5.98761998 24 P 0 0;1=4
P 10.72901024 5.98761998 24 P 0 0;1=4
P 10.77901024 5.98761998 24 P 0 0;1=4
P 10.82901024 5.98761998 24 P 0 0;1=4
P 10.87901024 5.98761998 24 P 0 0;1=4
P 10.92901024 5.98761998 24 P 0 0;1=4
P 10.97901024 5.98761998 24 P 0 0;1=4
P 11.02901024 5.98761998 24 P 0 0;1=4
P 11.07901024 5.98761998 24 P 0 0;1=4
P 11.12901024 5.98761998 24 P 0 0;1=4
P 11.17901024 5.98761998 24 P 0 0;1=4
P 11.22901024 5.98761998 24 P 0 0;1=4
P 11.27901024 5.98761998 24 P 0 0;1=4
P 11.32901024 5.98761998 24 P 0 0;1=4
P 11.37901024 5.98761998 24 P 0 0;1=4
P 11.42901024 5.98761998 24 P 0 0;1=4
P 11.47901024 5.98761998 24 P 0 0;1=4
P 11.52901024 5.98761998 24 P 0 0;1=4
P 11.57901024 5.98761998 24 P 0 0;1=4
P 11.62901024 5.98761998 24 P 0 0;1=4
P 11.67901024 5.98761998 24 P 0 0;1=4
P 11.72901024 5.98761998 24 P 0 0;1=4
P 11.77901024 5.98761998 24 P 0 0;1=4
P 11.82901024 5.98761998 24 P 0 0;1=4
P 11.87901024 5.98761998 24 P 0 0;1=4
P 11.92901024 5.98761998 24 P 0 0;1=4
P 11.97901024 5.98761998 24 P 0 0;1=4
P 12.02901024 5.98761998 24 P 0 0;1=4
P 12.07901024 5.98761998 24 P 0 0;1=4
P 12.12901024 5.98761998 24 P 0 0;1=4
P 12.17901024 5.98761998 24 P 0 0;1=4
P 12.22901024 5.98761998 24 P 0 0;1=4
P 12.27901024 5.98761998 24 P 0 0;1=4
P 12.32901024 5.98761998 24 P 0 0;1=4
P 12.37901024 5.98761998 24 P 0 0;1=4
P 12.42901024 5.98761998 24 P 0 0;1=4
P 12.47901024 5.98761998 24 P 0 0;1=4
P 12.52901024 5.98761998 24 P 0 0;1=4
P 12.57901024 5.98761998 24 P 0 0;1=4
P 12.62901024 5.98761998 24 P 0 0;1=4
P 12.67901024 5.98761998 24 P 0 0;1=4
P 12.72901024 5.98761998 24 P 0 0;1=4
P 12.77901024 5.98761998 24 P 0 0;1=4
P 12.82901024 5.98761998 24 P 0 0;1=4
P 12.87725994 5.97451004 24 P 0 0;1=4
P 12.8892 5.92595974 24 P 0 0;1=4
P 12.8892 5.87595974 24 P 0 0;1=4
P 12.8892 5.82595974 24 P 0 0;1=4
P 12.8892 5.77595974 24 P 0 0;1=4
P 4.33605 4.9231 24 P 0 0;1=4
P 4.38105 4.9231 24 P 0 0;1=4
P 4.30105 4.9431 24 P 0 0;1=4
P 4.42105 4.9431 24 P 0 0;1=4
P 4.46105 4.9431 24 P 0 0;1=4
P 4.26105 4.9431 24 P 0 0;1=4
P 4.72605 4.9231 24 P 0 0;1=4
P 4.65105 4.9431 24 P 0 0;1=4
P 4.69105 4.9431 24 P 0 0;1=4
P 4.85105 4.9431 24 P 0 0;1=4
P 4.81105 4.9431 24 P 0 0;1=4
P 4.77105 4.9231 24 P 0 0;1=4
P 4.30105 5.0281 24 P 0 0;1=4
P 4.30105 5.0731 24 P 0 0;1=4
P 4.30105 4.9831 24 P 0 0;1=4
P 4.34105 5.1181 24 P 0 0;1=4
P 4.38105 5.1181 24 P 0 0;1=4
P 4.46105 5.1181 24 P 0 0;1=4
P 4.42105 5.1181 24 P 0 0;1=4
P 4.42105 4.9831 24 P 0 0;1=4
P 4.42105 5.0731 24 P 0 0;1=4
P 4.42105 5.0281 24 P 0 0;1=4
P 4.46105 4.9831 24 P 0 0;1=4
P 4.46105 5.0731 24 P 0 0;1=4
P 4.46105 5.0281 24 P 0 0;1=4
P 4.26105 5.0281 24 P 0 0;1=4
P 4.26105 5.0731 24 P 0 0;1=4
P 4.26105 4.9831 24 P 0 0;1=4
P 4.73105 5.1181 24 P 0 0;1=4
P 4.69105 5.1181 24 P 0 0;1=4
P 4.65105 5.1181 24 P 0 0;1=4
P 4.65105 4.9831 24 P 0 0;1=4
P 4.65105 5.0731 24 P 0 0;1=4
P 4.65105 5.0281 24 P 0 0;1=4
P 4.69105 4.9831 24 P 0 0;1=4
P 4.69105 5.0731 24 P 0 0;1=4
P 4.69105 5.0281 24 P 0 0;1=4
P 4.85105 5.0281 24 P 0 0;1=4
P 4.85105 5.0731 24 P 0 0;1=4
P 4.85105 4.9831 24 P 0 0;1=4
P 4.81105 5.0281 24 P 0 0;1=4
P 4.81105 5.0731 24 P 0 0;1=4
P 4.81105 4.9831 24 P 0 0;1=4
P 4.81105 5.1181 24 P 0 0;1=4
P 4.85105 5.1181 24 P 0 0;1=4
P 4.77105 5.1181 24 P 0 0;1=4
P 4.30105 5.1181 24 P 0 0;1=4
P 4.26105 5.1181 24 P 0 0;1=4
P 9.45795 0.36633002 24 P 0 0;1=4
P 6.62 4.645 24 P 0 0;1=4
P 6.62 4.61 24 P 0 0;1=4
P 6.605 4.77 24 P 0 0;1=4
P 6.315 4.9 24 P 0 0;1=4
P 6.315 4.865 24 P 0 0;1=4
P 6.315 4.82 24 P 0 0;1=4
P 6.315 4.785 24 P 0 0;1=4
P 6.315 4.705 24 P 0 0;1=4
P 6.315 4.74 24 P 0 0;1=4
P 6.315 4.66 24 P 0 0;1=4
P 6.315 4.625 24 P 0 0;1=4
P 1.51672972 5.78 24 P 0 0;1=4
P 1.12303002 5.46015974 24 P 0 0;1=4
P 1.20176998 5.46016004 24 P 0 0;1=4
P 1.51673002 5.46015974 24 P 0 0;1=4
P 1.36 5.355 24 P 0 0;1=4
P 1.41 5.355 24 P 0 0;1=4
P 1.46 5.355 24 P 0 0;1=4
P 1.305 5.885 24 P 0 0;1=4
P 1.355 5.885 24 P 0 0;1=4
P 1.405 5.885 24 P 0 0;1=4
P 1.455 5.885 24 P 0 0;1=4
P 0.705 5.355 24 P 0 0;1=4
P 0.7 5.267 24 P 0 0;1=0
P 0.73 5.175 24 P 0 0;1=4
P 1.03 5.065 24 P 0 0;1=4
P 1.28050994 5.46016004 24 P 0 0;1=4
P 12.215 4.915 24 P 0 0;1=4
P 12.055 4.915 24 P 0 0;1=4
P 10.465 5.245 24 P 0 0;1=4
P 10.465 5.165 24 P 0 0;1=4
P 11.7719 4.80998976 24 P 0 0;1=4
P 11.7719 4.85498976 24 P 0 0;1=4
P 11.7719 4.90498976 24 P 0 0;1=4
P 11.7719 4.94998976 24 P 0 0;1=4
P 11.9719 4.94998976 24 P 0 0;1=4
P 11.9719 4.80998976 24 P 0 0;1=4
P 11.9719 4.85498976 24 P 0 0;1=4
P 11.9719 4.90498976 24 P 0 0;1=4
P 11.9219 4.94998976 24 P 0 0;1=4
P 11.9219 4.80998976 24 P 0 0;1=4
P 11.8719 4.94998976 24 P 0 0;1=4
P 11.8719 4.80998976 24 P 0 0;1=4
P 11.8219 4.80998976 24 P 0 0;1=4
P 11.8219 4.94998976 24 P 0 0;1=4
P 11.69315974 2.6635 24 P 0 0;1=4
P 10.125 2.008 24 P 0 0;1=4
P 5.53530974 1.6642 24 P 0 0;1=4
P 5.53530974 1.7213 24 P 0 0;1=4
P 5.53530974 2.0802 24 P 0 0;1=4
P 5.53530974 1.9393 24 P 0 0;1=4
P 5.53530974 2.2156 24 P 0 0;1=4
P 5.53530974 2.4081 24 P 0 0;1=4
P 5.53530974 2.5473 24 P 0 0;1=4
P 2.86855 4.92 24 P 0 0;1=4
P 2.79767972 4.92 24 P 0 0;1=4
P 3.08113976 4.92 24 P 0 0;1=4
P 3.36460974 4.926 24 P 0 0;1=4
P 3.22287972 4.92 24 P 0 0;1=4
P 3.50633976 4.92 24 P 0 0;1=4
P 3.43546998 4.928 24 P 0 0;1=4
P 3.15398002 4.81401998 24 P 0 0;1=4
P 3.22288002 4.81401998 24 P 0 0;1=4
P 3.36461024 4.81401998 24 P 0 0;1=4
P 3.43547028 4.81401998 24 P 0 0;1=4
P 3.50634026 4.81401998 24 P 0 0;1=4
P 3.22287972 5.023 24 P 0 0;1=4
P 3.50633976 5.023 24 P 0 0;1=4
P 3.43546998 5.023 24 P 0 0;1=4
P 3.14 4.92 24 P 0 0;1=4
P 3.275 4.92 24 P 0 0;1=4
P 3.26 5.332 24 P 0 0;1=4
P 3.06792028 5.332 24 P 0 0;1=4
P 3.51176998 5.17874026 24 P 0 0;1=4
P 3.57176998 5.17874026 24 P 0 0;1=4
P 3.15743996 4.74418002 24 P 0 0;1=4
P 1.63307972 4.92 24 P 0 0;1=4
P 1.84567972 4.92 24 P 0 0;1=4
P 1.77480974 4.92 24 P 0 0;1=4
P 1.70395 4.92 24 P 0 0;1=4
P 2.12913976 4.92 24 P 0 0;1=4
P 2.05827972 4.92 24 P 0 0;1=4
P 1.98740974 4.92 24 P 0 0;1=4
P 1.91653976 4.92 24 P 0 0;1=4
P 2.34173976 4.92 24 P 0 0;1=4
P 2.27086998 4.92 24 P 0 0;1=4
P 2.20000974 4.926 24 P 0 0;1=4
P 2.34173976 4.81 24 P 0 0;1=4
P 2.27086998 4.81 24 P 0 0;1=4
P 2.20000974 4.81 24 P 0 0;1=4
P 1.63173002 4.81526998 24 P 0 0;1=4
P 1.7 4.812 24 P 0 0;1=4
P 1.84567972 4.81 24 P 0 0;1=4
P 1.776 4.812 24 P 0 0;1=4
P 2.12913976 4.81 24 P 0 0;1=4
P 1.99 4.81 24 P 0 0;1=4
P 1.92 4.81 24 P 0 0;1=4
P 2.40716998 5.15374026 24 P 0 0;1=4
P 2.34716998 5.15374026 24 P 0 0;1=4
P 10.58660974 2.16615 24 P 0 0;1=3
P 10.63660974 2.16615 24 P 0 0;1=3
P 10.63660974 2.21615 24 P 0 0;1=3
P 10.88660974 1.91615 24 P 0 0;1=3
P 10.88660974 2.41615 24 P 0 0;1=3
P 10.88660974 2.66615 24 P 0 0;1=3
P 11.03660974 2.41615 24 P 0 0;1=3
P 11.03660974 2.36615 24 P 0 0;1=3
P 1.91110994 4.61826004 24 P 0 0;1=4
P 2.40716998 4.70326004 24 P 0 0;1=4
P 2.945 4.92 24 P 0 0;1=4
P 3.01027972 4.92 24 P 0 0;1=4
P 7.78 2.4781 24 P 0 0;1=0
P 2.24606024 3.86615 24 P 0 0;1=3
P 2.49606024 3.86615 24 P 0 0;1=3
P 2.24606024 3.81615 24 P 0 0;1=3
P 2.19606024 3.76615 24 P 0 0;1=3
P 2.24606024 3.76615 24 P 0 0;1=3
P 2.29606024 3.76615 24 P 0 0;1=3
P 2.49606024 3.71615 24 P 0 0;1=3
P 2.49606024 3.56615 24 P 0 0;1=3
P 2.44606024 3.56615 24 P 0 0;1=3
P 2.39606024 3.56615 24 P 0 0;1=3
P 2.29606024 3.61615 24 P 0 0;1=3
P 2.24606024 3.71615 24 P 0 0;1=3
P 2.24606024 3.66615 24 P 0 0;1=3
P 2.24606024 3.61615 24 P 0 0;1=3
P 2.19606024 3.61615 24 P 0 0;1=3
P 2.19606024 3.56615 24 P 0 0;1=3
P 2.14606024 3.56615 24 P 0 0;1=3
P 2.04606024 3.56615 24 P 0 0;1=3
P 1.99605974 3.56615 24 P 0 0;1=3
P 2.04606024 3.51615 24 P 0 0;1=3
P 2.04605974 3.46615 24 P 0 0;1=3
P 2.19606024 3.51615 24 P 0 0;1=3
P 2.24606024 3.51615 24 P 0 0;1=3
P 2.29606024 3.51615 24 P 0 0;1=3
P 2.49606024 3.41615 24 P 0 0;1=3
P 2.44606024 3.36615 24 P 0 0;1=3
P 2.24606024 3.46615 24 P 0 0;1=3
P 2.24606024 3.41615 24 P 0 0;1=3
P 2.29606024 3.36615 24 P 0 0;1=3
P 2.24606024 3.36615 24 P 0 0;1=3
P 2.19606024 3.36615 24 P 0 0;1=3
P 1.99605974 3.41615 24 P 0 0;1=3
P 2.09606024 3.36615 24 P 0 0;1=3
P 2.24606024 3.31615 24 P 0 0;1=3
P 2.24606024 3.26615 24 P 0 0;1=3
P 2.29606024 3.21615 24 P 0 0;1=3
P 2.24606024 3.21615 24 P 0 0;1=3
P 2.19606024 3.21615 24 P 0 0;1=3
P 2.09606024 3.21615 24 P 0 0;1=3
P 2.14606024 3.16615 24 P 0 0;1=3
P 2.04606024 3.16615 24 P 0 0;1=3
P 2.24606024 3.16615 24 P 0 0;1=3
P 2.29606024 3.16615 24 P 0 0;1=3
P 2.34606024 3.21615 24 P 0 0;1=3
P 2.44606024 3.21615 24 P 0 0;1=3
P 2.49606024 3.21615 24 P 0 0;1=3
P 2.49606024 3.26615 24 P 0 0;1=3
P 2.49606024 3.16615 24 P 0 0;1=3
P 2.39606024 3.16615 24 P 0 0;1=3
P 2.29606024 3.06615 24 P 0 0;1=3
P 2.29606024 3.11615 24 P 0 0;1=3
P 2.29606024 2.96615 24 P 0 0;1=3
P 2.29606024 3.01615 24 P 0 0;1=3
P 2.24606024 3.06615 24 P 0 0;1=3
P 2.24606024 3.11615 24 P 0 0;1=3
P 2.24606024 2.96615 24 P 0 0;1=3
P 2.24606024 3.01615 24 P 0 0;1=3
P 2.34606024 2.86615 24 P 0 0;1=3
P 2.34606024 2.91615 24 P 0 0;1=3
P 2.29606024 2.76615 24 P 0 0;1=3
P 2.29606024 2.81615 24 P 0 0;1=3
P 2.24606024 2.76615 24 P 0 0;1=3
P 2.24606024 2.81615 24 P 0 0;1=3
P 2.19606024 2.81615 24 P 0 0;1=3
P 2.09606024 2.81615 24 P 0 0;1=3
P 2.09606024 2.86615 24 P 0 0;1=3
P 2.19606024 3.06615 24 P 0 0;1=3
P 2.14606024 3.01615 24 P 0 0;1=3
P 2.09606024 3.06615 24 P 0 0;1=3
P 2.04606024 3.01615 24 P 0 0;1=3
P 2.09606024 2.91615 24 P 0 0;1=3
P 2.14606024 2.86615 24 P 0 0;1=3
P 2.04606024 2.86615 24 P 0 0;1=3
P 2.19606024 2.91615 24 P 0 0;1=3
P 2.24606024 2.91615 24 P 0 0;1=3
P 2.29606024 2.91615 24 P 0 0;1=3
P 2.39606024 3.01615 24 P 0 0;1=3
P 2.34606024 3.06615 24 P 0 0;1=3
P 2.44606024 3.06615 24 P 0 0;1=3
P 2.49606024 3.01615 24 P 0 0;1=3
P 2.44606024 2.91615 24 P 0 0;1=3
P 2.44606024 2.86615 24 P 0 0;1=3
P 2.39606024 2.86615 24 P 0 0;1=3
P 2.34606024 2.81615 24 P 0 0;1=3
P 2.44606024 2.81615 24 P 0 0;1=3
P 2.49606024 2.86615 24 P 0 0;1=3
P 2.49606024 2.71615 24 P 0 0;1=3
P 2.44606024 2.66615 24 P 0 0;1=3
P 2.39606024 2.71615 24 P 0 0;1=3
P 2.34606024 2.66615 24 P 0 0;1=3
P 2.29606024 2.71615 24 P 0 0;1=3
P 2.29606024 2.66615 24 P 0 0;1=3
P 2.24606024 2.71615 24 P 0 0;1=3
P 2.24606024 2.66615 24 P 0 0;1=3
P 2.19606024 2.66615 24 P 0 0;1=3
P 2.14606024 2.71615 24 P 0 0;1=3
P 2.09606024 2.66615 24 P 0 0;1=3
P 2.04606024 2.71615 24 P 0 0;1=3
P 2.04606024 2.56615 24 P 0 0;1=3
P 2.04606024 2.51615 24 P 0 0;1=3
P 2.04606024 2.46615 24 P 0 0;1=3
P 2.09606024 2.51615 24 P 0 0;1=3
P 2.14606024 2.56615 24 P 0 0;1=3
P 2.24606024 2.61615 24 P 0 0;1=3
P 2.24606024 2.56615 24 P 0 0;1=3
P 2.29606024 2.61615 24 P 0 0;1=3
P 2.29606024 2.56615 24 P 0 0;1=3
P 2.34606024 2.51615 24 P 0 0;1=3
P 2.29606024 2.51615 24 P 0 0;1=3
P 2.24606024 2.51615 24 P 0 0;1=3
P 2.19606024 2.51615 24 P 0 0;1=3
P 2.14606024 2.46615 24 P 0 0;1=3
P 2.24606024 2.46615 24 P 0 0;1=3
P 2.29606024 2.46615 24 P 0 0;1=3
P 2.29606024 2.41615 24 P 0 0;1=3
P 2.24606024 2.41615 24 P 0 0;1=3
P 2.24606024 2.36615 24 P 0 0;1=3
P 2.19606024 2.36615 24 P 0 0;1=3
P 2.29606024 2.36615 24 P 0 0;1=3
P 2.39606024 2.46615 24 P 0 0;1=3
P 2.39606024 2.51615 24 P 0 0;1=3
P 2.39606024 2.56615 24 P 0 0;1=3
P 2.44606024 2.51615 24 P 0 0;1=3
P 2.49606024 2.56615 24 P 0 0;1=3
P 2.49606024 2.51615 24 P 0 0;1=3
P 2.49606024 2.46615 24 P 0 0;1=3
P 2.44606024 2.36615 24 P 0 0;1=3
P 2.49606024 2.31615 24 P 0 0;1=3
P 2.39606024 2.31615 24 P 0 0;1=3
P 2.34606024 2.36615 24 P 0 0;1=3
P 2.29606024 2.31615 24 P 0 0;1=3
P 2.24606024 2.31615 24 P 0 0;1=3
P 2.04606024 2.31615 24 P 0 0;1=3
P 2.04606024 2.16615 24 P 0 0;1=3
P 2.04606024 2.11615 24 P 0 0;1=3
P 2.04606024 1.96615 24 P 0 0;1=3
P 2.09606024 2.01615 24 P 0 0;1=3
P 2.14606024 1.96615 24 P 0 0;1=3
P 2.09606024 1.86615 24 P 0 0;1=3
P 2.19606024 1.86615 24 P 0 0;1=3
P 2.24606024 1.86615 24 P 0 0;1=3
P 2.29606024 1.86615 24 P 0 0;1=3
P 2.34606024 1.86615 24 P 0 0;1=3
P 2.24606024 1.91615 24 P 0 0;1=3
P 2.29606024 1.91615 24 P 0 0;1=3
P 2.24606024 1.96615 24 P 0 0;1=3
P 2.29606024 1.96615 24 P 0 0;1=3
P 2.19606024 2.01615 24 P 0 0;1=3
P 2.24606024 2.01615 24 P 0 0;1=3
P 2.29606024 2.01615 24 P 0 0;1=3
P 2.34606024 2.01615 24 P 0 0;1=3
P 2.39606024 1.96615 24 P 0 0;1=3
P 2.44606024 2.01615 24 P 0 0;1=3
P 2.49606024 1.96615 24 P 0 0;1=3
P 2.44606024 1.86615 24 P 0 0;1=3
P 2.49606024 2.11615 24 P 0 0;1=3
P 2.44606024 2.16615 24 P 0 0;1=3
P 2.49606024 2.16615 24 P 0 0;1=3
P 2.44606024 2.21615 24 P 0 0;1=3
P 2.39606024 2.16615 24 P 0 0;1=3
P 2.39606024 2.11615 24 P 0 0;1=3
P 2.34606024 2.16615 24 P 0 0;1=3
P 2.34606024 2.21615 24 P 0 0;1=3
P 2.29606024 2.21615 24 P 0 0;1=3
P 2.29606024 2.16615 24 P 0 0;1=3
P 2.29606024 2.06615 24 P 0 0;1=3
P 2.29606024 2.11615 24 P 0 0;1=3
P 2.24606024 2.11615 24 P 0 0;1=3
P 2.24606024 2.16615 24 P 0 0;1=3
P 2.24606024 2.06615 24 P 0 0;1=3
P 2.24606024 2.21615 24 P 0 0;1=3
P 2.29606024 2.26615 24 P 0 0;1=3
P 2.24606024 2.26615 24 P 0 0;1=3
P 2.19606024 2.21615 24 P 0 0;1=3
P 2.19606024 2.16615 24 P 0 0;1=3
P 2.14606024 2.11615 24 P 0 0;1=3
P 2.14606024 2.16615 24 P 0 0;1=3
P 2.09606024 2.21615 24 P 0 0;1=3
P 2.09606024 2.16615 24 P 0 0;1=3
P 2.09606024 2.36615 24 P 0 0;1=3
P 2.14606024 2.31615 24 P 0 0;1=3
P 1.99605974 2.71615 24 P 0 0;1=3
P 1.99605974 2.86615 24 P 0 0;1=3
P 2.04605974 2.81615 24 P 0 0;1=3
P 2.04605974 2.76615 24 P 0 0;1=3
P 3.29373976 5.023 24 P 0 0;1=4
P 2.14606024 3.26615 24 P 0 0;1=3
P 2.04606024 3.26615 24 P 0 0;1=3
P 2.04606024 3.21615 24 P 0 0;1=3
P 2.14606024 3.21615 24 P 0 0;1=3
P 2.39606024 3.21615 24 P 0 0;1=3
P 2.39606024 3.26615 24 P 0 0;1=3
P 2.29606024 3.26615 24 P 0 0;1=3
P 2.29606024 3.31615 24 P 0 0;1=3
P 2.34606024 3.36615 24 P 0 0;1=3
P 2.14606024 3.41615 24 P 0 0;1=3
P 2.09606024 3.61615 24 P 0 0;1=3
P 2.29606024 3.46615 24 P 0 0;1=3
P 2.29606024 3.41615 24 P 0 0;1=3
P 2.39606024 3.41615 24 P 0 0;1=3
P 2.34606024 3.51615 24 P 0 0;1=3
P 2.34606024 3.61615 24 P 0 0;1=3
P 2.34606024 3.56615 24 P 0 0;1=3
P 2.44606024 3.51615 24 P 0 0;1=3
P 2.44606024 3.61615 24 P 0 0;1=3
P 2.14606024 3.71615 24 P 0 0;1=3
P 2.04606024 3.71615 24 P 0 0;1=3
P 2.09606024 3.76615 24 P 0 0;1=3
P 2.14606024 3.86615 24 P 0 0;1=3
P 2.04606024 3.86615 24 P 0 0;1=3
P 2.29606024 3.71615 24 P 0 0;1=3
P 2.29606024 3.66615 24 P 0 0;1=3
P 2.39606024 3.71615 24 P 0 0;1=3
P 2.34606024 3.76615 24 P 0 0;1=3
P 2.29606024 3.81615 24 P 0 0;1=3
P 2.39606024 3.86615 24 P 0 0;1=3
P 2.29606024 3.86615 24 P 0 0;1=3
P 2.44606024 3.76615 24 P 0 0;1=3
P 2.19606024 2.86615 24 P 0 0;1=3
P 3.36460974 5.023 24 P 0 0;1=4
P 3.29374026 4.81401998 24 P 0 0;1=4
P 3.01028002 4.81401998 24 P 0 0;1=4
P 2.94141024 4.81401998 24 P 0 0;1=4
P 2.86555 4.81401998 24 P 0 0;1=4
P 2.79768002 4.81401998 24 P 0 0;1=4
P 3.15200974 5.023 24 P 0 0;1=4
P 3.08113976 5.023 24 P 0 0;1=4
P 3.01027972 5.023 24 P 0 0;1=4
P 2.93940974 5.023 24 P 0 0;1=4
P 2.86855 5.023 24 P 0 0;1=4
P 2.79767972 5.023 24 P 0 0;1=4
P 1.70395 5.023 24 P 0 0;1=4
P 1.63307972 5.023 24 P 0 0;1=4
P 1.77480974 5.023 24 P 0 0;1=4
P 1.91653976 5.023 24 P 0 0;1=4
P 1.84567972 5.023 24 P 0 0;1=4
P 1.98740974 5.023 24 P 0 0;1=4
P 2.05827972 5.023 24 P 0 0;1=4
P 2.12913976 5.023 24 P 0 0;1=4
P 2.20000974 5.023 24 P 0 0;1=4
P 2.27086998 5.023 24 P 0 0;1=4
P 2.34173976 5.023 24 P 0 0;1=4
P 1.56220974 5.023 24 P 0 0;1=4
P 1.56221024 4.81401998 24 P 0 0;1=4
P 2.06086998 4.81 24 P 0 0;1=4
P 2.41260974 5.023 24 P 0 0;1=4
P 2.41261024 4.81401998 24 P 0 0;1=4
P 2.72680974 5.023 24 P 0 0;1=4
P 2.72681024 4.81401998 24 P 0 0;1=4
P 3.57721024 4.81401998 24 P 0 0;1=4
P 3.57720974 5.023 24 P 0 0;1=4
P 4.88267972 1.91615 24 P 0 0;1=3
P 4.78267972 1.91615 24 P 0 0;1=3
P 5.03267972 2.36615 24 P 0 0;1=3
P 5.03267972 2.41615 24 P 0 0;1=3
P 4.88267972 3.66615 24 P 0 0;1=3
P 4.83267972 3.66615 24 P 0 0;1=3
P 5.03267972 3.66615 24 P 0 0;1=3
P 4.93267972 3.66615 24 P 0 0;1=3
P 4.98267972 3.66615 24 P 0 0;1=3
P 4.88267972 3.51615 24 P 0 0;1=3
P 4.83267972 3.51615 24 P 0 0;1=3
P 5.03267972 3.51615 24 P 0 0;1=3
P 4.93267972 3.51615 24 P 0 0;1=3
P 4.98267972 3.51615 24 P 0 0;1=3
P 4.88267972 3.81615 24 P 0 0;1=3
P 4.83267972 3.81615 24 P 0 0;1=3
P 4.93267972 3.81615 24 P 0 0;1=3
P 4.98267972 3.81615 24 P 0 0;1=3
P 4.88267972 3.36615 24 P 0 0;1=3
P 4.83267972 3.36615 24 P 0 0;1=3
P 5.03267972 3.36615 24 P 0 0;1=3
P 4.93267972 3.36615 24 P 0 0;1=3
P 4.98267972 3.36615 24 P 0 0;1=3
P 4.83267972 3.21615 24 P 0 0;1=3
P 4.88267972 3.21615 24 P 0 0;1=3
P 4.98267972 3.21615 24 P 0 0;1=3
P 4.93267972 3.21615 24 P 0 0;1=3
P 5.03267972 3.21615 24 P 0 0;1=3
P 4.83267972 3.06615 24 P 0 0;1=3
P 4.88267972 3.06615 24 P 0 0;1=3
P 4.98267972 3.06615 24 P 0 0;1=3
P 4.93267972 3.06615 24 P 0 0;1=3
P 5.03267972 3.06615 24 P 0 0;1=3
P 4.83267972 2.91615 24 P 0 0;1=3
P 4.88267972 2.91615 24 P 0 0;1=3
P 4.98267972 2.91615 24 P 0 0;1=3
P 4.93267972 2.91615 24 P 0 0;1=3
P 5.03267972 2.91615 24 P 0 0;1=3
P 4.78268002 2.51615 24 P 0 0;1=3
P 4.73268002 2.51615 24 P 0 0;1=3
P 4.68268002 2.51615 24 P 0 0;1=3
P 4.63268002 2.51615 24 P 0 0;1=3
P 4.58268002 2.51615 24 P 0 0;1=3
P 4.63268002 2.56615 24 P 0 0;1=3
P 4.73268002 2.56615 24 P 0 0;1=3
P 4.78268002 2.56615 24 P 0 0;1=3
P 4.78268002 2.61615 24 P 0 0;1=3
P 4.78268002 2.66615 24 P 0 0;1=3
P 4.68268002 2.66615 24 P 0 0;1=3
P 4.58268002 2.66615 24 P 0 0;1=3
P 4.73268002 2.71615 24 P 0 0;1=3
P 4.63268002 2.71615 24 P 0 0;1=3
P 4.63268002 2.76615 24 P 0 0;1=3
P 4.73268002 2.76615 24 P 0 0;1=3
P 4.78268002 2.76615 24 P 0 0;1=3
P 4.63267972 2.16615 24 P 0 0;1=3
P 4.78267972 2.16615 24 P 0 0;1=3
P 10.63660974 2.91615 24 P 0 0;1=3
P 10.58660974 2.91615 24 P 0 0;1=3
P 10.63660974 3.06615 24 P 0 0;1=3
P 10.58660974 3.06615 24 P 0 0;1=3
P 10.63660974 3.36615 24 P 0 0;1=3
P 10.58660974 3.36615 24 P 0 0;1=3
P 10.63660974 3.21615 24 P 0 0;1=3
P 10.58660974 3.21615 24 P 0 0;1=3
P 10.58660974 3.66615 24 P 0 0;1=3
P 10.63660974 3.51615 24 P 0 0;1=3
P 10.58660974 3.51615 24 P 0 0;1=3
P 10.63660974 3.81615 24 P 0 0;1=3
P 10.63660974 3.66615 24 P 0 0;1=3
P 10.58660974 3.81615 24 P 0 0;1=3
P 10.83660974 2.91615 24 P 0 0;1=3
P 10.78660974 2.91615 24 P 0 0;1=3
P 10.73660974 2.91615 24 P 0 0;1=3
P 10.68660974 2.91615 24 P 0 0;1=3
P 10.88660974 2.91615 24 P 0 0;1=3
P 10.88660974 3.06615 24 P 0 0;1=3
P 10.83660974 3.06615 24 P 0 0;1=3
P 10.78660974 3.06615 24 P 0 0;1=3
P 10.73660974 3.06615 24 P 0 0;1=3
P 10.68660974 3.06615 24 P 0 0;1=3
P 10.88660974 3.21615 24 P 0 0;1=3
P 10.83660974 3.21615 24 P 0 0;1=3
P 10.83660974 3.36615 24 P 0 0;1=3
P 10.88660974 3.36615 24 P 0 0;1=3
P 10.78660974 3.36615 24 P 0 0;1=3
P 10.73660974 3.36615 24 P 0 0;1=3
P 10.78660974 3.21615 24 P 0 0;1=3
P 10.73660974 3.21615 24 P 0 0;1=3
P 10.68660974 3.36615 24 P 0 0;1=3
P 10.68660974 3.21615 24 P 0 0;1=3
P 10.83660974 3.51615 24 P 0 0;1=3
P 10.88660974 3.51615 24 P 0 0;1=3
P 10.83660974 3.66615 24 P 0 0;1=3
P 10.78660974 3.66615 24 P 0 0;1=3
P 10.73660974 3.66615 24 P 0 0;1=3
P 10.68660974 3.66615 24 P 0 0;1=3
P 10.78660974 3.51615 24 P 0 0;1=3
P 10.73660974 3.51615 24 P 0 0;1=3
P 10.68660974 3.51615 24 P 0 0;1=3
P 10.83660974 3.81615 24 P 0 0;1=3
P 10.88660974 3.81615 24 P 0 0;1=3
P 10.88660974 3.66615 24 P 0 0;1=3
P 10.78660974 3.81615 24 P 0 0;1=3
P 10.73660974 3.81615 24 P 0 0;1=3
P 10.68660974 3.81615 24 P 0 0;1=3
P 11.03660974 2.91615 24 P 0 0;1=3
P 10.93660974 2.91615 24 P 0 0;1=3
P 10.98660974 2.91615 24 P 0 0;1=3
P 11.03660974 3.06615 24 P 0 0;1=3
P 10.93660974 3.06615 24 P 0 0;1=3
P 10.98660974 3.06615 24 P 0 0;1=3
P 11.03660974 3.21615 24 P 0 0;1=3
P 10.93660974 3.21615 24 P 0 0;1=3
P 10.98660974 3.21615 24 P 0 0;1=3
P 10.98660974 3.36615 24 P 0 0;1=3
P 10.93660974 3.36615 24 P 0 0;1=3
P 11.03660974 3.36615 24 P 0 0;1=3
P 10.98660974 3.51615 24 P 0 0;1=3
P 10.93660974 3.51615 24 P 0 0;1=3
P 11.03660974 3.51615 24 P 0 0;1=3
P 10.98660974 3.66615 24 P 0 0;1=3
P 10.93660974 3.66615 24 P 0 0;1=3
P 11.03660974 3.66615 24 P 0 0;1=3
P 10.98660974 3.81615 24 P 0 0;1=3
P 10.93660974 3.81615 24 P 0 0;1=3
P 3.07691024 4.81401998 24 P 0 0;1=4
P 8.1 1.86615 24 P 0 0;1=3
P 8.15 2.16615 24 P 0 0;1=3
P 8.15 2.11615 24 P 0 0;1=3
P 8.15 1.96615 24 P 0 0;1=3
P 8.1 2.01615 24 P 0 0;1=3
P 8.05 1.96615 24 P 0 0;1=3
P 8.05 2.11615 24 P 0 0;1=3
P 8.05 2.16615 24 P 0 0;1=3
P 8.15 2.31615 24 P 0 0;1=3
P 8.1 2.36615 24 P 0 0;1=3
P 8.1 2.16615 24 P 0 0;1=3
P 8.1 2.21615 24 P 0 0;1=3
P 8.05 2.31615 24 P 0 0;1=3
P 8.15 2.46615 24 P 0 0;1=3
P 8.15 2.56615 24 P 0 0;1=3
P 8.1 2.51615 24 P 0 0;1=3
P 8.05 2.46615 24 P 0 0;1=3
P 8.05 2.51615 24 P 0 0;1=3
P 8.05 2.56615 24 P 0 0;1=3
P 8.1 2.66615 24 P 0 0;1=3
P 8.05 2.76615 24 P 0 0;1=3
P 8.05 2.81615 24 P 0 0;1=3
P 8 2.86615 24 P 0 0;1=3
P 8 2.71615 24 P 0 0;1=3
P 8.05 2.71615 24 P 0 0;1=3
P 8.15 2.71615 24 P 0 0;1=3
P 8.05 2.86615 24 P 0 0;1=3
P 8.15 2.86615 24 P 0 0;1=3
P 8.1 2.91615 24 P 0 0;1=3
P 8.1 2.86615 24 P 0 0;1=3
P 8.1 2.81615 24 P 0 0;1=3
P 8.05 3.01615 24 P 0 0;1=3
P 8.1 3.06615 24 P 0 0;1=3
P 8.15 3.01615 24 P 0 0;1=3
P 8.15 3.16615 24 P 0 0;1=3
P 8.05 3.16615 24 P 0 0;1=3
P 8 3.41615 24 P 0 0;1=3
P 8.05 3.41615 24 P 0 0;1=3
P 8.1 3.36615 24 P 0 0;1=3
P 8.1 3.21615 24 P 0 0;1=3
P 8.15 3.56615 24 P 0 0;1=3
P 8.05 3.56615 24 P 0 0;1=3
P 8 3.56615 24 P 0 0;1=3
P 8.05 3.51615 24 P 0 0;1=3
P 8.05 3.46615 24 P 0 0;1=3
P 8.1 3.51615 24 P 0 0;1=3
P 8.35 1.86615 24 P 0 0;1=3
P 8.3 1.86615 24 P 0 0;1=3
P 8.25 1.86615 24 P 0 0;1=3
P 8.2 1.86615 24 P 0 0;1=3
P 8.25 2.06615 24 P 0 0;1=3
P 8.25 2.16615 24 P 0 0;1=3
P 8.25 2.11615 24 P 0 0;1=3
P 8.3 2.11615 24 P 0 0;1=3
P 8.3 2.06615 24 P 0 0;1=3
P 8.4 2.11615 24 P 0 0;1=3
P 8.4 2.16615 24 P 0 0;1=3
P 8.4 1.96615 24 P 0 0;1=3
P 8.35 2.01615 24 P 0 0;1=3
P 8.3 2.01615 24 P 0 0;1=3
P 8.25 2.01615 24 P 0 0;1=3
P 8.2 2.01615 24 P 0 0;1=3
P 8.3 1.96615 24 P 0 0;1=3
P 8.25 1.96615 24 P 0 0;1=3
P 8.3 1.91615 24 P 0 0;1=3
P 8.25 1.91615 24 P 0 0;1=3
P 8.2 2.16615 24 P 0 0;1=3
P 8.2 2.21615 24 P 0 0;1=3
P 8.25 2.26615 24 P 0 0;1=3
P 8.3 2.26615 24 P 0 0;1=3
P 8.25 2.21615 24 P 0 0;1=3
P 8.3 2.16615 24 P 0 0;1=3
P 8.3 2.21615 24 P 0 0;1=3
P 8.35 2.21615 24 P 0 0;1=3
P 8.35 2.16615 24 P 0 0;1=3
P 8.25 2.31615 24 P 0 0;1=3
P 8.3 2.31615 24 P 0 0;1=3
P 8.35 2.36615 24 P 0 0;1=3
P 8.4 2.31615 24 P 0 0;1=3
P 8.3 2.36615 24 P 0 0;1=3
P 8.2 2.36615 24 P 0 0;1=3
P 8.25 2.36615 24 P 0 0;1=3
P 8.25 2.41615 24 P 0 0;1=3
P 8.3 2.41615 24 P 0 0;1=3
P 8.4 2.56615 24 P 0 0;1=3
P 8.4 2.51615 24 P 0 0;1=3
P 8.4 2.46615 24 P 0 0;1=3
P 8.3 2.46615 24 P 0 0;1=3
P 8.25 2.46615 24 P 0 0;1=3
P 8.2 2.51615 24 P 0 0;1=3
P 8.25 2.51615 24 P 0 0;1=3
P 8.3 2.51615 24 P 0 0;1=3
P 8.35 2.51615 24 P 0 0;1=3
P 8.3 2.56615 24 P 0 0;1=3
P 8.3 2.61615 24 P 0 0;1=3
P 8.25 2.56615 24 P 0 0;1=3
P 8.25 2.61615 24 P 0 0;1=3
P 8.2 2.66615 24 P 0 0;1=3
P 8.25 2.66615 24 P 0 0;1=3
P 8.3 2.66615 24 P 0 0;1=3
P 8.35 2.66615 24 P 0 0;1=3
P 8.25 2.71615 24 P 0 0;1=3
P 8.3 2.71615 24 P 0 0;1=3
P 8.4 2.71615 24 P 0 0;1=3
P 8.35 2.81615 24 P 0 0;1=3
P 8.4 2.86615 24 P 0 0;1=3
P 8.3 2.91615 24 P 0 0;1=3
P 8.25 2.91615 24 P 0 0;1=3
P 8.2 2.91615 24 P 0 0;1=3
P 8.2 2.81615 24 P 0 0;1=3
P 8.25 2.81615 24 P 0 0;1=3
P 8.25 2.76615 24 P 0 0;1=3
P 8.3 2.81615 24 P 0 0;1=3
P 8.3 2.76615 24 P 0 0;1=3
P 8.35 2.91615 24 P 0 0;1=3
P 8.35 2.86615 24 P 0 0;1=3
P 8.35 3.06615 24 P 0 0;1=3
P 8.4 3.01615 24 P 0 0;1=3
P 8.2 3.06615 24 P 0 0;1=3
P 8.25 3.01615 24 P 0 0;1=3
P 8.25 2.96615 24 P 0 0;1=3
P 8.25 3.11615 24 P 0 0;1=3
P 8.25 3.06615 24 P 0 0;1=3
P 8.3 3.01615 24 P 0 0;1=3
P 8.3 2.96615 24 P 0 0;1=3
P 8.3 3.11615 24 P 0 0;1=3
P 8.3 3.06615 24 P 0 0;1=3
P 8.25 3.16615 24 P 0 0;1=3
P 8.3 3.16615 24 P 0 0;1=3
P 8.4 3.16615 24 P 0 0;1=3
P 8.25 3.41615 24 P 0 0;1=3
P 8.3 3.36615 24 P 0 0;1=3
P 8.25 3.36615 24 P 0 0;1=3
P 8.2 3.36615 24 P 0 0;1=3
P 8.25 3.31615 24 P 0 0;1=3
P 8.25 3.26615 24 P 0 0;1=3
P 8.3 3.21615 24 P 0 0;1=3
P 8.25 3.21615 24 P 0 0;1=3
P 8.2 3.21615 24 P 0 0;1=3
P 8.35 3.21615 24 P 0 0;1=3
P 8.4 3.56615 24 P 0 0;1=3
P 8.3 3.61615 24 P 0 0;1=3
P 8.25 3.66615 24 P 0 0;1=3
P 8.25 3.61615 24 P 0 0;1=3
P 8.2 3.61615 24 P 0 0;1=3
P 8.2 3.56615 24 P 0 0;1=3
P 8.2 3.51615 24 P 0 0;1=3
P 8.25 3.51615 24 P 0 0;1=3
P 8.3 3.51615 24 P 0 0;1=3
P 8.25 3.46615 24 P 0 0;1=3
P 8.25 3.86615 24 P 0 0;1=3
P 8.25 3.81615 24 P 0 0;1=3
P 8.2 3.76615 24 P 0 0;1=3
P 8.25 3.76615 24 P 0 0;1=3
P 8.3 3.76615 24 P 0 0;1=3
P 8.25 3.71615 24 P 0 0;1=3
P 8.45 1.86615 24 P 0 0;1=3
P 8.5 2.16615 24 P 0 0;1=3
P 8.5 2.11615 24 P 0 0;1=3
P 8.5 1.96615 24 P 0 0;1=3
P 8.45 2.01615 24 P 0 0;1=3
P 8.45 2.21615 24 P 0 0;1=3
P 8.45 2.16615 24 P 0 0;1=3
P 8.5 2.31615 24 P 0 0;1=3
P 8.45 2.36615 24 P 0 0;1=3
P 8.5 2.46615 24 P 0 0;1=3
P 8.5 2.51615 24 P 0 0;1=3
P 8.5 2.56615 24 P 0 0;1=3
P 8.45 2.51615 24 P 0 0;1=3
P 8.45 2.66615 24 P 0 0;1=3
P 8.5 2.71615 24 P 0 0;1=3
P 8.5 2.86615 24 P 0 0;1=3
P 8.45 2.81615 24 P 0 0;1=3
P 8.45 2.86615 24 P 0 0;1=3
P 8.45 2.91615 24 P 0 0;1=3
P 8.5 3.01615 24 P 0 0;1=3
P 8.45 3.06615 24 P 0 0;1=3
P 8.5 3.16615 24 P 0 0;1=3
P 8.5 3.41615 24 P 0 0;1=3
P 8.45 3.36615 24 P 0 0;1=3
P 8.45 3.21615 24 P 0 0;1=3
P 8.5 3.21615 24 P 0 0;1=3
P 8.5 3.26615 24 P 0 0;1=3
P 8.5 3.56615 24 P 0 0;1=3
P 8.45 3.56615 24 P 0 0;1=3
P 8.5 3.86615 24 P 0 0;1=3
P 8.5 3.71615 24 P 0 0;1=3
P 8.2 2.86615 24 P 0 0;1=3
P 8.05 3.26615 24 P 0 0;1=3
P 8.05 3.21615 24 P 0 0;1=3
P 8.3 3.26615 24 P 0 0;1=3
P 8.3 3.31615 24 P 0 0;1=3
P 8.35 3.36615 24 P 0 0;1=3
P 8.15 3.26615 24 P 0 0;1=3
P 8.15 3.21615 24 P 0 0;1=3
P 8.4 3.21615 24 P 0 0;1=3
P 8.4 3.26615 24 P 0 0;1=3
P 8.1 3.61615 24 P 0 0;1=3
P 8.3 3.46615 24 P 0 0;1=3
P 8.3 3.41615 24 P 0 0;1=3
P 8.35 3.51615 24 P 0 0;1=3
P 8.35 3.61615 24 P 0 0;1=3
P 8.35 3.56615 24 P 0 0;1=3
P 8.15 3.41615 24 P 0 0;1=3
P 8.45 3.51615 24 P 0 0;1=3
P 8.45 3.61615 24 P 0 0;1=3
P 8.4 3.41615 24 P 0 0;1=3
P 8.05 3.71615 24 P 0 0;1=3
P 8.1 3.76615 24 P 0 0;1=3
P 8.05 3.86615 24 P 0 0;1=3
P 8.3 3.71615 24 P 0 0;1=3
P 8.3 3.66615 24 P 0 0;1=3
P 8.35 3.76615 24 P 0 0;1=3
P 8.3 3.81615 24 P 0 0;1=3
P 8.3 3.86615 24 P 0 0;1=3
P 8.15 3.71615 24 P 0 0;1=3
P 8.15 3.86615 24 P 0 0;1=3
P 8.45 3.76615 24 P 0 0;1=3
P 8.4 3.71615 24 P 0 0;1=3
P 8.4 3.86615 24 P 0 0;1=3
P 3.28831004 4.68073996 24 P 0 0;1=4
P 3.22831004 4.68073996 24 P 0 0;1=4
P 3.50091004 4.62573996 24 P 0 0;1=4
P 3.44091004 4.62573996 24 P 0 0;1=4
P 7.56575 5.023 24 P 0 0;1=4
P 7.63661998 5.023 24 P 0 0;1=4
P 7.84921998 5.023 24 P 0 0;1=4
P 7.77835 5.023 24 P 0 0;1=4
P 7.70748976 5.023 24 P 0 0;1=4
P 7.92007972 5.023 24 P 0 0;1=4
P 8.06181998 5.023 24 P 0 0;1=4
P 8.13267972 5.023 24 P 0 0;1=4
P 7.99095 5.023 24 P 0 0;1=4
P 8.34527972 5.023 24 P 0 0;1=4
P 8.27440974 5.023 24 P 0 0;1=4
P 8.20355 5.023 24 P 0 0;1=4
P 8.41615 5.023 24 P 0 0;1=4
P 7.63661998 4.92 24 P 0 0;1=4
P 7.84921998 4.9207 24 P 0 0;1=4
P 7.70748976 4.9207 24 P 0 0;1=4
P 7.77835 4.9207 24 P 0 0;1=4
P 7.99095 4.9207 24 P 0 0;1=4
P 7.92007972 4.9207 24 P 0 0;1=4
P 8.06181998 4.9207 24 P 0 0;1=4
P 8.13267972 4.9207 24 P 0 0;1=4
P 8.27440974 4.9207 24 P 0 0;1=4
P 8.20355 4.9267 24 P 0 0;1=4
P 8.34527972 4.9207 24 P 0 0;1=4
P 7.63526998 4.81527028 24 P 0 0;1=4
P 7.84921998 4.81 24 P 0 0;1=4
P 7.77953976 4.812 24 P 0 0;1=4
P 7.70353976 4.812 24 P 0 0;1=4
P 8.13267972 4.81 24 P 0 0;1=4
P 8.06440974 4.81 24 P 0 0;1=4
P 7.99353976 4.81 24 P 0 0;1=4
P 7.92353976 4.81 24 P 0 0;1=4
P 8.27440974 4.81 24 P 0 0;1=4
P 8.34527972 4.81 24 P 0 0;1=4
P 8.20355 4.81 24 P 0 0;1=4
P 8.41615 4.81401998 24 P 0 0;1=4
P 8.86909026 4.81401998 24 P 0 0;1=4
P 8.73035 4.81401998 24 P 0 0;1=4
P 8.80122028 4.81401998 24 P 0 0;1=4
P 8.94495 4.81401998 24 P 0 0;1=4
P 9.08045 4.81401998 24 P 0 0;1=4
P 9.01382028 4.81401998 24 P 0 0;1=4
P 9.36815 4.81401998 24 P 0 0;1=4
P 9.29728002 4.81401998 24 P 0 0;1=4
P 9.22642028 4.81401998 24 P 0 0;1=4
P 9.15752028 4.81401998 24 P 0 0;1=4
P 9.43901024 4.81401998 24 P 0 0;1=4
P 9.50988002 4.81401998 24 P 0 0;1=4
P 9.58075 4.81401998 24 P 0 0;1=4
P 8.80121998 5.023 24 P 0 0;1=4
P 8.73035 5.023 24 P 0 0;1=4
P 8.87208976 5.023 24 P 0 0;1=4
P 9.08467972 5.023 24 P 0 0;1=4
P 9.01381998 5.023 24 P 0 0;1=4
P 8.94295 5.023 24 P 0 0;1=4
P 8.87208976 4.92 24 P 0 0;1=4
P 8.80121998 4.92 24 P 0 0;1=4
P 9.01381998 4.92 24 P 0 0;1=4
P 9.08467972 4.92 24 P 0 0;1=4
P 9.22641998 4.92 24 P 0 0;1=4
P 9.36815 4.926 24 P 0 0;1=4
P 9.50987972 4.92 24 P 0 0;1=4
P 9.43900974 4.928 24 P 0 0;1=4
P 9.36815 5.023 24 P 0 0;1=4
P 9.29727972 5.023 24 P 0 0;1=4
P 9.22641998 5.023 24 P 0 0;1=4
P 9.15555 5.023 24 P 0 0;1=4
P 9.50987972 5.023 24 P 0 0;1=4
P 9.43900974 5.023 24 P 0 0;1=4
P 9.58075 5.023 24 P 0 0;1=4
P 8.94853976 4.92 24 P 0 0;1=4
P 9.27853976 4.92 24 P 0 0;1=4
P 9.14353976 4.92 24 P 0 0;1=4
P 8.13811004 5.09223996 24 P 0 0;1=4
P 8.35071004 5.15373996 24 P 0 0;1=4
P 8.41071004 5.15373996 24 P 0 0;1=4
P 7.56575 4.81401998 24 P 0 0;1=4
P 8.88061998 4.70574026 24 P 0 0;1=4
P 2.45985 4.77875 26 P 0 0;1=9
P 1.51496998 4.77875 26 P 0 0;1=9
P 2.44016998 5.05826998 26 P 0 0;1=9
P 1.53465 5.05826998 26 P 0 0;1=9
P 3.60476998 4.77875 26 P 0 0;1=9
P 2.67956998 4.77875 26 P 0 0;1=9
P 3.60476998 5.05826998 26 P 0 0;1=9
P 2.69925 5.05826998 26 P 0 0;1=9
P 8.46338996 4.77875 26 P 0 0;1=9
P 7.51850994 4.77875 26 P 0 0;1=9
P 8.44370994 5.05826998 26 P 0 0;1=9
P 7.53818996 5.05826998 26 P 0 0;1=9
P 9.60830994 4.77875 26 P 0 0;1=9
P 8.68310994 4.77875 26 P 0 0;1=9
P 9.60830994 5.05826998 26 P 0 0;1=9
P 8.70278996 5.05826998 26 P 0 0;1=9
P 10.82676998 5.49685 27 P 0 2;1=10
P 10.99213002 5.49685 27 P 0 2;1=10
P 11.15748002 5.49685 27 P 0 2;1=10
P 11.32283996 5.49685 27 P 0 2;1=10
P 11.48818996 5.49685 27 P 0 2;1=10
P 11.65353996 5.49685 27 P 0 2;1=10
P 11.8189 5.49685 27 P 0 2;1=10
P 11.98425 5.49685 27 P 0 2;1=10
P 12.14961004 5.49685 27 P 0 2;1=11
P 10.83662028 1.37795 24 P 0 2;1=12
P 10.83661998 1.6378 24 P 0 2;1=12
P 8.25 1.6378 24 P 0 2;1=12
P 8.25 1.37795 24 P 0 2;1=12
P 6.96457008 1.39763996 24 P 0 2;1=12
P 6.96456998 1.65748002 24 P 0 2;1=12
P 6.96457028 4.0748 24 P 0 2;1=12
P 6.96456998 4.33465 24 P 0 2;1=12
P 8.25 4.09448976 24 P 0 2;1=12
P 8.25 4.35433002 24 P 0 2;1=12
P 10.83662008 4.09448996 24 P 0 2;1=12
P 10.83661998 4.35433002 24 P 0 2;1=12
P 12.12205 4.0748 24 P 0 2;1=12
P 12.12205 4.33465 24 P 0 2;1=12
P 12.12205 1.65748002 24 P 0 2;1=12
P 12.12205 1.39763976 24 P 0 2;1=12
P 11.99212972 4.20473002 24 P 0 2;1=4
P 12.03020522 4.11286004 24 P 0 2;1=4
P 12.03018002 4.2965747 24 P 0 2;1=4
P 12.21391998 4.11288524 24 P 0 2;1=4
P 12.25196998 4.20473002 24 P 0 2;1=4
P 12.21389469 4.2966 24 P 0 2;1=4
P 10.7067 4.22441024 24 P 0 2;1=4
P 10.7447752 4.13253996 24 P 0 2;1=4
P 10.74475 4.31625472 24 P 0 2;1=4
P 10.92848996 4.13256516 24 P 0 2;1=4
P 10.96653996 4.22441004 24 P 0 2;1=4
P 10.92846467 4.31628002 24 P 0 2;1=4
P 8.12007992 4.22441004 24 P 0 2;1=4
P 8.15815522 4.13253996 24 P 0 2;1=4
P 8.15813002 4.31625472 24 P 0 2;1=4
P 8.34186998 4.13256516 24 P 0 2;1=4
P 8.37991998 4.22441004 24 P 0 2;1=4
P 8.34184469 4.31628002 24 P 0 2;1=4
P 6.83465 4.20473002 24 P 0 2;1=4
P 6.8727252 4.11286004 24 P 0 2;1=4
P 6.8727 4.2965747 24 P 0 2;1=4
P 7.05643996 4.11288524 24 P 0 2;1=4
P 7.09448996 4.20473002 24 P 0 2;1=4
P 7.05641467 4.2966 24 P 0 2;1=4
P 6.83465 1.52756024 24 P 0 2;1=4
P 6.8727252 1.43568996 24 P 0 2;1=4
P 6.8727 1.61940472 24 P 0 2;1=4
P 7.05643996 1.43571516 24 P 0 2;1=4
P 7.09448996 1.52756004 24 P 0 2;1=4
P 7.05641467 1.61943002 24 P 0 2;1=4
P 8.15815522 1.416 24 P 0 2;1=4
P 8.12008002 1.50786998 24 P 0 2;1=4
P 8.15813002 1.5997247 24 P 0 2;1=4
P 8.34186998 1.4160252 24 P 0 2;1=4
P 8.34184469 1.59975 24 P 0 2;1=4
P 8.37992028 1.50786998 24 P 0 2;1=4
P 10.74475 1.5997247 24 P 0 2;1=4
P 10.92846467 1.59975 24 P 0 2;1=4
P 10.96654026 1.50786998 24 P 0 2;1=4
P 10.92848996 1.4160252 24 P 0 2;1=4
P 10.7447752 1.416 24 P 0 2;1=4
P 10.7067 1.50787028 24 P 0 2;1=4
P 12.2126 1.43700974 24 P 0 2;1=4
P 12.25196998 1.52756004 24 P 0 2;1=4
P 12.2126 1.61810974 24 P 0 2;1=4
P 12.0315 1.61810974 24 P 0 2;1=4
P 11.99213002 1.52755974 24 P 0 2;1=4
P 12.0315 1.43700974 24 P 0 2;1=4
P 4.83268002 1.37795 24 P 0 2;1=12
P 4.83267972 1.6378 24 P 0 2;1=12
P 2.24605974 1.6378 24 P 0 2;1=12
P 2.24606024 1.37795 24 P 0 2;1=12
P 0.96063002 1.39763976 24 P 0 2;1=12
P 0.96062972 1.65748002 24 P 0 2;1=12
P 0.96063002 4.0748 24 P 0 2;1=12
P 0.96062972 4.33465 24 P 0 2;1=12
P 2.24606004 4.09448996 24 P 0 2;1=12
P 2.24605974 4.35433002 24 P 0 2;1=12
P 4.83268002 4.09448976 24 P 0 2;1=12
P 4.83267972 4.35433002 24 P 0 2;1=12
P 6.11811024 4.0748 24 P 0 2;1=12
P 6.11810974 4.33465 24 P 0 2;1=12
P 6.11810974 1.65748002 24 P 0 2;1=12
P 6.11811004 1.39763996 24 P 0 2;1=12
P 5.98818976 4.20473002 24 P 0 2;1=4
P 6.02626516 4.11286004 24 P 0 2;1=4
P 6.02623996 4.2965747 24 P 0 2;1=4
P 6.20998002 4.11288524 24 P 0 2;1=4
P 6.24803002 4.20472972 24 P 0 2;1=4
P 6.20995472 4.2966 24 P 0 2;1=4
P 4.70275994 4.22441004 24 P 0 2;1=4
P 4.74083524 4.13253996 24 P 0 2;1=4
P 4.74081004 4.31625472 24 P 0 2;1=4
P 4.92455 4.13256516 24 P 0 2;1=4
P 4.9626 4.22440974 24 P 0 2;1=4
P 4.9245247 4.31628002 24 P 0 2;1=4
P 2.11613996 4.22441004 24 P 0 2;1=4
P 2.15421516 4.13253996 24 P 0 2;1=4
P 2.15418996 4.31625472 24 P 0 2;1=4
P 2.33793002 4.13256516 24 P 0 2;1=4
P 2.37598002 4.22440974 24 P 0 2;1=4
P 2.33790472 4.31628002 24 P 0 2;1=4
P 0.83070974 4.20473002 24 P 0 2;1=4
P 0.86878524 4.11286004 24 P 0 2;1=4
P 0.86876004 4.2965747 24 P 0 2;1=4
P 1.0525 4.11288524 24 P 0 2;1=4
P 1.09055 4.20472972 24 P 0 2;1=4
P 1.0524747 4.2966 24 P 0 2;1=4
P 0.83070994 1.52756004 24 P 0 2;1=4
P 0.86878524 1.43568996 24 P 0 2;1=4
P 0.86876004 1.61940472 24 P 0 2;1=4
P 1.0525 1.43571516 24 P 0 2;1=4
P 1.09055 1.52755974 24 P 0 2;1=4
P 1.0524747 1.61943002 24 P 0 2;1=4
P 2.15421516 1.416 24 P 0 2;1=4
P 2.11614006 1.50786998 24 P 0 2;1=4
P 2.15418996 1.5997247 24 P 0 2;1=4
P 2.33793002 1.4160252 24 P 0 2;1=4
P 2.33790472 1.59975 24 P 0 2;1=4
P 2.37598002 1.50786998 24 P 0 2;1=4
P 4.74081004 1.5997247 24 P 0 2;1=4
P 4.9245247 1.59975 24 P 0 2;1=4
P 4.9626 1.50786998 24 P 0 2;1=4
P 4.92455 1.4160252 24 P 0 2;1=4
P 4.74083524 1.416 24 P 0 2;1=4
P 4.70276004 1.50786998 24 P 0 2;1=4
P 6.20865994 1.43701004 24 P 0 2;1=4
P 6.24803002 1.52755974 24 P 0 2;1=4
P 6.20865994 1.61811004 24 P 0 2;1=4
P 6.02755994 1.61811004 24 P 0 2;1=4
P 5.98818996 1.52756004 24 P 0 2;1=4
P 6.02755994 1.43701004 24 P 0 2;1=4
P 12.59646998 0.8189 24 P 0 0;1=4
P 12.5571 0.72835 24 P 0 0;1=4
P 12.59646998 0.6378 24 P 0 0;1=4
P 12.68701998 0.59843002 24 P 0 0;1=12
P 12.77756998 0.6378 24 P 0 0;1=4
P 12.81693976 0.72835 24 P 0 0;1=4
P 12.77756998 0.8189 24 P 0 0;1=4
P 12.68701998 0.85827028 24 P 0 0;1=12
P 12.59646998 5.24803002 24 P 0 0;1=4
P 12.5571 5.15748002 24 P 0 0;1=4
P 12.59646998 5.06693002 24 P 0 0;1=4
P 12.68701998 5.02756004 24 P 0 0;1=12
P 12.77756998 5.06693002 24 P 0 0;1=4
P 12.81693976 5.15748002 24 P 0 0;1=4
P 12.77756998 5.24803002 24 P 0 0;1=4
P 12.68701998 5.2874 24 P 0 0;1=12
P 0.1319 5.20866024 24 P 0 0;1=4
P 0.09252992 5.11811004 24 P 0 0;1=4
P 0.1319 5.02756024 24 P 0 0;1=4
P 0.22245 4.98818976 24 P 0 0;1=12
P 0.313 5.02756024 24 P 0 0;1=4
P 0.35236998 5.11811024 24 P 0 0;1=4
P 0.313 5.20866024 24 P 0 0;1=4
P 0.22245 5.24803002 24 P 0 0;1=12
P 0.1319 0.77953002 24 P 0 0;1=4
P 0.09252972 0.68898002 24 P 0 0;1=4
P 0.1319 0.59843002 24 P 0 0;1=4
P 0.22245 0.55905974 24 P 0 0;1=12
P 0.313 0.59843002 24 P 0 0;1=4
P 0.35236998 0.68898002 24 P 0 0;1=4
P 0.313 0.77953002 24 P 0 0;1=4
P 0.22245 0.8189 24 P 0 0;1=12
P 10.80498996 5.56656004 24 P 0 0;1=4
P 10.84498996 5.56656004 24 P 0 0;1=4
P 10.80498996 5.42656004 24 P 0 0;1=4
P 10.84498996 5.42656004 24 P 0 0;1=4
P 11.01035 5.42656024 24 P 0 0;1=4
P 10.97035 5.42656024 24 P 0 0;1=4
P 11.01035 5.56656024 24 P 0 0;1=4
P 10.97035 5.56656024 24 P 0 0;1=4
P 11.17570994 5.42656004 24 P 0 0;1=4
P 11.13570994 5.42656004 24 P 0 0;1=4
P 11.17570994 5.56656004 24 P 0 0;1=4
P 11.13570994 5.56656004 24 P 0 0;1=4
P 11.34106998 5.42656024 24 P 0 0;1=4
P 11.30106998 5.42656024 24 P 0 0;1=4
P 11.34106998 5.56656024 24 P 0 0;1=4
P 11.30106998 5.56656024 24 P 0 0;1=4
P 11.50642992 5.42656004 24 P 0 0;1=4
P 11.46642992 5.42656004 24 P 0 0;1=4
P 11.50642992 5.56656004 24 P 0 0;1=4
P 11.46642992 5.56656004 24 P 0 0;1=4
P 11.67178996 5.42656004 24 P 0 0;1=4
P 11.63178996 5.42656004 24 P 0 0;1=4
P 11.67178996 5.56656004 24 P 0 0;1=4
P 11.63178996 5.56656004 24 P 0 0;1=4
P 11.83715 5.42656024 24 P 0 0;1=4
P 11.79715 5.42656024 24 P 0 0;1=4
P 11.83715 5.56656024 24 P 0 0;1=4
P 11.79715 5.56656024 24 P 0 0;1=4
P 12.00250994 5.42656004 24 P 0 0;1=4
P 11.96250994 5.42656004 24 P 0 0;1=4
P 12.00250994 5.56656004 24 P 0 0;1=4
P 11.96250994 5.56656004 24 P 0 0;1=4
P 12.16786998 5.42656024 24 P 0 0;1=4
P 12.12786998 5.42656024 24 P 0 0;1=4
P 12.16786998 5.56656024 24 P 0 0;1=4
P 12.12786998 5.56656024 24 P 0 0;1=4
P 7.32284006 0.23621998 24 P 0 0;1=4
P 7.28019518 0.33921998 24 P 0 0;1=4
P 7.17716998 0.38189026 24 P 0 0;1=13
P 7.28016998 0.13319469 24 P 0 0;1=4
P 7.17717028 0.09055 24 P 0 0;1=13
P 7.07414469 0.13321998 24 P 0 0;1=4
P 7.0315 0.23621998 24 P 0 0;1=4
P 7.07416998 0.33924518 24 P 0 0;1=4
P 7.32283976 5.7874 24 P 0 0;1=4
P 7.28019518 5.8904 24 P 0 0;1=4
P 7.17716998 5.93307028 24 P 0 0;1=13
P 7.28016998 5.6843747 24 P 0 0;1=4
P 7.17716998 5.64173002 24 P 0 0;1=13
P 7.07414469 5.6844 24 P 0 0;1=4
P 7.0315 5.7874 24 P 0 0;1=4
P 7.07416998 5.8904252 24 P 0 0;1=4
P 2.24606004 3.56615 5 P 0 0;1=3
P 8.2 3.26615 5 P 0 0;1=3
P 7.65203996 5.0535 5 P 0 0;1=3
P 2.29606004 2.86615 5 P 0 0;1=3
P 2.29606004 3.56615 5 P 0 0;1=3
P 7.69203996 5.0535 5 P 0 0;1=3
P 8.2 3.31615 5 P 0 0;1=3
P 1.33906004 4.69351004 4 P 0 0;1=0
P 0.80806998 5.46193996 4 P 0 0;1=0
P 3.733 5.075 4 P 0 0;1=4
P 1.28906004 4.69351004 4 P 0 0;1=0
P 8.2 3.41615 5 P 0 0;1=3
P 7.86465 5.169 5 P 0 0;1=3
P 3.94 4.765 4 P 0 0;1=0
P 2.34606004 3.26615 5 P 0 0;1=3
P 2.39716998 4.742 5 P 0 0;1=3
P 8.2 3.46615 5 P 0 0;1=3
P 7.90465 5.169 5 P 0 0;1=3
P 2.06646004 5.29 4 P 0 0;1=0
P 2.34606004 3.31615 5 P 0 0;1=3
P 2.35716998 4.742 5 P 0 0;1=3
P 1.33906004 5.15351004 4 P 0 0;1=0
P 3.105 4.47 4 P 0 0;1=4
P 8 3.46615 5 P 0 0;1=3
P 7.93551004 5.0535 5 P 0 0;1=3
P 2.00146004 5.29 4 P 0 0;1=0
P 2.25855 4.667 5 P 0 0;1=3
P 2.39606004 3.31615 5 P 0 0;1=3
P 1.18906004 5.15351004 4 P 0 0;1=0
P 3.07 4.42 4 P 0 0;1=4
P 8 3.51615 5 P 0 0;1=3
P 7.97551004 5.0535 5 P 0 0;1=3
P 2.21855 4.667 5 P 0 0;1=3
P 2.39606004 3.36615 5 P 0 0;1=3
P 8.11725 5.169 5 P 0 0;1=3
P 8.4 3.46615 5 P 0 0;1=3
P 3.635 0.715 4 P 0 0;1=0
P 4.63268002 2.81615 5 P 0 0;1=3
P 2.44606004 3.26615 5 P 0 0;1=3
P 2.39716998 5.115 5 P 0 0;1=3
P 8.07725 5.169 5 P 0 0;1=3
P 8.4 3.51615 5 P 0 0;1=3
P 2.44606004 3.31615 5 P 0 0;1=3
P 2.35716998 5.115 5 P 0 0;1=3
P 8.5 3.46615 5 P 0 0;1=3
P 8.07206998 4.66688996 5 P 0 0;1=3
P 2.25543996 4.78291998 5 P 0 0;1=3
P 2.49606004 3.31615 5 P 0 0;1=3
P 8.5 3.51615 5 P 0 0;1=3
P 8.03206998 4.66688996 5 P 0 0;1=3
P 4.02 4.42 4 P 0 0;1=0
P 4.58268002 2.76615 5 P 0 0;1=3
P 2.21543996 4.78291998 5 P 0 0;1=3
P 2.49606004 3.36615 5 P 0 0;1=3
P 8.35 3.41615 5 P 0 0;1=3
P 8.11725 4.78291998 5 P 0 0;1=3
P 4.78268002 2.71615 5 P 0 0;1=3
P 2.11371004 4.78291998 5 P 0 0;1=3
P 2.34606004 3.41615 5 P 0 0;1=3
P 8.35 3.46615 5 P 0 0;1=3
P 8.07725 4.78291998 5 P 0 0;1=3
P 5.08268002 2.71615 5 P 0 0;1=3
P 4.06 4.86 4 P 0 0;1=0
P 2.07371004 4.78291998 5 P 0 0;1=3
P 2.34606004 3.46615 5 P 0 0;1=3
P 2.18456998 5.0535 5 P 0 0;1=3
P 2.44606004 3.41615 5 P 0 0;1=3
P 10.93661004 2.41615 5 P 0 0;1=3
P 2.14456998 5.0535 5 P 0 0;1=3
P 2.44606004 3.46615 5 P 0 0;1=3
P 10.93661004 2.46615 5 P 0 0;1=3
P 8.5 3.31615 5 P 0 0;1=3
P 8.25898002 4.78291998 5 P 0 0;1=3
P 4.88268002 2.71615 5 P 0 0;1=3
P 2.06853002 4.66688996 5 P 0 0;1=3
P 2.49606004 3.46615 5 P 0 0;1=3
P 8.5 3.36615 5 P 0 0;1=3
P 8.21898002 4.78291998 5 P 0 0;1=3
P 2.02853002 4.66688996 5 P 0 0;1=3
P 2.49606004 3.51615 5 P 0 0;1=3
P 8.4 3.31615 5 P 0 0;1=3
P 8.26208996 4.667 5 P 0 0;1=3
P 2.11371004 5.169 5 P 0 0;1=3
P 2.39606004 3.46615 5 P 0 0;1=3
P 8.4 3.36615 5 P 0 0;1=3
P 8.22208996 4.667 5 P 0 0;1=3
P 3.84 0.69 4 P 0 0;1=0
P 4.68268002 2.76615 5 P 0 0;1=3
P 2.07371004 5.169 5 P 0 0;1=3
P 2.39606004 3.51615 5 P 0 0;1=3
P 3.56 0.49 4 P 0 0;1=0
P 4.73268002 2.81615 5 P 0 0;1=3
P 1.57765 5.169 5 P 0 0;1=3
P 2.04606004 3.31615 5 P 0 0;1=3
P 9.10853996 4.47 4 P 0 0;1=4
P 7.3426 5.15351004 4 P 0 0;1=0
P 3.785 0.69 4 P 0 0;1=0
P 4.78268002 2.81615 5 P 0 0;1=3
P 1.61765 5.169 5 P 0 0;1=3
P 2.04606004 3.36615 5 P 0 0;1=3
P 8.1 3.26615 5 P 0 0;1=3
P 7.58118996 4.707 5 P 0 0;1=3
P 2.09606004 3.26615 5 P 0 0;1=3
P 1.57765 4.707 5 P 0 0;1=3
P 5.08268002 1.96615 5 P 0 0;1=3
P 8.1 3.31615 5 P 0 0;1=3
P 7.62118996 4.707 5 P 0 0;1=3
P 3.75998996 0.345 4 P 0 0;1=0
P 4.68268002 2.81615 5 P 0 0;1=3
P 2.09606004 3.31615 5 P 0 0;1=3
P 1.61765 4.707 5 P 0 0;1=3
P 0.58 5.591 4 P 0 0;1=0
P 11.67761998 2.85 4 P 0 0;1=4
P 11.865 4.455 4 P 0 0;1=0
P 5.67368996 2.85 4 P 0 0;1=4
P 5.855 3.07 4 P 0 0;1=4
P 5.8522 2.97 4 P 0 0;1=4
P 7.2926 5.15351004 4 P 0 0;1=4
P 7.2426 5.15351004 4 P 0 0;1=4
P 7.1926 4.95351004 4 P 0 0;1=4
P 7.42603996 5.15895 4 P 0 0;1=0
P 3.94 4.655 4 P 0 0;1=4
P 3.77 4.765 4 P 0 0;1=4
P 4.14 4.745 4 P 0 0;1=4
P 4.76 5.375 4 P 0 0;1=4
P 4.96 5.5 4 P 0 0;1=4
P 5.16 5.555 4 P 0 0;1=4
P 4.892 5.767 4 P 0 0;1=4
P 5.088 5.767 4 P 0 0;1=4
P 0.91 5.075 4 P 0 0;1=4
P 1.03 4.96 4 P 0 0;1=4
P 1.03 5.155 4 P 0 0;1=4
P 1.38906004 5.15351004 4 P 0 0;1=0
P 1.23906004 5.15351004 4 P 0 0;1=4
P 1.28906004 5.15351004 4 P 0 0;1=4
P 1.18906004 4.95351004 4 P 0 0;1=4
P 0.83 5.355 4 P 0 0;1=4
P 0.9 5.355 4 P 0 0;1=4
P 0.755 5.355 4 P 0 0;1=4
P 0.73 5.205 4 P 0 0;1=4
P 0.81016004 5.17 4 P 0 0;1=4
P 1.094 5.356 4 P 0 0;1=0
P 1.044 5.448 4 P 0 0;1=4
P 1.4 5.46 4 P 0 0;1=4
P 1.32 5.46 4 P 0 0;1=4
P 1.43798996 5.46016004 4 P 0 0;1=4
P 1.35925 5.46016004 4 P 0 0;1=4
P 0.89 5.885 4 P 0 0;1=4
P 0.81 5.885 4 P 0 0;1=4
P 0.73 5.885 4 P 0 0;1=4
P 0.97 5.885 4 P 0 0;1=4
P 1.04 5.885 4 P 0 0;1=4
P 1.12 5.885 4 P 0 0;1=4
P 8.15 3.31615 5 P 0 0;1=3
P 7.65205 4.78291998 5 P 0 0;1=3
P 11.235 3.3 4 P 0 0;1=4
P 5.815 0.925 4 P 0 0;1=0
P 3.635 0.49 4 P 0 0;1=0
P 4.58268002 2.81615 5 P 0 0;1=3
P 2.19606004 3.26615 5 P 0 0;1=3
P 1.6485 5.0535 5 P 0 0;1=3
P 8.15 3.36615 5 P 0 0;1=3
P 7.69205 4.78291998 5 P 0 0;1=3
P 2.19606004 3.31615 5 P 0 0;1=3
P 1.6885 5.0535 5 P 0 0;1=3
P 8.1 3.41615 5 P 0 0;1=3
P 7.79378996 4.78291998 5 P 0 0;1=3
P 2.14606004 3.31615 5 P 0 0;1=3
P 1.64851004 4.78291998 5 P 0 0;1=3
P 8.1 3.46615 5 P 0 0;1=3
P 7.83378996 4.78291998 5 P 0 0;1=3
P 2.14606004 3.36615 5 P 0 0;1=3
P 1.68851004 4.78291998 5 P 0 0;1=3
P 0.73 4.96 4 P 0 0;1=0
P 3.795 4.6 4 P 0 0;1=4
P 4.86 5.375 4 P 0 0;1=4
P 8.15 3.46615 5 P 0 0;1=3
P 7.86465 4.657 5 P 0 0;1=3
P 2.09606004 3.41615 5 P 0 0;1=3
P 1.79025 4.78291998 5 P 0 0;1=3
P 8.15 3.51615 5 P 0 0;1=3
P 7.90465 4.657 5 P 0 0;1=3
P 2.09606004 3.46615 5 P 0 0;1=3
P 1.83025 4.78291998 5 P 0 0;1=3
P 2.19606004 3.41615 5 P 0 0;1=3
P 1.86111004 5.169 5 P 0 0;1=3
P 2.19606004 3.46615 5 P 0 0;1=3
P 1.90111004 5.169 5 P 0 0;1=3
P 6.72708996 4.5652 4 P 0 0;1=4
P 6.76208996 4.5652 4 P 0 0;1=4
P 6.79708996 4.5652 4 P 0 0;1=4
P 6.83708996 4.5652 4 P 0 0;1=0
P 6.90208996 4.5652 4 P 0 0;1=4
P 6.87208996 4.5652 4 P 0 0;1=4
P 10.99998996 4.9531 4 P 0 0;1=4
P 11.03998996 4.9531 4 P 0 0;1=4
P 10.99998996 4.9131 4 P 0 0;1=4
P 11.03998996 4.9131 4 P 0 0;1=4
P 11.21998996 4.9531 4 P 0 0;1=4
P 11.17998996 4.9531 4 P 0 0;1=4
P 11.13498996 4.9531 4 P 0 0;1=4
P 11.08498996 4.9531 4 P 0 0;1=4
P 11.21998996 4.9131 4 P 0 0;1=4
P 11.17998996 4.9131 4 P 0 0;1=4
P 11.08498996 4.9131 4 P 0 0;1=4
P 11.13498996 4.9131 4 P 0 0;1=4
P 10.99998996 5.1631 4 P 0 0;1=4
P 11.03998996 5.1631 4 P 0 0;1=4
P 10.99998996 5.1231 4 P 0 0;1=4
P 10.99998996 5.0381 4 P 0 0;1=4
P 10.99998996 5.0831 4 P 0 0;1=4
P 10.99998996 4.9931 4 P 0 0;1=4
P 11.03998996 4.9931 4 P 0 0;1=4
P 11.03998996 5.0831 4 P 0 0;1=4
P 11.03998996 5.0381 4 P 0 0;1=4
P 11.03998996 5.1231 4 P 0 0;1=4
P 11.21998996 5.1631 4 P 0 0;1=4
P 11.17998996 5.1631 4 P 0 0;1=4
P 11.08498996 5.1631 4 P 0 0;1=4
P 11.13498996 5.1631 4 P 0 0;1=4
P 11.21998996 5.1231 4 P 0 0;1=4
P 11.21998996 5.0381 4 P 0 0;1=4
P 11.21998996 5.0831 4 P 0 0;1=4
P 11.21998996 4.9931 4 P 0 0;1=4
P 11.17998996 4.9931 4 P 0 0;1=4
P 11.17998996 5.1231 4 P 0 0;1=4
P 11.17998996 5.0831 4 P 0 0;1=4
P 11.17998996 5.0381 4 P 0 0;1=4
P 11.13498996 5.1231 4 P 0 0;1=4
P 11.08498996 5.1231 4 P 0 0;1=4
P 11.6269 4.90498996 4 P 0 0;1=4
P 11.6269 4.85498996 4 P 0 0;1=4
P 11.4269 4.80998996 4 P 0 0;1=4
P 11.4269 4.85498996 4 P 0 0;1=4
P 11.4269 4.90498996 4 P 0 0;1=4
P 11.4269 4.94998996 4 P 0 0;1=4
P 11.4769 4.94998996 4 P 0 0;1=4
P 11.4769 4.80998996 4 P 0 0;1=4
P 11.5269 4.94998996 4 P 0 0;1=4
P 11.5269 4.80998996 4 P 0 0;1=4
P 11.5769 4.94998996 4 P 0 0;1=4
P 11.6269 4.94998996 4 P 0 0;1=4
P 11.6269 4.80998996 4 P 0 0;1=4
P 11.5769 4.80998996 4 P 0 0;1=4
P 10.82676998 5.71338996 12 P 0 0;1=10
P 10.99213002 5.71338996 12 P 0 0;1=10
P 11.15748002 5.71338996 12 P 0 0;1=10
P 11.32283996 5.71338996 12 P 0 0;1=10
P 11.48818996 5.71338996 12 P 0 0;1=10
P 11.65353996 5.71338996 12 P 0 0;1=10
P 11.8189 5.71338996 12 P 0 0;1=10
P 11.98425 5.71338996 12 P 0 0;1=10
P 12.14961004 5.71338996 12 P 0 0;1=10
P 10.80498996 5.7831 4 P 0 0;1=4
P 10.84498996 5.7831 4 P 0 0;1=4
P 10.80498996 5.6431 4 P 0 0;1=4
P 10.84498996 5.6431 4 P 0 0;1=4
P 11.01035 5.6431 4 P 0 0;1=4
P 10.97035 5.6431 4 P 0 0;1=4
P 11.01035 5.7831 4 P 0 0;1=4
P 10.97035 5.7831 4 P 0 0;1=4
P 11.17571004 5.6431 4 P 0 0;1=4
P 11.13571004 5.6431 4 P 0 0;1=4
P 11.17571004 5.7831 4 P 0 0;1=4
P 11.13571004 5.7831 4 P 0 0;1=4
P 11.34106998 5.6431 4 P 0 0;1=4
P 11.30106998 5.6431 4 P 0 0;1=4
P 11.34106998 5.7831 4 P 0 0;1=4
P 11.30106998 5.7831 4 P 0 0;1=4
P 11.50643002 5.6431 4 P 0 0;1=4
P 11.46643002 5.6431 4 P 0 0;1=4
P 11.50643002 5.7831 4 P 0 0;1=4
P 11.46643002 5.7831 4 P 0 0;1=4
P 11.67178996 5.6431 4 P 0 0;1=4
P 11.63178996 5.6431 4 P 0 0;1=4
P 11.67178996 5.7831 4 P 0 0;1=4
P 11.63178996 5.7831 4 P 0 0;1=4
P 11.83715 5.6431 4 P 0 0;1=4
P 11.79715 5.6431 4 P 0 0;1=4
P 11.83715 5.7831 4 P 0 0;1=4
P 11.79715 5.7831 4 P 0 0;1=4
P 12.00251004 5.6431 4 P 0 0;1=4
P 11.96251004 5.6431 4 P 0 0;1=4
P 12.00251004 5.7831 4 P 0 0;1=4
P 11.96251004 5.7831 4 P 0 0;1=4
P 12.16786998 5.6431 4 P 0 0;1=4
P 12.12786998 5.6431 4 P 0 0;1=4
P 12.16786998 5.7831 4 P 0 0;1=4
P 12.12786998 5.7831 4 P 0 0;1=4
P 5.03605 5.1631 4 P 0 0;1=4
P 5.03605 4.9931 4 P 0 0;1=4
P 5.03605 5.0831 4 P 0 0;1=4
P 5.03605 5.0381 4 P 0 0;1=4
P 5.03605 5.1231 4 P 0 0;1=4
P 5.21605 5.1631 4 P 0 0;1=4
P 5.17605 5.1631 4 P 0 0;1=4
P 5.08105 5.1631 4 P 0 0;1=4
P 5.13105 5.1631 4 P 0 0;1=4
P 5.21605 5.1231 4 P 0 0;1=4
P 5.21605 5.0381 4 P 0 0;1=4
P 5.21605 5.0831 4 P 0 0;1=4
P 5.21605 4.9931 4 P 0 0;1=4
P 5.17605 4.9931 4 P 0 0;1=4
P 5.17605 5.1231 4 P 0 0;1=4
P 5.17605 5.0831 4 P 0 0;1=4
P 5.17605 5.0381 4 P 0 0;1=4
P 5.13105 5.1231 4 P 0 0;1=4
P 5.08105 5.1231 4 P 0 0;1=4
P 4.99605 5.1631 4 P 0 0;1=4
P 4.99605 5.1231 4 P 0 0;1=4
P 4.99605 5.0381 4 P 0 0;1=4
P 4.99605 5.0831 4 P 0 0;1=4
P 4.99605 4.9931 4 P 0 0;1=4
P 5.03605 4.9531 4 P 0 0;1=4
P 5.03605 4.9131 4 P 0 0;1=4
P 5.21605 4.9531 4 P 0 0;1=4
P 5.17605 4.9531 4 P 0 0;1=4
P 5.13105 4.9531 4 P 0 0;1=4
P 5.08105 4.9531 4 P 0 0;1=4
P 5.21605 4.9131 4 P 0 0;1=4
P 5.17605 4.9131 4 P 0 0;1=4
P 5.08105 4.9131 4 P 0 0;1=4
P 5.13105 4.9131 4 P 0 0;1=4
P 4.99605 4.9531 4 P 0 0;1=4
P 4.99605 4.9131 4 P 0 0;1=4
P 6.34948996 5.03 4 P 0 0;1=4
P 2.74225 5.14 5 P 0 0;1=3
P 2.04606004 3.61615 5 P 0 0;1=3
P 2.14606004 3.46615 5 P 0 0;1=3
P 1.86111004 4.657 5 P 0 0;1=3
P 2.78225 5.14 5 P 0 0;1=3
P 2.04606004 3.66615 5 P 0 0;1=3
P 2.14606004 3.51615 5 P 0 0;1=3
P 1.90111004 4.657 5 P 0 0;1=3
P 1.93196998 5.0535 5 P 0 0;1=3
P 1.99606004 3.46615 5 P 0 0;1=3
P 4.58268002 2.56615 5 P 0 0;1=3
P 1.97196998 5.0535 5 P 0 0;1=3
P 1.99606004 3.51615 5 P 0 0;1=3
P 2.88086998 5.17001998 5 P 0 0;1=3
P 2.14606004 3.61615 5 P 0 0;1=3
P 2.34606004 3.66615 5 P 0 0;1=3
P 3.56176998 4.71973002 5 P 0 0;1=3
P 2.92086998 5.17001998 5 P 0 0;1=3
P 2.14606004 3.66615 5 P 0 0;1=3
P 2.34606004 3.71615 5 P 0 0;1=3
P 3.52176998 4.71973002 5 P 0 0;1=3
P 2.39606004 3.61615 5 P 0 0;1=3
P 3.49091004 4.587 5 P 0 0;1=3
P 2.39606004 3.66615 5 P 0 0;1=3
P 3.45091004 4.587 5 P 0 0;1=3
P 2.49606004 3.61615 5 P 0 0;1=3
P 3.56176998 5.14 5 P 0 0;1=3
P 2.49606004 3.66615 5 P 0 0;1=3
P 3.52176998 5.14 5 P 0 0;1=3
P 2.44606004 3.66615 5 P 0 0;1=3
P 3.42003996 4.78291998 5 P 0 0;1=3
P 4.30605 4.6631 4 P 0 0;1=4
P 4.34105 4.6431 4 P 0 0;1=4
P 4.38605 4.6431 4 P 0 0;1=4
P 4.42605 4.6631 4 P 0 0;1=4
P 4.46605 4.6631 4 P 0 0;1=4
P 4.30605 4.7031 4 P 0 0;1=4
P 4.42605 4.7031 4 P 0 0;1=4
P 4.46605 4.7031 4 P 0 0;1=4
P 4.26605 4.6631 4 P 0 0;1=4
P 4.26605 4.7031 4 P 0 0;1=4
P 4.65605 4.6631 4 P 0 0;1=4
P 4.69605 4.6631 4 P 0 0;1=4
P 4.65605 4.7031 4 P 0 0;1=4
P 4.69605 4.7031 4 P 0 0;1=4
P 4.73105 4.6431 4 P 0 0;1=4
P 4.81605 4.6631 4 P 0 0;1=4
P 4.85605 4.6631 4 P 0 0;1=4
P 4.81605 4.7031 4 P 0 0;1=4
P 4.85605 4.7031 4 P 0 0;1=4
P 4.77605 4.6431 4 P 0 0;1=4
P 5.17605 4.7131 4 P 0 0;1=4
P 5.17605 4.6731 4 P 0 0;1=4
P 5.08105 4.6731 4 P 0 0;1=4
P 5.13105 4.6731 4 P 0 0;1=4
P 5.03605 4.6731 4 P 0 0;1=4
P 5.03605 4.7131 4 P 0 0;1=4
P 4.30605 4.7481 4 P 0 0;1=4
P 4.30605 4.7931 4 P 0 0;1=4
P 4.30605 4.8381 4 P 0 0;1=4
P 4.38605 4.8381 4 P 0 0;1=4
P 4.34605 4.8381 4 P 0 0;1=4
P 4.46605 4.8381 4 P 0 0;1=4
P 4.42605 4.8381 4 P 0 0;1=4
P 4.42605 4.7931 4 P 0 0;1=4
P 4.42605 4.7481 4 P 0 0;1=4
P 4.46605 4.7931 4 P 0 0;1=4
P 4.46605 4.7481 4 P 0 0;1=4
P 4.26605 4.7481 4 P 0 0;1=4
P 4.26605 4.7931 4 P 0 0;1=4
P 4.26605 4.8381 4 P 0 0;1=4
P 4.65605 4.8381 4 P 0 0;1=4
P 4.65605 4.7931 4 P 0 0;1=4
P 4.65605 4.7481 4 P 0 0;1=4
P 4.69605 4.8381 4 P 0 0;1=4
P 4.69605 4.7931 4 P 0 0;1=4
P 4.69605 4.7481 4 P 0 0;1=4
P 4.73605 4.8381 4 P 0 0;1=4
P 4.81605 4.8381 4 P 0 0;1=4
P 4.81605 4.7931 4 P 0 0;1=4
P 4.81605 4.7481 4 P 0 0;1=4
P 4.85605 4.8381 4 P 0 0;1=4
P 4.85605 4.7931 4 P 0 0;1=4
P 4.85605 4.7481 4 P 0 0;1=4
P 4.77605 4.8381 4 P 0 0;1=4
P 5.08105 4.8431 4 P 0 0;1=4
P 5.13105 4.8431 4 P 0 0;1=4
P 5.17605 4.8431 4 P 0 0;1=4
P 5.17605 4.8031 4 P 0 0;1=4
P 5.17605 4.7581 4 P 0 0;1=4
P 5.03605 4.8431 4 P 0 0;1=4
P 5.03605 4.8031 4 P 0 0;1=4
P 5.03605 4.7581 4 P 0 0;1=4
P 4.58268002 2.96615 5 P 0 0;1=3
P 4.63268002 2.96615 5 P 0 0;1=3
P 4.63268002 3.11615 5 P 0 0;1=3
P 4.58268002 3.01615 5 P 0 0;1=3
P 4.58268002 3.11615 5 P 0 0;1=3
P 4.63268002 3.01615 5 P 0 0;1=3
P 4.63268002 3.31615 5 P 0 0;1=3
P 4.58268002 3.26615 5 P 0 0;1=3
P 4.58268002 3.31615 5 P 0 0;1=3
P 4.63268002 3.26615 5 P 0 0;1=3
P 4.63268002 3.16615 5 P 0 0;1=3
P 4.58268002 3.16615 5 P 0 0;1=3
P 4.58268002 3.46615 5 P 0 0;1=3
P 4.63268002 3.41615 5 P 0 0;1=3
P 4.63268002 3.46615 5 P 0 0;1=3
P 4.58268002 3.41615 5 P 0 0;1=3
P 4.58268002 3.61615 5 P 0 0;1=3
P 4.58268002 3.56615 5 P 0 0;1=3
P 4.63268002 3.61615 5 P 0 0;1=3
P 4.63268002 3.56615 5 P 0 0;1=3
P 4.58268002 3.71615 5 P 0 0;1=3
P 4.63268002 3.71615 5 P 0 0;1=3
P 4.58268002 3.76615 5 P 0 0;1=3
P 4.58268002 3.86615 5 P 0 0;1=3
P 4.63268002 3.76615 5 P 0 0;1=3
P 4.63268002 3.86615 5 P 0 0;1=3
P 4.68268002 2.96615 5 P 0 0;1=3
P 4.73268002 2.96615 5 P 0 0;1=3
P 4.78268002 2.96615 5 P 0 0;1=3
P 4.68268002 3.11615 5 P 0 0;1=3
P 4.68268002 3.01615 5 P 0 0;1=3
P 4.73268002 3.11615 5 P 0 0;1=3
P 4.73268002 3.01615 5 P 0 0;1=3
P 4.78268002 3.11615 5 P 0 0;1=3
P 4.78268002 3.01615 5 P 0 0;1=3
P 4.73268002 3.31615 5 P 0 0;1=3
P 4.73268002 3.26615 5 P 0 0;1=3
P 4.68268002 3.26615 5 P 0 0;1=3
P 4.68268002 3.31615 5 P 0 0;1=3
P 4.78268002 3.26615 5 P 0 0;1=3
P 4.78268002 3.31615 5 P 0 0;1=3
P 4.73268002 3.16615 5 P 0 0;1=3
P 4.68268002 3.16615 5 P 0 0;1=3
P 4.78268002 3.16615 5 P 0 0;1=3
P 4.73268002 3.41615 5 P 0 0;1=3
P 4.68268002 3.41615 5 P 0 0;1=3
P 4.68268002 3.46615 5 P 0 0;1=3
P 4.73268002 3.46615 5 P 0 0;1=3
P 4.78268002 3.46615 5 P 0 0;1=3
P 4.78268002 3.41615 5 P 0 0;1=3
P 4.73268002 3.56615 5 P 0 0;1=3
P 4.73268002 3.61615 5 P 0 0;1=3
P 4.68268002 3.56615 5 P 0 0;1=3
P 4.68268002 3.61615 5 P 0 0;1=3
P 4.78268002 3.61615 5 P 0 0;1=3
P 4.78268002 3.56615 5 P 0 0;1=3
P 4.73268002 3.71615 5 P 0 0;1=3
P 4.68268002 3.71615 5 P 0 0;1=3
P 4.78268002 3.71615 5 P 0 0;1=3
P 4.73268002 3.76615 5 P 0 0;1=3
P 4.73268002 3.86615 5 P 0 0;1=3
P 4.68268002 3.76615 5 P 0 0;1=3
P 4.68268002 3.86615 5 P 0 0;1=3
P 4.78268002 3.76615 5 P 0 0;1=3
P 4.78268002 3.86615 5 P 0 0;1=3
P 4.88268002 3.86615 5 P 0 0;1=3
P 4.83268002 3.86615 5 P 0 0;1=3
P 5.03268002 3.86615 5 P 0 0;1=3
P 4.93268002 3.86615 5 P 0 0;1=3
P 4.98268002 3.86615 5 P 0 0;1=3
P 4.88268002 3.76615 5 P 0 0;1=3
P 4.83268002 3.76615 5 P 0 0;1=3
P 5.03268002 3.76615 5 P 0 0;1=3
P 4.93268002 3.76615 5 P 0 0;1=3
P 4.98268002 3.76615 5 P 0 0;1=3
P 4.88268002 3.71615 5 P 0 0;1=3
P 4.83268002 3.71615 5 P 0 0;1=3
P 5.03268002 3.71615 5 P 0 0;1=3
P 4.93268002 3.71615 5 P 0 0;1=3
P 4.98268002 3.71615 5 P 0 0;1=3
P 4.88268002 3.61615 5 P 0 0;1=3
P 4.83268002 3.61615 5 P 0 0;1=3
P 5.03268002 3.61615 5 P 0 0;1=3
P 4.93268002 3.61615 5 P 0 0;1=3
P 4.98268002 3.61615 5 P 0 0;1=3
P 4.88268002 3.56615 5 P 0 0;1=3
P 4.83268002 3.56615 5 P 0 0;1=3
P 5.03268002 3.56615 5 P 0 0;1=3
P 4.93268002 3.56615 5 P 0 0;1=3
P 4.98268002 3.56615 5 P 0 0;1=3
P 4.88268002 3.46615 5 P 0 0;1=3
P 4.83268002 3.46615 5 P 0 0;1=3
P 5.03268002 3.46615 5 P 0 0;1=3
P 4.93268002 3.46615 5 P 0 0;1=3
P 4.98268002 3.46615 5 P 0 0;1=3
P 4.88268002 3.41615 5 P 0 0;1=3
P 4.83268002 3.41615 5 P 0 0;1=3
P 5.03268002 3.41615 5 P 0 0;1=3
P 4.93268002 3.41615 5 P 0 0;1=3
P 4.98268002 3.41615 5 P 0 0;1=3
P 4.88268002 3.31615 5 P 0 0;1=3
P 4.83268002 3.31615 5 P 0 0;1=3
P 5.03268002 3.31615 5 P 0 0;1=3
P 4.93268002 3.31615 5 P 0 0;1=3
P 4.98268002 3.31615 5 P 0 0;1=3
P 4.83268002 3.26615 5 P 0 0;1=3
P 4.88268002 3.26615 5 P 0 0;1=3
P 4.98268002 3.26615 5 P 0 0;1=3
P 4.93268002 3.26615 5 P 0 0;1=3
P 5.03268002 3.26615 5 P 0 0;1=3
P 4.83268002 3.16615 5 P 0 0;1=3
P 4.88268002 3.16615 5 P 0 0;1=3
P 4.98268002 3.16615 5 P 0 0;1=3
P 4.93268002 3.16615 5 P 0 0;1=3
P 5.03268002 3.16615 5 P 0 0;1=3
P 4.83268002 3.11615 5 P 0 0;1=3
P 4.88268002 3.11615 5 P 0 0;1=3
P 4.98268002 3.11615 5 P 0 0;1=3
P 4.93268002 3.11615 5 P 0 0;1=3
P 5.03268002 3.11615 5 P 0 0;1=3
P 4.83268002 3.01615 5 P 0 0;1=3
P 4.88268002 3.01615 5 P 0 0;1=3
P 4.98268002 3.01615 5 P 0 0;1=3
P 4.93268002 3.01615 5 P 0 0;1=3
P 5.03268002 3.01615 5 P 0 0;1=3
P 4.83268002 2.96615 5 P 0 0;1=3
P 4.88268002 2.96615 5 P 0 0;1=3
P 4.98268002 2.96615 5 P 0 0;1=3
P 4.93268002 2.96615 5 P 0 0;1=3
P 5.03268002 2.96615 5 P 0 0;1=3
P 2.44606004 3.71615 5 P 0 0;1=3
P 3.38003996 4.78291998 5 P 0 0;1=3
P 2.19606004 3.81615 5 P 0 0;1=3
P 3.02571004 4.667 5 P 0 0;1=3
P 2.19606004 3.86615 5 P 0 0;1=3
P 3.06571004 4.667 5 P 0 0;1=3
P 3.27831004 4.642 5 P 0 0;1=3
P 2.39606004 3.76615 5 P 0 0;1=3
P 4.73268002 2.66615 5 P 0 0;1=3
P 10.73661004 2.66615 5 P 0 0;1=3
P 3.23831004 4.642 5 P 0 0;1=3
P 2.39606004 3.81615 5 P 0 0;1=3
P 5.03268002 2.61615 5 P 0 0;1=3
P 3.34916998 5.1035 5 P 0 0;1=3
P 2.49606004 3.76615 5 P 0 0;1=3
P 3.30916998 5.1035 5 P 0 0;1=3
P 2.49606004 3.81615 5 P 0 0;1=3
P 11.03661004 2.61615 5 P 0 0;1=3
P 2.74225 4.667 5 P 0 0;1=3
P 2.09606004 3.66615 5 P 0 0;1=3
P 2.44606004 3.81615 5 P 0 0;1=3
P 3.20743996 4.78291998 5 P 0 0;1=3
P 2.78225 4.667 5 P 0 0;1=3
P 2.09606004 3.71615 5 P 0 0;1=3
P 2.44606004 3.86615 5 P 0 0;1=3
P 3.16743996 4.78291998 5 P 0 0;1=3
P 2.34606004 3.81615 5 P 0 0;1=3
P 3.27831004 5.22001998 5 P 0 0;1=3
P 2.34606004 3.86615 5 P 0 0;1=3
P 3.23831004 5.22001998 5 P 0 0;1=3
P 4.63268002 2.61615 5 P 0 0;1=3
P 10.98661004 2.61615 5 P 0 0;1=3
P 2.19606004 3.66615 5 P 0 0;1=3
P 2.81311004 4.78291998 5 P 0 0;1=3
P 10.98661004 2.56615 5 P 0 0;1=3
P 2.19606004 3.71615 5 P 0 0;1=3
P 2.85311004 4.78291998 5 P 0 0;1=3
P 0.64808996 1.655 4 P 0 0;1=4
P 5.76 2.66 4 P 0 0;1=0
P 10.63661004 2.61615 5 P 0 0;1=3
P 2.09606004 3.81615 5 P 0 0;1=3
P 3.09656998 5.0535 5 P 0 0;1=3
P 2.09606004 3.86615 5 P 0 0;1=3
P 3.13656998 5.0535 5 P 0 0;1=3
P 2.88708002 4.667 5 P 0 0;1=3
P 2.04606004 3.76615 5 P 0 0;1=3
P 10.73661004 2.61615 5 P 0 0;1=3
P 2.92708002 4.667 5 P 0 0;1=3
P 2.04606004 3.81615 5 P 0 0;1=3
P 10.68661004 2.61615 5 P 0 0;1=3
P 5.03268002 2.46615 5 P 0 0;1=3
P 5.03268002 2.51615 5 P 0 0;1=3
P 11.08661004 2.56615 5 P 0 0;1=3
P 10.68661004 2.56615 5 P 0 0;1=3
P 9.175 5.255 4 P 0 0;1=0
P 4.73268002 2.61615 5 P 0 0;1=3
P 9.11853996 5.255 4 P 0 0;1=0
P 5.08268002 2.41615 5 P 0 0;1=3
P 10.93661004 2.66615 5 P 0 0;1=3
P 10.58661004 2.61615 5 P 0 0;1=3
P 8.15 3.76615 5 P 0 0;1=3
P 9.02925 5.165 5 P 0 0;1=3
P 4.98268002 2.21615 5 P 0 0;1=3
P 10.58661004 2.56615 5 P 0 0;1=3
P 8.15 3.81615 5 P 0 0;1=3
P 9.06925 5.165 5 P 0 0;1=3
P 11.03661004 2.66615 5 P 0 0;1=3
P 4.98268002 2.26615 5 P 0 0;1=3
P 10.93661004 2.61615 5 P 0 0;1=3
P 5.03268002 2.26615 5 P 0 0;1=3
P 11.08661004 2.61615 5 P 0 0;1=3
P 5.03268002 2.31615 5 P 0 0;1=3
P 10.63661004 2.66615 5 P 0 0;1=3
P 3.775 5.295 4 P 0 0;1=0
P 0.73 5.78 4 P 0 0;1=4
P 8.07 5.29 4 P 0 0;1=0
P 3.8399 4.765 4 P 0 0;1=0
P 0.81 5.78 4 P 0 0;1=4
P 8.005 5.29 4 P 0 0;1=0
P 11.08661004 1.91615 5 P 0 0;1=3
P 4.98268002 1.91615 5 P 0 0;1=3
P 4.98268002 1.96615 5 P 0 0;1=3
P 4.93268002 1.86615 5 P 0 0;1=3
P 4.93268002 1.91615 5 P 0 0;1=3
P 5.03268002 1.86615 5 P 0 0;1=3
P 5.08268002 1.91615 5 P 0 0;1=3
P 5.08268002 2.56615 5 P 0 0;1=3
P 8.15 2.51615 5 P 0 0;1=3
P 4.98268002 2.61615 5 P 0 0;1=3
P 10.68661004 2.71615 5 P 0 0;1=3
P 10.98661004 2.71615 5 P 0 0;1=3
P 10.78661004 2.71615 5 P 0 0;1=3
P 4.93268002 2.66615 5 P 0 0;1=3
P 10.88661004 2.71615 5 P 0 0;1=3
P 10.68661004 2.76615 5 P 0 0;1=3
P 9.64 0.71 4 P 0 0;1=0
P 10.58661004 2.81615 5 P 0 0;1=3
P 9.43296004 0.49133002 4 P 0 0;1=0
P 9.43296004 0.73633002 4 P 0 0;1=0
P 10.63661004 2.81615 5 P 0 0;1=3
P 4.68268002 2.56615 5 P 0 0;1=3
P 10.68661004 2.81615 5 P 0 0;1=3
P 9.55795 0.36633002 4 P 0 0;1=0
P 10.73661004 2.81615 5 P 0 0;1=3
P 9.35796004 0.49133002 4 P 0 0;1=0
P 5.03268002 2.66615 5 P 0 0;1=3
P 10.78661004 2.81615 5 P 0 0;1=3
P 9.58296004 0.71133002 4 P 0 0;1=0
P 5.08268002 2.61615 5 P 0 0;1=3
P 11.08661004 1.96615 5 P 0 0;1=3
P 11.03661004 1.86615 5 P 0 0;1=3
P 11.03661004 1.91615 5 P 0 0;1=3
P 10.93661004 1.86615 5 P 0 0;1=3
P 10.93661004 1.91615 5 P 0 0;1=3
P 10.98661004 1.91615 5 P 0 0;1=3
P 10.98661004 1.96615 5 P 0 0;1=3
P 4.93268002 2.61615 5 P 0 0;1=3
P 11.03661004 2.01615 5 P 0 0;1=3
P 11.03661004 2.06615 5 P 0 0;1=3
P 10.93661004 2.01615 5 P 0 0;1=3
P 10.93661004 2.06615 5 P 0 0;1=3
P 10.98661004 2.06615 5 P 0 0;1=3
P 10.98661004 2.11615 5 P 0 0;1=3
P 11.08661004 2.06615 5 P 0 0;1=3
P 11.08661004 2.11615 5 P 0 0;1=3
P 3.115 5.255 4 P 0 0;1=0
P 4.63268002 2.66615 5 P 0 0;1=3
P 11.08661004 2.21615 5 P 0 0;1=3
P 4.98268002 2.56615 5 P 0 0;1=3
P 11.08661004 2.26615 5 P 0 0;1=3
P 11.03661004 2.26615 5 P 0 0;1=3
P 2.14606004 3.76615 5 P 0 0;1=3
P 3.02571004 5.165 5 P 0 0;1=3
P 11.03661004 2.31615 5 P 0 0;1=3
P 10.98661004 2.21615 5 P 0 0;1=3
P 10.98661004 2.26615 5 P 0 0;1=3
P 3.17146004 5.255 4 P 0 0;1=0
P 4.68268002 2.61615 5 P 0 0;1=3
P 10.93661004 2.26615 5 P 0 0;1=3
P 10.58661004 2.76615 5 P 0 0;1=3
P 4 5.29 4 P 0 0;1=0
P 10.93661004 2.31615 5 P 0 0;1=3
P 10.88661004 2.16615 5 P 0 0;1=3
P 10.73661004 1.91615 5 P 0 0;1=3
P 10.395 1.28555 5 P 0 0;1=3
P 12.81495 1.96456998 10 P 0 0;1=1
P 9.42358002 5.22001998 5 P 0 0;1=3
P 8.98115 2.825 5 P 0 0;1=3
P 4.58268002 2.61615 5 P 0 0;1=3
P 9.38358002 5.22001998 5 P 0 0;1=3
P 8.98115 2.865 5 P 0 0;1=3
P 2.14606004 3.81615 5 P 0 0;1=3
P 3.06571004 5.165 5 P 0 0;1=3
P 11.08661004 2.71615 5 P 0 0;1=3
P 3.985 4.88998996 4 P 0 0;1=0
P 11.73316004 2.652 5 P 0 0;1=3
P 12.55905 4.40551004 10 P 0 0;1=1
P 11.73316004 2.612 5 P 0 0;1=3
P 12.63778996 4.44488002 10 P 0 0;1=1
P 8.3 2.86615 5 P 0 0;1=3
P 4.83268002 2.16615 5 P 0 0;1=3
P 0.69348996 1.90611998 5 P 0 0;1=3
P 11.73316004 2.492 5 P 0 0;1=3
P 12.55905 4.24803002 10 P 0 0;1=1
P 4.88268002 2.16615 5 P 0 0;1=3
P 0.69348996 1.86611998 5 P 0 0;1=3
P 11.73316004 2.452 5 P 0 0;1=3
P 12.63778996 4.2874 10 P 0 0;1=1
P 8.25 2.86615 5 P 0 0;1=3
P 12.55905 3.93306998 10 P 0 0;1=1
P 11.73316004 2.332 5 P 0 0;1=3
P 12.63778996 3.97243996 10 P 0 0;1=1
P 11.73316004 2.292 5 P 0 0;1=3
P 10.83661004 2.16615 5 P 0 0;1=3
P 11.53316004 2.092 5 P 0 0;1=3
P 12.55905 3.77558996 10 P 0 0;1=1
P 11.53316004 2.052 5 P 0 0;1=3
P 12.63778996 3.81496004 10 P 0 0;1=1
P 12.81495 3.53936998 10 P 0 0;1=1
P 10.68661004 2.26615 5 P 0 0;1=3
P 9.975 2.3758 5 P 0 0;1=3
P 12.81495 3.38188996 10 P 0 0;1=1
P 10.73661004 2.31615 5 P 0 0;1=3
P 9.975 2.23955 5 P 0 0;1=3
P 12.81495 2.20078996 10 P 0 0;1=1
P 10.68661004 1.91615 5 P 0 0;1=3
P 10.42445 1.395 5 P 0 0;1=3
P 12.81495 2.75196998 10 P 0 0;1=1
P 10.73661004 2.01615 5 P 0 0;1=3
P 10.26025 1.82845 5 P 0 0;1=3
P 12.73621004 3.73621998 10 P 0 0;1=1
P 10.58661004 2.21615 5 P 0 0;1=3
P 10.09 2.26825 5 P 0 0;1=3
P 10.73661004 2.41615 5 P 0 0;1=3
P 10.09 2.69655 5 P 0 0;1=3
P 12.73621004 4.52361998 10 P 0 0;1=1
P 7.3426 4.69351004 4 P 0 0;1=0
P 11.73316004 1.532 5 P 0 0;1=3
P 12.55905 2.27953002 10 P 0 0;1=1
P 7.2926 4.69351004 4 P 0 0;1=0
P 12.73621004 3.57873996 10 P 0 0;1=1
P 10.68661004 2.21615 5 P 0 0;1=3
P 9.975 2.3358 5 P 0 0;1=3
P 12.73621004 3.42126004 10 P 0 0;1=1
P 10.73661004 2.26615 5 P 0 0;1=3
P 9.975 2.19955 5 P 0 0;1=3
P 11.73316004 2.172 5 P 0 0;1=3
P 12.55905 3.46063002 10 P 0 0;1=1
P 4.98268002 2.36615 5 P 0 0;1=3
P 10.73661004 1.86615 5 P 0 0;1=3
P 10.395 1.32555 5 P 0 0;1=3
P 12.73621004 2.00393996 10 P 0 0;1=1
P 11.73316004 2.132 5 P 0 0;1=3
P 12.63778996 3.5 10 P 0 0;1=1
P 3.38003996 5.22001998 5 P 0 0;1=3
P 2.97721004 2.865 5 P 0 0;1=3
P 4.98268002 2.41615 5 P 0 0;1=3
P 12.63778996 1.76771998 10 P 0 0;1=1
P 3.42003996 5.22001998 5 P 0 0;1=3
P 2.97721004 2.825 5 P 0 0;1=3
P 4.88268002 2.81615 5 P 0 0;1=3
P 4.93268002 2.81615 5 P 0 0;1=3
P 4.98268002 2.81615 5 P 0 0;1=3
P 5.03268002 2.81615 5 P 0 0;1=3
P 5.08268002 2.81615 5 P 0 0;1=3
P 11.03661004 2.81615 5 P 0 0;1=3
P 11.08661004 2.81615 5 P 0 0;1=3
P 10.98661004 2.81615 5 P 0 0;1=3
P 10.93661004 2.81615 5 P 0 0;1=3
P 10.88661004 2.81615 5 P 0 0;1=3
P 5.27886004 3.0214 4 P 0 0;1=4
P 5.27886004 3.0564 4 P 0 0;1=4
P 5.27886004 3.1014 4 P 0 0;1=4
P 5.27886004 3.1364 4 P 0 0;1=4
P 5.27886004 2.9764 4 P 0 0;1=4
P 5.27886004 2.9414 4 P 0 0;1=4
P 5.27886004 3.2614 4 P 0 0;1=4
P 5.27886004 3.2964 4 P 0 0;1=4
P 5.27886004 3.2164 4 P 0 0;1=4
P 5.27886004 3.1814 4 P 0 0;1=4
P 11.28278996 3.1814 4 P 0 0;1=4
P 11.28278996 3.2164 4 P 0 0;1=4
P 11.28278996 3.2964 4 P 0 0;1=4
P 11.28278996 3.2614 4 P 0 0;1=4
P 11.28278996 2.9414 4 P 0 0;1=4
P 11.28278996 2.9764 4 P 0 0;1=4
P 11.28278996 3.1364 4 P 0 0;1=4
P 11.28278996 3.1014 4 P 0 0;1=4
P 11.28278996 3.0564 4 P 0 0;1=4
P 11.28278996 3.0214 4 P 0 0;1=4
P 5.59708996 4.7302 4 P 0 0;1=4
P 5.57708996 4.6802 4 P 0 0;1=4
P 5.75708996 4.7302 4 P 0 0;1=4
P 5.83708996 4.7302 4 P 0 0;1=4
P 5.69708996 4.6802 4 P 0 0;1=4
P 5.73708996 4.6802 4 P 0 0;1=4
P 5.77708996 4.6802 4 P 0 0;1=4
P 5.81708996 4.6802 4 P 0 0;1=4
P 5.85708996 4.6802 4 P 0 0;1=4
P 5.67708996 4.7302 4 P 0 0;1=4
P 5.65708996 4.6802 4 P 0 0;1=4
P 5.61708996 4.6802 4 P 0 0;1=4
P 6.13708996 4.7602 4 P 0 0;1=4
P 6.09708996 4.6802 4 P 0 0;1=4
P 6.13708996 4.6402 4 P 0 0;1=4
P 6.13708996 4.6802 4 P 0 0;1=4
P 6.13708996 4.7202 4 P 0 0;1=4
P 5.91708996 4.7302 4 P 0 0;1=4
P 5.99708996 4.7302 4 P 0 0;1=4
P 6.07708996 4.7302 4 P 0 0;1=4
P 5.89708996 4.6802 4 P 0 0;1=4
P 5.93708996 4.6802 4 P 0 0;1=4
P 5.97708996 4.6802 4 P 0 0;1=4
P 6.01708996 4.6802 4 P 0 0;1=4
P 6.05708996 4.6802 4 P 0 0;1=4
P 5.59708996 4.7702 4 P 0 0;1=4
P 5.59708996 4.8102 4 P 0 0;1=4
P 5.75708996 4.8102 4 P 0 0;1=4
P 5.83708996 4.8102 4 P 0 0;1=4
P 5.75708996 4.7702 4 P 0 0;1=4
P 5.83708996 4.7702 4 P 0 0;1=4
P 5.67708996 4.8102 4 P 0 0;1=4
P 5.67708996 4.7702 4 P 0 0;1=4
P 6.13708996 4.9252 4 P 0 0;1=4
P 6.13708996 4.8402 4 P 0 0;1=4
P 6.13708996 4.8002 4 P 0 0;1=4
P 6.13708996 4.8852 4 P 0 0;1=4
P 5.91708996 4.8102 4 P 0 0;1=4
P 5.99708996 4.8102 4 P 0 0;1=4
P 5.91708996 4.7702 4 P 0 0;1=4
P 5.99708996 4.7702 4 P 0 0;1=4
P 6.07708996 4.8102 4 P 0 0;1=4
P 6.07708996 4.7702 4 P 0 0;1=4
P 4.93268002 2.26615 5 P 0 0;1=3
P 4.93268002 2.31615 5 P 0 0;1=3
P 5.08268002 2.36615 5 P 0 0;1=3
P 12.81495 3.22441004 10 P 0 0;1=1
P 10.68661004 2.06615 5 P 0 0;1=3
P 10.09 2.13095 5 P 0 0;1=3
P 10.63661004 2.31615 5 P 0 0;1=3
P 10.09 2.40335 5 P 0 0;1=3
P 12.81495 3.85433002 10 P 0 0;1=1
P 11.73316004 2.012 5 P 0 0;1=3
P 12.63778996 3.1063 10 P 0 0;1=1
P 11.73316004 1.972 5 P 0 0;1=3
P 12.55905 3.14566998 10 P 0 0;1=1
P 11.53316004 1.732 5 P 0 0;1=3
P 12.55905 2.98818996 10 P 0 0;1=1
P 12.81495 3.69685 10 P 0 0;1=1
P 10.58661004 2.26615 5 P 0 0;1=3
P 10.09 2.30825 5 P 0 0;1=3
P 11.53316004 1.772 5 P 0 0;1=3
P 12.63778996 2.94881998 10 P 0 0;1=1
P 12.81495 4.32676998 10 P 0 0;1=1
P 10.63661004 2.46615 5 P 0 0;1=3
P 9.975 2.62445 5 P 0 0;1=3
P 12.63778996 2.79133996 10 P 0 0;1=1
P 11.73316004 1.852 5 P 0 0;1=3
P 12.55905 2.83071004 10 P 0 0;1=1
P 11.73316004 1.812 5 P 0 0;1=3
P 10.73661004 2.46615 5 P 0 0;1=3
P 10.09 2.73655 5 P 0 0;1=3
P 12.81495 4.48425 10 P 0 0;1=1
P 10.63661004 2.26615 5 P 0 0;1=3
P 10.09 2.44335 5 P 0 0;1=3
P 12.73621004 3.8937 10 P 0 0;1=1
P 10.58661004 2.41615 5 P 0 0;1=3
P 9.975 2.5109 5 P 0 0;1=3
P 12.81495 4.16928996 10 P 0 0;1=1
P 1.025 -0.35 26 P 0 3;1=6
P 1.325 -0.35 26 P 0 3;1=6
P 1.175 -0.35 26 P 0 3;1=6
P 0.725 -0.35 26 P 0 3;1=6
P 0.875 -0.35 26 P 0 3;1=6
P 12.73621004 4.05118002 10 P 0 0;1=1
P 10.68661004 2.36615 5 P 0 0;1=3
P 10.09 2.53845 5 P 0 0;1=3
P 12.81495 2.35826998 10 P 0 0;1=1
P 10.63661004 1.86615 5 P 0 0;1=3
P 10.35543002 1.52156998 5 P 0 0;1=3
P 5.03268002 2.01615 5 P 0 0;1=3
P 5.08268002 2.21615 5 P 0 0;1=3
P 12.73621004 2.16141998 10 P 0 0;1=1
P 10.68661004 1.96615 5 P 0 0;1=3
P 10.46445 1.395 5 P 0 0;1=3
P 0.2 -0.293 18 P 0 0;1=14
P 12.27 0.29 18 P 0 0;1=14
P 0.66 0.29 18 P 0 0;1=14
P 0.2 5.82361998 18 P 0 0;1=14
P 12.81495 1.57086998 10 P 0 0;1=1
P 12.73621004 1.5315 10 P 0 0;1=1
P 12.63778996 2.7126 10 P 0 0;1=1
P 12.55905 2.67323002 10 P 0 0;1=1
P 12.55905 1.64961004 10 P 0 0;1=1
P 12.63778996 1.61023996 10 P 0 0;1=1
P 12.55905 1.57086998 10 P 0 0;1=1
P 12.63778996 1.5315 10 P 0 0;1=1
P 12.73621004 1.68898002 10 P 0 0;1=1
P 12.81495 1.64961004 10 P 0 0;1=1
P 12.63778996 1.68898002 10 P 0 0;1=1
P 12.55905 1.72835 10 P 0 0;1=1
P 12.81495 1.72835 10 P 0 0;1=1
P 12.73621004 1.45276004 10 P 0 0;1=1
P 12.81495 1.41338996 10 P 0 0;1=1
P 12.73621004 1.37401998 10 P 0 0;1=7
P 12.63778996 1.45276004 10 P 0 0;1=1
P 12.55905 1.41338996 10 P 0 0;1=1
P 0.35038996 1.5315 10 P 0 0;1=1
P 0.27165 1.49213002 10 P 0 0;1=1
P 0.17323002 2.67323002 10 P 0 0;1=1
P 0.09448996 2.63386004 10 P 0 0;1=1
P 0.09448996 1.61023996 10 P 0 0;1=1
P 0.17323002 1.57086998 10 P 0 0;1=1
P 0.09448996 1.5315 10 P 0 0;1=1
P 0.17323002 1.49213002 10 P 0 0;1=1
P 0.27165 1.64961004 10 P 0 0;1=1
P 0.35038996 1.61023996 10 P 0 0;1=1
P 0.17323002 1.64961004 10 P 0 0;1=1
P 0.09448996 1.68898002 10 P 0 0;1=1
P 0.35038996 1.68898002 10 P 0 0;1=1
P 0.27165 1.41338996 10 P 0 0;1=1
P 0.35038996 1.37401998 10 P 0 0;1=1
P 0.27165 1.33465 10 P 0 0;1=7
P 0.17323002 1.41338996 10 P 0 0;1=1
P 0.09448996 1.37401998 10 P 0 0;1=1
P 10.20866004 5.4441 23 P 0 0;1=15
P 5.78346004 5.4441 23 P 0 0;1=15
P 12.7252 6.31661998 18 P 0 0;1=14
P 0.2 6.31661998 18 P 0 0;1=14
P 12.7252 -0.293 18 P 0 0;1=14
P 0.22245 4.87401004 16 P 0 0;1=5
P 12.68701004 0.46063002 19 P 0 0;1=16
P 12.68701998 5.4252 19 P 0 0;1=16
P 0.22245 0.42126004 19 P 0 0;1=16
P 0.22255 5.38583002 19 P 0 0;1=16
P 7.17716998 5.7874 22 P 0 0;1=17
P 7.17716998 0.23621998 22 P 0 0;1=17
P 0.22245 0.68898002 21 P 0 0;1=18
P 0.22245 5.11811004 21 P 0 0;1=18
P 12.68701998 5.15748002 21 P 0 0;1=18
P 12.68701998 0.72835 21 P 0 0;1=18
P 6.11811004 1.52756004 21 P 0 0;1=18
P 6.11811004 4.20473002 21 P 0 0;1=18
P 4.83268002 4.22441004 21 P 0 0;1=18
P 2.24606004 4.22441004 21 P 0 0;1=18
P 0.96063002 4.20473002 21 P 0 0;1=18
P 0.96063002 1.52756004 21 P 0 0;1=18
P 2.24606004 1.50786998 21 P 0 0;1=18
P 4.83268002 1.50786998 21 P 0 0;1=18
P 6.04921004 2.58268002 20 P 0 0;1=19
P 1.05905 2.58268002 25 P 0 0;1=20
P 12.12205 1.52756004 21 P 0 0;1=18
P 12.12205 4.20473002 21 P 0 0;1=18
P 10.83661998 4.22441004 21 P 0 0;1=18
P 8.25 4.22441004 21 P 0 0;1=18
P 6.96456998 4.20473002 21 P 0 0;1=18
P 6.96456998 1.52756004 21 P 0 0;1=18
P 8.25 1.50786998 21 P 0 0;1=18
P 10.83661998 1.50786998 21 P 0 0;1=18
P 12.05315 2.58268002 20 P 0 0;1=19
P 7.06298996 2.58268002 25 P 0 0;1=20
P 12.33465 5.69528002 17 P 0 0;1=21
P 3.58311004 4.91851004 13 P 0 0;1=22
P 2.72091004 4.91851004 13 P 0 0;1=22
P 9.58665 4.91851004 13 P 0 0;1=22
P 8.72445 4.91851004 13 P 0 0;1=22
P 2.41851004 4.91851004 13 P 0 0;1=22
P 1.55631004 4.91851004 13 P 0 0;1=22
P 8.42205 4.91851004 13 P 0 0;1=22
P 7.55985 4.91851004 13 P 0 0;1=22
P 0.22243996 1.79331004 15 P 0 0;1=23
P 0.22243996 4.67323002 15 P 0 0;1=23
P 12.687 1.83268002 15 P 0 0;1=23
P 12.687 4.7126 15 P 0 0;1=23
P 0.7687 5.62008002 11 P 0 0;1=24
P 1.47736004 5.62008002 11 P 0 0;1=24
L 1.88908002 -1.91246004 1.89293002 -1.91246004 0 P 0 ;0
L 1.89126998 -1.91146004 1.89656998 -1.91146004 0 P 0 ;0
L 1.89393996 -1.91046004 1.9155 -1.91046004 0 P 0 ;0
L 1.91593996 -1.91246004 1.92048996 -1.91246004 0 P 0 ;0
L 1.9126 -1.91146004 1.9184 -1.91146004 0 P 0 ;0
L 1.89763002 -1.90946004 1.91016998 -1.90946004 0 P 0 ;0
L 1.89053002 -1.96001004 1.8974 -1.96001004 0 P 0 ;0
L 1.89053002 -1.95901004 1.8974 -1.95901004 0 P 0 ;0
L 1.89053002 -1.95801004 1.8974 -1.95801004 0 P 0 ;0
L 1.89053002 -1.95701004 1.8974 -1.95701004 0 P 0 ;0
L 1.89053002 -1.95601004 1.8974 -1.95601004 0 P 0 ;0
L 1.89053002 -1.95501004 1.8974 -1.95501004 0 P 0 ;0
L 1.89053002 -1.95401004 1.8974 -1.95401004 0 P 0 ;0
L 1.89053002 -1.95301004 1.89741004 -1.95301004 0 P 0 ;0
L 1.89053002 -1.95201004 1.89741998 -1.95201004 0 P 0 ;0
L 1.89053002 -1.95101004 1.89743996 -1.95101004 0 P 0 ;0
L 1.89053002 -1.95001004 1.89745 -1.95001004 0 P 0 ;0
L 1.89053002 -1.94901004 1.89746004 -1.94901004 0 P 0 ;0
L 1.89053002 -1.94801004 1.89753002 -1.94801004 0 P 0 ;0
L 1.89053002 -1.94701004 1.8977 -1.94701004 0 P 0 ;0
L 1.89053002 -1.94601004 1.89798002 -1.94601004 0 P 0 ;0
L 1.89053002 -1.94501004 1.89861004 -1.94501004 0 P 0 ;0
L 1.89053002 -1.94401004 1.90005 -1.94401004 0 P 0 ;0
L 1.89053002 -1.94301004 1.9113 -1.94301004 0 P 0 ;0
L 1.89053002 -1.94201004 1.91168002 -1.94201004 0 P 0 ;0
L 1.89053002 -1.94101004 1.91246998 -1.94101004 0 P 0 ;0
L 1.89053002 -1.94001004 1.90093996 -1.94001004 0 P 0 ;0
L 1.89053002 -1.93901004 1.89856004 -1.93901004 0 P 0 ;0
L 1.89053002 -1.93801004 1.89786998 -1.93801004 0 P 0 ;0
L 1.89053002 -1.93701004 1.89753996 -1.93701004 0 P 0 ;0
L 1.89053002 -1.93601004 1.89746998 -1.93601004 0 P 0 ;0
L 1.89053002 -1.93501004 1.89743996 -1.93501004 0 P 0 ;0
L 1.89053002 -1.93401004 1.89741998 -1.93401004 0 P 0 ;0
L 1.89053002 -1.93301004 1.8974 -1.93301004 0 P 0 ;0
L 1.89053002 -1.93201004 1.8974 -1.93201004 0 P 0 ;0
L 1.89053002 -1.93101004 1.8974 -1.93101004 0 P 0 ;0
L 1.89053002 -1.93001004 1.8974 -1.93001004 0 P 0 ;0
L 1.89053002 -1.92901004 1.8974 -1.92901004 0 P 0 ;0
L 1.89053002 -1.92801004 1.89753002 -1.92801004 0 P 0 ;0
L 1.89053002 -1.92701004 1.89793996 -1.92701004 0 P 0 ;0
L 1.89053002 -1.92601004 1.91713002 -1.92601004 0 P 0 ;0
L 1.89053002 -1.92501004 1.91628996 -1.92501004 0 P 0 ;0
L 1.89053002 -1.92401004 1.91513996 -1.92401004 0 P 0 ;0
L 1.89053002 -1.92301004 1.91321998 -1.92301004 0 P 0 ;0
L 1.89053002 -1.92201004 1.90551004 -1.92201004 0 P 0 ;0
L 1.89438996 -1.97246004 1.91331004 -1.97246004 0 P 0 ;0
L 1.89106998 -1.97146004 1.89973002 -1.97146004 0 P 0 ;0
L 1.88878002 -1.97046004 1.8949 -1.97046004 0 P 0 ;0
L 1.88698002 -1.96946004 1.89206998 -1.96946004 0 P 0 ;0
L 1.88546004 -1.96846004 1.88986998 -1.96846004 0 P 0 ;0
L 1.88416998 -1.96746004 1.88808996 -1.96746004 0 P 0 ;0
L 1.88288002 -1.96646004 1.88655 -1.96646004 0 P 0 ;0
L 1.88176998 -1.96546004 1.88518002 -1.96546004 0 P 0 ;0
L 1.88068996 -1.96446004 1.88393996 -1.96446004 0 P 0 ;0
L 1.87968996 -1.96346004 1.88286004 -1.96346004 0 P 0 ;0
L 1.87878002 -1.96246004 1.88186004 -1.96246004 0 P 0 ;0
L 1.8786 -1.92046004 1.88126998 -1.92046004 0 P 0 ;0
L 1.87946998 -1.91946004 1.88223002 -1.91946004 0 P 0 ;0
L 1.88048002 -1.91846004 1.88321004 -1.91846004 0 P 0 ;0
L 1.88153996 -1.91746004 1.88436998 -1.91746004 0 P 0 ;0
L 1.88273002 -1.91646004 1.88558996 -1.91646004 0 P 0 ;0
L 1.88406004 -1.91546004 1.88696998 -1.91546004 0 P 0 ;0
L 1.88548996 -1.91446004 1.88853002 -1.91446004 0 P 0 ;0
L 1.88718002 -1.91346004 1.89041998 -1.91346004 0 P 0 ;0
L 1.90896004 -1.92963996 1.90921998 -1.92991998 0 P 0 ;0
L 1.90921998 -1.92991998 1.90945 -1.93021998 0 P 0 ;0
L 1.90945 -1.93021998 1.90966004 -1.93053002 0 P 0 ;0
L 1.90966004 -1.93053002 1.90983002 -1.93086004 0 P 0 ;0
L 1.90983002 -1.93086004 1.90998002 -1.93121004 0 P 0 ;0
L 1.90998002 -1.93121004 1.9101 -1.93156998 0 P 0 ;0
L 1.9101 -1.93156998 1.91018996 -1.93193996 0 P 0 ;0
L 1.91018996 -1.93193996 1.91023996 -1.93231004 0 P 0 ;0
L 1.91023996 -1.93231004 1.91026998 -1.93265 0 P 0 ;0
L 1.91026998 -1.93265 1.91026004 -1.93298002 0 P 0 ;0
L 1.91026004 -1.93298002 1.91023002 -1.93331004 0 P 0 ;0
L 1.91023002 -1.93331004 1.91016998 -1.93363996 0 P 0 ;0
L 1.91016998 -1.93363996 1.91008996 -1.93396004 0 P 0 ;0
L 1.91008996 -1.93396004 1.90998002 -1.93428002 0 P 0 ;0
L 1.90998002 -1.93428002 1.90983996 -1.93458002 0 P 0 ;0
L 1.90983996 -1.93458002 1.90968996 -1.93486998 0 P 0 ;0
L 1.90968996 -1.93486998 1.90951004 -1.93516004 0 P 0 ;0
L 1.90951004 -1.93516004 1.90921004 -1.93556004 0 P 0 ;0
L 1.90921004 -1.93556004 1.90888002 -1.93593002 0 P 0 ;0
L 1.90888002 -1.93593002 1.90853002 -1.93626998 0 P 0 ;0
L 1.90853002 -1.93626998 1.90815 -1.93658996 0 P 0 ;0
L 1.90815 -1.93658996 1.90773996 -1.93686998 0 P 0 ;0
L 1.90773996 -1.93686998 1.90731998 -1.93711998 0 P 0 ;0
L 1.90731998 -1.93711998 1.90686998 -1.93733996 0 P 0 ;0
L 1.90686998 -1.93733996 1.90615 -1.93761004 0 P 0 ;0
L 1.90615 -1.93761004 1.90541998 -1.93783002 0 P 0 ;0
L 1.90541998 -1.93783002 1.90466004 -1.93798002 0 P 0 ;0
L 1.90466004 -1.93798002 1.9039 -1.93808002 0 P 0 ;0
L 1.9039 -1.93808002 1.90311998 -1.9381 0 P 0 ;0
L 1.90311998 -1.9381 1.90196004 -1.93808002 0 P 0 ;0
L 1.90196004 -1.93808002 1.90078996 -1.93798996 0 P 0 ;0
L 1.90078996 -1.93798996 1.90068002 -1.93798002 0 P 0 ;0
L 1.90068002 -1.93798002 1.90058002 -1.93795 0 P 0 ;0
L 1.90058002 -1.93795 1.90046998 -1.93791998 0 P 0 ;0
L 1.90046998 -1.93791998 1.90038002 -1.93788002 0 P 0 ;0
L 1.90038002 -1.93788002 1.90028002 -1.93783002 0 P 0 ;0
L 1.90028002 -1.93783002 1.90018996 -1.93778002 0 P 0 ;0
L 1.90018996 -1.93778002 1.9001 -1.93771004 0 P 0 ;0
L 1.9001 -1.93771004 1.90001998 -1.93763996 0 P 0 ;0
L 1.90001998 -1.93763996 1.89988002 -1.93748002 0 P 0 ;0
L 1.89988002 -1.93748002 1.89978002 -1.93733996 0 P 0 ;0
L 1.89978002 -1.93733996 1.89961998 -1.93703996 0 P 0 ;0
L 1.89961998 -1.93703996 1.89956998 -1.93688002 0 P 0 ;0
L 1.89956998 -1.93688002 1.89951998 -1.93671004 0 P 0 ;0
L 1.89951998 -1.93671004 1.89948996 -1.93655 0 P 0 ;0
L 1.89948996 -1.93655 1.89946998 -1.93636998 0 P 0 ;0
L 1.89946998 -1.93636998 1.8994 -1.93323002 0 P 0 ;0
L 1.8994 -1.93323002 1.8994 -1.92833002 0 P 0 ;0
L 1.8994 -1.92833002 1.90353996 -1.92833002 0 P 0 ;0
L 1.90353996 -1.92833002 1.90436998 -1.92835 0 P 0 ;0
L 1.90436998 -1.92835 1.9052 -1.92843002 0 P 0 ;0
L 1.9052 -1.92843002 1.90603002 -1.92853996 0 P 0 ;0
L 1.90603002 -1.92853996 1.90683996 -1.92871004 0 P 0 ;0
L 1.90683996 -1.92871004 1.90751004 -1.9289 0 P 0 ;0
L 1.90751004 -1.9289 1.90818002 -1.92913002 0 P 0 ;0
L 1.90818002 -1.92913002 1.90851998 -1.92928996 0 P 0 ;0
L 1.90851998 -1.92928996 1.90868002 -1.92938996 0 P 0 ;0
L 1.90868002 -1.92938996 1.90883002 -1.92951004 0 P 0 ;0
L 1.90883002 -1.92951004 1.90896004 -1.92963996 0 P 0 ;0
L 1.91188996 -1.96001004 1.91638996 -1.96001004 0 P 0 ;0
L 1.91156998 -1.95901004 1.91926998 -1.95901004 0 P 0 ;0
L 1.91125 -1.95801004 1.91891998 -1.95801004 0 P 0 ;0
L 1.91091998 -1.95701004 1.91853002 -1.95701004 0 P 0 ;0
L 1.9106 -1.95601004 1.91811004 -1.95601004 0 P 0 ;0
L 1.91025 -1.95501004 1.91765 -1.95501004 0 P 0 ;0
L 1.90988996 -1.95401004 1.91718996 -1.95401004 0 P 0 ;0
L 1.90953002 -1.95301004 1.91673002 -1.95301004 0 P 0 ;0
L 1.90918002 -1.95201004 1.91626998 -1.95201004 0 P 0 ;0
L 1.90881998 -1.95101004 1.91576004 -1.95101004 0 P 0 ;0
L 1.90841004 -1.95001004 1.91523996 -1.95001004 0 P 0 ;0
L 1.90793996 -1.94901004 1.91471004 -1.94901004 0 P 0 ;0
L 1.90738996 -1.94801004 1.91418002 -1.94801004 0 P 0 ;0
L 1.90676998 -1.94701004 1.9136 -1.94701004 0 P 0 ;0
L 1.90598996 -1.94601004 1.91261004 -1.94601004 0 P 0 ;0
L 1.90495 -1.94501004 1.91175 -1.94501004 0 P 0 ;0
L 1.90325 -1.94401004 1.91133002 -1.94401004 0 P 0 ;0
L 1.90456004 -1.94001004 1.91383002 -1.94001004 0 P 0 ;0
L 1.90801004 -1.93901004 1.91523002 -1.93901004 0 P 0 ;0
L 1.90956998 -1.93801004 1.91635 -1.93801004 0 P 0 ;0
L 1.9106 -1.93701004 1.91718002 -1.93701004 0 P 0 ;0
L 1.91133996 -1.93601004 1.91781004 -1.93601004 0 P 0 ;0
L 1.91183996 -1.93501004 1.91826004 -1.93501004 0 P 0 ;0
L 1.91213002 -1.93401004 1.9186 -1.93401004 0 P 0 ;0
L 1.91226004 -1.93301004 1.9188 -1.93301004 0 P 0 ;0
L 1.91221998 -1.93201004 1.9189 -1.93201004 0 P 0 ;0
L 1.91201998 -1.93101004 1.9189 -1.93101004 0 P 0 ;0
L 1.91163996 -1.93001004 1.91878996 -1.93001004 0 P 0 ;0
L 1.91105 -1.92901004 1.91856998 -1.92901004 0 P 0 ;0
L 1.91013996 -1.92801004 1.91823002 -1.92801004 0 P 0 ;0
L 1.90816998 -1.92701004 1.91776004 -1.92701004 0 P 0 ;0
L 1.90313996 -1.94011004 1.90316998 -1.9401 0 P 0 ;0
L 1.90316998 -1.9401 1.9032 -1.9401 0 P 0 ;0
L 1.9032 -1.9401 1.90398002 -1.94006998 0 P 0 ;0
L 1.90398002 -1.94006998 1.90406004 -1.94006998 0 P 0 ;0
L 1.90406004 -1.94006998 1.90413996 -1.94006004 0 P 0 ;0
L 1.90413996 -1.94006004 1.9049 -1.93996998 0 P 0 ;0
L 1.9049 -1.93996998 1.90493996 -1.93996004 0 P 0 ;0
L 1.90493996 -1.93996004 1.90498996 -1.93996004 0 P 0 ;0
L 1.90498996 -1.93996004 1.90506998 -1.93993996 0 P 0 ;0
L 1.90506998 -1.93993996 1.90581998 -1.93978002 0 P 0 ;0
L 1.90581998 -1.93978002 1.90586004 -1.93978002 0 P 0 ;0
L 1.90586004 -1.93978002 1.90593996 -1.93976004 0 P 0 ;0
L 1.90593996 -1.93976004 1.90596998 -1.93973996 0 P 0 ;0
L 1.90596998 -1.93973996 1.90671004 -1.93953002 0 P 0 ;0
L 1.90671004 -1.93953002 1.90678996 -1.93951004 0 P 0 ;0
L 1.90678996 -1.93951004 1.90758996 -1.93921004 0 P 0 ;0
L 1.90758996 -1.93921004 1.90766004 -1.93916998 0 P 0 ;0
L 1.90766004 -1.93916998 1.9077 -1.93915 0 P 0 ;0
L 1.9077 -1.93915 1.90773996 -1.93913996 0 P 0 ;0
L 1.90773996 -1.93913996 1.90818996 -1.93891998 0 P 0 ;0
L 1.90818996 -1.93891998 1.90821998 -1.9389 0 P 0 ;0
L 1.90821998 -1.9389 1.90826004 -1.93888996 0 P 0 ;0
L 1.90826004 -1.93888996 1.90828996 -1.93886998 0 P 0 ;0
L 1.90828996 -1.93886998 1.90833002 -1.93885 0 P 0 ;0
L 1.90833002 -1.93885 1.90875 -1.9386 0 P 0 ;0
L 1.90875 -1.9386 1.90883002 -1.93856004 0 P 0 ;0
L 1.90883002 -1.93856004 1.90888996 -1.93851004 0 P 0 ;0
L 1.90888996 -1.93851004 1.90928996 -1.93823002 0 P 0 ;0
L 1.90928996 -1.93823002 1.90933002 -1.9382 0 P 0 ;0
L 1.90933002 -1.9382 1.90936004 -1.93818002 0 P 0 ;0
L 1.90936004 -1.93818002 1.90938996 -1.93815 0 P 0 ;0
L 1.90938996 -1.93815 1.90941998 -1.93813002 0 P 0 ;0
L 1.90941998 -1.93813002 1.9098 -1.93781998 0 P 0 ;0
L 1.9098 -1.93781998 1.90986004 -1.93776004 0 P 0 ;0
L 1.90986004 -1.93776004 1.90988996 -1.93773996 0 P 0 ;0
L 1.90988996 -1.93773996 1.90991998 -1.93771004 0 P 0 ;0
L 1.90991998 -1.93771004 1.91028002 -1.93736004 0 P 0 ;0
L 1.91028002 -1.93736004 1.91038996 -1.93725 0 P 0 ;0
L 1.91038996 -1.93725 1.91071004 -1.93688002 0 P 0 ;0
L 1.91071004 -1.93688002 1.91073996 -1.93685 0 P 0 ;0
L 1.91073996 -1.93685 1.91116004 -1.9363 0 P 0 ;0
L 1.91116004 -1.9363 1.9112 -1.93623002 0 P 0 ;0
L 1.9112 -1.93623002 1.91138002 -1.93595 0 P 0 ;0
L 1.91138002 -1.93595 1.9114 -1.93591004 0 P 0 ;0
L 1.9114 -1.93591004 1.91143996 -1.93585 0 P 0 ;0
L 1.91143996 -1.93585 1.91146004 -1.93581004 0 P 0 ;0
L 1.91146004 -1.93581004 1.91161004 -1.93551998 0 P 0 ;0
L 1.91161004 -1.93551998 1.91163002 -1.93548996 0 P 0 ;0
L 1.91163002 -1.93548996 1.91165 -1.93545 0 P 0 ;0
L 1.91165 -1.93545 1.91166004 -1.93541004 0 P 0 ;0
L 1.91166004 -1.93541004 1.91168002 -1.93538002 0 P 0 ;0
L 1.91168002 -1.93538002 1.91181004 -1.93506998 0 P 0 ;0
L 1.91181004 -1.93506998 1.91183996 -1.935 0 P 0 ;0
L 1.91183996 -1.935 1.91186004 -1.93496004 0 P 0 ;0
L 1.91186004 -1.93496004 1.91186998 -1.93493002 0 P 0 ;0
L 1.91186998 -1.93493002 1.91198002 -1.93461004 0 P 0 ;0
L 1.91198002 -1.93461004 1.91198996 -1.93456998 0 P 0 ;0
L 1.91198996 -1.93456998 1.912 -1.93453996 0 P 0 ;0
L 1.912 -1.93453996 1.9121 -1.93413996 0 P 0 ;0
L 1.9121 -1.93413996 1.91211998 -1.9341 0 P 0 ;0
L 1.91211998 -1.9341 1.91211998 -1.93406004 0 P 0 ;0
L 1.91211998 -1.93406004 1.91213002 -1.93401998 0 P 0 ;0
L 1.91213002 -1.93401998 1.91213996 -1.93398996 0 P 0 ;0
L 1.91213996 -1.93398996 1.9122 -1.93366004 0 P 0 ;0
L 1.9122 -1.93366004 1.91221004 -1.93358002 0 P 0 ;0
L 1.91221004 -1.93358002 1.91221004 -1.93353996 0 P 0 ;0
L 1.91221004 -1.93353996 1.91221998 -1.9335 0 P 0 ;0
L 1.91221998 -1.9335 1.91225 -1.93316998 0 P 0 ;0
L 1.91225 -1.93316998 1.91226004 -1.93308996 0 P 0 ;0
L 1.91226004 -1.93308996 1.91226004 -1.93268002 0 P 0 ;0
L 1.91226004 -1.93268002 1.91226998 -1.93263996 0 P 0 ;0
L 1.91226998 -1.93263996 1.91226998 -1.9326 0 P 0 ;0
L 1.91226998 -1.9326 1.91226004 -1.93251998 0 P 0 ;0
L 1.91226004 -1.93251998 1.91223996 -1.93218996 0 P 0 ;0
L 1.91223996 -1.93218996 1.91223996 -1.93215 0 P 0 ;0
L 1.91223996 -1.93215 1.91223002 -1.9321 0 P 0 ;0
L 1.91223002 -1.9321 1.91223002 -1.93206004 0 P 0 ;0
L 1.91223002 -1.93206004 1.91221998 -1.93201998 0 P 0 ;0
L 1.91221998 -1.93201998 1.91216998 -1.93163996 0 P 0 ;0
L 1.91216998 -1.93163996 1.91216004 -1.9316 0 P 0 ;0
L 1.91216004 -1.9316 1.91213996 -1.93151004 0 P 0 ;0
L 1.91213996 -1.93151004 1.91213002 -1.93146998 0 P 0 ;0
L 1.91213002 -1.93146998 1.91205 -1.93111004 0 P 0 ;0
L 1.91205 -1.93111004 1.91203996 -1.93106004 0 P 0 ;0
L 1.91203996 -1.93106004 1.91203002 -1.93101998 0 P 0 ;0
L 1.91203002 -1.93101998 1.91201004 -1.93098002 0 P 0 ;0
L 1.91201004 -1.93098002 1.912 -1.93093996 0 P 0 ;0
L 1.912 -1.93093996 1.91188002 -1.93058002 0 P 0 ;0
L 1.91188002 -1.93058002 1.91186998 -1.93053996 0 P 0 ;0
L 1.91186998 -1.93053996 1.91185 -1.9305 0 P 0 ;0
L 1.91185 -1.9305 1.91183996 -1.93046004 0 P 0 ;0
L 1.91183996 -1.93046004 1.91181998 -1.93043002 0 P 0 ;0
L 1.91181998 -1.93043002 1.91166998 -1.93008002 0 P 0 ;0
L 1.91166998 -1.93008002 1.91166004 -1.93003996 0 P 0 ;0
L 1.91166004 -1.93003996 1.9116 -1.92991998 0 P 0 ;0
L 1.9116 -1.92991998 1.91141998 -1.92958996 0 P 0 ;0
L 1.91141998 -1.92958996 1.9114 -1.92955 0 P 0 ;0
L 1.9114 -1.92955 1.91138002 -1.92951998 0 P 0 ;0
L 1.91138002 -1.92951998 1.91133002 -1.92945 0 P 0 ;0
L 1.91133002 -1.92945 1.91113002 -1.92913002 0 P 0 ;0
L 1.91113002 -1.92913002 1.91111004 -1.92908996 0 P 0 ;0
L 1.91111004 -1.92908996 1.91108996 -1.92906004 0 P 0 ;0
L 1.91108996 -1.92906004 1.91106004 -1.92901998 0 P 0 ;0
L 1.91106004 -1.92901998 1.91103002 -1.92898996 0 P 0 ;0
L 1.91103002 -1.92898996 1.9108 -1.92868996 0 P 0 ;0
L 1.9108 -1.92868996 1.91076998 -1.92866004 0 P 0 ;0
L 1.91076998 -1.92866004 1.91075 -1.92861998 0 P 0 ;0
L 1.91075 -1.92861998 1.91068996 -1.92856004 0 P 0 ;0
L 1.91068996 -1.92856004 1.91043002 -1.92828002 0 P 0 ;0
L 1.91043002 -1.92828002 1.91035 -1.9282 0 P 0 ;0
L 1.91035 -1.9282 1.91033002 -1.92816998 0 P 0 ;0
L 1.91033002 -1.92816998 1.91018996 -1.92803996 0 P 0 ;0
L 1.91018996 -1.92803996 1.91018002 -1.92803996 0 P 0 ;0
L 1.91018002 -1.92803996 1.91016004 -1.92801998 0 P 0 ;0
L 1.91016004 -1.92801998 1.91011998 -1.92798996 0 P 0 ;0
L 1.91011998 -1.92798996 1.91006004 -1.92793002 0 P 0 ;0
L 1.91006004 -1.92793002 1.90991004 -1.92781998 0 P 0 ;0
L 1.90991004 -1.92781998 1.90988002 -1.9278 0 P 0 ;0
L 1.90988002 -1.9278 1.90983996 -1.92776998 0 P 0 ;0
L 1.90983996 -1.92776998 1.90976998 -1.92771998 0 P 0 ;0
L 1.90976998 -1.92771998 1.90961004 -1.92761998 0 P 0 ;0
L 1.90961004 -1.92761998 1.90953996 -1.92756998 0 P 0 ;0
L 1.90953996 -1.92756998 1.9095 -1.92755 0 P 0 ;0
L 1.9095 -1.92755 1.90946998 -1.92753002 0 P 0 ;0
L 1.90946998 -1.92753002 1.9093 -1.92743996 0 P 0 ;0
L 1.9093 -1.92743996 1.90926004 -1.92741998 0 P 0 ;0
L 1.90926004 -1.92741998 1.90923002 -1.9274 0 P 0 ;0
L 1.90923002 -1.9274 1.90915 -1.92736998 0 P 0 ;0
L 1.90915 -1.92736998 1.90896998 -1.92728996 0 P 0 ;0
L 1.90896998 -1.92728996 1.90893996 -1.92728002 0 P 0 ;0
L 1.90893996 -1.92728002 1.9089 -1.92726004 0 P 0 ;0
L 1.9089 -1.92726004 1.90886998 -1.92725 0 P 0 ;0
L 1.90886998 -1.92725 1.90883002 -1.92723996 0 P 0 ;0
L 1.90883002 -1.92723996 1.90816004 -1.92701004 0 P 0 ;0
L 1.90816004 -1.92701004 1.90813996 -1.927 0 P 0 ;0
L 1.90813996 -1.927 1.9081 -1.92698996 0 P 0 ;0
L 1.9081 -1.92698996 1.90803996 -1.92696998 0 P 0 ;0
L 1.90803996 -1.92696998 1.90736998 -1.92678002 0 P 0 ;0
L 1.90736998 -1.92678002 1.90723996 -1.92675 0 P 0 ;0
L 1.90723996 -1.92675 1.90643002 -1.92658996 0 P 0 ;0
L 1.90643002 -1.92658996 1.90636998 -1.92656998 0 P 0 ;0
L 1.90636998 -1.92656998 1.90633996 -1.92656998 0 P 0 ;0
L 1.90633996 -1.92656998 1.90631004 -1.92656004 0 P 0 ;0
L 1.90631004 -1.92656004 1.90548996 -1.92645 0 P 0 ;0
L 1.90548996 -1.92645 1.90543996 -1.92643996 0 P 0 ;0
L 1.90543996 -1.92643996 1.9054 -1.92643002 0 P 0 ;0
L 1.9054 -1.92643002 1.90538002 -1.92643002 0 P 0 ;0
L 1.90538002 -1.92643002 1.90455 -1.92636004 0 P 0 ;0
L 1.90455 -1.92636004 1.90443002 -1.92636004 0 P 0 ;0
L 1.90443002 -1.92636004 1.9036 -1.92633002 0 P 0 ;0
L 1.9036 -1.92633002 1.8994 -1.92633002 0 P 0 ;0
L 1.8994 -1.92633002 1.89798002 -1.92691004 0 P 0 ;0
L 1.89798002 -1.92691004 1.8974 -1.92833002 0 P 0 ;0
L 1.8974 -1.92833002 1.8974 -1.93328002 0 P 0 ;0
L 1.8974 -1.93328002 1.89748002 -1.93643002 0 P 0 ;0
L 1.89748002 -1.93643002 1.89748002 -1.93656004 0 P 0 ;0
L 1.89748002 -1.93656004 1.8975 -1.93673002 0 P 0 ;0
L 1.8975 -1.93673002 1.89751004 -1.93681004 0 P 0 ;0
L 1.89751004 -1.93681004 1.89751998 -1.9369 0 P 0 ;0
L 1.89751998 -1.9369 1.89755 -1.93706004 0 P 0 ;0
L 1.89755 -1.93706004 1.89758002 -1.93718996 0 P 0 ;0
L 1.89758002 -1.93718996 1.89758996 -1.93723002 0 P 0 ;0
L 1.89758996 -1.93723002 1.89763002 -1.9374 0 P 0 ;0
L 1.89763002 -1.9374 1.89763996 -1.93743996 0 P 0 ;0
L 1.89763996 -1.93743996 1.89766004 -1.93748002 0 P 0 ;0
L 1.89766004 -1.93748002 1.89768002 -1.93756004 0 P 0 ;0
L 1.89768002 -1.93756004 1.89773996 -1.93771998 0 P 0 ;0
L 1.89773996 -1.93771998 1.89776004 -1.93776004 0 P 0 ;0
L 1.89776004 -1.93776004 1.89776998 -1.9378 0 P 0 ;0
L 1.89776998 -1.9378 1.89781004 -1.93788002 0 P 0 ;0
L 1.89781004 -1.93788002 1.89788002 -1.93803996 0 P 0 ;0
L 1.89788002 -1.93803996 1.8979 -1.93808002 0 P 0 ;0
L 1.8979 -1.93808002 1.89791998 -1.93811004 0 P 0 ;0
L 1.89791998 -1.93811004 1.89796004 -1.93818996 0 P 0 ;0
L 1.89796004 -1.93818996 1.89803996 -1.93833996 0 P 0 ;0
L 1.89803996 -1.93833996 1.89813996 -1.93848002 0 P 0 ;0
L 1.89813996 -1.93848002 1.89823002 -1.93861998 0 P 0 ;0
L 1.89823002 -1.93861998 1.89828002 -1.93868996 0 P 0 ;0
L 1.89828002 -1.93868996 1.89831004 -1.93873002 0 P 0 ;0
L 1.89831004 -1.93873002 1.89833996 -1.93876004 0 P 0 ;0
L 1.89833996 -1.93876004 1.8984 -1.93883996 0 P 0 ;0
L 1.8984 -1.93883996 1.89848996 -1.93893002 0 P 0 ;0
L 1.89848996 -1.93893002 1.89851004 -1.93896004 0 P 0 ;0
L 1.89851004 -1.93896004 1.89868002 -1.93913002 0 P 0 ;0
L 1.89868002 -1.93913002 1.89871004 -1.93915 0 P 0 ;0
L 1.89871004 -1.93915 1.89878996 -1.93921998 0 P 0 ;0
L 1.89878996 -1.93921998 1.89885 -1.93928002 0 P 0 ;0
L 1.89885 -1.93928002 1.89888002 -1.9393 0 P 0 ;0
L 1.89888002 -1.9393 1.89891998 -1.93931998 0 P 0 ;0
L 1.89891998 -1.93931998 1.89901004 -1.93938996 0 P 0 ;0
L 1.89901004 -1.93938996 1.89903996 -1.93941004 0 P 0 ;0
L 1.89903996 -1.93941004 1.89906998 -1.93943996 0 P 0 ;0
L 1.89906998 -1.93943996 1.8991 -1.93946004 0 P 0 ;0
L 1.8991 -1.93946004 1.89913996 -1.93948002 0 P 0 ;0
L 1.89913996 -1.93948002 1.89923002 -1.93953996 0 P 0 ;0
L 1.89923002 -1.93953996 1.89926998 -1.93956004 0 P 0 ;0
L 1.89926998 -1.93956004 1.8993 -1.93958002 0 P 0 ;0
L 1.8993 -1.93958002 1.89933996 -1.9396 0 P 0 ;0
L 1.89933996 -1.9396 1.89936998 -1.93961004 0 P 0 ;0
L 1.89936998 -1.93961004 1.89938002 -1.93961004 0 P 0 ;0
L 1.89938002 -1.93961004 1.89946998 -1.93966004 0 P 0 ;0
L 1.89946998 -1.93966004 1.89953996 -1.9397 0 P 0 ;0
L 1.89953996 -1.9397 1.89971998 -1.93976998 0 P 0 ;0
L 1.89971998 -1.93976998 1.89975 -1.93978996 0 P 0 ;0
L 1.89975 -1.93978996 1.89978996 -1.9398 0 P 0 ;0
L 1.89978996 -1.9398 1.89986998 -1.93983002 0 P 0 ;0
L 1.89986998 -1.93983002 1.89996998 -1.93986004 0 P 0 ;0
L 1.89996998 -1.93986004 1.90001004 -1.93986998 0 P 0 ;0
L 1.90001004 -1.93986998 1.90005 -1.93988996 0 P 0 ;0
L 1.90005 -1.93988996 1.90013002 -1.9399 0 P 0 ;0
L 1.90013002 -1.9399 1.90023002 -1.93993002 0 P 0 ;0
L 1.90023002 -1.93993002 1.90023996 -1.93993002 0 P 0 ;0
L 1.90023996 -1.93993002 1.90028002 -1.93993996 0 P 0 ;0
L 1.90028002 -1.93993996 1.90031004 -1.93995 0 P 0 ;0
L 1.90031004 -1.93995 1.90036004 -1.93995 0 P 0 ;0
L 1.90036004 -1.93995 1.9004 -1.93996004 0 P 0 ;0
L 1.9004 -1.93996004 1.9005 -1.93996998 0 P 0 ;0
L 1.9005 -1.93996998 1.90061004 -1.93998996 0 P 0 ;0
L 1.90061004 -1.93998996 1.90063996 -1.93998996 0 P 0 ;0
L 1.90063996 -1.93998996 1.90181004 -1.94006998 0 P 0 ;0
L 1.90181004 -1.94006998 1.90183996 -1.94008002 0 P 0 ;0
L 1.90183996 -1.94008002 1.90191004 -1.94008002 0 P 0 ;0
L 1.90191004 -1.94008002 1.90308002 -1.9401 0 P 0 ;0
L 1.90308002 -1.9401 1.90311004 -1.9401 0 P 0 ;0
L 1.90311004 -1.9401 1.90313996 -1.94011004 0 P 0 ;0
L 1.90841004 -1.97146004 1.91683996 -1.97146004 0 P 0 ;0
L 1.9135 -1.97046004 1.91931004 -1.97046004 0 P 0 ;0
L 1.91655 -1.96946004 1.92131004 -1.96946004 0 P 0 ;0
L 1.91891998 -1.96846004 1.92301004 -1.96846004 0 P 0 ;0
L 1.92088996 -1.96746004 1.9245 -1.96746004 0 P 0 ;0
L 1.92251004 -1.96646004 1.9258 -1.96646004 0 P 0 ;0
L 1.92391004 -1.96546004 1.92696004 -1.96546004 0 P 0 ;0
L 1.92513002 -1.96446004 1.92803002 -1.96446004 0 P 0 ;0
L 1.9262 -1.96346004 1.92898996 -1.96346004 0 P 0 ;0
L 1.92713996 -1.96246004 1.92986004 -1.96246004 0 P 0 ;0
L 1.928 -1.96146004 1.93068996 -1.96146004 0 P 0 ;0
L 1.92878002 -1.96046004 1.93143002 -1.96046004 0 P 0 ;0
L 1.92951004 -1.95946004 1.93216004 -1.95946004 0 P 0 ;0
L 1.93016998 -1.95846004 1.93278996 -1.95846004 0 P 0 ;0
L 1.93078002 -1.95746004 1.93341004 -1.95746004 0 P 0 ;0
L 1.93133002 -1.95646004 1.93396004 -1.95646004 0 P 0 ;0
L 1.93185 -1.95546004 1.93448996 -1.95546004 0 P 0 ;0
L 1.93231004 -1.95446004 1.93495 -1.95446004 0 P 0 ;0
L 1.93275 -1.95346004 1.93541004 -1.95346004 0 P 0 ;0
L 1.93311998 -1.95246004 1.93586004 -1.95246004 0 P 0 ;0
L 1.93348002 -1.95146004 1.93628996 -1.95146004 0 P 0 ;0
L 1.93376998 -1.95046004 1.93666004 -1.95046004 0 P 0 ;0
L 1.93405 -1.94946004 1.93693002 -1.94946004 0 P 0 ;0
L 1.93428002 -1.94846004 1.93715 -1.94846004 0 P 0 ;0
L 1.93446998 -1.94746004 1.93733002 -1.94746004 0 P 0 ;0
L 1.93466004 -1.94646004 1.93743002 -1.94646004 0 P 0 ;0
L 1.93478996 -1.94546004 1.93748996 -1.94546004 0 P 0 ;0
L 1.9349 -1.94446998 1.93751998 -1.94446998 0 P 0 ;0
L 1.93496998 -1.94346004 1.93755 -1.94346004 0 P 0 ;0
L 1.93501998 -1.94246004 1.93758002 -1.94246004 0 P 0 ;0
L 1.93505 -1.94146998 1.93758996 -1.94146998 0 P 0 ;0
L 1.93503002 -1.94046004 1.93755 -1.94046004 0 P 0 ;0
L 1.935 -1.93946004 1.93751998 -1.93946004 0 P 0 ;0
L 1.93491998 -1.93846004 1.93748002 -1.93846004 0 P 0 ;0
L 1.93481004 -1.93746004 1.93738996 -1.93746004 0 P 0 ;0
L 1.93468996 -1.93646004 1.93726998 -1.93646004 0 P 0 ;0
L 1.93451004 -1.93546004 1.93716004 -1.93546004 0 P 0 ;0
L 1.93433002 -1.93446004 1.93703996 -1.93446004 0 P 0 ;0
L 1.93408996 -1.93346004 1.93685 -1.93346004 0 P 0 ;0
L 1.93383002 -1.93246004 1.93666004 -1.93246004 0 P 0 ;0
L 1.93353002 -1.93146004 1.93638996 -1.93146004 0 P 0 ;0
L 1.9332 -1.93046004 1.93611998 -1.93046004 0 P 0 ;0
L 1.93283996 -1.92946004 1.93576998 -1.92946004 0 P 0 ;0
L 1.93241004 -1.92846004 1.93541004 -1.92846004 0 P 0 ;0
L 1.93198996 -1.92746004 1.93498002 -1.92746004 0 P 0 ;0
L 1.93146998 -1.92646004 1.93451004 -1.92646004 0 P 0 ;0
L 1.93096004 -1.92546004 1.93398002 -1.92546004 0 P 0 ;0
L 1.93035 -1.92446998 1.93338002 -1.92446998 0 P 0 ;0
L 1.92973002 -1.92346004 1.93275 -1.92346004 0 P 0 ;0
L 1.92903002 -1.92246004 1.93201004 -1.92246004 0 P 0 ;0
L 1.92831004 -1.92146004 1.93125 -1.92146004 0 P 0 ;0
L 1.92746998 -1.92046004 1.93041004 -1.92046004 0 P 0 ;0
L 1.92661004 -1.91946004 1.92948996 -1.91946004 0 P 0 ;0
L 1.92558996 -1.91846004 1.92851004 -1.91846004 0 P 0 ;0
L 1.9245 -1.91746004 1.92741998 -1.91746004 0 P 0 ;0
L 1.92328996 -1.91646004 1.92621998 -1.91646004 0 P 0 ;0
L 1.92188002 -1.91546004 1.92491998 -1.91546004 0 P 0 ;0
L 1.92026004 -1.91446004 1.92358996 -1.91446004 0 P 0 ;0
L 1.91835 -1.91346004 1.92208002 -1.91346004 0 P 0 ;0
L 1.82446998 -2.08323996 1.87608002 -2.08323996 0 P 0 ;0
L 1.82403002 -2.08223996 1.87601004 -2.08223996 0 P 0 ;0
L 1.8234 -2.08123996 1.87591004 -2.08123996 0 P 0 ;0
L 1.82256004 -2.08023996 1.87578002 -2.08023996 0 P 0 ;0
L 1.82166004 -2.07923996 1.87558996 -2.07923996 0 P 0 ;0
L 1.82061998 -2.07823996 1.87533002 -2.07823996 0 P 0 ;0
L 1.81946004 -2.07723996 1.87498996 -2.07723996 0 P 0 ;0
L 1.81818002 -2.07623996 1.8746 -2.07623996 0 P 0 ;0
L 1.8168 -2.07523996 1.87416998 -2.07523996 0 P 0 ;0
L 1.81541998 -2.07423996 1.87371004 -2.07423996 0 P 0 ;0
L 1.81403002 -2.07323996 1.87316998 -2.07323996 0 P 0 ;0
L 1.81265 -2.07223996 1.87261004 -2.07223996 0 P 0 ;0
L 1.81126998 -2.07123996 1.87196004 -2.07123996 0 P 0 ;0
L 1.80986004 -2.07023996 1.87128002 -2.07023996 0 P 0 ;0
L 1.80843996 -2.06923996 1.87051998 -2.06923996 0 P 0 ;0
L 1.80703002 -2.06823996 1.8697 -2.06823996 0 P 0 ;0
L 1.80561004 -2.06723996 1.86883002 -2.06723996 0 P 0 ;0
L 1.8042 -2.06623996 1.86796004 -2.06623996 0 P 0 ;0
L 1.80278002 -2.06523996 1.86705 -2.06523996 0 P 0 ;0
L 1.80136004 -2.06423996 1.86608002 -2.06423996 0 P 0 ;0
L 1.79995 -2.06323996 1.8651 -2.06323996 0 P 0 ;0
L 1.79865 -2.06223996 1.86411004 -2.06223996 0 P 0 ;0
L 1.79735 -2.06123996 1.86301998 -2.06123996 0 P 0 ;0
L 1.79605 -2.06023996 1.86193002 -2.06023996 0 P 0 ;0
L 1.79475 -2.05923996 1.86083996 -2.05923996 0 P 0 ;0
L 1.79345 -2.05823996 1.85966998 -2.05823996 0 P 0 ;0
L 1.79215 -2.05723996 1.85846004 -2.05723996 0 P 0 ;0
L 1.79088002 -2.05623996 1.85726004 -2.05623996 0 P 0 ;0
L 1.78971998 -2.05523996 1.85598996 -2.05523996 0 P 0 ;0
L 1.78856004 -2.05423996 1.85461998 -2.05423996 0 P 0 ;0
L 1.7874 -2.05323996 1.85326004 -2.05323996 0 P 0 ;0
L 1.78623002 -2.05223996 1.8519 -2.05223996 0 P 0 ;0
L 1.78506998 -2.05123996 1.85053996 -2.05123996 0 P 0 ;0
L 1.78398002 -2.05023996 1.84918002 -2.05023996 0 P 0 ;0
L 1.783 -2.04923996 1.84781004 -2.04923996 0 P 0 ;0
L 1.87086004 -2.03023996 1.87535 -2.03023996 0 P 0 ;0
L 1.91633002 -1.91473002 1.9183 -1.91565 0 P 0 ;0
L 1.9183 -1.91565 1.92018996 -1.91673002 0 P 0 ;0
L 1.92018996 -1.91673002 1.92196998 -1.91796998 0 P 0 ;0
L 1.92196998 -1.91796998 1.92365 -1.91936004 0 P 0 ;0
L 1.92365 -1.91936004 1.9252 -1.92088002 0 P 0 ;0
L 1.9252 -1.92088002 1.92661004 -1.92253996 0 P 0 ;0
L 1.92661004 -1.92253996 1.92795 -1.92436998 0 P 0 ;0
L 1.92795 -1.92436998 1.92913996 -1.9263 0 P 0 ;0
L 1.92913996 -1.9263 1.93018002 -1.92831998 0 P 0 ;0
L 1.93018002 -1.92831998 1.93106998 -1.93041004 0 P 0 ;0
L 1.93106998 -1.93041004 1.93178996 -1.93256004 0 P 0 ;0
L 1.93178996 -1.93256004 1.93236004 -1.93476004 0 P 0 ;0
L 1.93236004 -1.93476004 1.93276004 -1.93703996 0 P 0 ;0
L 1.93276004 -1.93703996 1.93298996 -1.93933996 0 P 0 ;0
L 1.93298996 -1.93933996 1.93306004 -1.94165 0 P 0 ;0
L 1.93306004 -1.94165 1.93295 -1.94396998 0 P 0 ;0
L 1.93295 -1.94396998 1.93268002 -1.94626004 0 P 0 ;0
L 1.93268002 -1.94626004 1.93223002 -1.94853996 0 P 0 ;0
L 1.93223002 -1.94853996 1.93161998 -1.95071998 0 P 0 ;0
L 1.93161998 -1.95071998 1.93085 -1.95285 0 P 0 ;0
L 1.93085 -1.95285 1.92991004 -1.95491004 0 P 0 ;0
L 1.92991004 -1.95491004 1.92881004 -1.95688996 0 P 0 ;0
L 1.92881004 -1.95688996 1.92756004 -1.95878002 0 P 0 ;0
L 1.92756004 -1.95878002 1.92616004 -1.96056998 0 P 0 ;0
L 1.92616004 -1.96056998 1.92493996 -1.9619 0 P 0 ;0
L 1.92493996 -1.9619 1.92361998 -1.96313996 0 P 0 ;0
L 1.92361998 -1.96313996 1.9222 -1.96426004 0 P 0 ;0
L 1.9222 -1.96426004 1.9207 -1.96526998 0 P 0 ;0
L 1.9207 -1.96526998 1.91911004 -1.96616998 0 P 0 ;0
L 1.91911004 -1.96616998 1.91686998 -1.96721004 0 P 0 ;0
L 1.91686998 -1.96721004 1.91456004 -1.96806998 0 P 0 ;0
L 1.91456004 -1.96806998 1.91218996 -1.96876004 0 P 0 ;0
L 1.91218996 -1.96876004 1.90975 -1.96926998 0 P 0 ;0
L 1.90975 -1.96926998 1.90725 -1.9696 0 P 0 ;0
L 1.90725 -1.9696 1.90473002 -1.96973996 0 P 0 ;0
L 1.90473002 -1.96973996 1.9022 -1.96968996 0 P 0 ;0
L 1.9022 -1.96968996 1.89966998 -1.96945 0 P 0 ;0
L 1.89966998 -1.96945 1.89778002 -1.96913002 0 P 0 ;0
L 1.89778002 -1.96913002 1.89591998 -1.96868996 0 P 0 ;0
L 1.89591998 -1.96868996 1.8941 -1.96811004 0 P 0 ;0
L 1.8941 -1.96811004 1.89231004 -1.96741004 0 P 0 ;0
L 1.89231004 -1.96741004 1.89058002 -1.96658002 0 P 0 ;0
L 1.89058002 -1.96658002 1.88875 -1.96553996 0 P 0 ;0
L 1.88875 -1.96553996 1.88698996 -1.96435 0 P 0 ;0
L 1.88698996 -1.96435 1.88533996 -1.96303002 0 P 0 ;0
L 1.88533996 -1.96303002 1.88378996 -1.9616 0 P 0 ;0
L 1.88378996 -1.9616 1.88235 -1.96003996 0 P 0 ;0
L 1.88235 -1.96003996 1.88103002 -1.95838996 0 P 0 ;0
L 1.88103002 -1.95838996 1.87983996 -1.95663002 0 P 0 ;0
L 1.87983996 -1.95663002 1.87861998 -1.95446998 0 P 0 ;0
L 1.87861998 -1.95446998 1.87758002 -1.9522 0 P 0 ;0
L 1.87758002 -1.9522 1.87673996 -1.94986004 0 P 0 ;0
L 1.87673996 -1.94986004 1.8761 -1.94745 0 P 0 ;0
L 1.8761 -1.94745 1.87568002 -1.945 0 P 0 ;0
L 1.87568002 -1.945 1.87546004 -1.94248996 0 P 0 ;0
L 1.87546004 -1.94248996 1.87546004 -1.93998996 0 P 0 ;0
L 1.87546004 -1.93998996 1.87566998 -1.93748996 0 P 0 ;0
L 1.87566998 -1.93748996 1.87608996 -1.93501998 0 P 0 ;0
L 1.87608996 -1.93501998 1.87671998 -1.9326 0 P 0 ;0
L 1.87671998 -1.9326 1.87755 -1.93023002 0 P 0 ;0
L 1.87755 -1.93023002 1.8786 -1.92793002 0 P 0 ;0
L 1.8786 -1.92793002 1.87981998 -1.92575 0 P 0 ;0
L 1.87981998 -1.92575 1.88123002 -1.92368002 0 P 0 ;0
L 1.88123002 -1.92368002 1.88281004 -1.92175 0 P 0 ;0
L 1.88281004 -1.92175 1.88455 -1.91996004 0 P 0 ;0
L 1.88455 -1.91996004 1.88643002 -1.91831998 0 P 0 ;0
L 1.88643002 -1.91831998 1.88845 -1.91686004 0 P 0 ;0
L 1.88845 -1.91686004 1.88986998 -1.91598996 0 P 0 ;0
L 1.88986998 -1.91598996 1.89135 -1.91523002 0 P 0 ;0
L 1.89135 -1.91523002 1.89288002 -1.91458996 0 P 0 ;0
L 1.89288002 -1.91458996 1.89446998 -1.91406004 0 P 0 ;0
L 1.89446998 -1.91406004 1.89688996 -1.91343996 0 P 0 ;0
L 1.89688996 -1.91343996 1.89935 -1.91298996 0 P 0 ;0
L 1.89935 -1.91298996 1.90183996 -1.91271004 0 P 0 ;0
L 1.90183996 -1.91271004 1.9044 -1.91261004 0 P 0 ;0
L 1.9044 -1.91261004 1.90695 -1.91268002 0 P 0 ;0
L 1.90695 -1.91268002 1.90948996 -1.91291998 0 P 0 ;0
L 1.90948996 -1.91291998 1.91181998 -1.91331998 0 P 0 ;0
L 1.91181998 -1.91331998 1.91408996 -1.91393002 0 P 0 ;0
L 1.91408996 -1.91393002 1.91633002 -1.91473002 0 P 0 ;0
L 1.89498002 -1.90801998 1.8922 -1.90893002 0 P 0 ;0
L 1.8922 -1.90893002 1.88948002 -1.91003002 0 P 0 ;0
L 1.88948002 -1.91003002 1.88686004 -1.91133002 0 P 0 ;0
L 1.88686004 -1.91133002 1.88431004 -1.91283996 0 P 0 ;0
L 1.88431004 -1.91283996 1.88201004 -1.91446004 0 P 0 ;0
L 1.88201004 -1.91446004 1.87985 -1.91626998 0 P 0 ;0
L 1.87985 -1.91626998 1.87785 -1.91826004 0 P 0 ;0
L 1.87785 -1.91826004 1.87601998 -1.92041004 0 P 0 ;0
L 1.87601998 -1.92041004 1.87441004 -1.92266998 0 P 0 ;0
L 1.87441004 -1.92266998 1.87298996 -1.92505 0 P 0 ;0
L 1.87298996 -1.92505 1.87178002 -1.92756004 0 P 0 ;0
L 1.87178002 -1.92756004 1.87078996 -1.93015 0 P 0 ;0
L 1.87078996 -1.93015 1.87 -1.93286998 0 P 0 ;0
L 1.87 -1.93286998 1.86943996 -1.93563996 0 P 0 ;0
L 1.86943996 -1.93563996 1.86908996 -1.93845 0 P 0 ;0
L 1.86908996 -1.93845 1.86898002 -1.94128996 0 P 0 ;0
L 1.86898002 -1.94128996 1.86911998 -1.94485 0 P 0 ;0
L 1.86911998 -1.94485 1.86953996 -1.94841004 0 P 0 ;0
L 1.86953996 -1.94841004 1.86996004 -1.95048996 0 P 0 ;0
L 1.86996004 -1.95048996 1.87053002 -1.95251998 0 P 0 ;0
L 1.87053002 -1.95251998 1.87125 -1.95451998 0 P 0 ;0
L 1.87125 -1.95451998 1.87211004 -1.95643002 0 P 0 ;0
L 1.87211004 -1.95643002 1.8731 -1.95826004 0 P 0 ;0
L 1.8731 -1.95826004 1.87423996 -1.96001998 0 P 0 ;0
L 1.87423996 -1.96001998 1.87636998 -1.96278996 0 P 0 ;0
L 1.87636998 -1.96278996 1.87871998 -1.96536998 0 P 0 ;0
L 1.87871998 -1.96536998 1.88145 -1.96788002 0 P 0 ;0
L 1.88145 -1.96788002 1.88436998 -1.97015 0 P 0 ;0
L 1.88436998 -1.97015 1.88621004 -1.97135 0 P 0 ;0
L 1.88621004 -1.97135 1.88813002 -1.97238002 0 P 0 ;0
L 1.88813002 -1.97238002 1.89013002 -1.97326004 0 P 0 ;0
L 1.89013002 -1.97326004 1.89228002 -1.97398996 0 P 0 ;0
L 1.89228002 -1.97398996 1.89446998 -1.97455 0 P 0 ;0
L 1.89446998 -1.97455 1.89671004 -1.97493996 0 P 0 ;0
L 1.89671004 -1.97493996 1.90076998 -1.97533996 0 P 0 ;0
L 1.90076998 -1.97533996 1.90485 -1.97546998 0 P 0 ;0
L 1.90485 -1.97546998 1.90821004 -1.97531998 0 P 0 ;0
L 1.90821004 -1.97531998 1.91153996 -1.97488996 0 P 0 ;0
L 1.91153996 -1.97488996 1.91481998 -1.97418996 0 P 0 ;0
L 1.91481998 -1.97418996 1.9171 -1.9735 0 P 0 ;0
L 1.9171 -1.9735 1.91933002 -1.97266004 0 P 0 ;0
L 1.91933002 -1.97266004 1.92148002 -1.97166004 0 P 0 ;0
L 1.92148002 -1.97166004 1.92356998 -1.97048996 0 P 0 ;0
L 1.92356998 -1.97048996 1.92553996 -1.96918996 0 P 0 ;0
L 1.92553996 -1.96918996 1.92741004 -1.96773996 0 P 0 ;0
L 1.92741004 -1.96773996 1.92916004 -1.96616998 0 P 0 ;0
L 1.92916004 -1.96616998 1.93081004 -1.96446004 0 P 0 ;0
L 1.93081004 -1.96446004 1.93236998 -1.96256998 0 P 0 ;0
L 1.93236998 -1.96256998 1.93381004 -1.96058996 0 P 0 ;0
L 1.93381004 -1.96058996 1.93511998 -1.95851004 0 P 0 ;0
L 1.93511998 -1.95851004 1.93628996 -1.95633996 0 P 0 ;0
L 1.93628996 -1.95633996 1.93803996 -1.95251998 0 P 0 ;0
L 1.93803996 -1.95251998 1.93858002 -1.95101998 0 P 0 ;0
L 1.93858002 -1.95101998 1.93898996 -1.94948002 0 P 0 ;0
L 1.93898996 -1.94948002 1.93928996 -1.94786998 0 P 0 ;0
L 1.93928996 -1.94786998 1.93946004 -1.94625 0 P 0 ;0
L 1.93946004 -1.94625 1.9396 -1.94178002 0 P 0 ;0
L 1.9396 -1.94178002 1.93946004 -1.93803996 0 P 0 ;0
L 1.93946004 -1.93803996 1.93905 -1.9343 0 P 0 ;0
L 1.93905 -1.9343 1.93863996 -1.93213996 0 P 0 ;0
L 1.93863996 -1.93213996 1.93808002 -1.93001998 0 P 0 ;0
L 1.93808002 -1.93001998 1.93736004 -1.92795 0 P 0 ;0
L 1.93736004 -1.92795 1.93653002 -1.92601004 0 P 0 ;0
L 1.93653002 -1.92601004 1.93555 -1.92415 0 P 0 ;0
L 1.93555 -1.92415 1.93441998 -1.92236004 0 P 0 ;0
L 1.93441998 -1.92236004 1.9331 -1.92056004 0 P 0 ;0
L 1.9331 -1.92056004 1.93166998 -1.91885 0 P 0 ;0
L 1.93166998 -1.91885 1.93011998 -1.91723002 0 P 0 ;0
L 1.93011998 -1.91723002 1.92896004 -1.91615 0 P 0 ;0
L 1.92896004 -1.91615 1.92775 -1.91511004 0 P 0 ;0
L 1.92775 -1.91511004 1.92493002 -1.91295 0 P 0 ;0
L 1.92493002 -1.91295 1.9221 -1.91108002 0 P 0 ;0
L 1.9221 -1.91108002 1.92095 -1.91043002 0 P 0 ;0
L 1.92095 -1.91043002 1.91975 -1.90985 0 P 0 ;0
L 1.91975 -1.90985 1.91796004 -1.90913996 0 P 0 ;0
L 1.91796004 -1.90913996 1.91613002 -1.90856004 0 P 0 ;0
L 1.91613002 -1.90856004 1.91423996 -1.9081 0 P 0 ;0
L 1.91423996 -1.9081 1.91086004 -1.90751998 0 P 0 ;0
L 1.91086004 -1.90751998 1.90743002 -1.90716004 0 P 0 ;0
L 1.90743002 -1.90716004 1.90401004 -1.90701004 0 P 0 ;0
L 1.90401004 -1.90701004 1.90058002 -1.90708002 0 P 0 ;0
L 1.90058002 -1.90708002 1.8987 -1.90726004 0 P 0 ;0
L 1.8987 -1.90726004 1.89683002 -1.90756998 0 P 0 ;0
L 1.89683002 -1.90756998 1.89498002 -1.90801998 0 P 0 ;0
L 1.86643002 -2.02923996 1.87525 -2.02923996 0 P 0 ;0
L 1.86176998 -2.02823996 1.87515 -2.02823996 0 P 0 ;0
L 1.85588996 -2.02723996 1.87505 -2.02723996 0 P 0 ;0
L 1.78365 -2.00523996 1.87281004 -2.00523996 0 P 0 ;0
L 1.78451004 -2.00423996 1.87271004 -2.00423996 0 P 0 ;0
L 1.78546998 -2.00323996 1.87261004 -2.00323996 0 P 0 ;0
L 1.78655 -2.00223996 1.8725 -2.00223996 0 P 0 ;0
L 1.78776004 -2.00123996 1.8724 -2.00123996 0 P 0 ;0
L 1.78915 -2.00023996 1.8723 -2.00023996 0 P 0 ;0
L 1.79078996 -1.99923996 1.8722 -1.99923996 0 P 0 ;0
L 1.79263996 -1.99823996 1.87208996 -1.99823996 0 P 0 ;0
L 1.79458996 -1.99723996 1.87198996 -1.99723996 0 P 0 ;0
L 1.79686998 -1.99623996 1.87188002 -1.99623996 0 P 0 ;0
L 1.79946004 -1.99523996 1.87178002 -1.99523996 0 P 0 ;0
L 1.80231004 -1.99423996 1.86961998 -1.99423996 0 P 0 ;0
L 1.80596004 -1.99323996 1.86218002 -1.99323996 0 P 0 ;0
L 1.81051004 -1.99223996 1.85398002 -1.99223996 0 P 0 ;0
L 1.81676004 -1.99123996 1.84395 -1.99123996 0 P 0 ;0
L 1.87786998 -1.96146004 1.88093996 -1.96146004 0 P 0 ;0
L 1.8771 -1.96046004 1.88013002 -1.96046004 0 P 0 ;0
L 1.87633996 -1.95946004 1.87933996 -1.95946004 0 P 0 ;0
L 1.87561998 -1.95846004 1.87866998 -1.95846004 0 P 0 ;0
L 1.87496998 -1.95746004 1.87801998 -1.95746004 0 P 0 ;0
L 1.8744 -1.95646004 1.87745 -1.95646004 0 P 0 ;0
L 1.87386998 -1.95546004 1.87688002 -1.95546004 0 P 0 ;0
L 1.87341998 -1.95446004 1.87641998 -1.95446004 0 P 0 ;0
L 1.87298996 -1.95346004 1.87596004 -1.95346004 0 P 0 ;0
L 1.87263002 -1.95246004 1.87555 -1.95246004 0 P 0 ;0
L 1.87231004 -1.95146004 1.87518996 -1.95146004 0 P 0 ;0
L 1.87203002 -1.95046004 1.87483002 -1.95046004 0 P 0 ;0
L 1.87178996 -1.94946004 1.87456998 -1.94946004 0 P 0 ;0
L 1.87158996 -1.94846004 1.87431004 -1.94846004 0 P 0 ;0
L 1.87143996 -1.94746004 1.87408002 -1.94746004 0 P 0 ;0
L 1.87133002 -1.94646004 1.8739 -1.94646004 0 P 0 ;0
L 1.87121004 -1.94546004 1.87373002 -1.94546004 0 P 0 ;0
L 1.8711 -1.94446998 1.87361998 -1.94446998 0 P 0 ;0
L 1.87106998 -1.94346004 1.87353996 -1.94346004 0 P 0 ;0
L 1.87103002 -1.94246004 1.87346004 -1.94246004 0 P 0 ;0
L 1.87098996 -1.94146998 1.87346004 -1.94146998 0 P 0 ;0
L 1.87101004 -1.94046004 1.87346004 -1.94046004 0 P 0 ;0
L 1.87106004 -1.93946004 1.87348996 -1.93946004 0 P 0 ;0
L 1.87111004 -1.93846004 1.87358002 -1.93846004 0 P 0 ;0
L 1.87123002 -1.93746004 1.87366004 -1.93746004 0 P 0 ;0
L 1.87135 -1.93646004 1.87381998 -1.93646004 0 P 0 ;0
L 1.87151004 -1.93546004 1.87398996 -1.93546004 0 P 0 ;0
L 1.87171998 -1.93446004 1.87416998 -1.93446004 0 P 0 ;0
L 1.87191998 -1.93346004 1.87443002 -1.93346004 0 P 0 ;0
L 1.8722 -1.93246004 1.87468996 -1.93246004 0 P 0 ;0
L 1.87248996 -1.93146004 1.875 -1.93146004 0 P 0 ;0
L 1.87281004 -1.93046004 1.87535 -1.93046004 0 P 0 ;0
L 1.87318996 -1.92946004 1.87571004 -1.92946004 0 P 0 ;0
L 1.87356998 -1.92846004 1.87616004 -1.92846004 0 P 0 ;0
L 1.87405 -1.92746004 1.87661004 -1.92746004 0 P 0 ;0
L 1.87453002 -1.92646004 1.87711998 -1.92646004 0 P 0 ;0
L 1.87506998 -1.92546004 1.87768996 -1.92546004 0 P 0 ;0
L 1.87566004 -1.92446998 1.87826998 -1.92446998 0 P 0 ;0
L 1.87628996 -1.92346004 1.87896004 -1.92346004 0 P 0 ;0
L 1.87701004 -1.92246004 1.87963996 -1.92246004 0 P 0 ;0
L 1.87775 -1.92146004 1.88046004 -1.92146004 0 P 0 ;0
L 1.90483996 -1.97346004 1.9009 -1.97333996 0 P 0 ;0
L 1.9009 -1.97333996 1.89698002 -1.97295 0 P 0 ;0
L 1.89698002 -1.97295 1.89488996 -1.97258996 0 P 0 ;0
L 1.89488996 -1.97258996 1.89285 -1.97206998 0 P 0 ;0
L 1.89285 -1.97206998 1.89086004 -1.97138996 0 P 0 ;0
L 1.89086004 -1.97138996 1.889 -1.97058002 0 P 0 ;0
L 1.889 -1.97058002 1.88723002 -1.96961998 0 P 0 ;0
L 1.88723002 -1.96961998 1.88553002 -1.96851998 0 P 0 ;0
L 1.88553002 -1.96851998 1.88273996 -1.96636004 0 P 0 ;0
L 1.88273996 -1.96636004 1.88013996 -1.96396004 0 P 0 ;0
L 1.88013996 -1.96396004 1.8779 -1.9615 0 P 0 ;0
L 1.8779 -1.9615 1.87588002 -1.95886998 0 P 0 ;0
L 1.87588002 -1.95886998 1.87483002 -1.95723996 0 P 0 ;0
L 1.87483002 -1.95723996 1.8739 -1.95553996 0 P 0 ;0
L 1.8739 -1.95553996 1.87311004 -1.95376998 0 P 0 ;0
L 1.87311004 -1.95376998 1.87243002 -1.95191004 0 P 0 ;0
L 1.87243002 -1.95191004 1.8719 -1.95001998 0 P 0 ;0
L 1.8719 -1.95001998 1.87151998 -1.9481 0 P 0 ;0
L 1.87151998 -1.9481 1.87111004 -1.94468996 0 P 0 ;0
L 1.87111004 -1.94468996 1.87098002 -1.94128996 0 P 0 ;0
L 1.87098002 -1.94128996 1.87108996 -1.93861004 0 P 0 ;0
L 1.87108996 -1.93861004 1.87141004 -1.93596998 0 P 0 ;0
L 1.87141004 -1.93596998 1.87195 -1.93335 0 P 0 ;0
L 1.87195 -1.93335 1.87268996 -1.93078996 0 P 0 ;0
L 1.87268996 -1.93078996 1.87361998 -1.92835 0 P 0 ;0
L 1.87361998 -1.92835 1.87475 -1.926 0 P 0 ;0
L 1.87475 -1.926 1.87608996 -1.92376004 0 P 0 ;0
L 1.87608996 -1.92376004 1.8776 -1.92163996 0 P 0 ;0
L 1.8776 -1.92163996 1.87931998 -1.91961998 0 P 0 ;0
L 1.87931998 -1.91961998 1.8812 -1.91775 0 P 0 ;0
L 1.8812 -1.91775 1.88323002 -1.91605 0 P 0 ;0
L 1.88323002 -1.91605 1.8854 -1.91451998 0 P 0 ;0
L 1.8854 -1.91451998 1.88781004 -1.91308996 0 P 0 ;0
L 1.88781004 -1.91308996 1.89031004 -1.91186004 0 P 0 ;0
L 1.89031004 -1.91186004 1.89288002 -1.9108 0 P 0 ;0
L 1.89288002 -1.9108 1.89553002 -1.90995 0 P 0 ;0
L 1.89553002 -1.90995 1.89723002 -1.90953002 0 P 0 ;0
L 1.89723002 -1.90953002 1.89896004 -1.90923996 0 P 0 ;0
L 1.89896004 -1.90923996 1.90068996 -1.90908002 0 P 0 ;0
L 1.90068996 -1.90908002 1.90398996 -1.90901004 0 P 0 ;0
L 1.90398996 -1.90901004 1.90728002 -1.90915 0 P 0 ;0
L 1.90728002 -1.90915 1.91058996 -1.90951004 0 P 0 ;0
L 1.91058996 -1.90951004 1.91383996 -1.91006004 0 P 0 ;0
L 1.91383996 -1.91006004 1.91558996 -1.91048996 0 P 0 ;0
L 1.91558996 -1.91048996 1.91728996 -1.91101998 0 P 0 ;0
L 1.91728996 -1.91101998 1.91895 -1.91168002 0 P 0 ;0
L 1.91895 -1.91168002 1.92001998 -1.9122 0 P 0 ;0
L 1.92001998 -1.9122 1.92105 -1.91278996 0 P 0 ;0
L 1.92105 -1.91278996 1.92376998 -1.91458002 0 P 0 ;0
L 1.92376998 -1.91458002 1.92648996 -1.91666998 0 P 0 ;0
L 1.92648996 -1.91666998 1.92763002 -1.91763996 0 P 0 ;0
L 1.92763002 -1.91763996 1.92871004 -1.91865 0 P 0 ;0
L 1.92871004 -1.91865 1.93018002 -1.92018996 0 P 0 ;0
L 1.93018002 -1.92018996 1.93153002 -1.9218 0 P 0 ;0
L 1.93153002 -1.9218 1.93276998 -1.92348996 0 P 0 ;0
L 1.93276998 -1.92348996 1.93381004 -1.92515 0 P 0 ;0
L 1.93381004 -1.92515 1.93471998 -1.92686998 0 P 0 ;0
L 1.93471998 -1.92686998 1.9355 -1.92866998 0 P 0 ;0
L 1.9355 -1.92866998 1.93616998 -1.93061004 0 P 0 ;0
L 1.93616998 -1.93061004 1.93668996 -1.93258002 0 P 0 ;0
L 1.93668996 -1.93258002 1.93706998 -1.93458996 0 P 0 ;0
L 1.93706998 -1.93458996 1.93746998 -1.93818996 0 P 0 ;0
L 1.93746998 -1.93818996 1.9376 -1.94178996 0 P 0 ;0
L 1.9376 -1.94178996 1.93746004 -1.94611004 0 P 0 ;0
L 1.93746004 -1.94611004 1.93731004 -1.94758996 0 P 0 ;0
L 1.93731004 -1.94758996 1.93705 -1.94903996 0 P 0 ;0
L 1.93705 -1.94903996 1.93666998 -1.95041998 0 P 0 ;0
L 1.93666998 -1.95041998 1.93618002 -1.95176004 0 P 0 ;0
L 1.93618002 -1.95176004 1.9345 -1.95545 0 P 0 ;0
L 1.9345 -1.95545 1.93338996 -1.9575 0 P 0 ;0
L 1.93338996 -1.9575 1.93216004 -1.95946998 0 P 0 ;0
L 1.93216004 -1.95946998 1.93078996 -1.96133996 0 P 0 ;0
L 1.93078996 -1.96133996 1.92931004 -1.96311998 0 P 0 ;0
L 1.92931004 -1.96311998 1.92776998 -1.96473002 0 P 0 ;0
L 1.92776998 -1.96473002 1.92613002 -1.96621004 0 P 0 ;0
L 1.92613002 -1.96621004 1.92438002 -1.96756004 0 P 0 ;0
L 1.92438002 -1.96756004 1.92253002 -1.96878002 0 P 0 ;0
L 1.92253002 -1.96878002 1.92056998 -1.96986998 0 P 0 ;0
L 1.92056998 -1.96986998 1.91855 -1.97081998 0 P 0 ;0
L 1.91855 -1.97081998 1.91646004 -1.97161004 0 P 0 ;0
L 1.91646004 -1.97161004 1.91433002 -1.97223996 0 P 0 ;0
L 1.91433002 -1.97223996 1.9112 -1.97291004 0 P 0 ;0
L 1.9112 -1.97291004 1.90803996 -1.97331998 0 P 0 ;0
L 1.90803996 -1.97331998 1.90483996 -1.97346004 0 P 0 ;0
L 1.90476004 -1.97173996 1.9048 -1.97173996 0 P 0 ;0
L 1.9048 -1.97173996 1.90483996 -1.97173002 0 P 0 ;0
L 1.90483996 -1.97173002 1.90736004 -1.9716 0 P 0 ;0
L 1.90736004 -1.9716 1.9074 -1.97158996 0 P 0 ;0
L 1.9074 -1.97158996 1.90746998 -1.97158996 0 P 0 ;0
L 1.90746998 -1.97158996 1.90751004 -1.97158002 0 P 0 ;0
L 1.90751004 -1.97158002 1.91001004 -1.97126004 0 P 0 ;0
L 1.91001004 -1.97126004 1.91005 -1.97125 0 P 0 ;0
L 1.91005 -1.97125 1.91008002 -1.97123996 0 P 0 ;0
L 1.91008002 -1.97123996 1.91011998 -1.97123996 0 P 0 ;0
L 1.91011998 -1.97123996 1.91016004 -1.97123002 0 P 0 ;0
L 1.91016004 -1.97123002 1.9126 -1.97071998 0 P 0 ;0
L 1.9126 -1.97071998 1.9126 -1.97071004 0 P 0 ;0
L 1.9126 -1.97071004 1.91266998 -1.97071004 0 P 0 ;0
L 1.91266998 -1.97071004 1.91271004 -1.97068996 0 P 0 ;0
L 1.91271004 -1.97068996 1.91275 -1.97068002 0 P 0 ;0
L 1.91275 -1.97068002 1.91511998 -1.96998996 0 P 0 ;0
L 1.91511998 -1.96998996 1.91515 -1.96998996 0 P 0 ;0
L 1.91515 -1.96998996 1.91518996 -1.96996998 0 P 0 ;0
L 1.91518996 -1.96996998 1.91523002 -1.96996004 0 P 0 ;0
L 1.91523002 -1.96996004 1.91526004 -1.96995 0 P 0 ;0
L 1.91526004 -1.96995 1.91756998 -1.96908002 0 P 0 ;0
L 1.91756998 -1.96908002 1.91761004 -1.96906998 0 P 0 ;0
L 1.91761004 -1.96906998 1.91768002 -1.96903996 0 P 0 ;0
L 1.91768002 -1.96903996 1.91771004 -1.96901998 0 P 0 ;0
L 1.91771004 -1.96901998 1.91995 -1.96798002 0 P 0 ;0
L 1.91995 -1.96798002 1.92001998 -1.96795 0 P 0 ;0
L 1.92001998 -1.96795 1.92005 -1.96793002 0 P 0 ;0
L 1.92005 -1.96793002 1.92008996 -1.96791004 0 P 0 ;0
L 1.92008996 -1.96791004 1.92168002 -1.96701998 0 P 0 ;0
L 1.92168002 -1.96701998 1.92171998 -1.967 0 P 0 ;0
L 1.92171998 -1.967 1.92175 -1.96698002 0 P 0 ;0
L 1.92175 -1.96698002 1.92178996 -1.96695 0 P 0 ;0
L 1.92178996 -1.96695 1.92181998 -1.96693002 0 P 0 ;0
L 1.92181998 -1.96693002 1.92331998 -1.96591998 0 P 0 ;0
L 1.92331998 -1.96591998 1.92336004 -1.9659 0 P 0 ;0
L 1.92336004 -1.9659 1.92341998 -1.96586004 0 P 0 ;0
L 1.92341998 -1.96586004 1.92345 -1.96583002 0 P 0 ;0
L 1.92345 -1.96583002 1.92486004 -1.9647 0 P 0 ;0
L 1.92486004 -1.9647 1.92493002 -1.96465 0 P 0 ;0
L 1.92493002 -1.96465 1.92496004 -1.96463002 0 P 0 ;0
L 1.92496004 -1.96463002 1.92498996 -1.9646 0 P 0 ;0
L 1.92498996 -1.9646 1.92631004 -1.96336998 0 P 0 ;0
L 1.92631004 -1.96336998 1.9264 -1.96328002 0 P 0 ;0
L 1.9264 -1.96328002 1.92641998 -1.96325 0 P 0 ;0
L 1.92641998 -1.96325 1.92763996 -1.96191998 0 P 0 ;0
L 1.92763996 -1.96191998 1.92766998 -1.96188996 0 P 0 ;0
L 1.92766998 -1.96188996 1.92768996 -1.96186004 0 P 0 ;0
L 1.92768996 -1.96186004 1.92771998 -1.96183002 0 P 0 ;0
L 1.92771998 -1.96183002 1.92773996 -1.9618 0 P 0 ;0
L 1.92773996 -1.9618 1.92913996 -1.96001004 0 P 0 ;0
L 1.92913996 -1.96001004 1.92918996 -1.95995 0 P 0 ;0
L 1.92918996 -1.95995 1.92921004 -1.95991004 0 P 0 ;0
L 1.92921004 -1.95991004 1.92923002 -1.95988002 0 P 0 ;0
L 1.92923002 -1.95988002 1.93048002 -1.95798996 0 P 0 ;0
L 1.93048002 -1.95798996 1.93051998 -1.95793002 0 P 0 ;0
L 1.93051998 -1.95793002 1.93053996 -1.95788996 0 P 0 ;0
L 1.93053996 -1.95788996 1.93056004 -1.95786004 0 P 0 ;0
L 1.93056004 -1.95786004 1.93166004 -1.95588002 0 P 0 ;0
L 1.93166004 -1.95588002 1.93171004 -1.95576998 0 P 0 ;0
L 1.93171004 -1.95576998 1.93173002 -1.95573996 0 P 0 ;0
L 1.93173002 -1.95573996 1.93266998 -1.95366998 0 P 0 ;0
L 1.93266998 -1.95366998 1.93271004 -1.95356998 0 P 0 ;0
L 1.93271004 -1.95356998 1.93273002 -1.95353002 0 P 0 ;0
L 1.93273002 -1.95353002 1.9335 -1.9514 0 P 0 ;0
L 1.9335 -1.9514 1.93351004 -1.95136998 0 P 0 ;0
L 1.93351004 -1.95136998 1.93353002 -1.95133002 0 P 0 ;0
L 1.93353002 -1.95133002 1.93355 -1.95125 0 P 0 ;0
L 1.93355 -1.95125 1.93416004 -1.94906998 0 P 0 ;0
L 1.93416004 -1.94906998 1.93416998 -1.94903002 0 P 0 ;0
L 1.93416998 -1.94903002 1.93418002 -1.949 0 P 0 ;0
L 1.93418002 -1.949 1.93418002 -1.94896004 0 P 0 ;0
L 1.93418002 -1.94896004 1.93418996 -1.94891998 0 P 0 ;0
L 1.93418996 -1.94891998 1.93463996 -1.94665 0 P 0 ;0
L 1.93463996 -1.94665 1.93463996 -1.94661004 0 P 0 ;0
L 1.93463996 -1.94661004 1.93465 -1.94656998 0 P 0 ;0
L 1.93465 -1.94656998 1.93466004 -1.9465 0 P 0 ;0
L 1.93466004 -1.9465 1.93493996 -1.9442 0 P 0 ;0
L 1.93493996 -1.9442 1.93493996 -1.94413002 0 P 0 ;0
L 1.93493996 -1.94413002 1.93495 -1.94408996 0 P 0 ;0
L 1.93495 -1.94408996 1.93495 -1.94406004 0 P 0 ;0
L 1.93495 -1.94406004 1.93505 -1.94173996 0 P 0 ;0
L 1.93505 -1.94173996 1.93506004 -1.94171004 0 P 0 ;0
L 1.93506004 -1.94171004 1.93506004 -1.9416 0 P 0 ;0
L 1.93506004 -1.9416 1.93498996 -1.93928996 0 P 0 ;0
L 1.93498996 -1.93928996 1.93498996 -1.93921004 0 P 0 ;0
L 1.93498996 -1.93921004 1.93498002 -1.93913996 0 P 0 ;0
L 1.93498002 -1.93913996 1.93475 -1.93683996 0 P 0 ;0
L 1.93475 -1.93683996 1.93473996 -1.93676998 0 P 0 ;0
L 1.93473996 -1.93676998 1.93473002 -1.93673002 0 P 0 ;0
L 1.93473002 -1.93673002 1.93473002 -1.93668996 0 P 0 ;0
L 1.93473002 -1.93668996 1.93433002 -1.93441004 0 P 0 ;0
L 1.93433002 -1.93441004 1.93431998 -1.93436998 0 P 0 ;0
L 1.93431998 -1.93436998 1.93431004 -1.93433996 0 P 0 ;0
L 1.93431004 -1.93433996 1.93428996 -1.93426004 0 P 0 ;0
L 1.93428996 -1.93426004 1.93373002 -1.93206004 0 P 0 ;0
L 1.93373002 -1.93206004 1.93368996 -1.93191998 0 P 0 ;0
L 1.93368996 -1.93191998 1.93296004 -1.92976998 0 P 0 ;0
L 1.93296004 -1.92976998 1.93293996 -1.9297 0 P 0 ;0
L 1.93293996 -1.9297 1.93291004 -1.92963002 0 P 0 ;0
L 1.93291004 -1.92963002 1.93201998 -1.92753996 0 P 0 ;0
L 1.93201998 -1.92753996 1.93196998 -1.92743002 0 P 0 ;0
L 1.93196998 -1.92743002 1.93196004 -1.9274 0 P 0 ;0
L 1.93196004 -1.9274 1.93091998 -1.92538996 0 P 0 ;0
L 1.93091998 -1.92538996 1.9309 -1.92536004 0 P 0 ;0
L 1.9309 -1.92536004 1.93088002 -1.92531998 0 P 0 ;0
L 1.93088002 -1.92531998 1.93086004 -1.92528996 0 P 0 ;0
L 1.93086004 -1.92528996 1.93083996 -1.92525 0 P 0 ;0
L 1.93083996 -1.92525 1.92965 -1.92331998 0 P 0 ;0
L 1.92965 -1.92331998 1.92956998 -1.9232 0 P 0 ;0
L 1.92956998 -1.9232 1.92823002 -1.92136004 0 P 0 ;0
L 1.92823002 -1.92136004 1.92818002 -1.9213 0 P 0 ;0
L 1.92818002 -1.9213 1.92816004 -1.92126998 0 P 0 ;0
L 1.92816004 -1.92126998 1.92813002 -1.92123996 0 P 0 ;0
L 1.92813002 -1.92123996 1.92671998 -1.91958002 0 P 0 ;0
L 1.92671998 -1.91958002 1.9266 -1.91946004 0 P 0 ;0
L 1.9266 -1.91946004 1.92505 -1.91793002 0 P 0 ;0
L 1.92505 -1.91793002 1.92498996 -1.91786998 0 P 0 ;0
L 1.92498996 -1.91786998 1.92493002 -1.91781998 0 P 0 ;0
L 1.92493002 -1.91781998 1.92325 -1.91643002 0 P 0 ;0
L 1.92325 -1.91643002 1.92318996 -1.91636998 0 P 0 ;0
L 1.92318996 -1.91636998 1.92311998 -1.91631998 0 P 0 ;0
L 1.92311998 -1.91631998 1.92133002 -1.91508002 0 P 0 ;0
L 1.92133002 -1.91508002 1.92126004 -1.91503996 0 P 0 ;0
L 1.92126004 -1.91503996 1.92121998 -1.91501004 0 P 0 ;0
L 1.92121998 -1.91501004 1.92118002 -1.91498996 0 P 0 ;0
L 1.92118002 -1.91498996 1.91928996 -1.91391004 0 P 0 ;0
L 1.91928996 -1.91391004 1.91926004 -1.91388996 0 P 0 ;0
L 1.91926004 -1.91388996 1.91913996 -1.91383002 0 P 0 ;0
L 1.91913996 -1.91383002 1.91716998 -1.91291004 0 P 0 ;0
L 1.91716998 -1.91291004 1.91711998 -1.91288996 0 P 0 ;0
L 1.91711998 -1.91288996 1.91705 -1.91286004 0 P 0 ;0
L 1.91705 -1.91286004 1.917 -1.91285 0 P 0 ;0
L 1.917 -1.91285 1.91476998 -1.91203996 0 P 0 ;0
L 1.91476998 -1.91203996 1.91468996 -1.91201998 0 P 0 ;0
L 1.91468996 -1.91201998 1.91465 -1.912 0 P 0 ;0
L 1.91465 -1.912 1.9146 -1.91198996 0 P 0 ;0
L 1.9146 -1.91198996 1.91233002 -1.91138996 0 P 0 ;0
L 1.91233002 -1.91138996 1.91228002 -1.91138002 0 P 0 ;0
L 1.91228002 -1.91138002 1.91223996 -1.91136998 0 P 0 ;0
L 1.91223996 -1.91136998 1.91216004 -1.91136004 0 P 0 ;0
L 1.91216004 -1.91136004 1.90983002 -1.91095 0 P 0 ;0
L 1.90983002 -1.91095 1.9098 -1.91093996 0 P 0 ;0
L 1.9098 -1.91093996 1.90976004 -1.91093996 0 P 0 ;0
L 1.90976004 -1.91093996 1.90971998 -1.91093002 0 P 0 ;0
L 1.90971998 -1.91093002 1.90968002 -1.91093002 0 P 0 ;0
L 1.90968002 -1.91093002 1.90713996 -1.91068996 0 P 0 ;0
L 1.90713996 -1.91068996 1.9071 -1.91068002 0 P 0 ;0
L 1.9071 -1.91068002 1.907 -1.91068002 0 P 0 ;0
L 1.907 -1.91068002 1.90445 -1.91061004 0 P 0 ;0
L 1.90445 -1.91061004 1.90431004 -1.91061004 0 P 0 ;0
L 1.90431004 -1.91061004 1.90176004 -1.91071004 0 P 0 ;0
L 1.90176004 -1.91071004 1.90173002 -1.91071998 0 P 0 ;0
L 1.90173002 -1.91071998 1.90166004 -1.91071998 0 P 0 ;0
L 1.90166004 -1.91071998 1.90161998 -1.91073002 0 P 0 ;0
L 1.90161998 -1.91073002 1.89913002 -1.911 0 P 0 ;0
L 1.89913002 -1.911 1.89906004 -1.91101004 0 P 0 ;0
L 1.89906004 -1.91101004 1.89901998 -1.91101998 0 P 0 ;0
L 1.89901998 -1.91101998 1.89898996 -1.91101998 0 P 0 ;0
L 1.89898996 -1.91101998 1.89653002 -1.91146998 0 P 0 ;0
L 1.89653002 -1.91146998 1.8965 -1.91148002 0 P 0 ;0
L 1.8965 -1.91148002 1.89646004 -1.91148002 0 P 0 ;0
L 1.89646004 -1.91148002 1.8964 -1.9115 0 P 0 ;0
L 1.8964 -1.9115 1.89396998 -1.91211998 0 P 0 ;0
L 1.89396998 -1.91211998 1.89393996 -1.91213002 0 P 0 ;0
L 1.89393996 -1.91213002 1.89383002 -1.91216004 0 P 0 ;0
L 1.89383002 -1.91216004 1.89225 -1.91268996 0 P 0 ;0
L 1.89225 -1.91268996 1.89218002 -1.91271998 0 P 0 ;0
L 1.89218002 -1.91271998 1.89211004 -1.91273996 0 P 0 ;0
L 1.89211004 -1.91273996 1.8921 -1.91273996 0 P 0 ;0
L 1.8921 -1.91273996 1.89058002 -1.91338996 0 P 0 ;0
L 1.89058002 -1.91338996 1.89043996 -1.91345 0 P 0 ;0
L 1.89043996 -1.91345 1.88896004 -1.91421004 0 P 0 ;0
L 1.88896004 -1.91421004 1.88893002 -1.91423002 0 P 0 ;0
L 1.88893002 -1.91423002 1.8889 -1.91423996 0 P 0 ;0
L 1.8889 -1.91423996 1.88886004 -1.91426004 0 P 0 ;0
L 1.88886004 -1.91426004 1.88883002 -1.91428002 0 P 0 ;0
L 1.88883002 -1.91428002 1.88741004 -1.91515 0 P 0 ;0
L 1.88741004 -1.91515 1.88733996 -1.91518996 0 P 0 ;0
L 1.88733996 -1.91518996 1.88728002 -1.91523996 0 P 0 ;0
L 1.88728002 -1.91523996 1.88526004 -1.9167 0 P 0 ;0
L 1.88526004 -1.9167 1.88521998 -1.91673002 0 P 0 ;0
L 1.88521998 -1.91673002 1.88518996 -1.91675 0 P 0 ;0
L 1.88518996 -1.91675 1.88516004 -1.91678002 0 P 0 ;0
L 1.88516004 -1.91678002 1.88511998 -1.91681004 0 P 0 ;0
L 1.88511998 -1.91681004 1.88323002 -1.91845 0 P 0 ;0
L 1.88323002 -1.91845 1.8832 -1.91846998 0 P 0 ;0
L 1.8832 -1.91846998 1.88311004 -1.91856004 0 P 0 ;0
L 1.88311004 -1.91856004 1.88136998 -1.92036004 0 P 0 ;0
L 1.88136998 -1.92036004 1.88128002 -1.92045 0 P 0 ;0
L 1.88128002 -1.92045 1.88125 -1.92048996 0 P 0 ;0
L 1.88125 -1.92048996 1.87968002 -1.92241998 0 P 0 ;0
L 1.87968002 -1.92241998 1.87965 -1.92245 0 P 0 ;0
L 1.87965 -1.92245 1.87961998 -1.92248996 0 P 0 ;0
L 1.87961998 -1.92248996 1.87956998 -1.92256004 0 P 0 ;0
L 1.87956998 -1.92256004 1.87816998 -1.92461998 0 P 0 ;0
L 1.87816998 -1.92461998 1.8781 -1.92473002 0 P 0 ;0
L 1.8781 -1.92473002 1.87808002 -1.92476998 0 P 0 ;0
L 1.87808002 -1.92476998 1.87685 -1.92695 0 P 0 ;0
L 1.87685 -1.92695 1.87683002 -1.92698996 0 P 0 ;0
L 1.87683002 -1.92698996 1.87681004 -1.92701998 0 P 0 ;0
L 1.87681004 -1.92701998 1.87678996 -1.92706998 0 P 0 ;0
L 1.87678996 -1.92706998 1.87676998 -1.92711004 0 P 0 ;0
L 1.87676998 -1.92711004 1.87573002 -1.92941004 0 P 0 ;0
L 1.87573002 -1.92941004 1.87571004 -1.92945 0 P 0 ;0
L 1.87571004 -1.92945 1.8757 -1.92948996 0 P 0 ;0
L 1.8757 -1.92948996 1.87568002 -1.92951998 0 P 0 ;0
L 1.87568002 -1.92951998 1.87566998 -1.92956998 0 P 0 ;0
L 1.87566998 -1.92956998 1.87483996 -1.93193002 0 P 0 ;0
L 1.87483996 -1.93193002 1.87481004 -1.93201004 0 P 0 ;0
L 1.87481004 -1.93201004 1.87478996 -1.93208996 0 P 0 ;0
L 1.87478996 -1.93208996 1.87416004 -1.93451998 0 P 0 ;0
L 1.87416004 -1.93451998 1.87413996 -1.93456004 0 P 0 ;0
L 1.87413996 -1.93456004 1.87413002 -1.9346 0 P 0 ;0
L 1.87413002 -1.9346 1.87413002 -1.93463996 0 P 0 ;0
L 1.87413002 -1.93463996 1.87411998 -1.93468002 0 P 0 ;0
L 1.87411998 -1.93468002 1.8737 -1.93715 0 P 0 ;0
L 1.8737 -1.93715 1.87368996 -1.93718996 0 P 0 ;0
L 1.87368996 -1.93718996 1.87368002 -1.93723996 0 P 0 ;0
L 1.87368002 -1.93723996 1.87368002 -1.93731998 0 P 0 ;0
L 1.87368002 -1.93731998 1.87346998 -1.93981998 0 P 0 ;0
L 1.87346998 -1.93981998 1.87346004 -1.93986004 0 P 0 ;0
L 1.87346004 -1.93986004 1.87346004 -1.94258002 0 P 0 ;0
L 1.87346004 -1.94258002 1.87346998 -1.94266004 0 P 0 ;0
L 1.87346998 -1.94266004 1.87368002 -1.94516998 0 P 0 ;0
L 1.87368002 -1.94516998 1.87368996 -1.94521004 0 P 0 ;0
L 1.87368996 -1.94521004 1.87368996 -1.94525 0 P 0 ;0
L 1.87368996 -1.94525 1.87371004 -1.94533996 0 P 0 ;0
L 1.87371004 -1.94533996 1.87413996 -1.94778996 0 P 0 ;0
L 1.87413996 -1.94778996 1.87413996 -1.94783996 0 P 0 ;0
L 1.87413996 -1.94783996 1.87416998 -1.94796004 0 P 0 ;0
L 1.87416998 -1.94796004 1.87481004 -1.95036998 0 P 0 ;0
L 1.87481004 -1.95036998 1.87483996 -1.95048996 0 P 0 ;0
L 1.87483996 -1.95048996 1.87486004 -1.95053002 0 P 0 ;0
L 1.87486004 -1.95053002 1.8757 -1.95288002 0 P 0 ;0
L 1.8757 -1.95288002 1.87571004 -1.95291998 0 P 0 ;0
L 1.87571004 -1.95291998 1.87575 -1.953 0 P 0 ;0
L 1.87575 -1.953 1.87576004 -1.95303996 0 P 0 ;0
L 1.87576004 -1.95303996 1.8768 -1.9553 0 P 0 ;0
L 1.8768 -1.9553 1.87686004 -1.95541998 0 P 0 ;0
L 1.87686004 -1.95541998 1.87688002 -1.95545 0 P 0 ;0
L 1.87688002 -1.95545 1.8781 -1.95761004 0 P 0 ;0
L 1.8781 -1.95761004 1.87811998 -1.95761004 0 P 0 ;0
L 1.87811998 -1.95761004 1.8781 -1.95761998 0 P 0 ;0
L 1.8781 -1.95761998 1.87813996 -1.95768996 0 P 0 ;0
L 1.87813996 -1.95768996 1.87816998 -1.95771998 0 P 0 ;0
L 1.87816998 -1.95771998 1.87818996 -1.95775 0 P 0 ;0
L 1.87818996 -1.95775 1.87938002 -1.95951004 0 P 0 ;0
L 1.87938002 -1.95951004 1.87943996 -1.9596 0 P 0 ;0
L 1.87943996 -1.9596 1.87946998 -1.95963002 0 P 0 ;0
L 1.87946998 -1.95963002 1.88078002 -1.96128996 0 P 0 ;0
L 1.88078002 -1.96128996 1.88081004 -1.96131998 0 P 0 ;0
L 1.88081004 -1.96131998 1.88083002 -1.96135 0 P 0 ;0
L 1.88083002 -1.96135 1.88086004 -1.96136998 0 P 0 ;0
L 1.88086004 -1.96136998 1.88088002 -1.9614 0 P 0 ;0
L 1.88088002 -1.9614 1.88231998 -1.96295 0 P 0 ;0
L 1.88231998 -1.96295 1.88233996 -1.96298002 0 P 0 ;0
L 1.88233996 -1.96298002 1.8824 -1.96303996 0 P 0 ;0
L 1.8824 -1.96303996 1.88243002 -1.96306004 0 P 0 ;0
L 1.88243002 -1.96306004 1.88398002 -1.9645 0 P 0 ;0
L 1.88398002 -1.9645 1.88401004 -1.96451998 0 P 0 ;0
L 1.88401004 -1.96451998 1.88403002 -1.96455 0 P 0 ;0
L 1.88403002 -1.96455 1.88406998 -1.96458002 0 P 0 ;0
L 1.88406998 -1.96458002 1.88408996 -1.9646 0 P 0 ;0
L 1.88408996 -1.9646 1.88575 -1.96591004 0 P 0 ;0
L 1.88575 -1.96591004 1.88578002 -1.96593996 0 P 0 ;0
L 1.88578002 -1.96593996 1.88586998 -1.966 0 P 0 ;0
L 1.88586998 -1.966 1.88761998 -1.96718996 0 P 0 ;0
L 1.88761998 -1.96718996 1.88766004 -1.96721004 0 P 0 ;0
L 1.88766004 -1.96721004 1.88775 -1.96726998 0 P 0 ;0
L 1.88775 -1.96726998 1.88958996 -1.96831998 0 P 0 ;0
L 1.88958996 -1.96831998 1.88965 -1.96836004 0 P 0 ;0
L 1.88965 -1.96836004 1.88968002 -1.96836998 0 P 0 ;0
L 1.88968002 -1.96836998 1.88971998 -1.96838996 0 P 0 ;0
L 1.88971998 -1.96838996 1.89145 -1.96921998 0 P 0 ;0
L 1.89145 -1.96921998 1.89151004 -1.96925 0 P 0 ;0
L 1.89151004 -1.96925 1.89155 -1.96926004 0 P 0 ;0
L 1.89155 -1.96926004 1.89158002 -1.96926998 0 P 0 ;0
L 1.89158002 -1.96926998 1.89336004 -1.96996998 0 P 0 ;0
L 1.89336004 -1.96996998 1.89336004 -1.96998002 0 P 0 ;0
L 1.89336004 -1.96998002 1.89346004 -1.97001004 0 P 0 ;0
L 1.89346004 -1.97001004 1.89348996 -1.97001998 0 P 0 ;0
L 1.89348996 -1.97001998 1.89531998 -1.9706 0 P 0 ;0
L 1.89531998 -1.9706 1.89536004 -1.97061004 0 P 0 ;0
L 1.89536004 -1.97061004 1.89541998 -1.97063002 0 P 0 ;0
L 1.89541998 -1.97063002 1.89546004 -1.97063002 0 P 0 ;0
L 1.89546004 -1.97063002 1.89731998 -1.97108002 0 P 0 ;0
L 1.89731998 -1.97108002 1.89741998 -1.9711 0 P 0 ;0
L 1.89741998 -1.9711 1.89746004 -1.9711 0 P 0 ;0
L 1.89746004 -1.9711 1.89746004 -1.97111004 0 P 0 ;0
L 1.89746004 -1.97111004 1.89933996 -1.97141998 0 P 0 ;0
L 1.89933996 -1.97141998 1.89936998 -1.97143002 0 P 0 ;0
L 1.89936998 -1.97143002 1.89941004 -1.97143002 0 P 0 ;0
L 1.89941004 -1.97143002 1.89945 -1.97143996 0 P 0 ;0
L 1.89945 -1.97143996 1.89948002 -1.97143996 0 P 0 ;0
L 1.89948002 -1.97143996 1.90201004 -1.97168002 0 P 0 ;0
L 1.90201004 -1.97168002 1.90205 -1.97168002 0 P 0 ;0
L 1.90205 -1.97168002 1.90208996 -1.97168996 0 P 0 ;0
L 1.90208996 -1.97168996 1.90216004 -1.97168996 0 P 0 ;0
L 1.90216004 -1.97168996 1.90468996 -1.97173996 0 P 0 ;0
L 1.90468996 -1.97173996 1.90476004 -1.97173996 0 P 0 ;0
L 1.80616004 -2.12823996 1.83348996 -2.12823996 0 P 0 ;0
L 1.79591998 -2.12723996 1.8396 -2.12723996 0 P 0 ;0
L 1.78818002 -2.12623996 1.84465 -2.12623996 0 P 0 ;0
L 1.82003996 -2.09123996 1.87618996 -2.09123996 0 P 0 ;0
L 1.82198996 -2.09023996 1.8762 -2.09023996 0 P 0 ;0
L 1.82325 -2.08923996 1.8762 -2.08923996 0 P 0 ;0
L 1.82411998 -2.08823996 1.87618996 -2.08823996 0 P 0 ;0
L 1.82463002 -2.08723996 1.87616998 -2.08723996 0 P 0 ;0
L 1.82488002 -2.08623996 1.87615 -2.08623996 0 P 0 ;0
L 1.82493002 -2.08523996 1.87613002 -2.08523996 0 P 0 ;0
L 1.82476998 -2.08423996 1.87611004 -2.08423996 0 P 0 ;0
L 1.64846004 -2.08295 1.73316998 -2.08295 0 P 0 ;0
L 1.64811998 -2.08195 1.73356998 -2.08195 0 P 0 ;0
L 1.64776998 -2.08095 1.73398002 -2.08095 0 P 0 ;0
L 1.64743002 -2.07995 1.73438002 -2.07995 0 P 0 ;0
L 1.64708996 -2.07895 1.73478996 -2.07895 0 P 0 ;0
L 1.64673996 -2.07795 1.7352 -2.07795 0 P 0 ;0
L 1.6464 -2.07695 1.7356 -2.07695 0 P 0 ;0
L 1.64605 -2.07595 1.73601004 -2.07595 0 P 0 ;0
L 1.64571004 -2.07495 1.73641004 -2.07495 0 P 0 ;0
L 1.64536004 -2.07395 1.73681004 -2.07395 0 P 0 ;0
L 1.64501998 -2.07295 1.73721998 -2.07295 0 P 0 ;0
L 1.64466998 -2.07195 1.73761998 -2.07195 0 P 0 ;0
L 1.64433002 -2.07095 1.73803002 -2.07095 0 P 0 ;0
L 1.64398002 -2.06995 1.69251004 -2.06995 0 P 0 ;0
L 1.69583002 -2.06995 1.73843996 -2.06995 0 P 0 ;0
L 1.64363002 -2.06895 1.69168002 -2.06895 0 P 0 ;0
L 1.69671998 -2.06895 1.73883996 -2.06895 0 P 0 ;0
L 1.64328996 -2.06795 1.69136004 -2.06795 0 P 0 ;0
L 1.69708996 -2.06795 1.73925 -2.06795 0 P 0 ;0
L 1.64293996 -2.06695 1.69108002 -2.06695 0 P 0 ;0
L 1.69738002 -2.06695 1.73965 -2.06695 0 P 0 ;0
L 1.64258996 -2.06595 1.6908 -2.06595 0 P 0 ;0
L 1.69768002 -2.06595 1.74006004 -2.06595 0 P 0 ;0
L 1.64223996 -2.06495 1.69051998 -2.06495 0 P 0 ;0
L 1.69796998 -2.06495 1.74046004 -2.06495 0 P 0 ;0
L 1.6419 -2.06395 1.69023002 -2.06395 0 P 0 ;0
L 1.69826998 -2.06395 1.74086004 -2.06395 0 P 0 ;0
L 1.64155 -2.06295 1.68996004 -2.06295 0 P 0 ;0
L 1.69856004 -2.06295 1.74126998 -2.06295 0 P 0 ;0
L 1.6412 -2.06195 1.68966998 -2.06195 0 P 0 ;0
L 1.69886004 -2.06195 1.74168002 -2.06195 0 P 0 ;0
L 1.64085 -2.06095 1.68938996 -2.06095 0 P 0 ;0
L 1.69915 -2.06095 1.74208002 -2.06095 0 P 0 ;0
L 1.6405 -2.05995 1.68911004 -2.05995 0 P 0 ;0
L 1.69945 -2.05995 1.74248002 -2.05995 0 P 0 ;0
L 1.64016004 -2.05895 1.68883002 -2.05895 0 P 0 ;0
L 1.69973996 -2.05895 1.74288996 -2.05895 0 P 0 ;0
L 1.63981004 -2.05795 1.68855 -2.05795 0 P 0 ;0
L 1.70003996 -2.05795 1.74328996 -2.05795 0 P 0 ;0
L 1.63946004 -2.05695 1.68826998 -2.05695 0 P 0 ;0
L 1.70033002 -2.05695 1.7437 -2.05695 0 P 0 ;0
L 1.63911004 -2.05595 1.68798996 -2.05595 0 P 0 ;0
L 1.70063002 -2.05595 1.7441 -2.05595 0 P 0 ;0
L 1.63876998 -2.05495 1.68771004 -2.05495 0 P 0 ;0
L 1.70091998 -2.05495 1.74451004 -2.05495 0 P 0 ;0
L 1.63841998 -2.05395 1.68741998 -2.05395 0 P 0 ;0
L 1.70121998 -2.05395 1.74491004 -2.05395 0 P 0 ;0
L 1.63806998 -2.05295 1.68713996 -2.05295 0 P 0 ;0
L 1.70151004 -2.05295 1.74531004 -2.05295 0 P 0 ;0
L 1.63771998 -2.05195 1.68686004 -2.05195 0 P 0 ;0
L 1.70181004 -2.05195 1.74571998 -2.05195 0 P 0 ;0
L 1.63738002 -2.05095 1.68658002 -2.05095 0 P 0 ;0
L 1.7021 -2.05095 1.74611998 -2.05095 0 P 0 ;0
L 1.63703002 -2.04995 1.6863 -2.04995 0 P 0 ;0
L 1.7024 -2.04995 1.74653002 -2.04995 0 P 0 ;0
L 1.63668002 -2.04895 1.68601998 -2.04895 0 P 0 ;0
L 1.70268996 -2.04895 1.74693002 -2.04895 0 P 0 ;0
L 1.63633002 -2.04795 1.68573996 -2.04795 0 P 0 ;0
L 1.70298996 -2.04795 1.74733002 -2.04795 0 P 0 ;0
L 1.63598002 -2.04695 1.68546004 -2.04695 0 P 0 ;0
L 1.70328002 -2.04695 1.74773996 -2.04695 0 P 0 ;0
L 1.63563996 -2.04595 1.68518002 -2.04595 0 P 0 ;0
L 1.70358002 -2.04595 1.74813996 -2.04595 0 P 0 ;0
L 1.63528996 -2.04495 1.6849 -2.04495 0 P 0 ;0
L 1.70386998 -2.04495 1.74855 -2.04495 0 P 0 ;0
L 1.63493996 -2.04395 1.68461004 -2.04395 0 P 0 ;0
L 1.70416998 -2.04395 1.74895 -2.04395 0 P 0 ;0
L 1.63458996 -2.04295 1.68433002 -2.04295 0 P 0 ;0
L 1.70446004 -2.04295 1.74936004 -2.04295 0 P 0 ;0
L 1.63425 -2.04195 1.68405 -2.04195 0 P 0 ;0
L 1.70475 -2.04195 1.74976004 -2.04195 0 P 0 ;0
L 1.6339 -2.04095 1.68376998 -2.04095 0 P 0 ;0
L 1.70503002 -2.04095 1.75016004 -2.04095 0 P 0 ;0
L 1.63355 -2.03995 1.68348996 -2.03995 0 P 0 ;0
L 1.70531998 -2.03995 1.75056998 -2.03995 0 P 0 ;0
L 1.6332 -2.03895 1.68321004 -2.03895 0 P 0 ;0
L 1.7056 -2.03895 1.75096998 -2.03895 0 P 0 ;0
L 1.63286004 -2.03795 1.68293002 -2.03795 0 P 0 ;0
L 1.70588996 -2.03795 1.75138002 -2.03795 0 P 0 ;0
L 1.63251004 -2.03695 1.68266004 -2.03695 0 P 0 ;0
L 1.70618002 -2.03695 1.75178002 -2.03695 0 P 0 ;0
L 1.63216004 -2.03595 1.68238002 -2.03595 0 P 0 ;0
L 1.70646998 -2.03595 1.75218996 -2.03595 0 P 0 ;0
L 1.63181004 -2.03495 1.6821 -2.03495 0 P 0 ;0
L 1.70675 -2.03495 1.75258996 -2.03495 0 P 0 ;0
L 1.63146998 -2.03395 1.68183002 -2.03395 0 P 0 ;0
L 1.70703996 -2.03395 1.75298996 -2.03395 0 P 0 ;0
L 1.63111998 -2.03295 1.68155 -2.03295 0 P 0 ;0
L 1.70733002 -2.03295 1.7534 -2.03295 0 P 0 ;0
L 1.63076998 -2.03195 1.68126998 -2.03195 0 P 0 ;0
L 1.70761004 -2.03195 1.75381004 -2.03195 0 P 0 ;0
L 1.63041998 -2.03095 1.68098996 -2.03095 0 P 0 ;0
L 1.7079 -2.03095 1.75421004 -2.03095 0 P 0 ;0
L 1.63006998 -2.02995 1.68071004 -2.02995 0 P 0 ;0
L 1.70818996 -2.02995 1.75461004 -2.02995 0 P 0 ;0
L 1.62973002 -2.02895 1.68043996 -2.02895 0 P 0 ;0
L 1.70846998 -2.02895 1.75501998 -2.02895 0 P 0 ;0
L 1.62938002 -2.02795 1.68016004 -2.02795 0 P 0 ;0
L 1.70876004 -2.02795 1.75541998 -2.02795 0 P 0 ;0
L 1.62903002 -2.02695 1.67988002 -2.02695 0 P 0 ;0
L 1.70905 -2.02695 1.75583002 -2.02695 0 P 0 ;0
L 1.62868002 -2.02595 1.6796 -2.02595 0 P 0 ;0
L 1.70933996 -2.02595 1.75623002 -2.02595 0 P 0 ;0
L 1.62831004 -2.02495 1.67933002 -2.02495 0 P 0 ;0
L 1.70961998 -2.02495 1.75663996 -2.02495 0 P 0 ;0
L 1.62793996 -2.02395 1.67905 -2.02395 0 P 0 ;0
L 1.70991004 -2.02395 1.75703996 -2.02395 0 P 0 ;0
L 1.62756998 -2.02295 1.67876998 -2.02295 0 P 0 ;0
L 1.7102 -2.02295 1.75743996 -2.02295 0 P 0 ;0
L 1.6272 -2.02195 1.6785 -2.02195 0 P 0 ;0
L 1.71048002 -2.02195 1.75785 -2.02195 0 P 0 ;0
L 1.62683002 -2.02095 1.67821998 -2.02095 0 P 0 ;0
L 1.71076004 -2.02095 1.75825 -2.02095 0 P 0 ;0
L 1.62646998 -2.01995 1.67793996 -2.01995 0 P 0 ;0
L 1.71101004 -2.01995 1.75866004 -2.01995 0 P 0 ;0
L 1.6261 -2.01895 1.67766004 -2.01895 0 P 0 ;0
L 1.71126998 -2.01895 1.75906004 -2.01895 0 P 0 ;0
L 1.62573002 -2.01795 1.67738996 -2.01795 0 P 0 ;0
L 1.71151998 -2.01795 1.75946998 -2.01795 0 P 0 ;0
L 1.62536004 -2.01695 1.67711004 -2.01695 0 P 0 ;0
L 1.71176998 -2.01695 1.75986998 -2.01695 0 P 0 ;0
L 1.62498996 -2.01595 1.67683002 -2.01595 0 P 0 ;0
L 1.71203002 -2.01595 1.76026998 -2.01595 0 P 0 ;0
L 1.62461998 -2.01495 1.67656004 -2.01495 0 P 0 ;0
L 1.71228002 -2.01495 1.76068002 -2.01495 0 P 0 ;0
L 1.62425 -2.01395 1.67628002 -2.01395 0 P 0 ;0
L 1.71253996 -2.01395 1.76108002 -2.01395 0 P 0 ;0
L 1.62388002 -2.01295 1.67601998 -2.01295 0 P 0 ;0
L 1.71278996 -2.01295 1.76148996 -2.01295 0 P 0 ;0
L 1.62351004 -2.01195 1.67576998 -2.01195 0 P 0 ;0
L 1.71305 -2.01195 1.76188996 -2.01195 0 P 0 ;0
L 1.62313996 -2.01095 1.67551998 -2.01095 0 P 0 ;0
L 1.7133 -2.01095 1.76228996 -2.01095 0 P 0 ;0
L 1.62276998 -2.00995 1.67528002 -2.00995 0 P 0 ;0
L 1.71355 -2.00995 1.7627 -2.00995 0 P 0 ;0
L 1.6224 -2.00895 1.67503002 -2.00895 0 P 0 ;0
L 1.71381004 -2.00895 1.7631 -2.00895 0 P 0 ;0
L 1.62203002 -2.00795 1.67478996 -2.00795 0 P 0 ;0
L 1.71406004 -2.00795 1.76351004 -2.00795 0 P 0 ;0
L 1.62166004 -2.00695 1.67453996 -2.00695 0 P 0 ;0
L 1.71431004 -2.00695 1.76391004 -2.00695 0 P 0 ;0
L 1.62128996 -2.00595 1.67428996 -2.00595 0 P 0 ;0
L 1.71453996 -2.00595 1.76431998 -2.00595 0 P 0 ;0
L 1.62091004 -2.00495 1.67405 -2.00495 0 P 0 ;0
L 1.71476998 -2.00495 1.76471998 -2.00495 0 P 0 ;0
L 1.62051998 -2.00395 1.6738 -2.00395 0 P 0 ;0
L 1.715 -2.00395 1.76511998 -2.00395 0 P 0 ;0
L 1.62013002 -2.00295 1.67355 -2.00295 0 P 0 ;0
L 1.71523002 -2.00295 1.76553002 -2.00295 0 P 0 ;0
L 1.61973996 -2.00195 1.67331004 -2.00195 0 P 0 ;0
L 1.71546004 -2.00195 1.76593996 -2.00195 0 P 0 ;0
L 1.61935 -2.00095 1.67306004 -2.00095 0 P 0 ;0
L 1.71568996 -2.00095 1.76633996 -2.00095 0 P 0 ;0
L 1.61896004 -1.99995 1.67283996 -1.99995 0 P 0 ;0
L 1.71591998 -1.99995 1.76673996 -1.99995 0 P 0 ;0
L 1.61856998 -1.99895 1.67261998 -1.99895 0 P 0 ;0
L 1.71613996 -1.99895 1.76715 -1.99895 0 P 0 ;0
L 1.71638002 -1.99795 1.76755 -1.99795 0 P 0 ;0
L 1.7166 -1.99695 1.76796004 -1.99695 0 P 0 ;0
L 1.71683002 -1.99595 1.76836004 -1.99595 0 P 0 ;0
L 1.71866998 -1.99495 1.76876998 -1.99495 0 P 0 ;0
L 1.78213996 -2.04823996 1.84641998 -2.04823996 0 P 0 ;0
L 1.78138002 -2.04723996 1.84498996 -2.04723996 0 P 0 ;0
L 1.78071004 -2.04623996 1.84356004 -2.04623996 0 P 0 ;0
L 1.7801 -2.04523996 1.84213996 -2.04523996 0 P 0 ;0
L 1.77956004 -2.04423996 1.84071004 -2.04423996 0 P 0 ;0
L 1.77908996 -2.04323996 1.83928002 -2.04323996 0 P 0 ;0
L 1.77866004 -2.04223996 1.83786004 -2.04223996 0 P 0 ;0
L 1.77831004 -2.04123996 1.83658996 -2.04123996 0 P 0 ;0
L 1.77796004 -2.04023996 1.83536004 -2.04023996 0 P 0 ;0
L 1.77761004 -2.03923996 1.83428002 -2.03923996 0 P 0 ;0
L 1.77733996 -2.03823996 1.83321998 -2.03823996 0 P 0 ;0
L 1.77706998 -2.03723996 1.83236998 -2.03723996 0 P 0 ;0
L 1.7768 -2.03623996 1.83171004 -2.03623996 0 P 0 ;0
L 1.7766 -2.03523996 1.83121004 -2.03523996 0 P 0 ;0
L 1.77641004 -2.03423996 1.83085 -2.03423996 0 P 0 ;0
L 1.77621004 -2.03323996 1.83071004 -2.03323996 0 P 0 ;0
L 1.77608002 -2.03223996 1.83076998 -2.03223996 0 P 0 ;0
L 1.77596004 -2.03123996 1.83106004 -2.03123996 0 P 0 ;0
L 1.77583996 -2.03023996 1.83158996 -2.03023996 0 P 0 ;0
L 1.77576004 -2.02923996 1.83238002 -2.02923996 0 P 0 ;0
L 1.7757 -2.02823996 1.83356998 -2.02823996 0 P 0 ;0
L 1.7757 -2.02723996 1.83591998 -2.02723996 0 P 0 ;0
L 1.77571998 -2.02623996 1.87495 -2.02623996 0 P 0 ;0
L 1.7758 -2.02523996 1.87485 -2.02523996 0 P 0 ;0
L 1.77588996 -2.02423996 1.87475 -2.02423996 0 P 0 ;0
L 1.77605 -2.02323996 1.87465 -2.02323996 0 P 0 ;0
L 1.77621004 -2.02223996 1.87455 -2.02223996 0 P 0 ;0
L 1.7764 -2.02123996 1.87445 -2.02123996 0 P 0 ;0
L 1.77665 -2.02023996 1.87433996 -2.02023996 0 P 0 ;0
L 1.7769 -2.01923996 1.87425 -2.01923996 0 P 0 ;0
L 1.7772 -2.01823996 1.87413996 -2.01823996 0 P 0 ;0
L 1.77753002 -2.01723996 1.87405 -2.01723996 0 P 0 ;0
L 1.77786004 -2.01623996 1.87393996 -2.01623996 0 P 0 ;0
L 1.77823002 -2.01523996 1.87383996 -2.01523996 0 P 0 ;0
L 1.77863996 -2.01423996 1.87373996 -2.01423996 0 P 0 ;0
L 1.77903996 -2.01323996 1.87363996 -2.01323996 0 P 0 ;0
L 1.7795 -2.01223996 1.87353996 -2.01223996 0 P 0 ;0
L 1.77998996 -2.01123996 1.87343996 -2.01123996 0 P 0 ;0
L 1.78046998 -2.01023996 1.87333002 -2.01023996 0 P 0 ;0
L 1.78103996 -2.00923996 1.87323002 -2.00923996 0 P 0 ;0
L 1.78161004 -2.00823996 1.87311998 -2.00823996 0 P 0 ;0
L 1.78221004 -2.00723996 1.87301998 -2.00723996 0 P 0 ;0
L 1.78288002 -2.00623996 1.87291998 -2.00623996 0 P 0 ;0
L 1.64213996 -2.14795 1.70566004 -2.14795 0 P 0 ;0
L 1.64518996 -2.14695 1.7062 -2.14695 0 P 0 ;0
L 1.64728996 -2.14595 1.70673996 -2.14595 0 P 0 ;0
L 1.64906998 -2.14495 1.70728002 -2.14495 0 P 0 ;0
L 1.65058002 -2.14395 1.70783002 -2.14395 0 P 0 ;0
L 1.6519 -2.14295 1.70836998 -2.14295 0 P 0 ;0
L 1.65311998 -2.14195 1.70881998 -2.14195 0 P 0 ;0
L 1.65416998 -2.14095 1.70926998 -2.14095 0 P 0 ;0
L 1.65508996 -2.13995 1.70973002 -2.13995 0 P 0 ;0
L 1.65588002 -2.13895 1.71018002 -2.13895 0 P 0 ;0
L 1.65658002 -2.13795 1.71063002 -2.13795 0 P 0 ;0
L 1.65726998 -2.13695 1.71108996 -2.13695 0 P 0 ;0
L 1.65791998 -2.13595 1.71153996 -2.13595 0 P 0 ;0
L 1.65853002 -2.13495 1.71198996 -2.13495 0 P 0 ;0
L 1.65913002 -2.13395 1.71245 -2.13395 0 P 0 ;0
L 1.65968002 -2.13295 1.7129 -2.13295 0 P 0 ;0
L 1.66021998 -2.13195 1.71331004 -2.13195 0 P 0 ;0
L 1.66071998 -2.13095 1.71371998 -2.13095 0 P 0 ;0
L 1.66121004 -2.12995 1.71411998 -2.12995 0 P 0 ;0
L 1.66166998 -2.12895 1.71453002 -2.12895 0 P 0 ;0
L 1.66201004 -2.12795 1.71493996 -2.12795 0 P 0 ;0
L 1.66223996 -2.12695 1.71533996 -2.12695 0 P 0 ;0
L 1.66235 -2.12595 1.71575 -2.12595 0 P 0 ;0
L 1.66236004 -2.12495 1.71615 -2.12495 0 P 0 ;0
L 1.66228002 -2.12395 1.71656004 -2.12395 0 P 0 ;0
L 1.66211998 -2.12295 1.71696004 -2.12295 0 P 0 ;0
L 1.66188002 -2.12195 1.71736004 -2.12195 0 P 0 ;0
L 1.66156004 -2.12095 1.71776998 -2.12095 0 P 0 ;0
L 1.66121004 -2.11995 1.71818002 -2.11995 0 P 0 ;0
L 1.66086998 -2.11895 1.71858002 -2.11895 0 P 0 ;0
L 1.66053002 -2.11795 1.71898996 -2.11795 0 P 0 ;0
L 1.66018002 -2.11695 1.71938996 -2.11695 0 P 0 ;0
L 1.65983996 -2.11595 1.7198 -2.11595 0 P 0 ;0
L 1.65948996 -2.11495 1.7202 -2.11495 0 P 0 ;0
L 1.65913996 -2.11395 1.72061004 -2.11395 0 P 0 ;0
L 1.6588 -2.11295 1.72101004 -2.11295 0 P 0 ;0
L 1.65846004 -2.11195 1.72141998 -2.11195 0 P 0 ;0
L 1.65811004 -2.11095 1.72181998 -2.11095 0 P 0 ;0
L 1.65776998 -2.10995 1.72223002 -2.10995 0 P 0 ;0
L 1.65741998 -2.10895 1.72263002 -2.10895 0 P 0 ;0
L 1.65708002 -2.10795 1.72303996 -2.10795 0 P 0 ;0
L 1.65673002 -2.10695 1.72343996 -2.10695 0 P 0 ;0
L 1.65638996 -2.10595 1.72385 -2.10595 0 P 0 ;0
L 1.65605 -2.10495 1.72425 -2.10495 0 P 0 ;0
L 1.6557 -2.10395 1.72466004 -2.10395 0 P 0 ;0
L 1.65536004 -2.10295 1.72506998 -2.10295 0 P 0 ;0
L 1.65501004 -2.10195 1.72546998 -2.10195 0 P 0 ;0
L 1.65466998 -2.10095 1.72588002 -2.10095 0 P 0 ;0
L 1.65431998 -2.09995 1.72628002 -2.09995 0 P 0 ;0
L 1.65398002 -2.09895 1.72668996 -2.09895 0 P 0 ;0
L 1.65363002 -2.09795 1.72708996 -2.09795 0 P 0 ;0
L 1.65328996 -2.09695 1.72748996 -2.09695 0 P 0 ;0
L 1.65293996 -2.09595 1.7279 -2.09595 0 P 0 ;0
L 1.6526 -2.09495 1.72831004 -2.09495 0 P 0 ;0
L 1.65225 -2.09395 1.72871004 -2.09395 0 P 0 ;0
L 1.65191004 -2.09295 1.72911998 -2.09295 0 P 0 ;0
L 1.65156998 -2.09195 1.72951998 -2.09195 0 P 0 ;0
L 1.65121998 -2.09095 1.72993002 -2.09095 0 P 0 ;0
L 1.65088002 -2.08995 1.73033002 -2.08995 0 P 0 ;0
L 1.65053002 -2.08895 1.73073996 -2.08895 0 P 0 ;0
L 1.65018996 -2.08795 1.73113996 -2.08795 0 P 0 ;0
L 1.64983996 -2.08695 1.73155 -2.08695 0 P 0 ;0
L 1.6495 -2.08595 1.73195 -2.08595 0 P 0 ;0
L 1.64915 -2.08495 1.73236004 -2.08495 0 P 0 ;0
L 1.64881004 -2.08395 1.73276004 -2.08395 0 P 0 ;0
L 1.81726998 -1.98915 1.81196004 -1.9899 0 P 0 ;0
L 1.81196004 -1.9899 1.80668996 -1.99096998 0 P 0 ;0
L 1.80668996 -1.99096998 1.8019 -1.99226004 0 P 0 ;0
L 1.8019 -1.99226004 1.79718996 -1.99391004 0 P 0 ;0
L 1.79718996 -1.99391004 1.79316004 -1.99568002 0 P 0 ;0
L 1.79316004 -1.99568002 1.78926998 -1.99778002 0 P 0 ;0
L 1.78926998 -1.99778002 1.78771004 -1.99878002 0 P 0 ;0
L 1.78771004 -1.99878002 1.78623002 -1.99988002 0 P 0 ;0
L 1.78623002 -1.99988002 1.78481004 -2.00108002 0 P 0 ;0
L 1.78481004 -2.00108002 1.78346998 -2.00238996 0 P 0 ;0
L 1.78346998 -2.00238996 1.78228996 -2.00371998 0 P 0 ;0
L 1.78228996 -2.00371998 1.78121004 -2.00513002 0 P 0 ;0
L 1.78121004 -2.00513002 1.78023002 -2.00661004 0 P 0 ;0
L 1.78023002 -2.00661004 1.77868002 -2.00933996 0 P 0 ;0
L 1.77868002 -2.00933996 1.77731998 -2.01216998 0 P 0 ;0
L 1.77731998 -2.01216998 1.77611004 -2.01516004 0 P 0 ;0
L 1.77611004 -2.01516004 1.77508996 -2.01823002 0 P 0 ;0
L 1.77508996 -2.01823002 1.77436998 -2.02111004 0 P 0 ;0
L 1.77436998 -2.02111004 1.77388996 -2.02406004 0 P 0 ;0
L 1.77388996 -2.02406004 1.77371998 -2.02603996 0 P 0 ;0
L 1.77371998 -2.02603996 1.77368996 -2.02801998 0 P 0 ;0
L 1.77368996 -2.02801998 1.7738 -2.03001998 0 P 0 ;0
L 1.7738 -2.03001998 1.7742 -2.03338996 0 P 0 ;0
L 1.7742 -2.03338996 1.77485 -2.03671004 0 P 0 ;0
L 1.77485 -2.03671004 1.77573002 -2.03993996 0 P 0 ;0
L 1.77573002 -2.03993996 1.77683996 -2.04308002 0 P 0 ;0
L 1.77683996 -2.04308002 1.7776 -2.04481998 0 P 0 ;0
L 1.7776 -2.04481998 1.7785 -2.04648996 0 P 0 ;0
L 1.7785 -2.04648996 1.77953002 -2.04808996 0 P 0 ;0
L 1.77953002 -2.04808996 1.78061004 -2.04953996 0 P 0 ;0
L 1.78061004 -2.04953996 1.78181004 -2.05091004 0 P 0 ;0
L 1.78181004 -2.05091004 1.78311004 -2.05218996 0 P 0 ;0
L 1.78311004 -2.05218996 1.78988996 -2.05801998 0 P 0 ;0
L 1.78988996 -2.05801998 1.79883996 -2.06491004 0 P 0 ;0
L 1.79883996 -2.06491004 1.80976998 -2.07261004 0 P 0 ;0
L 1.80976998 -2.07261004 1.81753002 -2.07823002 0 P 0 ;0
L 1.81753002 -2.07823002 1.81896998 -2.07943002 0 P 0 ;0
L 1.81896998 -2.07943002 1.82033002 -2.08073002 0 P 0 ;0
L 1.82033002 -2.08073002 1.82156998 -2.08213996 0 P 0 ;0
L 1.82156998 -2.08213996 1.82186004 -2.08251004 0 P 0 ;0
L 1.82186004 -2.08251004 1.82211004 -2.0829 0 P 0 ;0
L 1.82211004 -2.0829 1.82233002 -2.08331004 0 P 0 ;0
L 1.82233002 -2.08331004 1.82253002 -2.08373996 0 P 0 ;0
L 1.82253002 -2.08373996 1.82268002 -2.08418002 0 P 0 ;0
L 1.82268002 -2.08418002 1.82281004 -2.08463002 0 P 0 ;0
L 1.82281004 -2.08463002 1.8229 -2.0851 0 P 0 ;0
L 1.8229 -2.0851 1.82293002 -2.08533996 0 P 0 ;0
L 1.82293002 -2.08533996 1.82293996 -2.08558996 0 P 0 ;0
L 1.82293996 -2.08558996 1.82291998 -2.08583996 0 P 0 ;0
L 1.82291998 -2.08583996 1.82288002 -2.08608002 0 P 0 ;0
L 1.82288002 -2.08608002 1.82283002 -2.08631998 0 P 0 ;0
L 1.82283002 -2.08631998 1.82275 -2.08656004 0 P 0 ;0
L 1.82275 -2.08656004 1.82265 -2.08678996 0 P 0 ;0
L 1.82265 -2.08678996 1.82253996 -2.087 0 P 0 ;0
L 1.82253996 -2.087 1.8224 -2.08721004 0 P 0 ;0
L 1.8224 -2.08721004 1.82225 -2.08741004 0 P 0 ;0
L 1.82225 -2.08741004 1.82208996 -2.08758996 0 P 0 ;0
L 1.82208996 -2.08758996 1.8216 -2.08803996 0 P 0 ;0
L 1.8216 -2.08803996 1.82106998 -2.08845 0 P 0 ;0
L 1.82106998 -2.08845 1.82051004 -2.08881004 0 P 0 ;0
L 1.82051004 -2.08881004 1.81991998 -2.08911998 0 P 0 ;0
L 1.81991998 -2.08911998 1.81931004 -2.08936998 0 P 0 ;0
L 1.81931004 -2.08936998 1.81868002 -2.08958002 0 P 0 ;0
L 1.81868002 -2.08958002 1.81803002 -2.08973002 0 P 0 ;0
L 1.81803002 -2.08973002 1.81736004 -2.08981998 0 P 0 ;0
L 1.81736004 -2.08981998 1.81293002 -2.09001998 0 P 0 ;0
L 1.81293002 -2.09001998 1.80846998 -2.08986004 0 P 0 ;0
L 1.80846998 -2.08986004 1.80256998 -2.08923002 0 P 0 ;0
L 1.80256998 -2.08923002 1.79668002 -2.08818996 0 P 0 ;0
L 1.79668002 -2.08818996 1.78223002 -2.08458002 0 P 0 ;0
L 1.78223002 -2.08458002 1.77788996 -2.08338002 0 P 0 ;0
L 1.77788996 -2.08338002 1.77415 -2.08246004 0 P 0 ;0
L 1.77415 -2.08246004 1.77095 -2.08175 0 P 0 ;0
L 1.77095 -2.08175 1.7709 -2.08173996 0 P 0 ;0
L 1.7709 -2.08173996 1.77076998 -2.08173996 0 P 0 ;0
L 1.77076998 -2.08173996 1.77068996 -2.08176004 0 P 0 ;0
L 1.77068996 -2.08176004 1.77053002 -2.08183996 0 P 0 ;0
L 1.77053002 -2.08183996 1.77043002 -2.08193996 0 P 0 ;0
L 1.77043002 -2.08193996 1.77036998 -2.08201998 0 P 0 ;0
L 1.77036998 -2.08201998 1.77031998 -2.08211998 0 P 0 ;0
L 1.77031998 -2.08211998 1.7703 -2.08216998 0 P 0 ;0
L 1.7703 -2.08216998 1.77028996 -2.08223002 0 P 0 ;0
L 1.77028996 -2.08223002 1.77028002 -2.08228002 0 P 0 ;0
L 1.77028002 -2.08228002 1.77028002 -2.08238996 0 P 0 ;0
L 1.77028002 -2.08238996 1.77056998 -2.08838996 0 P 0 ;0
L 1.77056998 -2.08838996 1.77096004 -2.09526004 0 P 0 ;0
L 1.77096004 -2.09526004 1.77153996 -2.1033 0 P 0 ;0
L 1.77153996 -2.1033 1.77236004 -2.11291004 0 P 0 ;0
L 1.77236004 -2.11291004 1.77311004 -2.1194 0 P 0 ;0
L 1.77311004 -2.1194 1.77383002 -2.12398002 0 P 0 ;0
L 1.77383002 -2.12398002 1.77386004 -2.12411004 0 P 0 ;0
L 1.77386004 -2.12411004 1.7739 -2.12423002 0 P 0 ;0
L 1.7739 -2.12423002 1.77395 -2.12436004 0 P 0 ;0
L 1.77395 -2.12436004 1.77401004 -2.12448002 0 P 0 ;0
L 1.77401004 -2.12448002 1.77408002 -2.12458996 0 P 0 ;0
L 1.77408002 -2.12458996 1.77416004 -2.1247 0 P 0 ;0
L 1.77416004 -2.1247 1.77425 -2.1248 0 P 0 ;0
L 1.77425 -2.1248 1.77435 -2.12488996 0 P 0 ;0
L 1.77435 -2.12488996 1.77445 -2.12496998 0 P 0 ;0
L 1.77445 -2.12496998 1.77456998 -2.12505 0 P 0 ;0
L 1.77456998 -2.12505 1.77571004 -2.12568996 0 P 0 ;0
L 1.77571004 -2.12568996 1.7769 -2.12623996 0 P 0 ;0
L 1.7769 -2.12623996 1.77813002 -2.12668996 0 P 0 ;0
L 1.77813002 -2.12668996 1.7794 -2.12703996 0 P 0 ;0
L 1.7794 -2.12703996 1.78068996 -2.12728996 0 P 0 ;0
L 1.78068996 -2.12728996 1.79791998 -2.12951004 0 P 0 ;0
L 1.79791998 -2.12951004 1.81536004 -2.13106004 0 P 0 ;0
L 1.81536004 -2.13106004 1.82125 -2.13123996 0 P 0 ;0
L 1.82125 -2.13123996 1.82716004 -2.13098996 0 P 0 ;0
L 1.82716004 -2.13098996 1.83583996 -2.12998002 0 P 0 ;0
L 1.83583996 -2.12998002 1.84445 -2.12836004 0 P 0 ;0
L 1.84445 -2.12836004 1.84911998 -2.12711004 0 P 0 ;0
L 1.84911998 -2.12711004 1.85366004 -2.12548002 0 P 0 ;0
L 1.85366004 -2.12548002 1.85806998 -2.12348002 0 P 0 ;0
L 1.85806998 -2.12348002 1.86078996 -2.12196998 0 P 0 ;0
L 1.86078996 -2.12196998 1.8634 -2.12026998 0 P 0 ;0
L 1.8634 -2.12026998 1.86586998 -2.11836998 0 P 0 ;0
L 1.86586998 -2.11836998 1.86821004 -2.11628002 0 P 0 ;0
L 1.86821004 -2.11628002 1.87026004 -2.11413002 0 P 0 ;0
L 1.87026004 -2.11413002 1.8721 -2.11181998 0 P 0 ;0
L 1.8721 -2.11181998 1.87375 -2.10936004 0 P 0 ;0
L 1.87375 -2.10936004 1.87516998 -2.10673996 0 P 0 ;0
L 1.87516998 -2.10673996 1.87605 -2.10483996 0 P 0 ;0
L 1.87605 -2.10483996 1.87683996 -2.10291004 0 P 0 ;0
L 1.87683996 -2.10291004 1.8772 -2.10188002 0 P 0 ;0
L 1.8772 -2.10188002 1.87748996 -2.10083002 0 P 0 ;0
L 1.87748996 -2.10083002 1.87771004 -2.09976998 0 P 0 ;0
L 1.87771004 -2.09976998 1.87798002 -2.09788996 0 P 0 ;0
L 1.87798002 -2.09788996 1.87811998 -2.09601004 0 P 0 ;0
L 1.87811998 -2.09601004 1.87821004 -2.08966998 0 P 0 ;0
L 1.87821004 -2.08966998 1.8781 -2.08353996 0 P 0 ;0
L 1.8781 -2.08353996 1.87798002 -2.08166004 0 P 0 ;0
L 1.87798002 -2.08166004 1.87773002 -2.07976998 0 P 0 ;0
L 1.87773002 -2.07976998 1.87753002 -2.07873996 0 P 0 ;0
L 1.87753002 -2.07873996 1.87726998 -2.07773996 0 P 0 ;0
L 1.87726998 -2.07773996 1.87695 -2.07673996 0 P 0 ;0
L 1.87695 -2.07673996 1.87628996 -2.07505 0 P 0 ;0
L 1.87628996 -2.07505 1.87553002 -2.07338002 0 P 0 ;0
L 1.87553002 -2.07338002 1.87441004 -2.07133996 0 P 0 ;0
L 1.87441004 -2.07133996 1.87313996 -2.06938002 0 P 0 ;0
L 1.87313996 -2.06938002 1.87171004 -2.06751004 0 P 0 ;0
L 1.87171004 -2.06751004 1.8688 -2.06416004 0 P 0 ;0
L 1.8688 -2.06416004 1.86566998 -2.06095 0 P 0 ;0
L 1.86566998 -2.06095 1.86181998 -2.05741998 0 P 0 ;0
L 1.86181998 -2.05741998 1.85778002 -2.05406998 0 P 0 ;0
L 1.85778002 -2.05406998 1.84833996 -2.04715 0 P 0 ;0
L 1.84833996 -2.04715 1.83913996 -2.0407 0 P 0 ;0
L 1.83913996 -2.0407 1.83686004 -2.0389 0 P 0 ;0
L 1.83686004 -2.0389 1.83471998 -2.03691998 0 P 0 ;0
L 1.83471998 -2.03691998 1.83428002 -2.03643002 0 P 0 ;0
L 1.83428002 -2.03643002 1.83386998 -2.0359 0 P 0 ;0
L 1.83386998 -2.0359 1.83351004 -2.03535 0 P 0 ;0
L 1.83351004 -2.03535 1.83318996 -2.03476004 0 P 0 ;0
L 1.83318996 -2.03476004 1.83291998 -2.03415 0 P 0 ;0
L 1.83291998 -2.03415 1.83283996 -2.03393996 0 P 0 ;0
L 1.83283996 -2.03393996 1.83278002 -2.03371004 0 P 0 ;0
L 1.83278002 -2.03371004 1.83273002 -2.03348996 0 P 0 ;0
L 1.83273002 -2.03348996 1.83271004 -2.03326004 0 P 0 ;0
L 1.83271004 -2.03326004 1.8327 -2.03303002 0 P 0 ;0
L 1.8327 -2.03303002 1.83271004 -2.0328 0 P 0 ;0
L 1.83271004 -2.0328 1.83275 -2.03258002 0 P 0 ;0
L 1.83275 -2.03258002 1.83278996 -2.03235 0 P 0 ;0
L 1.83278996 -2.03235 1.83286004 -2.03213002 0 P 0 ;0
L 1.83286004 -2.03213002 1.83293996 -2.03191998 0 P 0 ;0
L 1.83293996 -2.03191998 1.83305 -2.03171004 0 P 0 ;0
L 1.83305 -2.03171004 1.83325 -2.03135 0 P 0 ;0
L 1.83325 -2.03135 1.83348996 -2.03101998 0 P 0 ;0
L 1.83348996 -2.03101998 1.83375 -2.03071004 0 P 0 ;0
L 1.83375 -2.03071004 1.83403002 -2.03041004 0 P 0 ;0
L 1.83403002 -2.03041004 1.83433996 -2.03015 0 P 0 ;0
L 1.83433996 -2.03015 1.83466998 -2.02991004 0 P 0 ;0
L 1.83466998 -2.02991004 1.83501998 -2.02968996 0 P 0 ;0
L 1.83501998 -2.02968996 1.83538002 -2.02951004 0 P 0 ;0
L 1.83538002 -2.02951004 1.83576004 -2.02936004 0 P 0 ;0
L 1.83576004 -2.02936004 1.83615 -2.02923996 0 P 0 ;0
L 1.83615 -2.02923996 1.83655 -2.02915 0 P 0 ;0
L 1.83655 -2.02915 1.8392 -2.02873996 0 P 0 ;0
L 1.8392 -2.02873996 1.84188002 -2.0285 0 P 0 ;0
L 1.84188002 -2.0285 1.84458002 -2.02841004 0 P 0 ;0
L 1.84458002 -2.02841004 1.84993996 -2.02858002 0 P 0 ;0
L 1.84993996 -2.02858002 1.85526998 -2.02916004 0 P 0 ;0
L 1.85526998 -2.02916004 1.86155 -2.03023002 0 P 0 ;0
L 1.86155 -2.03023002 1.86778002 -2.03158002 0 P 0 ;0
L 1.86778002 -2.03158002 1.8713 -2.03238996 0 P 0 ;0
L 1.8713 -2.03238996 1.87428996 -2.03303002 0 P 0 ;0
L 1.87428996 -2.03303002 1.8769 -2.03356004 0 P 0 ;0
L 1.8769 -2.03356004 1.87691998 -2.03356998 0 P 0 ;0
L 1.87691998 -2.03356998 1.87696004 -2.03356998 0 P 0 ;0
L 1.87696004 -2.03356998 1.87696998 -2.03356004 0 P 0 ;0
L 1.87696998 -2.03356004 1.87701004 -2.03356004 0 P 0 ;0
L 1.87701004 -2.03356004 1.87703996 -2.03353996 0 P 0 ;0
L 1.87703996 -2.03353996 1.87706004 -2.03353002 0 P 0 ;0
L 1.87706004 -2.03353002 1.87706998 -2.03351998 0 P 0 ;0
L 1.87706998 -2.03351998 1.87708996 -2.03351004 0 P 0 ;0
L 1.87708996 -2.03351004 1.8771 -2.03348996 0 P 0 ;0
L 1.8771 -2.03348996 1.87711004 -2.03348002 0 P 0 ;0
L 1.87711004 -2.03348002 1.87721998 -2.0333 0 P 0 ;0
L 1.87721998 -2.0333 1.87731998 -2.0331 0 P 0 ;0
L 1.87731998 -2.0331 1.8774 -2.0329 0 P 0 ;0
L 1.8774 -2.0329 1.87746004 -2.03268996 0 P 0 ;0
L 1.87746004 -2.03268996 1.87751004 -2.03248002 0 P 0 ;0
L 1.87751004 -2.03248002 1.87753002 -2.03226998 0 P 0 ;0
L 1.87753002 -2.03226998 1.87753996 -2.03205 0 P 0 ;0
L 1.87753996 -2.03205 1.87753002 -2.03183002 0 P 0 ;0
L 1.87753002 -2.03183002 1.87565 -2.01323996 0 P 0 ;0
L 1.87565 -2.01323996 1.87371004 -1.99451998 0 P 0 ;0
L 1.87371004 -1.99451998 1.8737 -1.99438996 0 P 0 ;0
L 1.8737 -1.99438996 1.87366998 -1.99426998 0 P 0 ;0
L 1.87366998 -1.99426998 1.87363002 -1.99415 0 P 0 ;0
L 1.87363002 -1.99415 1.87358002 -1.99403002 0 P 0 ;0
L 1.87358002 -1.99403002 1.87351998 -1.99391004 0 P 0 ;0
L 1.87351998 -1.99391004 1.87346004 -1.9938 0 P 0 ;0
L 1.87346004 -1.9938 1.87338002 -1.9937 0 P 0 ;0
L 1.87338002 -1.9937 1.87328996 -1.9936 0 P 0 ;0
L 1.87328996 -1.9936 1.8732 -1.99351004 0 P 0 ;0
L 1.8732 -1.99351004 1.8731 -1.99343002 0 P 0 ;0
L 1.8731 -1.99343002 1.87298996 -1.99335 0 P 0 ;0
L 1.87298996 -1.99335 1.87248002 -1.99305 0 P 0 ;0
L 1.87248002 -1.99305 1.87193996 -1.99278002 0 P 0 ;0
L 1.87193996 -1.99278002 1.87136998 -1.99256998 0 P 0 ;0
L 1.87136998 -1.99256998 1.87078996 -1.99241004 0 P 0 ;0
L 1.87078996 -1.99241004 1.8702 -1.9923 0 P 0 ;0
L 1.8702 -1.9923 1.85876004 -1.99076004 0 P 0 ;0
L 1.85876004 -1.99076004 1.84691998 -1.98943002 0 P 0 ;0
L 1.84691998 -1.98943002 1.83693002 -1.98876004 0 P 0 ;0
L 1.83693002 -1.98876004 1.8318 -1.98863002 0 P 0 ;0
L 1.8318 -1.98863002 1.82623002 -1.98866998 0 P 0 ;0
L 1.82623002 -1.98866998 1.82106004 -1.98883996 0 P 0 ;0
L 1.82106004 -1.98883996 1.81726998 -1.98915 0 P 0 ;0
L 1.78061004 -2.12523996 1.84838002 -2.12523996 0 P 0 ;0
L 1.77733002 -2.12423996 1.85121004 -2.12423996 0 P 0 ;0
L 1.77573996 -2.12323996 1.85376998 -2.12323996 0 P 0 ;0
L 1.77558002 -2.12223996 1.85596998 -2.12223996 0 P 0 ;0
L 1.77541998 -2.12123996 1.85798996 -2.12123996 0 P 0 ;0
L 1.77526998 -2.12023996 1.85978996 -2.12023996 0 P 0 ;0
L 1.77511004 -2.11923996 1.86131998 -2.11923996 0 P 0 ;0
L 1.77498996 -2.11823996 1.86276004 -2.11823996 0 P 0 ;0
L 1.77486998 -2.11723996 1.86406998 -2.11723996 0 P 0 ;0
L 1.77475 -2.11623996 1.86526004 -2.11623996 0 P 0 ;0
L 1.77463996 -2.11523996 1.86638002 -2.11523996 0 P 0 ;0
L 1.77451998 -2.11423996 1.8674 -2.11423996 0 P 0 ;0
L 1.77441004 -2.11323996 1.86835 -2.11323996 0 P 0 ;0
L 1.77431004 -2.11223996 1.86921004 -2.11223996 0 P 0 ;0
L 1.77421998 -2.11123996 1.87001004 -2.11123996 0 P 0 ;0
L 1.77413996 -2.11023996 1.87075 -2.11023996 0 P 0 ;0
L 1.77405 -2.10923996 1.87141998 -2.10923996 0 P 0 ;0
L 1.77396998 -2.10823996 1.87208002 -2.10823996 0 P 0 ;0
L 1.77388002 -2.10723996 1.87261998 -2.10723996 0 P 0 ;0
L 1.7738 -2.10623996 1.87316998 -2.10623996 0 P 0 ;0
L 1.77371004 -2.10523996 1.87366004 -2.10523996 0 P 0 ;0
L 1.77363002 -2.10423996 1.87411998 -2.10423996 0 P 0 ;0
L 1.77353996 -2.10323996 1.87453996 -2.10323996 0 P 0 ;0
L 1.77346998 -2.10223996 1.87495 -2.10223996 0 P 0 ;0
L 1.7734 -2.10123996 1.8753 -2.10123996 0 P 0 ;0
L 1.77333002 -2.10023996 1.87556998 -2.10023996 0 P 0 ;0
L 1.77325 -2.09923996 1.87576998 -2.09923996 0 P 0 ;0
L 1.77318002 -2.09823996 1.87591998 -2.09823996 0 P 0 ;0
L 1.77311004 -2.09723996 1.87603002 -2.09723996 0 P 0 ;0
L 1.77303996 -2.09623996 1.8761 -2.09623996 0 P 0 ;0
L 1.77296998 -2.09523996 1.87613002 -2.09523996 0 P 0 ;0
L 1.77291004 -2.09423996 1.87613996 -2.09423996 0 P 0 ;0
L 1.77285 -2.09323996 1.87616004 -2.09323996 0 P 0 ;0
L 1.77278996 -2.09223996 1.87616998 -2.09223996 0 P 0 ;0
L 1.77273002 -2.09123996 1.80256998 -2.09123996 0 P 0 ;0
L 1.77268002 -2.09023996 1.7968 -2.09023996 0 P 0 ;0
L 1.77261998 -2.08923996 1.79263002 -2.08923996 0 P 0 ;0
L 1.77256004 -2.08823996 1.78861998 -2.08823996 0 P 0 ;0
L 1.77251004 -2.08723996 1.7846 -2.08723996 0 P 0 ;0
L 1.77246004 -2.08623996 1.7807 -2.08623996 0 P 0 ;0
L 1.77241998 -2.08523996 1.77705 -2.08523996 0 P 0 ;0
L 1.77236998 -2.08423996 1.77293996 -2.08423996 0 P 0 ;0
L 1.62463996 -2.18195 1.65948996 -2.18195 0 P 0 ;0
L 1.61963996 -2.18095 1.66483002 -2.18095 0 P 0 ;0
L 1.61818002 -1.99795 1.6724 -1.99795 0 P 0 ;0
L 1.61778996 -1.99695 1.67218002 -1.99695 0 P 0 ;0
L 1.6174 -1.99595 1.67196004 -1.99595 0 P 0 ;0
L 1.61701004 -1.99495 1.67173996 -1.99495 0 P 0 ;0
L 1.61391998 -2.15695 1.70026004 -2.15695 0 P 0 ;0
L 1.61386004 -2.15595 1.70088002 -2.15595 0 P 0 ;0
L 1.61381004 -2.15495 1.70151004 -2.15495 0 P 0 ;0
L 1.61375 -2.15395 1.70213996 -2.15395 0 P 0 ;0
L 1.6137 -2.15295 1.70276004 -2.15295 0 P 0 ;0
L 1.61365 -2.15195 1.70338996 -2.15195 0 P 0 ;0
L 1.6136 -2.15095 1.70401004 -2.15095 0 P 0 ;0
L 1.61355 -2.14995 1.70456998 -2.14995 0 P 0 ;0
L 1.61348996 -2.14895 1.70511998 -2.14895 0 P 0 ;0
L 1.61343996 -2.14795 1.61738002 -2.14795 0 P 0 ;0
L 1.55341004 -2.08286998 1.60538002 -2.08286998 0 P 0 ;0
L 1.55286004 -2.08186998 1.60526998 -2.08186998 0 P 0 ;0
L 1.5521 -2.08086998 1.6051 -2.08086998 0 P 0 ;0
L 1.55126998 -2.07986998 1.6049 -2.07986998 0 P 0 ;0
L 1.55033996 -2.07886998 1.60463996 -2.07886998 0 P 0 ;0
L 1.54928996 -2.07786998 1.60433002 -2.07786998 0 P 0 ;0
L 1.54806998 -2.07686998 1.60398996 -2.07686998 0 P 0 ;0
L 1.5467 -2.07586998 1.60356998 -2.07586998 0 P 0 ;0
L 1.54531004 -2.07486998 1.6031 -2.07486998 0 P 0 ;0
L 1.54391004 -2.07386998 1.60258996 -2.07386998 0 P 0 ;0
L 1.54251004 -2.07286998 1.60201004 -2.07286998 0 P 0 ;0
L 1.54111998 -2.07186998 1.60138002 -2.07186998 0 P 0 ;0
L 1.53971998 -2.07086998 1.60068002 -2.07086998 0 P 0 ;0
L 1.53833002 -2.06986998 1.59993002 -2.06986998 0 P 0 ;0
L 1.53693002 -2.06886998 1.59908002 -2.06886998 0 P 0 ;0
L 1.53556004 -2.06786998 1.59821004 -2.06786998 0 P 0 ;0
L 1.53418996 -2.06686998 1.59733996 -2.06686998 0 P 0 ;0
L 1.53281998 -2.06586998 1.59646998 -2.06586998 0 P 0 ;0
L 1.53145 -2.06486998 1.5955 -2.06486998 0 P 0 ;0
L 1.53008002 -2.06386998 1.59453002 -2.06386998 0 P 0 ;0
L 1.52871004 -2.06286998 1.59356004 -2.06286998 0 P 0 ;0
L 1.52733996 -2.06186998 1.59253002 -2.06186998 0 P 0 ;0
L 1.52596998 -2.06086998 1.59145 -2.06086998 0 P 0 ;0
L 1.5246 -2.05986998 1.59038002 -2.05986998 0 P 0 ;0
L 1.52323002 -2.05886998 1.5893 -2.05886998 0 P 0 ;0
L 1.52186004 -2.05786998 1.58813996 -2.05786998 0 P 0 ;0
L 1.52053996 -2.05686998 1.58696004 -2.05686998 0 P 0 ;0
L 1.51935 -2.05586998 1.58576998 -2.05586998 0 P 0 ;0
L 1.51816004 -2.05486998 1.58456998 -2.05486998 0 P 0 ;0
L 1.51706998 -2.05386998 1.58321004 -2.05386998 0 P 0 ;0
L 1.51603996 -2.05286998 1.58185 -2.05286998 0 P 0 ;0
L 1.51501998 -2.05186998 1.58048996 -2.05186998 0 P 0 ;0
L 1.51408996 -2.05086998 1.57913002 -2.05086998 0 P 0 ;0
L 1.5132 -2.04986998 1.57776998 -2.04986998 0 P 0 ;0
L 1.51231998 -2.04886998 1.57641998 -2.04886998 0 P 0 ;0
L 1.51151004 -2.04786998 1.57505 -2.04786998 0 P 0 ;0
L 1.51075 -2.04686998 1.57365 -2.04686998 0 P 0 ;0
L 1.51008002 -2.04586998 1.57223002 -2.04586998 0 P 0 ;0
L 1.50945 -2.04486998 1.57081004 -2.04486998 0 P 0 ;0
L 1.50888002 -2.04386998 1.56938996 -2.04386998 0 P 0 ;0
L 1.50836004 -2.04286998 1.56796998 -2.04286998 0 P 0 ;0
L 1.5079 -2.04186998 1.56655 -2.04186998 0 P 0 ;0
L 1.50748002 -2.04086998 1.56518996 -2.04086998 0 P 0 ;0
L 1.50708996 -2.03986998 1.564 -2.03986998 0 P 0 ;0
L 1.50676004 -2.03886998 1.56296998 -2.03886998 0 P 0 ;0
L 1.50641998 -2.03786998 1.56206004 -2.03786998 0 P 0 ;0
L 1.50616998 -2.03686998 1.56125 -2.03686998 0 P 0 ;0
L 1.50591004 -2.03586998 1.56066998 -2.03586998 0 P 0 ;0
L 1.5057 -2.03486998 1.56031998 -2.03486998 0 P 0 ;0
L 1.50551998 -2.03386998 1.56016004 -2.03386998 0 P 0 ;0
L 1.50533996 -2.03286998 1.56016998 -2.03286998 0 P 0 ;0
L 1.50523996 -2.03186998 1.56036004 -2.03186998 0 P 0 ;0
L 1.50513002 -2.03086998 1.56071998 -2.03086998 0 P 0 ;0
L 1.50506998 -2.02986998 1.56131004 -2.02986998 0 P 0 ;0
L 1.50503996 -2.02886998 1.5622 -2.02886998 0 P 0 ;0
L 1.50501004 -2.02786998 1.56355 -2.02786998 0 P 0 ;0
L 1.50501998 -2.02686998 1.5657 -2.02686998 0 P 0 ;0
L 1.50506998 -2.02586998 1.60378996 -2.02586998 0 P 0 ;0
L 1.50511998 -2.02486998 1.60371004 -2.02486998 0 P 0 ;0
L 1.50521004 -2.02386998 1.60363996 -2.02386998 0 P 0 ;0
L 1.50533996 -2.02286998 1.60356998 -2.02286998 0 P 0 ;0
L 1.50546998 -2.02186998 1.6035 -2.02186998 0 P 0 ;0
L 1.50563996 -2.02086998 1.60343002 -2.02086998 0 P 0 ;0
L 1.50585 -2.01986998 1.60336004 -2.01986998 0 P 0 ;0
L 1.50606004 -2.01886998 1.60328996 -2.01886998 0 P 0 ;0
L 1.50633002 -2.01786998 1.60321998 -2.01786998 0 P 0 ;0
L 1.50661998 -2.01686998 1.60315 -2.01686998 0 P 0 ;0
L 1.50691004 -2.01586998 1.60308002 -2.01586998 0 P 0 ;0
L 1.50726998 -2.01486998 1.603 -2.01486998 0 P 0 ;0
L 1.50766004 -2.01386998 1.60293002 -2.01386998 0 P 0 ;0
L 1.50808996 -2.01286998 1.60285 -2.01286998 0 P 0 ;0
L 1.50856998 -2.01186998 1.60278002 -2.01186998 0 P 0 ;0
L 1.50908996 -2.01086998 1.6027 -2.01086998 0 P 0 ;0
L 1.50966004 -2.00986998 1.60261998 -2.00986998 0 P 0 ;0
L 1.51028996 -2.00886998 1.60255 -2.00886998 0 P 0 ;0
L 1.51096998 -2.00786998 1.60246998 -2.00786998 0 P 0 ;0
L 1.51171998 -2.00686998 1.6024 -2.00686998 0 P 0 ;0
L 1.51253996 -2.00586998 1.60233002 -2.00586998 0 P 0 ;0
L 1.51343996 -2.00486998 1.60225 -2.00486998 0 P 0 ;0
L 1.5144 -2.00386998 1.60218002 -2.00386998 0 P 0 ;0
L 1.51551998 -2.00286998 1.6021 -2.00286998 0 P 0 ;0
L 1.51663996 -2.00186998 1.60203002 -2.00186998 0 P 0 ;0
L 1.51795 -2.00086998 1.60195 -2.00086998 0 P 0 ;0
L 1.51928996 -1.99986998 1.60183996 -1.99986998 0 P 0 ;0
L 1.52086998 -1.99886998 1.60173002 -1.99886998 0 P 0 ;0
L 1.52258996 -1.99786998 1.60156998 -1.99786998 0 P 0 ;0
L 1.52451004 -1.99686998 1.60138996 -1.99686998 0 P 0 ;0
L 1.52686998 -1.99586998 1.60106998 -1.99586998 0 P 0 ;0
L 1.52976004 -1.99486998 1.59943996 -1.99486998 0 P 0 ;0
L 1.53283002 -1.99386998 1.59543002 -1.99386998 0 P 0 ;0
L 1.53678996 -1.99286998 1.59003996 -1.99286998 0 P 0 ;0
L 1.54173996 -1.99186998 1.58073996 -1.99186998 0 P 0 ;0
L 1.55036998 -1.99086998 1.56493002 -1.99086998 0 P 0 ;0
L 1.6036 -2.03086998 1.60413996 -2.03086998 0 P 0 ;0
L 1.59891004 -2.02986998 1.60406998 -2.02986998 0 P 0 ;0
L 1.59435 -2.02886998 1.604 -2.02886998 0 P 0 ;0
L 1.58838996 -2.02786998 1.60393002 -2.02786998 0 P 0 ;0
L 1.57981004 -2.02686998 1.60386004 -2.02686998 0 P 0 ;0
L 1.54575 -1.98923996 1.53931998 -1.99021998 0 P 0 ;0
L 1.53931998 -1.99021998 1.53298996 -1.99171998 0 P 0 ;0
L 1.53298996 -1.99171998 1.52678996 -1.99373996 0 P 0 ;0
L 1.52678996 -1.99373996 1.52376998 -1.995 0 P 0 ;0
L 1.52376998 -1.995 1.52086998 -1.99651004 0 P 0 ;0
L 1.52086998 -1.99651004 1.5181 -1.99826004 0 P 0 ;0
L 1.5181 -1.99826004 1.51548002 -2.00023002 0 P 0 ;0
L 1.51548002 -2.00023002 1.51301004 -2.00243002 0 P 0 ;0
L 1.51301004 -2.00243002 1.51128996 -2.00423002 0 P 0 ;0
L 1.51128996 -2.00423002 1.50971998 -2.00616004 0 P 0 ;0
L 1.50971998 -2.00616004 1.50831004 -2.00821004 0 P 0 ;0
L 1.50831004 -2.00821004 1.50706998 -2.01036998 0 P 0 ;0
L 1.50706998 -2.01036998 1.50598996 -2.01261998 0 P 0 ;0
L 1.50598996 -2.01261998 1.50508996 -2.01496998 0 P 0 ;0
L 1.50508996 -2.01496998 1.5042 -2.01801004 0 P 0 ;0
L 1.5042 -2.01801004 1.50355 -2.02111004 0 P 0 ;0
L 1.50355 -2.02111004 1.50313996 -2.02426004 0 P 0 ;0
L 1.50313996 -2.02426004 1.50298996 -2.02743002 0 P 0 ;0
L 1.50298996 -2.02743002 1.50308996 -2.03063002 0 P 0 ;0
L 1.50308996 -2.03063002 1.50338002 -2.03326998 0 P 0 ;0
L 1.50338002 -2.03326998 1.50385 -2.03588002 0 P 0 ;0
L 1.50385 -2.03588002 1.50451004 -2.03845 0 P 0 ;0
L 1.50451004 -2.03845 1.50535 -2.04096998 0 P 0 ;0
L 1.50535 -2.04096998 1.50633002 -2.0433 0 P 0 ;0
L 1.50633002 -2.0433 1.5075 -2.04553002 0 P 0 ;0
L 1.5075 -2.04553002 1.50883996 -2.04766998 0 P 0 ;0
L 1.50883996 -2.04766998 1.51036998 -2.04968996 0 P 0 ;0
L 1.51036998 -2.04968996 1.51323002 -2.05291998 0 P 0 ;0
L 1.51323002 -2.05291998 1.51631998 -2.05593996 0 P 0 ;0
L 1.51631998 -2.05593996 1.51961998 -2.05871004 0 P 0 ;0
L 1.51961998 -2.05871004 1.53591004 -2.0706 0 P 0 ;0
L 1.53591004 -2.0706 1.54668002 -2.07831004 0 P 0 ;0
L 1.54668002 -2.07831004 1.54793996 -2.07933996 0 P 0 ;0
L 1.54793996 -2.07933996 1.54911998 -2.08046998 0 P 0 ;0
L 1.54911998 -2.08046998 1.55021004 -2.08168002 0 P 0 ;0
L 1.55021004 -2.08168002 1.5512 -2.08298996 0 P 0 ;0
L 1.5512 -2.08298996 1.55136004 -2.08323002 0 P 0 ;0
L 1.55136004 -2.08323002 1.5515 -2.08348002 0 P 0 ;0
L 1.5515 -2.08348002 1.55161004 -2.08373996 0 P 0 ;0
L 1.55161004 -2.08373996 1.5517 -2.08401998 0 P 0 ;0
L 1.5517 -2.08401998 1.55176998 -2.0843 0 P 0 ;0
L 1.55176998 -2.0843 1.55181004 -2.08458002 0 P 0 ;0
L 1.55181004 -2.08458002 1.55183002 -2.08486998 0 P 0 ;0
L 1.55183002 -2.08486998 1.55181998 -2.08516004 0 P 0 ;0
L 1.55181998 -2.08516004 1.55178996 -2.08545 0 P 0 ;0
L 1.55178996 -2.08545 1.55173996 -2.08573002 0 P 0 ;0
L 1.55173996 -2.08573002 1.55166004 -2.086 0 P 0 ;0
L 1.55166004 -2.086 1.55156004 -2.08628002 0 P 0 ;0
L 1.55156004 -2.08628002 1.55136998 -2.08666998 0 P 0 ;0
L 1.55136998 -2.08666998 1.55115 -2.08703996 0 P 0 ;0
L 1.55115 -2.08703996 1.5509 -2.08738996 0 P 0 ;0
L 1.5509 -2.08738996 1.55063002 -2.08771998 0 P 0 ;0
L 1.55063002 -2.08771998 1.55033002 -2.08803002 0 P 0 ;0
L 1.55033002 -2.08803002 1.55 -2.08831004 0 P 0 ;0
L 1.55 -2.08831004 1.54966004 -2.08856004 0 P 0 ;0
L 1.54966004 -2.08856004 1.54928996 -2.08878996 0 P 0 ;0
L 1.54928996 -2.08878996 1.5489 -2.08898996 0 P 0 ;0
L 1.5489 -2.08898996 1.54786004 -2.08941004 0 P 0 ;0
L 1.54786004 -2.08941004 1.54678996 -2.08973996 0 P 0 ;0
L 1.54678996 -2.08973996 1.54568002 -2.08998002 0 P 0 ;0
L 1.54568002 -2.08998002 1.54456998 -2.09011998 0 P 0 ;0
L 1.54456998 -2.09011998 1.54343996 -2.09016998 0 P 0 ;0
L 1.54343996 -2.09016998 1.53906998 -2.09003002 0 P 0 ;0
L 1.53906998 -2.09003002 1.53468002 -2.08961998 0 P 0 ;0
L 1.53468002 -2.08961998 1.52908996 -2.08878996 0 P 0 ;0
L 1.52908996 -2.08878996 1.52351004 -2.08766004 0 P 0 ;0
L 1.52351004 -2.08766004 1.51005 -2.08418996 0 P 0 ;0
L 1.51005 -2.08418996 1.50631004 -2.08318002 0 P 0 ;0
L 1.50631004 -2.08318002 1.50308002 -2.08238996 0 P 0 ;0
L 1.50308002 -2.08238996 1.50033996 -2.08183002 0 P 0 ;0
L 1.50033996 -2.08183002 1.5003 -2.08181998 0 P 0 ;0
L 1.5003 -2.08181998 1.50016004 -2.08181998 0 P 0 ;0
L 1.50016004 -2.08181998 1.50011998 -2.08183002 0 P 0 ;0
L 1.50011998 -2.08183002 1.50006998 -2.08183996 0 P 0 ;0
L 1.50006998 -2.08183996 1.50003002 -2.08186004 0 P 0 ;0
L 1.50003002 -2.08186004 1.49998996 -2.08186998 0 P 0 ;0
L 1.49998996 -2.08186998 1.49995 -2.08188996 0 P 0 ;0
L 1.49995 -2.08188996 1.49991004 -2.08191998 0 P 0 ;0
L 1.49991004 -2.08191998 1.49988002 -2.08195 0 P 0 ;0
L 1.49988002 -2.08195 1.49983996 -2.08198002 0 P 0 ;0
L 1.49983996 -2.08198002 1.4997 -2.08213996 0 P 0 ;0
L 1.4997 -2.08213996 1.49956004 -2.08231998 0 P 0 ;0
L 1.49956004 -2.08231998 1.49943996 -2.0825 0 P 0 ;0
L 1.49943996 -2.0825 1.49933996 -2.0827 0 P 0 ;0
L 1.49933996 -2.0827 1.49925 -2.0829 0 P 0 ;0
L 1.49925 -2.0829 1.49918996 -2.08311004 0 P 0 ;0
L 1.49918996 -2.08311004 1.49913996 -2.08333002 0 P 0 ;0
L 1.49913996 -2.08333002 1.49911004 -2.08355 0 P 0 ;0
L 1.49911004 -2.08355 1.4991 -2.08376998 0 P 0 ;0
L 1.4991 -2.08376998 1.49911004 -2.08398996 0 P 0 ;0
L 1.49911004 -2.08398996 1.50071004 -2.10395 0 P 0 ;0
L 1.50071004 -2.10395 1.5024 -2.12403996 0 P 0 ;0
L 1.5024 -2.12403996 1.50241998 -2.12418002 0 P 0 ;0
L 1.50241998 -2.12418002 1.50246004 -2.12431004 0 P 0 ;0
L 1.50246004 -2.12431004 1.50248996 -2.12445 0 P 0 ;0
L 1.50248996 -2.12445 1.50255 -2.12456998 0 P 0 ;0
L 1.50255 -2.12456998 1.50261004 -2.1247 0 P 0 ;0
L 1.50261004 -2.1247 1.50276998 -2.12491998 0 P 0 ;0
L 1.50276998 -2.12491998 1.50286004 -2.12501998 0 P 0 ;0
L 1.50286004 -2.12501998 1.50296998 -2.12511998 0 P 0 ;0
L 1.50296998 -2.12511998 1.50308002 -2.12521004 0 P 0 ;0
L 1.50308002 -2.12521004 1.50318996 -2.12528002 0 P 0 ;0
L 1.50318996 -2.12528002 1.50331998 -2.12535 0 P 0 ;0
L 1.50331998 -2.12535 1.50343996 -2.1254 0 P 0 ;0
L 1.50343996 -2.1254 1.50391998 -2.12556004 0 P 0 ;0
L 1.50391998 -2.12556004 1.5044 -2.12568996 0 P 0 ;0
L 1.5044 -2.12568996 1.50848002 -2.12648996 0 P 0 ;0
L 1.50848002 -2.12648996 1.51328996 -2.12738002 0 P 0 ;0
L 1.51328996 -2.12738002 1.51873996 -2.12833996 0 P 0 ;0
L 1.51873996 -2.12833996 1.52606004 -2.12945 0 P 0 ;0
L 1.52606004 -2.12945 1.53343996 -2.13023002 0 P 0 ;0
L 1.53343996 -2.13023002 1.54886998 -2.13086998 0 P 0 ;0
L 1.54886998 -2.13086998 1.56305 -2.1303 0 P 0 ;0
L 1.56305 -2.1303 1.56666004 -2.12988996 0 P 0 ;0
L 1.56666004 -2.12988996 1.57023002 -2.12926998 0 P 0 ;0
L 1.57023002 -2.12926998 1.5738 -2.12843002 0 P 0 ;0
L 1.5738 -2.12843002 1.57945 -2.12668996 0 P 0 ;0
L 1.57945 -2.12668996 1.58498002 -2.12456998 0 P 0 ;0
L 1.58498002 -2.12456998 1.58793996 -2.12318002 0 P 0 ;0
L 1.58793996 -2.12318002 1.59078996 -2.12156004 0 P 0 ;0
L 1.59078996 -2.12156004 1.59348996 -2.11971998 0 P 0 ;0
L 1.59348996 -2.11971998 1.59525 -2.11833002 0 P 0 ;0
L 1.59525 -2.11833002 1.5969 -2.11681998 0 P 0 ;0
L 1.5969 -2.11681998 1.59846004 -2.11521004 0 P 0 ;0
L 1.59846004 -2.11521004 1.59991004 -2.11348002 0 P 0 ;0
L 1.59991004 -2.11348002 1.60175 -2.11093996 0 P 0 ;0
L 1.60175 -2.11093996 1.60338002 -2.10826998 0 P 0 ;0
L 1.60338002 -2.10826998 1.60481004 -2.10548002 0 P 0 ;0
L 1.60481004 -2.10548002 1.60573002 -2.10321004 0 P 0 ;0
L 1.60573002 -2.10321004 1.60646004 -2.10088002 0 P 0 ;0
L 1.60646004 -2.10088002 1.60698002 -2.09848996 0 P 0 ;0
L 1.60698002 -2.09848996 1.60756004 -2.09421998 0 P 0 ;0
L 1.60756004 -2.09421998 1.6078 -2.08991004 0 P 0 ;0
L 1.6078 -2.08991004 1.60768996 -2.08565 0 P 0 ;0
L 1.60768996 -2.08565 1.60723002 -2.08141998 0 P 0 ;0
L 1.60723002 -2.08141998 1.60691998 -2.07968002 0 P 0 ;0
L 1.60691998 -2.07968002 1.60646998 -2.07796998 0 P 0 ;0
L 1.60646998 -2.07796998 1.60591998 -2.0763 0 P 0 ;0
L 1.60591998 -2.0763 1.60523002 -2.07466998 0 P 0 ;0
L 1.60523002 -2.07466998 1.60411998 -2.07246998 0 P 0 ;0
L 1.60411998 -2.07246998 1.60281004 -2.07038002 0 P 0 ;0
L 1.60281004 -2.07038002 1.60131998 -2.06838996 0 P 0 ;0
L 1.60131998 -2.06838996 1.59803996 -2.06461998 0 P 0 ;0
L 1.59803996 -2.06461998 1.59455 -2.06101998 0 P 0 ;0
L 1.59455 -2.06101998 1.59031998 -2.05708996 0 P 0 ;0
L 1.59031998 -2.05708996 1.58586004 -2.05333996 0 P 0 ;0
L 1.58586004 -2.05333996 1.57588002 -2.04598996 0 P 0 ;0
L 1.57588002 -2.04598996 1.56685 -2.03963996 0 P 0 ;0
L 1.56685 -2.03963996 1.56578002 -2.03878996 0 P 0 ;0
L 1.56578002 -2.03878996 1.56476998 -2.03786004 0 P 0 ;0
L 1.56476998 -2.03786004 1.56383002 -2.03686998 0 P 0 ;0
L 1.56383002 -2.03686998 1.56295 -2.0358 0 P 0 ;0
L 1.56295 -2.0358 1.56276998 -2.03555 0 P 0 ;0
L 1.56276998 -2.03555 1.56261004 -2.03528002 0 P 0 ;0
L 1.56261004 -2.03528002 1.56246998 -2.035 0 P 0 ;0
L 1.56246998 -2.035 1.56236004 -2.03471998 0 P 0 ;0
L 1.56236004 -2.03471998 1.56226998 -2.03441998 0 P 0 ;0
L 1.56226998 -2.03441998 1.5622 -2.03411998 0 P 0 ;0
L 1.5622 -2.03411998 1.56216004 -2.03381998 0 P 0 ;0
L 1.56216004 -2.03381998 1.56213996 -2.03351004 0 P 0 ;0
L 1.56213996 -2.03351004 1.56215 -2.0332 0 P 0 ;0
L 1.56215 -2.0332 1.56218002 -2.03288996 0 P 0 ;0
L 1.56218002 -2.03288996 1.56225 -2.03253996 0 P 0 ;0
L 1.56225 -2.03253996 1.56233996 -2.03221004 0 P 0 ;0
L 1.56233996 -2.03221004 1.56246004 -2.03186998 0 P 0 ;0
L 1.56246004 -2.03186998 1.56261004 -2.03156004 0 P 0 ;0
L 1.56261004 -2.03156004 1.56278996 -2.03125 0 P 0 ;0
L 1.56278996 -2.03125 1.56298002 -2.03096004 0 P 0 ;0
L 1.56298002 -2.03096004 1.56321004 -2.03068996 0 P 0 ;0
L 1.56321004 -2.03068996 1.56345 -2.03043996 0 P 0 ;0
L 1.56345 -2.03043996 1.56371004 -2.0302 0 P 0 ;0
L 1.56371004 -2.0302 1.56416004 -2.02986004 0 P 0 ;0
L 1.56416004 -2.02986004 1.56463002 -2.02955 0 P 0 ;0
L 1.56463002 -2.02955 1.56511998 -2.02928002 0 P 0 ;0
L 1.56511998 -2.02928002 1.56561998 -2.02903002 0 P 0 ;0
L 1.56561998 -2.02903002 1.56611998 -2.02883996 0 P 0 ;0
L 1.56611998 -2.02883996 1.56663996 -2.02866998 0 P 0 ;0
L 1.56663996 -2.02866998 1.56716004 -2.02855 0 P 0 ;0
L 1.56716004 -2.02855 1.5677 -2.02846998 0 P 0 ;0
L 1.5677 -2.02846998 1.56926998 -2.02835 0 P 0 ;0
L 1.56926998 -2.02835 1.57085 -2.02833996 0 P 0 ;0
L 1.57085 -2.02833996 1.57725 -2.02866998 0 P 0 ;0
L 1.57725 -2.02866998 1.58205 -2.02906004 0 P 0 ;0
L 1.58205 -2.02906004 1.58746998 -2.02975 0 P 0 ;0
L 1.58746998 -2.02975 1.59271004 -2.03056998 0 P 0 ;0
L 1.59271004 -2.03056998 1.59681004 -2.03143002 0 P 0 ;0
L 1.59681004 -2.03143002 1.60016004 -2.03221998 0 P 0 ;0
L 1.60016004 -2.03221998 1.60308002 -2.03281004 0 P 0 ;0
L 1.60308002 -2.03281004 1.60553996 -2.03323996 0 P 0 ;0
L 1.60553996 -2.03323996 1.60568996 -2.03323996 0 P 0 ;0
L 1.60568996 -2.03323996 1.60576998 -2.03321998 0 P 0 ;0
L 1.60576998 -2.03321998 1.60586004 -2.03316004 0 P 0 ;0
L 1.60586004 -2.03316004 1.6059 -2.03313996 0 P 0 ;0
L 1.6059 -2.03313996 1.60591998 -2.03311004 0 P 0 ;0
L 1.60591998 -2.03311004 1.60598996 -2.03303996 0 P 0 ;0
L 1.60598996 -2.03303996 1.60605 -2.03296998 0 P 0 ;0
L 1.60605 -2.03296998 1.6061 -2.03288996 0 P 0 ;0
L 1.6061 -2.03288996 1.60618002 -2.03273002 0 P 0 ;0
L 1.60618002 -2.03273002 1.60621004 -2.03263002 0 P 0 ;0
L 1.60621004 -2.03263002 1.60623002 -2.03253996 0 P 0 ;0
L 1.60623002 -2.03253996 1.60625 -2.03236004 0 P 0 ;0
L 1.60625 -2.03236004 1.60623996 -2.03226004 0 P 0 ;0
L 1.60623996 -2.03226004 1.60508002 -2.01578002 0 P 0 ;0
L 1.60508002 -2.01578002 1.60393996 -2.00068002 0 P 0 ;0
L 1.60393996 -2.00068002 1.60368002 -1.99833996 0 P 0 ;0
L 1.60368002 -1.99833996 1.60326998 -1.99601004 0 P 0 ;0
L 1.60326998 -1.99601004 1.60321004 -1.99576998 0 P 0 ;0
L 1.60321004 -1.99576998 1.60313996 -1.99553002 0 P 0 ;0
L 1.60313996 -1.99553002 1.60303996 -1.9953 0 P 0 ;0
L 1.60303996 -1.9953 1.60293002 -1.99508002 0 P 0 ;0
L 1.60293002 -1.99508002 1.60281004 -1.99486004 0 P 0 ;0
L 1.60281004 -1.99486004 1.60261998 -1.9946 0 P 0 ;0
L 1.60261998 -1.9946 1.60241004 -1.99435 0 P 0 ;0
L 1.60241004 -1.99435 1.60218002 -1.99411998 0 P 0 ;0
L 1.60218002 -1.99411998 1.60191998 -1.99391004 0 P 0 ;0
L 1.60191998 -1.99391004 1.60161004 -1.99368996 0 P 0 ;0
L 1.60161004 -1.99368996 1.60128996 -1.99348996 0 P 0 ;0
L 1.60128996 -1.99348996 1.60095 -1.99331998 0 P 0 ;0
L 1.60095 -1.99331998 1.6006 -1.99316004 0 P 0 ;0
L 1.6006 -1.99316004 1.59966004 -1.99283002 0 P 0 ;0
L 1.59966004 -1.99283002 1.59871004 -1.99255 0 P 0 ;0
L 1.59871004 -1.99255 1.5933 -1.99135 0 P 0 ;0
L 1.5933 -1.99135 1.5878 -1.9905 0 P 0 ;0
L 1.5878 -1.9905 1.57285 -1.98915 0 P 0 ;0
L 1.57285 -1.98915 1.55763996 -1.98861004 0 P 0 ;0
L 1.55763996 -1.98861004 1.55171004 -1.98876004 0 P 0 ;0
L 1.55171004 -1.98876004 1.54575 -1.98923996 0 P 0 ;0
L 1.53011998 -2.12786998 1.5666 -2.12786998 0 P 0 ;0
L 1.52236004 -2.12686998 1.57168002 -2.12686998 0 P 0 ;0
L 1.51621998 -2.12586998 1.5753 -2.12586998 0 P 0 ;0
L 1.51071004 -2.12486998 1.57856004 -2.12486998 0 P 0 ;0
L 1.50553002 -2.12386998 1.58121004 -2.12386998 0 P 0 ;0
L 1.50431004 -2.12286998 1.58381998 -2.12286998 0 P 0 ;0
L 1.50423002 -2.12186998 1.58601998 -2.12186998 0 P 0 ;0
L 1.50413996 -2.12086998 1.58796004 -2.12086998 0 P 0 ;0
L 1.50406004 -2.11986998 1.58971004 -2.11986998 0 P 0 ;0
L 1.50396998 -2.11886998 1.59118002 -2.11886998 0 P 0 ;0
L 1.50388996 -2.11786998 1.5926 -2.11786998 0 P 0 ;0
L 1.50381004 -2.11686998 1.59386004 -2.11686998 0 P 0 ;0
L 1.50371998 -2.11586998 1.59496998 -2.11586998 0 P 0 ;0
L 1.50363996 -2.11486998 1.59601004 -2.11486998 0 P 0 ;0
L 1.50355 -2.11386998 1.59696998 -2.11386998 0 P 0 ;0
L 1.50346998 -2.11286998 1.59781004 -2.11286998 0 P 0 ;0
L 1.50338002 -2.11186998 1.5986 -2.11186998 0 P 0 ;0
L 1.5033 -2.11086998 1.59933002 -2.11086998 0 P 0 ;0
L 1.50321004 -2.10986998 1.60005 -2.10986998 0 P 0 ;0
L 1.50313002 -2.10886998 1.60066998 -2.10886998 0 P 0 ;0
L 1.50305 -2.10786998 1.60128002 -2.10786998 0 P 0 ;0
L 1.50296004 -2.10686998 1.60185 -2.10686998 0 P 0 ;0
L 1.50288002 -2.10586998 1.60236004 -2.10586998 0 P 0 ;0
L 1.50278996 -2.10486998 1.60286998 -2.10486998 0 P 0 ;0
L 1.50271004 -2.10386998 1.6033 -2.10386998 0 P 0 ;0
L 1.50263002 -2.10286998 1.60371004 -2.10286998 0 P 0 ;0
L 1.50255 -2.10186998 1.60405 -2.10186998 0 P 0 ;0
L 1.50246998 -2.10086998 1.60436004 -2.10086998 0 P 0 ;0
L 1.50238996 -2.09986998 1.60463002 -2.09986998 0 P 0 ;0
L 1.50231004 -2.09886998 1.60485 -2.09886998 0 P 0 ;0
L 1.50223002 -2.09786998 1.60505 -2.09786998 0 P 0 ;0
L 1.50215 -2.09686998 1.60518002 -2.09686998 0 P 0 ;0
L 1.50206998 -2.09586998 1.60531998 -2.09586998 0 P 0 ;0
L 1.50198996 -2.09486998 1.60545 -2.09486998 0 P 0 ;0
L 1.50191004 -2.09386998 1.60558002 -2.09386998 0 P 0 ;0
L 1.50183002 -2.09286998 1.60563002 -2.09286998 0 P 0 ;0
L 1.50175 -2.09186998 1.53725 -2.09186998 0 P 0 ;0
L 1.54638996 -2.09186998 1.60568996 -2.09186998 0 P 0 ;0
L 1.50166998 -2.09086998 1.5295 -2.09086998 0 P 0 ;0
L 1.54956998 -2.09086998 1.60573996 -2.09086998 0 P 0 ;0
L 1.50158996 -2.08986998 1.52436004 -2.08986998 0 P 0 ;0
L 1.55125 -2.08986998 1.60578996 -2.08986998 0 P 0 ;0
L 1.50151004 -2.08886998 1.52021004 -2.08886998 0 P 0 ;0
L 1.55226998 -2.08886998 1.60576998 -2.08886998 0 P 0 ;0
L 1.50143002 -2.08786998 1.51633002 -2.08786998 0 P 0 ;0
L 1.55298002 -2.08786998 1.60573996 -2.08786998 0 P 0 ;0
L 1.50133996 -2.08686998 1.51246004 -2.08686998 0 P 0 ;0
L 1.55346998 -2.08686998 1.60571998 -2.08686998 0 P 0 ;0
L 1.50126998 -2.08586998 1.50861998 -2.08586998 0 P 0 ;0
L 1.55375 -2.08586998 1.60568996 -2.08586998 0 P 0 ;0
L 1.50118002 -2.08486998 1.50481004 -2.08486998 0 P 0 ;0
L 1.55383002 -2.08486998 1.60558996 -2.08486998 0 P 0 ;0
L 1.55371998 -2.08386998 1.60548996 -2.08386998 0 P 0 ;0
L 1.54886998 -2.12886998 1.53358996 -2.12823996 0 P 0 ;0
L 1.53358996 -2.12823996 1.52631998 -2.12746998 0 P 0 ;0
L 1.52631998 -2.12746998 1.51906004 -2.12636998 0 P 0 ;0
L 1.51906004 -2.12636998 1.51363002 -2.12541004 0 P 0 ;0
L 1.51363002 -2.12541004 1.50886998 -2.12451998 0 P 0 ;0
L 1.50886998 -2.12451998 1.50483996 -2.12373996 0 P 0 ;0
L 1.50483996 -2.12373996 1.50448996 -2.12365 0 P 0 ;0
L 1.50448996 -2.12365 1.50438002 -2.12361004 0 P 0 ;0
L 1.50438002 -2.12361004 1.5027 -2.10378002 0 P 0 ;0
L 1.5027 -2.10378002 1.50111998 -2.08403002 0 P 0 ;0
L 1.50111998 -2.08403002 1.50263996 -2.08433996 0 P 0 ;0
L 1.50263996 -2.08433996 1.50581004 -2.08511004 0 P 0 ;0
L 1.50581004 -2.08511004 1.50955 -2.08611998 0 P 0 ;0
L 1.50955 -2.08611998 1.52306004 -2.08961004 0 P 0 ;0
L 1.52306004 -2.08961004 1.52311004 -2.08961998 0 P 0 ;0
L 1.52311004 -2.08961998 1.52875 -2.09076004 0 P 0 ;0
L 1.52875 -2.09076004 1.5288 -2.09076004 0 P 0 ;0
L 1.5288 -2.09076004 1.53443996 -2.09161004 0 P 0 ;0
L 1.53443996 -2.09161004 1.53893996 -2.09203002 0 P 0 ;0
L 1.53893996 -2.09203002 1.54346004 -2.09216998 0 P 0 ;0
L 1.54346004 -2.09216998 1.54473996 -2.09211004 0 P 0 ;0
L 1.54473996 -2.09211004 1.54603002 -2.09195 0 P 0 ;0
L 1.54603002 -2.09195 1.54728996 -2.09166998 0 P 0 ;0
L 1.54728996 -2.09166998 1.54853002 -2.09128996 0 P 0 ;0
L 1.54853002 -2.09128996 1.54973002 -2.09081004 0 P 0 ;0
L 1.54973002 -2.09081004 1.55026998 -2.09053996 0 P 0 ;0
L 1.55026998 -2.09053996 1.55076998 -2.09023002 0 P 0 ;0
L 1.55076998 -2.09023002 1.55118002 -2.08991998 0 P 0 ;0
L 1.55118002 -2.08991998 1.55118002 -2.08991004 0 P 0 ;0
L 1.55118002 -2.08991004 1.5512 -2.08991004 0 P 0 ;0
L 1.5512 -2.08991004 1.55125 -2.08986998 0 P 0 ;0
L 1.55125 -2.08986998 1.55131004 -2.08981998 0 P 0 ;0
L 1.55131004 -2.08981998 1.55126998 -2.08978002 0 P 0 ;0
L 1.55126998 -2.08978002 1.55136004 -2.08978002 0 P 0 ;0
L 1.55136004 -2.08978002 1.5517 -2.08948996 0 P 0 ;0
L 1.5517 -2.08948996 1.55206004 -2.08911998 0 P 0 ;0
L 1.55206004 -2.08911998 1.55205 -2.08911004 0 P 0 ;0
L 1.55205 -2.08911004 1.55206004 -2.08911004 0 P 0 ;0
L 1.55206004 -2.08911004 1.55211998 -2.08906004 0 P 0 ;0
L 1.55211998 -2.08906004 1.55248996 -2.08861004 0 P 0 ;0
L 1.55248996 -2.08861004 1.55283996 -2.08811998 0 P 0 ;0
L 1.55283996 -2.08811998 1.55313996 -2.08761004 0 P 0 ;0
L 1.55313996 -2.08761004 1.5534 -2.08706998 0 P 0 ;0
L 1.5534 -2.08706998 1.55356004 -2.08663002 0 P 0 ;0
L 1.55356004 -2.08663002 1.55368996 -2.08618996 0 P 0 ;0
L 1.55368996 -2.08618996 1.55376998 -2.08573996 0 P 0 ;0
L 1.55376998 -2.08573996 1.55378002 -2.08565 0 P 0 ;0
L 1.55378002 -2.08565 1.55381998 -2.08528002 0 P 0 ;0
L 1.55381998 -2.08528002 1.55383002 -2.08481998 0 P 0 ;0
L 1.55383002 -2.08481998 1.5538 -2.08436998 0 P 0 ;0
L 1.5538 -2.08436998 1.55373002 -2.08391998 0 P 0 ;0
L 1.55373002 -2.08391998 1.55361998 -2.08346998 0 P 0 ;0
L 1.55361998 -2.08346998 1.55348002 -2.08303996 0 P 0 ;0
L 1.55348002 -2.08303996 1.5533 -2.08261004 0 P 0 ;0
L 1.5533 -2.08261004 1.55308996 -2.08221004 0 P 0 ;0
L 1.55308996 -2.08221004 1.55283996 -2.08183002 0 P 0 ;0
L 1.55283996 -2.08183002 1.55175 -2.0804 0 P 0 ;0
L 1.55175 -2.0804 1.55055 -2.07908002 0 P 0 ;0
L 1.55055 -2.07908002 1.54926004 -2.07783996 0 P 0 ;0
L 1.54926004 -2.07783996 1.54788996 -2.07671998 0 P 0 ;0
L 1.54788996 -2.07671998 1.53706998 -2.06898002 0 P 0 ;0
L 1.53706998 -2.06898002 1.52085 -2.05713996 0 P 0 ;0
L 1.52085 -2.05713996 1.51766004 -2.05445 0 P 0 ;0
L 1.51766004 -2.05445 1.51468002 -2.05153996 0 P 0 ;0
L 1.51468002 -2.05153996 1.51191998 -2.04841998 0 P 0 ;0
L 1.51191998 -2.04841998 1.51048996 -2.04651998 0 P 0 ;0
L 1.51048996 -2.04651998 1.50923002 -2.04453002 0 P 0 ;0
L 1.50923002 -2.04453002 1.50813996 -2.04245 0 P 0 ;0
L 1.50813996 -2.04245 1.50721998 -2.04026004 0 P 0 ;0
L 1.50721998 -2.04026004 1.50643002 -2.03788002 0 P 0 ;0
L 1.50643002 -2.03788002 1.50581004 -2.03545 0 P 0 ;0
L 1.50581004 -2.03545 1.50536004 -2.03298996 0 P 0 ;0
L 1.50536004 -2.03298996 1.50508996 -2.0305 0 P 0 ;0
L 1.50508996 -2.0305 1.50498996 -2.02745 0 P 0 ;0
L 1.50498996 -2.02745 1.50513996 -2.02443996 0 P 0 ;0
L 1.50513996 -2.02443996 1.50551998 -2.02145 0 P 0 ;0
L 1.50551998 -2.02145 1.50613996 -2.0185 0 P 0 ;0
L 1.50613996 -2.0185 1.50698996 -2.01561004 0 P 0 ;0
L 1.50698996 -2.01561004 1.50783002 -2.01341004 0 P 0 ;0
L 1.50783002 -2.01341004 1.50883002 -2.0113 0 P 0 ;0
L 1.50883002 -2.0113 1.51 -2.00928002 0 P 0 ;0
L 1.51 -2.00928002 1.51133002 -2.00736004 0 P 0 ;0
L 1.51133002 -2.00736004 1.5128 -2.00555 0 P 0 ;0
L 1.5128 -2.00555 1.5144 -2.00386004 0 P 0 ;0
L 1.5144 -2.00386004 1.51675 -2.00176998 0 P 0 ;0
L 1.51675 -2.00176998 1.51923002 -1.9999 0 P 0 ;0
L 1.51923002 -1.9999 1.52186004 -1.99823996 0 P 0 ;0
L 1.52186004 -1.99823996 1.52461998 -1.99681004 0 P 0 ;0
L 1.52461998 -1.99681004 1.52748996 -1.99561004 0 P 0 ;0
L 1.52748996 -1.99561004 1.53353002 -1.99363996 0 P 0 ;0
L 1.53353002 -1.99363996 1.5397 -1.99218002 0 P 0 ;0
L 1.5397 -1.99218002 1.54598002 -1.99123002 0 P 0 ;0
L 1.54598002 -1.99123002 1.55181004 -1.99075 0 P 0 ;0
L 1.55181004 -1.99075 1.55763002 -1.99061998 0 P 0 ;0
L 1.55763002 -1.99061998 1.57273002 -1.99113996 0 P 0 ;0
L 1.57273002 -1.99113996 1.58755 -1.99248996 0 P 0 ;0
L 1.58755 -1.99248996 1.59293002 -1.99331998 0 P 0 ;0
L 1.59293002 -1.99331998 1.59821004 -1.99448996 0 P 0 ;0
L 1.59821004 -1.99448996 1.59905 -1.99473002 0 P 0 ;0
L 1.59905 -1.99473002 1.59986004 -1.99501998 0 P 0 ;0
L 1.59986004 -1.99501998 1.60008002 -1.99511998 0 P 0 ;0
L 1.60008002 -1.99511998 1.6003 -1.99523002 0 P 0 ;0
L 1.6003 -1.99523002 1.60051004 -1.99536004 0 P 0 ;0
L 1.60051004 -1.99536004 1.60071004 -1.9955 0 P 0 ;0
L 1.60071004 -1.9955 1.60083002 -1.99561004 0 P 0 ;0
L 1.60083002 -1.99561004 1.60093996 -1.99571004 0 P 0 ;0
L 1.60093996 -1.99571004 1.60103996 -1.99583002 0 P 0 ;0
L 1.60103996 -1.99583002 1.60111998 -1.99595 0 P 0 ;0
L 1.60111998 -1.99595 1.60116998 -1.99601998 0 P 0 ;0
L 1.60116998 -1.99601998 1.60121004 -1.99611004 0 P 0 ;0
L 1.60121004 -1.99611004 1.60125 -1.99621004 0 P 0 ;0
L 1.60125 -1.99621004 1.60128002 -1.9963 0 P 0 ;0
L 1.60128002 -1.9963 1.60131004 -1.99641004 0 P 0 ;0
L 1.60131004 -1.99641004 1.6017 -1.99861998 0 P 0 ;0
L 1.6017 -1.99861998 1.60195 -2.00086998 0 P 0 ;0
L 1.60195 -2.00086998 1.60308002 -2.01593002 0 P 0 ;0
L 1.60308002 -2.01593002 1.60415 -2.03096998 0 P 0 ;0
L 1.60415 -2.03096998 1.60345 -2.03083996 0 P 0 ;0
L 1.60345 -2.03083996 1.60058996 -2.03026004 0 P 0 ;0
L 1.60058996 -2.03026004 1.59723002 -2.02948002 0 P 0 ;0
L 1.59723002 -2.02948002 1.59721998 -2.02948002 0 P 0 ;0
L 1.59721998 -2.02948002 1.59306998 -2.0286 0 P 0 ;0
L 1.59306998 -2.0286 1.58776004 -2.02776998 0 P 0 ;0
L 1.58776004 -2.02776998 1.58226004 -2.02708002 0 P 0 ;0
L 1.58226004 -2.02708002 1.57738002 -2.02666998 0 P 0 ;0
L 1.57738002 -2.02666998 1.5709 -2.02633996 0 P 0 ;0
L 1.5709 -2.02633996 1.56918996 -2.02635 0 P 0 ;0
L 1.56918996 -2.02635 1.56746998 -2.02648996 0 P 0 ;0
L 1.56746998 -2.02648996 1.56678996 -2.02658996 0 P 0 ;0
L 1.56678996 -2.02658996 1.56611998 -2.02673996 0 P 0 ;0
L 1.56611998 -2.02673996 1.56546004 -2.02695 0 P 0 ;0
L 1.56546004 -2.02695 1.56481998 -2.0272 0 P 0 ;0
L 1.56481998 -2.0272 1.56418996 -2.0275 0 P 0 ;0
L 1.56418996 -2.0275 1.56358002 -2.02785 0 P 0 ;0
L 1.56358002 -2.02785 1.563 -2.02823002 0 P 0 ;0
L 1.563 -2.02823002 1.56245 -2.02865 0 P 0 ;0
L 1.56245 -2.02865 1.56206998 -2.02898996 0 P 0 ;0
L 1.56206998 -2.02898996 1.56171004 -2.02936004 0 P 0 ;0
L 1.56171004 -2.02936004 1.56138002 -2.02976004 0 P 0 ;0
L 1.56138002 -2.02976004 1.56108996 -2.03018996 0 P 0 ;0
L 1.56108996 -2.03018996 1.56083002 -2.03063996 0 P 0 ;0
L 1.56083002 -2.03063996 1.56061998 -2.0311 0 P 0 ;0
L 1.56061998 -2.0311 1.56043996 -2.03158996 0 P 0 ;0
L 1.56043996 -2.03158996 1.5603 -2.03208002 0 P 0 ;0
L 1.5603 -2.03208002 1.5602 -2.0326 0 P 0 ;0
L 1.5602 -2.0326 1.56015 -2.03308002 0 P 0 ;0
L 1.56015 -2.03308002 1.56013996 -2.03353996 0 P 0 ;0
L 1.56013996 -2.03353996 1.56016004 -2.03391004 0 P 0 ;0
L 1.56016004 -2.03391004 1.56048002 -2.03391004 0 P 0 ;0
L 1.56048002 -2.03391004 1.56016004 -2.03393002 0 P 0 ;0
L 1.56016004 -2.03393002 1.56016998 -2.03401004 0 P 0 ;0
L 1.56016998 -2.03401004 1.56023002 -2.03448002 0 P 0 ;0
L 1.56023002 -2.03448002 1.56025 -2.03456004 0 P 0 ;0
L 1.56025 -2.03456004 1.56033002 -2.03493002 0 P 0 ;0
L 1.56033002 -2.03493002 1.56046998 -2.03538002 0 P 0 ;0
L 1.56046998 -2.03538002 1.56063996 -2.03581998 0 P 0 ;0
L 1.56063996 -2.03581998 1.56085 -2.03623996 0 P 0 ;0
L 1.56085 -2.03623996 1.56108996 -2.03663996 0 P 0 ;0
L 1.56108996 -2.03663996 1.56136004 -2.03701998 0 P 0 ;0
L 1.56136004 -2.03701998 1.56233002 -2.03818996 0 P 0 ;0
L 1.56233002 -2.03818996 1.56336998 -2.03928996 0 P 0 ;0
L 1.56336998 -2.03928996 1.56448002 -2.04031004 0 P 0 ;0
L 1.56448002 -2.04031004 1.56566004 -2.04123996 0 P 0 ;0
L 1.56566004 -2.04123996 1.57471004 -2.04761998 0 P 0 ;0
L 1.57471004 -2.04761998 1.58461998 -2.05491004 0 P 0 ;0
L 1.58461998 -2.05491004 1.58898996 -2.05858996 0 P 0 ;0
L 1.58898996 -2.05858996 1.59315 -2.06245 0 P 0 ;0
L 1.59315 -2.06245 1.59656998 -2.06596998 0 P 0 ;0
L 1.59656998 -2.06596998 1.59976004 -2.06965 0 P 0 ;0
L 1.59976004 -2.06965 1.60116004 -2.07151004 0 P 0 ;0
L 1.60116004 -2.07151004 1.60238002 -2.07346004 0 P 0 ;0
L 1.60238002 -2.07346004 1.60341998 -2.0755 0 P 0 ;0
L 1.60341998 -2.0755 1.60403996 -2.077 0 P 0 ;0
L 1.60403996 -2.077 1.60456004 -2.07853996 0 P 0 ;0
L 1.60456004 -2.07853996 1.60496004 -2.08011004 0 P 0 ;0
L 1.60496004 -2.08011004 1.60525 -2.0817 0 P 0 ;0
L 1.60525 -2.0817 1.60568996 -2.08578002 0 P 0 ;0
L 1.60568996 -2.08578002 1.60578996 -2.08988002 0 P 0 ;0
L 1.60578996 -2.08988002 1.60556998 -2.09403002 0 P 0 ;0
L 1.60556998 -2.09403002 1.60501004 -2.09813996 0 P 0 ;0
L 1.60501004 -2.09813996 1.60451998 -2.10036998 0 P 0 ;0
L 1.60451998 -2.10036998 1.60383996 -2.10253996 0 P 0 ;0
L 1.60383996 -2.10253996 1.60298996 -2.10465 0 P 0 ;0
L 1.60298996 -2.10465 1.60163996 -2.1073 0 P 0 ;0
L 1.60163996 -2.1073 1.60008002 -2.10983002 0 P 0 ;0
L 1.60008002 -2.10983002 1.59833002 -2.11225 0 P 0 ;0
L 1.59833002 -2.11225 1.59696998 -2.11386998 0 P 0 ;0
L 1.59696998 -2.11386998 1.59551004 -2.11538996 0 P 0 ;0
L 1.59551004 -2.11538996 1.59395 -2.1168 0 P 0 ;0
L 1.59395 -2.1168 1.59231004 -2.11811004 0 P 0 ;0
L 1.59231004 -2.11811004 1.58973002 -2.11986004 0 P 0 ;0
L 1.58973002 -2.11986004 1.58701998 -2.1214 0 P 0 ;0
L 1.58701998 -2.1214 1.5842 -2.12273002 0 P 0 ;0
L 1.5842 -2.12273002 1.5788 -2.1248 0 P 0 ;0
L 1.5788 -2.1248 1.57326998 -2.12648996 0 P 0 ;0
L 1.57326998 -2.12648996 1.56983002 -2.12731004 0 P 0 ;0
L 1.56983002 -2.12731004 1.56638002 -2.12791004 0 P 0 ;0
L 1.56638002 -2.12791004 1.56288996 -2.1283 0 P 0 ;0
L 1.56288996 -2.1283 1.54886998 -2.12886998 0 P 0 ;0
L 1.35851998 -2.06545 1.47866004 -2.06545 0 P 0 ;0
L 1.35936004 -2.06445 1.47871004 -2.06445 0 P 0 ;0
L 1.36041004 -2.06345 1.47875 -2.06345 0 P 0 ;0
L 1.36163996 -2.06245 1.4788 -2.06245 0 P 0 ;0
L 1.36293996 -2.06145 1.47883996 -2.06145 0 P 0 ;0
L 1.36436004 -2.06045 1.47888996 -2.06045 0 P 0 ;0
L 1.36598002 -2.05945 1.47893996 -2.05945 0 P 0 ;0
L 1.36776004 -2.05845 1.47898996 -2.05845 0 P 0 ;0
L 1.36971004 -2.05745 1.47903002 -2.05745 0 P 0 ;0
L 1.37166004 -2.05645 1.47908002 -2.05645 0 P 0 ;0
L 1.37391004 -2.05545 1.47911998 -2.05545 0 P 0 ;0
L 1.37616998 -2.05445 1.47916998 -2.05445 0 P 0 ;0
L 1.37873002 -2.05345 1.47921004 -2.05345 0 P 0 ;0
L 1.38136004 -2.05245 1.47926004 -2.05245 0 P 0 ;0
L 1.36875 -2.03345 1.37108996 -2.03345 0 P 0 ;0
L 1.36886004 -2.03245 1.37385 -2.03245 0 P 0 ;0
L 1.36896998 -2.03145 1.37678002 -2.03145 0 P 0 ;0
L 1.36908996 -2.03045 1.3797 -2.03045 0 P 0 ;0
L 1.36921004 -2.02945 1.38261998 -2.02945 0 P 0 ;0
L 1.36933002 -2.02845 1.38638996 -2.02845 0 P 0 ;0
L 1.36946004 -2.02745 1.39023996 -2.02745 0 P 0 ;0
L 1.36958002 -2.02645 1.39503002 -2.02645 0 P 0 ;0
L 1.3697 -2.02545 1.40068002 -2.02545 0 P 0 ;0
L 1.36981998 -2.02445 1.41053996 -2.02445 0 P 0 ;0
L 1.36993996 -2.02345 1.47993996 -2.02345 0 P 0 ;0
L 1.37008002 -2.02245 1.47988002 -2.02245 0 P 0 ;0
L 1.37021004 -2.02145 1.47978002 -2.02145 0 P 0 ;0
L 1.37033996 -2.02045 1.47968002 -2.02045 0 P 0 ;0
L 1.37046998 -2.01945 1.47953002 -2.01945 0 P 0 ;0
L 1.3706 -2.01845 1.47936004 -2.01845 0 P 0 ;0
L 1.37073002 -2.01745 1.47918002 -2.01745 0 P 0 ;0
L 1.37086004 -2.01645 1.47893002 -2.01645 0 P 0 ;0
L 1.37098996 -2.01545 1.47868002 -2.01545 0 P 0 ;0
L 1.37113002 -2.01445 1.4784 -2.01445 0 P 0 ;0
L 1.37126998 -2.01345 1.47806004 -2.01345 0 P 0 ;0
L 1.3714 -2.01245 1.47773002 -2.01245 0 P 0 ;0
L 1.37153996 -2.01145 1.47733002 -2.01145 0 P 0 ;0
L 1.37168002 -2.01045 1.47691004 -2.01045 0 P 0 ;0
L 1.37181004 -2.00945 1.47641004 -2.00945 0 P 0 ;0
L 1.37195 -2.00845 1.47588996 -2.00845 0 P 0 ;0
L 1.37208002 -2.00745 1.47528002 -2.00745 0 P 0 ;0
L 1.37221004 -2.00645 1.47463996 -2.00645 0 P 0 ;0
L 1.37235 -2.00545 1.47391998 -2.00545 0 P 0 ;0
L 1.37248996 -2.00445 1.47311004 -2.00445 0 P 0 ;0
L 1.37261998 -2.00345 1.47225 -2.00345 0 P 0 ;0
L 1.37276004 -2.00245 1.47126998 -2.00245 0 P 0 ;0
L 1.3729 -2.00145 1.4702 -2.00145 0 P 0 ;0
L 1.37303002 -2.00045 1.46903996 -2.00045 0 P 0 ;0
L 1.37316998 -1.99945 1.46775 -1.99945 0 P 0 ;0
L 1.3733 -1.99845 1.46625 -1.99845 0 P 0 ;0
L 1.37343996 -1.99745 1.46455 -1.99745 0 P 0 ;0
L 1.37356998 -1.99645 1.46253996 -1.99645 0 P 0 ;0
L 1.37753002 -1.99545 1.46041004 -1.99545 0 P 0 ;0
L 1.38218996 -1.99445 1.45781004 -1.99445 0 P 0 ;0
L 1.42925 -2.08345 1.47785 -2.08345 0 P 0 ;0
L 1.42931998 -2.08245 1.47788996 -2.08245 0 P 0 ;0
L 1.42938002 -2.08145 1.47793002 -2.08145 0 P 0 ;0
L 1.42945 -2.08045 1.47796998 -2.08045 0 P 0 ;0
L 1.42951004 -2.07945 1.47801004 -2.07945 0 P 0 ;0
L 1.42958002 -2.07845 1.47806004 -2.07845 0 P 0 ;0
L 1.42963996 -2.07745 1.4781 -2.07745 0 P 0 ;0
L 1.4297 -2.07645 1.47815 -2.07645 0 P 0 ;0
L 1.42976998 -2.07545 1.4782 -2.07545 0 P 0 ;0
L 1.42983002 -2.07445 1.47825 -2.07445 0 P 0 ;0
L 1.4299 -2.07345 1.47828996 -2.07345 0 P 0 ;0
L 1.42963996 -2.07245 1.47833996 -2.07245 0 P 0 ;0
L 1.42918996 -2.07145 1.47838002 -2.07145 0 P 0 ;0
L 1.38425 -2.05145 1.47931004 -2.05145 0 P 0 ;0
L 1.38731998 -2.05045 1.47933996 -2.05045 0 P 0 ;0
L 1.39088002 -2.04945 1.47938002 -2.04945 0 P 0 ;0
L 1.3947 -2.04845 1.47941004 -2.04845 0 P 0 ;0
L 1.39851004 -2.04745 1.47945 -2.04745 0 P 0 ;0
L 1.40233002 -2.04645 1.47948002 -2.04645 0 P 0 ;0
L 1.40608002 -2.04545 1.47951004 -2.04545 0 P 0 ;0
L 1.40983002 -2.04445 1.47955 -2.04445 0 P 0 ;0
L 1.41306998 -2.04345 1.47958996 -2.04345 0 P 0 ;0
L 1.41591998 -2.04245 1.47961998 -2.04245 0 P 0 ;0
L 1.41876998 -2.04145 1.47965 -2.04145 0 P 0 ;0
L 1.42133996 -2.04045 1.47968996 -2.04045 0 P 0 ;0
L 1.42361998 -2.03945 1.47971998 -2.03945 0 P 0 ;0
L 1.42591004 -2.03845 1.47975 -2.03845 0 P 0 ;0
L 1.42805 -2.03745 1.47978002 -2.03745 0 P 0 ;0
L 1.42936004 -2.03645 1.47981004 -2.03645 0 P 0 ;0
L 1.43003002 -2.03545 1.47983002 -2.03545 0 P 0 ;0
L 1.43081998 -2.03445 1.47986004 -2.03445 0 P 0 ;0
L 1.43121004 -2.03345 1.47988002 -2.03345 0 P 0 ;0
L 1.43141998 -2.03245 1.4799 -2.03245 0 P 0 ;0
L 1.43146998 -2.03145 1.47993002 -2.03145 0 P 0 ;0
L 1.43136004 -2.03045 1.47996004 -2.03045 0 P 0 ;0
L 1.43108002 -2.02945 1.47998002 -2.02945 0 P 0 ;0
L 1.4306 -2.02845 1.48001004 -2.02845 0 P 0 ;0
L 1.42986998 -2.02745 1.48001004 -2.02745 0 P 0 ;0
L 1.42875 -2.02645 1.47998996 -2.02645 0 P 0 ;0
L 1.42658996 -2.02545 1.47996998 -2.02545 0 P 0 ;0
L 1.42203996 -2.02445 1.47996004 -2.02445 0 P 0 ;0
L 1.38748002 -1.99345 1.45483002 -1.99345 0 P 0 ;0
L 1.39331998 -1.99245 1.45108996 -1.99245 0 P 0 ;0
L 1.40051004 -1.99145 1.44503002 -1.99145 0 P 0 ;0
L 1.38096998 -2.12745 1.4051 -2.12745 0 P 0 ;0
L 1.37671004 -2.12645 1.41113996 -2.12645 0 P 0 ;0
L 1.3736 -2.12545 1.41238996 -2.12545 0 P 0 ;0
L 1.37096998 -2.12445 1.41268002 -2.12445 0 P 0 ;0
L 1.36876998 -2.12345 1.41296998 -2.12345 0 P 0 ;0
L 1.36685 -2.12245 1.41326998 -2.12245 0 P 0 ;0
L 1.36516004 -2.12145 1.41356004 -2.12145 0 P 0 ;0
L 1.36366004 -2.12045 1.41385 -2.12045 0 P 0 ;0
L 1.36225 -2.11945 1.41413996 -2.11945 0 P 0 ;0
L 1.361 -2.11845 1.41443002 -2.11845 0 P 0 ;0
L 1.35983002 -2.11745 1.41471998 -2.11745 0 P 0 ;0
L 1.35876004 -2.11645 1.41501004 -2.11645 0 P 0 ;0
L 1.42661998 -2.12445 1.47693002 -2.12445 0 P 0 ;0
L 1.42665 -2.12345 1.47693002 -2.12345 0 P 0 ;0
L 1.4267 -2.12245 1.47693002 -2.12245 0 P 0 ;0
L 1.42675 -2.12145 1.47693002 -2.12145 0 P 0 ;0
L 1.42681004 -2.12045 1.47693002 -2.12045 0 P 0 ;0
L 1.42686998 -2.11945 1.47693002 -2.11945 0 P 0 ;0
L 1.42691998 -2.11845 1.47693002 -2.11845 0 P 0 ;0
L 1.42698996 -2.11745 1.47693002 -2.11745 0 P 0 ;0
L 1.42705 -2.11645 1.47693002 -2.11645 0 P 0 ;0
L 1.42711004 -2.11545 1.47693002 -2.11545 0 P 0 ;0
L 1.42716998 -2.11445 1.47693002 -2.11445 0 P 0 ;0
L 1.42723002 -2.11345 1.47693996 -2.11345 0 P 0 ;0
L 1.4273 -2.11245 1.47695 -2.11245 0 P 0 ;0
L 1.42736998 -2.11145 1.47696004 -2.11145 0 P 0 ;0
L 1.42743996 -2.11045 1.47698002 -2.11045 0 P 0 ;0
L 1.42751004 -2.10945 1.47698996 -2.10945 0 P 0 ;0
L 1.42758002 -2.10845 1.47701004 -2.10845 0 P 0 ;0
L 1.42765 -2.10745 1.47703002 -2.10745 0 P 0 ;0
L 1.42771004 -2.10645 1.47703996 -2.10645 0 P 0 ;0
L 1.42778002 -2.10545 1.47706998 -2.10545 0 P 0 ;0
L 1.42783996 -2.10445 1.4771 -2.10445 0 P 0 ;0
L 1.42791004 -2.10345 1.47713002 -2.10345 0 P 0 ;0
L 1.42798002 -2.10245 1.47716004 -2.10245 0 P 0 ;0
L 1.42805 -2.10145 1.4772 -2.10145 0 P 0 ;0
L 1.42811004 -2.10045 1.47723002 -2.10045 0 P 0 ;0
L 1.40953002 -2.09945 1.41973002 -2.09945 0 P 0 ;0
L 1.42818002 -2.09945 1.47726004 -2.09945 0 P 0 ;0
L 1.41618002 -2.09845 1.41996998 -2.09845 0 P 0 ;0
L 1.42825 -2.09845 1.47728996 -2.09845 0 P 0 ;0
L 1.42831998 -2.09745 1.47733002 -2.09745 0 P 0 ;0
L 1.42838996 -2.09645 1.47736004 -2.09645 0 P 0 ;0
L 1.42846004 -2.09545 1.47738996 -2.09545 0 P 0 ;0
L 1.42851998 -2.09445 1.47741998 -2.09445 0 P 0 ;0
L 1.42858996 -2.09345 1.47746004 -2.09345 0 P 0 ;0
L 1.42866004 -2.09245 1.4775 -2.09245 0 P 0 ;0
L 1.42873002 -2.09145 1.47753996 -2.09145 0 P 0 ;0
L 1.42878996 -2.09045 1.47758002 -2.09045 0 P 0 ;0
L 1.42886004 -2.08945 1.47761998 -2.08945 0 P 0 ;0
L 1.42893002 -2.08845 1.47766004 -2.08845 0 P 0 ;0
L 1.42898996 -2.08745 1.4777 -2.08745 0 P 0 ;0
L 1.42906004 -2.08645 1.47773002 -2.08645 0 P 0 ;0
L 1.42911998 -2.08545 1.47776998 -2.08545 0 P 0 ;0
L 1.42918996 -2.08445 1.47781004 -2.08445 0 P 0 ;0
L 1.61686004 -2.17995 1.66846004 -2.17995 0 P 0 ;0
L 1.61591004 -2.17895 1.67158996 -2.17895 0 P 0 ;0
L 1.61553996 -2.17795 1.67431998 -2.17795 0 P 0 ;0
L 1.61526998 -2.17695 1.67675 -2.17695 0 P 0 ;0
L 1.61508002 -2.17595 1.67903996 -2.17595 0 P 0 ;0
L 1.61496998 -2.17495 1.68108002 -2.17495 0 P 0 ;0
L 1.61491004 -2.17395 1.68295 -2.17395 0 P 0 ;0
L 1.61485 -2.17295 1.68458996 -2.17295 0 P 0 ;0
L 1.61478996 -2.17195 1.6861 -2.17195 0 P 0 ;0
L 1.61473002 -2.17095 1.6875 -2.17095 0 P 0 ;0
L 1.61466998 -2.16995 1.68876998 -2.16995 0 P 0 ;0
L 1.61461004 -2.16895 1.68998002 -2.16895 0 P 0 ;0
L 1.61455 -2.16795 1.69108002 -2.16795 0 P 0 ;0
L 1.61448996 -2.16695 1.69211998 -2.16695 0 P 0 ;0
L 1.61443002 -2.16595 1.69316004 -2.16595 0 P 0 ;0
L 1.61436998 -2.16495 1.69411998 -2.16495 0 P 0 ;0
L 1.61431004 -2.16395 1.69498996 -2.16395 0 P 0 ;0
L 1.61425 -2.16295 1.69586004 -2.16295 0 P 0 ;0
L 1.61418996 -2.16195 1.69673002 -2.16195 0 P 0 ;0
L 1.61413002 -2.16095 1.69746998 -2.16095 0 P 0 ;0
L 1.61406998 -2.15995 1.6982 -2.15995 0 P 0 ;0
L 1.61401998 -2.15895 1.69893996 -2.15895 0 P 0 ;0
L 1.61396998 -2.15795 1.69963002 -2.15795 0 P 0 ;0
L 1.64433002 -2.18295 1.63151004 -2.18271004 0 P 0 ;0
L 1.63151004 -2.18271004 1.62658002 -2.18226998 0 P 0 ;0
L 1.62658002 -2.18226998 1.62168996 -2.18146998 0 P 0 ;0
L 1.62168996 -2.18146998 1.6201 -2.1811 0 P 0 ;0
L 1.6201 -2.1811 1.61853996 -2.18061004 0 P 0 ;0
L 1.61853996 -2.18061004 1.61701004 -2.18001998 0 P 0 ;0
L 1.61701004 -2.18001998 1.61686004 -2.17995 0 P 0 ;0
L 1.61686004 -2.17995 1.61671004 -2.17986998 0 P 0 ;0
L 1.61671004 -2.17986998 1.61656998 -2.17976998 0 P 0 ;0
L 1.61656998 -2.17976998 1.61643996 -2.17966998 0 P 0 ;0
L 1.61643996 -2.17966998 1.61631998 -2.17955 0 P 0 ;0
L 1.61631998 -2.17955 1.61621004 -2.17943002 0 P 0 ;0
L 1.61621004 -2.17943002 1.6161 -2.1793 0 P 0 ;0
L 1.6161 -2.1793 1.61601004 -2.17915 0 P 0 ;0
L 1.61601004 -2.17915 1.61593002 -2.179 0 P 0 ;0
L 1.61593002 -2.179 1.61586004 -2.17885 0 P 0 ;0
L 1.61586004 -2.17885 1.61553002 -2.17791004 0 P 0 ;0
L 1.61553002 -2.17791004 1.61526998 -2.17696004 0 P 0 ;0
L 1.61526998 -2.17696004 1.61508996 -2.17598996 0 P 0 ;0
L 1.61508996 -2.17598996 1.61496998 -2.17496998 0 P 0 ;0
L 1.61496998 -2.17496998 1.61408002 -2.16011004 0 P 0 ;0
L 1.61408002 -2.16011004 1.61341998 -2.14758996 0 P 0 ;0
L 1.61341998 -2.14758996 1.6202 -2.14821004 0 P 0 ;0
L 1.6202 -2.14821004 1.62023002 -2.14821004 0 P 0 ;0
L 1.62023002 -2.14821004 1.63216998 -2.14893996 0 P 0 ;0
L 1.63216998 -2.14893996 1.6349 -2.14893002 0 P 0 ;0
L 1.6349 -2.14893002 1.63761998 -2.14873002 0 P 0 ;0
L 1.63761998 -2.14873002 1.64031998 -2.14835 0 P 0 ;0
L 1.64031998 -2.14835 1.64198996 -2.14798996 0 P 0 ;0
L 1.64198996 -2.14798996 1.64363002 -2.14751998 0 P 0 ;0
L 1.64363002 -2.14751998 1.64523002 -2.14693002 0 P 0 ;0
L 1.64523002 -2.14693002 1.64678996 -2.14623002 0 P 0 ;0
L 1.64678996 -2.14623002 1.64888002 -2.14506998 0 P 0 ;0
L 1.64888002 -2.14506998 1.65086998 -2.14376004 0 P 0 ;0
L 1.65086998 -2.14376004 1.65093996 -2.14371004 0 P 0 ;0
L 1.65093996 -2.14371004 1.65275 -2.14228996 0 P 0 ;0
L 1.65275 -2.14228996 1.6539 -2.14123996 0 P 0 ;0
L 1.6539 -2.14123996 1.65496004 -2.14011004 0 P 0 ;0
L 1.65496004 -2.14011004 1.65591998 -2.13891004 0 P 0 ;0
L 1.65591998 -2.13891004 1.65755 -2.13653996 0 P 0 ;0
L 1.65755 -2.13653996 1.65901998 -2.13415 0 P 0 ;0
L 1.65901998 -2.13415 1.65903002 -2.13413002 0 P 0 ;0
L 1.65903002 -2.13413002 1.66035 -2.13171998 0 P 0 ;0
L 1.66035 -2.13171998 1.66155 -2.12925 0 P 0 ;0
L 1.66155 -2.12925 1.66183996 -2.12851998 0 P 0 ;0
L 1.66183996 -2.12851998 1.66206998 -2.12776004 0 P 0 ;0
L 1.66206998 -2.12776004 1.66223996 -2.12696998 0 P 0 ;0
L 1.66223996 -2.12696998 1.66233996 -2.12618002 0 P 0 ;0
L 1.66233996 -2.12618002 1.66236998 -2.12538996 0 P 0 ;0
L 1.66236998 -2.12538996 1.66233002 -2.12436004 0 P 0 ;0
L 1.66233002 -2.12436004 1.66221004 -2.12335 0 P 0 ;0
L 1.66221004 -2.12335 1.662 -2.12235 0 P 0 ;0
L 1.662 -2.12235 1.66171004 -2.12141004 0 P 0 ;0
L 1.66171004 -2.12141004 1.64438996 -2.07113002 0 P 0 ;0
L 1.64438996 -2.07113002 1.62871998 -2.02606004 0 P 0 ;0
L 1.62871998 -2.02606004 1.62116004 -2.00558996 0 P 0 ;0
L 1.62116004 -2.00558996 1.62116004 -2.00556998 0 P 0 ;0
L 1.62116004 -2.00556998 1.61681004 -1.99443996 0 P 0 ;0
L 1.61681004 -1.99443996 1.67163002 -1.99443996 0 P 0 ;0
L 1.67163002 -1.99443996 1.67301004 -2.00076004 0 P 0 ;0
L 1.67301004 -2.00076004 1.67613002 -2.01341998 0 P 0 ;0
L 1.67613002 -2.01341998 1.68331004 -2.03931998 0 P 0 ;0
L 1.68331004 -2.03931998 1.69153002 -2.06856998 0 P 0 ;0
L 1.69153002 -2.06856998 1.6916 -2.06876004 0 P 0 ;0
L 1.6916 -2.06876004 1.69168996 -2.06896998 0 P 0 ;0
L 1.69168996 -2.06896998 1.69181004 -2.06918002 0 P 0 ;0
L 1.69181004 -2.06918002 1.69193002 -2.06936998 0 P 0 ;0
L 1.69193002 -2.06936998 1.69208002 -2.06956004 0 P 0 ;0
L 1.69208002 -2.06956004 1.69223996 -2.06973002 0 P 0 ;0
L 1.69223996 -2.06973002 1.69241998 -2.06988002 0 P 0 ;0
L 1.69241998 -2.06988002 1.6926 -2.07001998 0 P 0 ;0
L 1.6926 -2.07001998 1.6928 -2.07015 0 P 0 ;0
L 1.6928 -2.07015 1.69301004 -2.07025 0 P 0 ;0
L 1.69301004 -2.07025 1.69323002 -2.07033996 0 P 0 ;0
L 1.69323002 -2.07033996 1.69346004 -2.07041004 0 P 0 ;0
L 1.69346004 -2.07041004 1.69368002 -2.07045 0 P 0 ;0
L 1.69368002 -2.07045 1.69391998 -2.07048002 0 P 0 ;0
L 1.69391998 -2.07048002 1.69413996 -2.07048996 0 P 0 ;0
L 1.69413996 -2.07048996 1.6944 -2.07048002 0 P 0 ;0
L 1.6944 -2.07048002 1.69465 -2.07045 0 P 0 ;0
L 1.69465 -2.07045 1.69488996 -2.07038996 0 P 0 ;0
L 1.69488996 -2.07038996 1.69513996 -2.07031998 0 P 0 ;0
L 1.69513996 -2.07031998 1.69536998 -2.07021998 0 P 0 ;0
L 1.69536998 -2.07021998 1.69558996 -2.0701 0 P 0 ;0
L 1.69558996 -2.0701 1.69581004 -2.06996998 0 P 0 ;0
L 1.69581004 -2.06996998 1.69601004 -2.06981998 0 P 0 ;0
L 1.69601004 -2.06981998 1.6962 -2.06965 0 P 0 ;0
L 1.6962 -2.06965 1.69636998 -2.06946004 0 P 0 ;0
L 1.69636998 -2.06946004 1.69653002 -2.06926004 0 P 0 ;0
L 1.69653002 -2.06926004 1.69666004 -2.06905 0 P 0 ;0
L 1.69666004 -2.06905 1.69678996 -2.06883002 0 P 0 ;0
L 1.69678996 -2.06883002 1.69688002 -2.0686 0 P 0 ;0
L 1.69688002 -2.0686 1.69695 -2.0684 0 P 0 ;0
L 1.69695 -2.0684 1.70426004 -2.04365 0 P 0 ;0
L 1.70426004 -2.04365 1.70426004 -2.04363002 0 P 0 ;0
L 1.70426004 -2.04363002 1.71066998 -2.0213 0 P 0 ;0
L 1.71066998 -2.0213 1.71068002 -2.02126004 0 P 0 ;0
L 1.71068002 -2.02126004 1.71431998 -2.00693996 0 P 0 ;0
L 1.71431998 -2.00693996 1.71706004 -1.99496998 0 P 0 ;0
L 1.71706004 -1.99496998 1.74335 -1.9947 0 P 0 ;0
L 1.74335 -1.9947 1.75403002 -1.99461004 0 P 0 ;0
L 1.75403002 -1.99461004 1.76301004 -1.99465 0 P 0 ;0
L 1.76301004 -1.99465 1.76886004 -1.99471004 0 P 0 ;0
L 1.76886004 -1.99471004 1.76883996 -1.99476004 0 P 0 ;0
L 1.76883996 -1.99476004 1.74021004 -2.06556004 0 P 0 ;0
L 1.74021004 -2.06556004 1.71298002 -2.13276998 0 P 0 ;0
L 1.71298002 -2.13276998 1.70836998 -2.14293996 0 P 0 ;0
L 1.70836998 -2.14293996 1.70413996 -2.15076004 0 P 0 ;0
L 1.70413996 -2.15076004 1.69941998 -2.15828996 0 P 0 ;0
L 1.69941998 -2.15828996 1.6967 -2.16198996 0 P 0 ;0
L 1.6967 -2.16198996 1.6937 -2.16541998 0 P 0 ;0
L 1.6937 -2.16541998 1.69041998 -2.1686 0 P 0 ;0
L 1.69041998 -2.1686 1.68793996 -2.17063002 0 P 0 ;0
L 1.68793996 -2.17063002 1.68535 -2.17248002 0 P 0 ;0
L 1.68535 -2.17248002 1.68263996 -2.17413996 0 P 0 ;0
L 1.68263996 -2.17413996 1.67981004 -2.17561004 0 P 0 ;0
L 1.67981004 -2.17561004 1.67525 -2.17761004 0 P 0 ;0
L 1.67525 -2.17761004 1.6706 -2.17931998 0 P 0 ;0
L 1.6706 -2.17931998 1.66586004 -2.18073002 0 P 0 ;0
L 1.66586004 -2.18073002 1.66141998 -2.1817 0 P 0 ;0
L 1.66141998 -2.1817 1.65691998 -2.18228996 0 P 0 ;0
L 1.65691998 -2.18228996 1.64433002 -2.18295 0 P 0 ;0
L 1.61928996 -2.00628002 1.62683996 -2.02673002 0 P 0 ;0
L 1.62683996 -2.02673002 1.6425 -2.07178002 0 P 0 ;0
L 1.6425 -2.07178002 1.65981004 -2.12201998 0 P 0 ;0
L 1.65981004 -2.12201998 1.66006004 -2.12283996 0 P 0 ;0
L 1.66006004 -2.12283996 1.66023002 -2.12368002 0 P 0 ;0
L 1.66023002 -2.12368002 1.66033996 -2.12451998 0 P 0 ;0
L 1.66033996 -2.12451998 1.66036998 -2.12538002 0 P 0 ;0
L 1.66036998 -2.12538002 1.66033996 -2.12601004 0 P 0 ;0
L 1.66033996 -2.12601004 1.66026998 -2.12663996 0 P 0 ;0
L 1.66026998 -2.12663996 1.66013996 -2.12725 0 P 0 ;0
L 1.66013996 -2.12725 1.65995 -2.12786004 0 P 0 ;0
L 1.65995 -2.12786004 1.65971004 -2.12843996 0 P 0 ;0
L 1.65971004 -2.12843996 1.65856998 -2.1308 0 P 0 ;0
L 1.65856998 -2.1308 1.6573 -2.13313002 0 P 0 ;0
L 1.6573 -2.13313002 1.65586998 -2.13545 0 P 0 ;0
L 1.65586998 -2.13545 1.65431004 -2.13771998 0 P 0 ;0
L 1.65431004 -2.13771998 1.65343996 -2.1388 0 P 0 ;0
L 1.65343996 -2.1388 1.65248996 -2.13981998 0 P 0 ;0
L 1.65248996 -2.13981998 1.65146004 -2.14076004 0 P 0 ;0
L 1.65146004 -2.14076004 1.64971004 -2.14213002 0 P 0 ;0
L 1.64971004 -2.14213002 1.64785 -2.14336004 0 P 0 ;0
L 1.64785 -2.14336004 1.64588996 -2.14443996 0 P 0 ;0
L 1.64588996 -2.14443996 1.64446998 -2.14508002 0 P 0 ;0
L 1.64446998 -2.14508002 1.64301004 -2.14561998 0 P 0 ;0
L 1.64301004 -2.14561998 1.64151004 -2.14605 0 P 0 ;0
L 1.64151004 -2.14605 1.63996998 -2.14636998 0 P 0 ;0
L 1.63996998 -2.14636998 1.63741004 -2.14673996 0 P 0 ;0
L 1.63741004 -2.14673996 1.63483002 -2.14693002 0 P 0 ;0
L 1.63483002 -2.14693002 1.63223002 -2.14693996 0 P 0 ;0
L 1.63223002 -2.14693996 1.62036004 -2.14621998 0 P 0 ;0
L 1.62036004 -2.14621998 1.6113 -2.14538002 0 P 0 ;0
L 1.6113 -2.14538002 1.61208996 -2.16023002 0 P 0 ;0
L 1.61208996 -2.16023002 1.61298002 -2.17515 0 P 0 ;0
L 1.61298002 -2.17515 1.6131 -2.17628002 0 P 0 ;0
L 1.6131 -2.17628002 1.61331998 -2.17741004 0 P 0 ;0
L 1.61331998 -2.17741004 1.61361998 -2.17851004 0 P 0 ;0
L 1.61361998 -2.17851004 1.614 -2.17958996 0 P 0 ;0
L 1.614 -2.17958996 1.61413996 -2.17988996 0 P 0 ;0
L 1.61413996 -2.17988996 1.61428996 -2.18018002 0 P 0 ;0
L 1.61428996 -2.18018002 1.61446998 -2.18045 0 P 0 ;0
L 1.61446998 -2.18045 1.61466998 -2.18071004 0 P 0 ;0
L 1.61466998 -2.18071004 1.61488996 -2.18095 0 P 0 ;0
L 1.61488996 -2.18095 1.61511998 -2.18116998 0 P 0 ;0
L 1.61511998 -2.18116998 1.61538002 -2.18138002 0 P 0 ;0
L 1.61538002 -2.18138002 1.61565 -2.18156004 0 P 0 ;0
L 1.61565 -2.18156004 1.61593002 -2.18173002 0 P 0 ;0
L 1.61593002 -2.18173002 1.61623002 -2.18186004 0 P 0 ;0
L 1.61623002 -2.18186004 1.61788002 -2.1825 0 P 0 ;0
L 1.61788002 -2.1825 1.61956998 -2.18301998 0 P 0 ;0
L 1.61956998 -2.18301998 1.6213 -2.18343002 0 P 0 ;0
L 1.6213 -2.18343002 1.62633002 -2.18426004 0 P 0 ;0
L 1.62633002 -2.18426004 1.6314 -2.18471004 0 P 0 ;0
L 1.6314 -2.18471004 1.64436004 -2.18495 0 P 0 ;0
L 1.64436004 -2.18495 1.65711004 -2.18428002 0 P 0 ;0
L 1.65711004 -2.18428002 1.66176998 -2.18366998 0 P 0 ;0
L 1.66176998 -2.18366998 1.66636004 -2.18266998 0 P 0 ;0
L 1.66636004 -2.18266998 1.67123002 -2.18121004 0 P 0 ;0
L 1.67123002 -2.18121004 1.676 -2.17946998 0 P 0 ;0
L 1.676 -2.17946998 1.68068002 -2.17741998 0 P 0 ;0
L 1.68068002 -2.17741998 1.68361998 -2.17588002 0 P 0 ;0
L 1.68361998 -2.17588002 1.68646004 -2.17415 0 P 0 ;0
L 1.68646004 -2.17415 1.68916004 -2.17221998 0 P 0 ;0
L 1.68916004 -2.17221998 1.69175 -2.17008996 0 P 0 ;0
L 1.69175 -2.17008996 1.69515 -2.1668 0 P 0 ;0
L 1.69515 -2.1668 1.69826004 -2.16323996 0 P 0 ;0
L 1.69826004 -2.16323996 1.70108002 -2.15941998 0 P 0 ;0
L 1.70108002 -2.15941998 1.70586004 -2.15176998 0 P 0 ;0
L 1.70586004 -2.15176998 1.71016004 -2.14383002 0 P 0 ;0
L 1.71016004 -2.14383002 1.71481998 -2.13356004 0 P 0 ;0
L 1.71481998 -2.13356004 1.74206998 -2.06631004 0 P 0 ;0
L 1.74206998 -2.06631004 1.77071004 -1.99548002 0 P 0 ;0
L 1.77071004 -1.99548002 1.77088002 -1.99498996 0 P 0 ;0
L 1.77088002 -1.99498996 1.77101998 -1.99448996 0 P 0 ;0
L 1.77101998 -1.99448996 1.77111998 -1.99398996 0 P 0 ;0
L 1.77111998 -1.99398996 1.77118002 -1.99346998 0 P 0 ;0
L 1.77118002 -1.99346998 1.7712 -1.99295 0 P 0 ;0
L 1.7712 -1.99295 1.7712 -1.99293002 0 P 0 ;0
L 1.7712 -1.99293002 1.77118996 -1.99286998 0 P 0 ;0
L 1.77118996 -1.99286998 1.77118002 -1.99286004 0 P 0 ;0
L 1.77118002 -1.99286004 1.77118002 -1.99283996 0 P 0 ;0
L 1.77118002 -1.99283996 1.77111004 -1.99276998 0 P 0 ;0
L 1.77111004 -1.99276998 1.77106998 -1.99275 0 P 0 ;0
L 1.77106998 -1.99275 1.77106004 -1.99273996 0 P 0 ;0
L 1.77106004 -1.99273996 1.771 -1.99273002 0 P 0 ;0
L 1.771 -1.99273002 1.77098002 -1.99273002 0 P 0 ;0
L 1.77098002 -1.99273002 1.76301004 -1.99265 0 P 0 ;0
L 1.76301004 -1.99265 1.75401998 -1.99261004 0 P 0 ;0
L 1.75401998 -1.99261004 1.74333002 -1.9927 0 P 0 ;0
L 1.74333002 -1.9927 1.71546004 -1.99298996 0 P 0 ;0
L 1.71546004 -1.99298996 1.71236998 -2.00646998 0 P 0 ;0
L 1.71236998 -2.00646998 1.70873996 -2.02078002 0 P 0 ;0
L 1.70873996 -2.02078002 1.70233996 -2.04308002 0 P 0 ;0
L 1.70233996 -2.04308002 1.69505 -2.0678 0 P 0 ;0
L 1.69505 -2.0678 1.69501998 -2.06788002 0 P 0 ;0
L 1.69501998 -2.06788002 1.69498996 -2.06795 0 P 0 ;0
L 1.69498996 -2.06795 1.69495 -2.06801998 0 P 0 ;0
L 1.69495 -2.06801998 1.69485 -2.06816004 0 P 0 ;0
L 1.69485 -2.06816004 1.69478996 -2.06821998 0 P 0 ;0
L 1.69478996 -2.06821998 1.69466998 -2.06831998 0 P 0 ;0
L 1.69466998 -2.06831998 1.69453002 -2.0684 0 P 0 ;0
L 1.69453002 -2.0684 1.69445 -2.06843002 0 P 0 ;0
L 1.69445 -2.06843002 1.69438002 -2.06846004 0 P 0 ;0
L 1.69438002 -2.06846004 1.69428996 -2.06846998 0 P 0 ;0
L 1.69428996 -2.06846998 1.69421004 -2.06848996 0 P 0 ;0
L 1.69421004 -2.06848996 1.69406998 -2.06848996 0 P 0 ;0
L 1.69406998 -2.06848996 1.69395 -2.06846998 0 P 0 ;0
L 1.69395 -2.06846998 1.69383002 -2.06843002 0 P 0 ;0
L 1.69383002 -2.06843002 1.69373002 -2.06836998 0 P 0 ;0
L 1.69373002 -2.06836998 1.69363002 -2.06828996 0 P 0 ;0
L 1.69363002 -2.06828996 1.69358996 -2.06823996 0 P 0 ;0
L 1.69358996 -2.06823996 1.69355 -2.0682 0 P 0 ;0
L 1.69355 -2.0682 1.69351998 -2.06815 0 P 0 ;0
L 1.69351998 -2.06815 1.69346004 -2.06803996 0 P 0 ;0
L 1.69346004 -2.06803996 1.69343996 -2.06798002 0 P 0 ;0
L 1.69343996 -2.06798002 1.68523002 -2.03878002 0 P 0 ;0
L 1.68523002 -2.03878002 1.67806998 -2.01291998 0 P 0 ;0
L 1.67806998 -2.01291998 1.67496004 -2.00031004 0 P 0 ;0
L 1.67496004 -2.00031004 1.67323002 -1.99243996 0 P 0 ;0
L 1.67323002 -1.99243996 1.61388002 -1.99243996 0 P 0 ;0
L 1.61388002 -1.99243996 1.61928996 -2.00628002 0 P 0 ;0
L 1.35018002 -2.08345 1.39488996 -2.08345 0 P 0 ;0
L 1.35026004 -2.08245 1.39586004 -2.08245 0 P 0 ;0
L 1.35041004 -2.08145 1.39708996 -2.08145 0 P 0 ;0
L 1.35058996 -2.08045 1.39853002 -2.08045 0 P 0 ;0
L 1.35083996 -2.07945 1.40031998 -2.07945 0 P 0 ;0
L 1.35116998 -2.07845 1.40271004 -2.07845 0 P 0 ;0
L 1.35158002 -2.07745 1.40561998 -2.07745 0 P 0 ;0
L 1.35203002 -2.07645 1.4092 -2.07645 0 P 0 ;0
L 1.35248002 -2.07545 1.41288996 -2.07545 0 P 0 ;0
L 1.35293002 -2.07445 1.4164 -2.07445 0 P 0 ;0
L 1.35338996 -2.07345 1.41975 -2.07345 0 P 0 ;0
L 1.35393996 -2.07245 1.42293996 -2.07245 0 P 0 ;0
L 1.35448996 -2.07145 1.42606998 -2.07145 0 P 0 ;0
L 1.35505 -2.07045 1.47843002 -2.07045 0 P 0 ;0
L 1.3557 -2.06945 1.47846998 -2.06945 0 P 0 ;0
L 1.35635 -2.06845 1.47851998 -2.06845 0 P 0 ;0
L 1.35701998 -2.06745 1.47856998 -2.06745 0 P 0 ;0
L 1.35776998 -2.06645 1.47861004 -2.06645 0 P 0 ;0
L 1.29346998 -2.00516004 1.33388996 -2.00516004 0 P 0 ;0
L 1.29448996 -2.00416004 1.33385 -2.00416004 0 P 0 ;0
L 1.29551004 -2.00316004 1.33381004 -2.00316004 0 P 0 ;0
L 1.29653996 -2.00216004 1.33376004 -2.00216004 0 P 0 ;0
L 1.29756004 -2.00116004 1.33371004 -2.00116004 0 P 0 ;0
L 1.29861998 -2.00016004 1.33366004 -2.00016004 0 P 0 ;0
L 1.29973002 -1.99916004 1.3336 -1.99916004 0 P 0 ;0
L 1.30101004 -1.99816004 1.33355 -1.99816004 0 P 0 ;0
L 1.30238996 -1.99716004 1.3335 -1.99716004 0 P 0 ;0
L 1.30393996 -1.99616004 1.33345 -1.99616004 0 P 0 ;0
L 1.30571004 -1.99516004 1.33338996 -1.99516004 0 P 0 ;0
L 1.3077 -1.99416004 1.33333002 -1.99416004 0 P 0 ;0
L 1.31001004 -1.99316004 1.33328002 -1.99316004 0 P 0 ;0
L 1.31288002 -1.99216004 1.33321998 -1.99216004 0 P 0 ;0
L 1.31688996 -1.99116004 1.33316004 -1.99116004 0 P 0 ;0
L 1.39798996 -1.98971998 1.39326998 -1.99043002 0 P 0 ;0
L 1.39326998 -1.99043002 1.38806998 -1.9913 0 P 0 ;0
L 1.38806998 -1.9913 1.38316004 -1.9922 0 P 0 ;0
L 1.38316004 -1.9922 1.37946004 -1.99296998 0 P 0 ;0
L 1.37946004 -1.99296998 1.3718 -1.99466998 0 P 0 ;0
L 1.3718 -1.99466998 1.36896004 -2.01553996 0 P 0 ;0
L 1.36896004 -2.01553996 1.36791004 -2.02358996 0 P 0 ;0
L 1.36791004 -2.02358996 1.36708002 -2.03043002 0 P 0 ;0
L 1.36708002 -2.03043002 1.36638996 -2.03646004 0 P 0 ;0
L 1.36638996 -2.03646004 1.36638002 -2.03648996 0 P 0 ;0
L 1.36638002 -2.03648996 1.36638996 -2.03653002 0 P 0 ;0
L 1.36638996 -2.03653002 1.36638996 -2.03656998 0 P 0 ;0
L 1.36638996 -2.03656998 1.3664 -2.03663996 0 P 0 ;0
L 1.3664 -2.03663996 1.36641998 -2.03666998 0 P 0 ;0
L 1.36641998 -2.03666998 1.36643002 -2.03671004 0 P 0 ;0
L 1.36643002 -2.03671004 1.36648996 -2.0368 0 P 0 ;0
L 1.36648996 -2.0368 1.36656004 -2.03686004 0 P 0 ;0
L 1.36656004 -2.03686004 1.3666 -2.03688996 0 P 0 ;0
L 1.3666 -2.03688996 1.36663002 -2.03691004 0 P 0 ;0
L 1.36663002 -2.03691004 1.36666004 -2.03691004 0 P 0 ;0
L 1.36666004 -2.03691004 1.36671004 -2.03693002 0 P 0 ;0
L 1.36671004 -2.03693002 1.36676998 -2.03693002 0 P 0 ;0
L 1.36676998 -2.03693002 1.36685 -2.03691998 0 P 0 ;0
L 1.36685 -2.03691998 1.36895 -2.03628002 0 P 0 ;0
L 1.36895 -2.03628002 1.37143002 -2.03545 0 P 0 ;0
L 1.37143002 -2.03545 1.37428996 -2.03441004 0 P 0 ;0
L 1.37428996 -2.03441004 1.38346004 -2.03126998 0 P 0 ;0
L 1.38346004 -2.03126998 1.39251998 -2.02891998 0 P 0 ;0
L 1.39251998 -2.02891998 1.40156004 -2.02731998 0 P 0 ;0
L 1.40156004 -2.02731998 1.41068002 -2.02643996 0 P 0 ;0
L 1.41068002 -2.02643996 1.41566998 -2.02628002 0 P 0 ;0
L 1.41566998 -2.02628002 1.42066004 -2.02633996 0 P 0 ;0
L 1.42066004 -2.02633996 1.42221004 -2.02646998 0 P 0 ;0
L 1.42221004 -2.02646998 1.42375 -2.02671998 0 P 0 ;0
L 1.42375 -2.02671998 1.42525 -2.0271 0 P 0 ;0
L 1.42525 -2.0271 1.42671998 -2.02761004 0 P 0 ;0
L 1.42671998 -2.02761004 1.42706004 -2.02776004 0 P 0 ;0
L 1.42706004 -2.02776004 1.42738002 -2.02793002 0 P 0 ;0
L 1.42738002 -2.02793002 1.42768002 -2.02813996 0 P 0 ;0
L 1.42768002 -2.02813996 1.42796998 -2.02836004 0 P 0 ;0
L 1.42796998 -2.02836004 1.42823002 -2.02861004 0 P 0 ;0
L 1.42823002 -2.02861004 1.42848002 -2.02888996 0 P 0 ;0
L 1.42848002 -2.02888996 1.4287 -2.02918002 0 P 0 ;0
L 1.4287 -2.02918002 1.42888996 -2.02948996 0 P 0 ;0
L 1.42888996 -2.02948996 1.42906004 -2.02981004 0 P 0 ;0
L 1.42906004 -2.02981004 1.4292 -2.03015 0 P 0 ;0
L 1.4292 -2.03015 1.42931998 -2.0305 0 P 0 ;0
L 1.42931998 -2.0305 1.4294 -2.03086004 0 P 0 ;0
L 1.4294 -2.03086004 1.42945 -2.03121998 0 P 0 ;0
L 1.42945 -2.03121998 1.42946998 -2.03158002 0 P 0 ;0
L 1.42946998 -2.03158002 1.42946004 -2.03195 0 P 0 ;0
L 1.42946004 -2.03195 1.42941998 -2.03231004 0 P 0 ;0
L 1.42941998 -2.03231004 1.42935 -2.03266998 0 P 0 ;0
L 1.42935 -2.03266998 1.42925 -2.03301998 0 P 0 ;0
L 1.42925 -2.03301998 1.42911998 -2.03336004 0 P 0 ;0
L 1.42911998 -2.03336004 1.42896004 -2.03368996 0 P 0 ;0
L 1.42896004 -2.03368996 1.42875 -2.03405 0 P 0 ;0
L 1.42875 -2.03405 1.42851004 -2.03438996 0 P 0 ;0
L 1.42851004 -2.03438996 1.42825 -2.03471004 0 P 0 ;0
L 1.42825 -2.03471004 1.42796004 -2.03501004 0 P 0 ;0
L 1.42796004 -2.03501004 1.42765 -2.03528996 0 P 0 ;0
L 1.42765 -2.03528996 1.42731998 -2.03553996 0 P 0 ;0
L 1.42731998 -2.03553996 1.42696998 -2.03576004 0 P 0 ;0
L 1.42696998 -2.03576004 1.4266 -2.03596004 0 P 0 ;0
L 1.4266 -2.03596004 1.41951004 -2.03906004 0 P 0 ;0
L 1.41951004 -2.03906004 1.4109 -2.04208996 0 P 0 ;0
L 1.4109 -2.04208996 1.40178002 -2.04451998 0 P 0 ;0
L 1.40178002 -2.04451998 1.3878 -2.04818996 0 P 0 ;0
L 1.3878 -2.04818996 1.38176998 -2.05015 0 P 0 ;0
L 1.38176998 -2.05015 1.3758 -2.05243002 0 P 0 ;0
L 1.3758 -2.05243002 1.37086998 -2.0546 0 P 0 ;0
L 1.37086998 -2.0546 1.36603996 -2.05708002 0 P 0 ;0
L 1.36603996 -2.05708002 1.36356004 -2.05856004 0 P 0 ;0
L 1.36356004 -2.05856004 1.36118996 -2.06023002 0 P 0 ;0
L 1.36118996 -2.06023002 1.35895 -2.06206004 0 P 0 ;0
L 1.35895 -2.06206004 1.35805 -2.06291004 0 P 0 ;0
L 1.35805 -2.06291004 1.35721998 -2.06385 0 P 0 ;0
L 1.35721998 -2.06385 1.35518996 -2.06655 0 P 0 ;0
L 1.35518996 -2.06655 1.3532 -2.06961998 0 P 0 ;0
L 1.3532 -2.06961998 1.35156004 -2.07263002 0 P 0 ;0
L 1.35156004 -2.07263002 1.34951004 -2.07718002 0 P 0 ;0
L 1.34951004 -2.07718002 1.34911004 -2.07825 0 P 0 ;0
L 1.34911004 -2.07825 1.34878996 -2.07935 0 P 0 ;0
L 1.34878996 -2.07935 1.34853002 -2.08046998 0 P 0 ;0
L 1.34853002 -2.08046998 1.34825 -2.08238002 0 P 0 ;0
L 1.34825 -2.08238002 1.34811998 -2.08431004 0 P 0 ;0
L 1.34811998 -2.08431004 1.348 -2.09128996 0 P 0 ;0
L 1.348 -2.09128996 1.3481 -2.09761004 0 P 0 ;0
L 1.3481 -2.09761004 1.34823002 -2.09961004 0 P 0 ;0
L 1.34823002 -2.09961004 1.34846998 -2.10161004 0 P 0 ;0
L 1.34846998 -2.10161004 1.34876998 -2.10321998 0 P 0 ;0
L 1.34876998 -2.10321998 1.3492 -2.10478996 0 P 0 ;0
L 1.3492 -2.10478996 1.3498 -2.10648996 0 P 0 ;0
L 1.3498 -2.10648996 1.3505 -2.10815 0 P 0 ;0
L 1.3505 -2.10815 1.35178996 -2.11066004 0 P 0 ;0
L 1.35178996 -2.11066004 1.35328002 -2.11305 0 P 0 ;0
L 1.35328002 -2.11305 1.35496998 -2.1153 0 P 0 ;0
L 1.35496998 -2.1153 1.35685 -2.1174 0 P 0 ;0
L 1.35685 -2.1174 1.35891998 -2.11933996 0 P 0 ;0
L 1.35891998 -2.11933996 1.36126998 -2.12121998 0 P 0 ;0
L 1.36126998 -2.12121998 1.36373996 -2.12293002 0 P 0 ;0
L 1.36373996 -2.12293002 1.36633002 -2.12446004 0 P 0 ;0
L 1.36633002 -2.12446004 1.36901004 -2.1258 0 P 0 ;0
L 1.36901004 -2.1258 1.3718 -2.12695 0 P 0 ;0
L 1.3718 -2.12695 1.37578996 -2.12828002 0 P 0 ;0
L 1.37578996 -2.12828002 1.37986998 -2.12928996 0 P 0 ;0
L 1.37986998 -2.12928996 1.38401998 -2.12998996 0 P 0 ;0
L 1.38401998 -2.12998996 1.3882 -2.13036004 0 P 0 ;0
L 1.3882 -2.13036004 1.39443002 -2.13045 0 P 0 ;0
L 1.39443002 -2.13045 1.40066004 -2.13006998 0 P 0 ;0
L 1.40066004 -2.13006998 1.40685 -2.12923002 0 P 0 ;0
L 1.40685 -2.12923002 1.41371004 -2.12801998 0 P 0 ;0
L 1.41371004 -2.12801998 1.41583002 -2.12081004 0 P 0 ;0
L 1.41583002 -2.12081004 1.41953996 -2.10798996 0 P 0 ;0
L 1.41953996 -2.10798996 1.42135 -2.10126998 0 P 0 ;0
L 1.42135 -2.10126998 1.42236998 -2.097 0 P 0 ;0
L 1.42236998 -2.097 1.42238996 -2.09691004 0 P 0 ;0
L 1.42238996 -2.09691004 1.4224 -2.09681998 0 P 0 ;0
L 1.4224 -2.09681998 1.4224 -2.09673996 0 P 0 ;0
L 1.4224 -2.09673996 1.42238002 -2.09656004 0 P 0 ;0
L 1.42238002 -2.09656004 1.42235 -2.09648002 0 P 0 ;0
L 1.42235 -2.09648002 1.42233002 -2.09638996 0 P 0 ;0
L 1.42233002 -2.09638996 1.42225 -2.09623002 0 P 0 ;0
L 1.42225 -2.09623002 1.4222 -2.09616004 0 P 0 ;0
L 1.4222 -2.09616004 1.42213996 -2.09608996 0 P 0 ;0
L 1.42213996 -2.09608996 1.42208996 -2.09601998 0 P 0 ;0
L 1.42208996 -2.09601998 1.42203996 -2.09598996 0 P 0 ;0
L 1.42203996 -2.09598996 1.42198996 -2.09595 0 P 0 ;0
L 1.42198996 -2.09595 1.42188996 -2.09588996 0 P 0 ;0
L 1.42188996 -2.09588996 1.42183002 -2.09586004 0 P 0 ;0
L 1.42183002 -2.09586004 1.42178002 -2.09585 0 P 0 ;0
L 1.42178002 -2.09585 1.42171998 -2.09583002 0 P 0 ;0
L 1.42171998 -2.09583002 1.42166004 -2.09581998 0 P 0 ;0
L 1.42166004 -2.09581998 1.42153996 -2.09581998 0 P 0 ;0
L 1.42153996 -2.09581998 1.41978002 -2.09591004 0 P 0 ;0
L 1.41978002 -2.09591004 1.41763996 -2.09615 0 P 0 ;0
L 1.41763996 -2.09615 1.41521998 -2.09658002 0 P 0 ;0
L 1.41521998 -2.09658002 1.4107 -2.09733002 0 P 0 ;0
L 1.4107 -2.09733002 1.40613002 -2.09775 0 P 0 ;0
L 1.40613002 -2.09775 1.40481004 -2.09778002 0 P 0 ;0
L 1.40481004 -2.09778002 1.40348996 -2.09771998 0 P 0 ;0
L 1.40348996 -2.09771998 1.40216998 -2.09756004 0 P 0 ;0
L 1.40216998 -2.09756004 1.40086998 -2.0973 0 P 0 ;0
L 1.40086998 -2.0973 1.39958996 -2.09695 0 P 0 ;0
L 1.39958996 -2.09695 1.39895 -2.09671998 0 P 0 ;0
L 1.39895 -2.09671998 1.39831998 -2.09643002 0 P 0 ;0
L 1.39831998 -2.09643002 1.39773002 -2.0961 0 P 0 ;0
L 1.39773002 -2.0961 1.39716004 -2.09571004 0 P 0 ;0
L 1.39716004 -2.09571004 1.39663002 -2.09528002 0 P 0 ;0
L 1.39663002 -2.09528002 1.39613996 -2.0948 0 P 0 ;0
L 1.39613996 -2.0948 1.39568002 -2.09428002 0 P 0 ;0
L 1.39568002 -2.09428002 1.39533996 -2.09381998 0 P 0 ;0
L 1.39533996 -2.09381998 1.39505 -2.09333996 0 P 0 ;0
L 1.39505 -2.09333996 1.39478996 -2.09281998 0 P 0 ;0
L 1.39478996 -2.09281998 1.39456998 -2.09228996 0 P 0 ;0
L 1.39456998 -2.09228996 1.3944 -2.09173996 0 P 0 ;0
L 1.3944 -2.09173996 1.39428002 -2.09118996 0 P 0 ;0
L 1.39428002 -2.09118996 1.39421004 -2.09061998 0 P 0 ;0
L 1.39421004 -2.09061998 1.39418002 -2.09003996 0 P 0 ;0
L 1.39418002 -2.09003996 1.39421004 -2.08943002 0 P 0 ;0
L 1.39421004 -2.08943002 1.39428002 -2.08883002 0 P 0 ;0
L 1.39428002 -2.08883002 1.39441004 -2.08823002 0 P 0 ;0
L 1.39441004 -2.08823002 1.3946 -2.08765 0 P 0 ;0
L 1.3946 -2.08765 1.39483002 -2.08708002 0 P 0 ;0
L 1.39483002 -2.08708002 1.39511004 -2.08653996 0 P 0 ;0
L 1.39511004 -2.08653996 1.39555 -2.08583996 0 P 0 ;0
L 1.39555 -2.08583996 1.39603996 -2.08518002 0 P 0 ;0
L 1.39603996 -2.08518002 1.39658002 -2.08456004 0 P 0 ;0
L 1.39658002 -2.08456004 1.39716004 -2.08396998 0 P 0 ;0
L 1.39716004 -2.08396998 1.39778002 -2.08343002 0 P 0 ;0
L 1.39778002 -2.08343002 1.39878996 -2.08266998 0 P 0 ;0
L 1.39878996 -2.08266998 1.39985 -2.08196998 0 P 0 ;0
L 1.39985 -2.08196998 1.40096004 -2.08135 0 P 0 ;0
L 1.40096004 -2.08135 1.40211998 -2.08081004 0 P 0 ;0
L 1.40211998 -2.08081004 1.40503002 -2.07971004 0 P 0 ;0
L 1.40503002 -2.07971004 1.40801998 -2.07881998 0 P 0 ;0
L 1.40801998 -2.07881998 1.41128996 -2.07796004 0 P 0 ;0
L 1.41128996 -2.07796004 1.41506004 -2.07691998 0 P 0 ;0
L 1.41506004 -2.07691998 1.41871998 -2.07585 0 P 0 ;0
L 1.41871998 -2.07585 1.42165 -2.07495 0 P 0 ;0
L 1.42165 -2.07495 1.42791998 -2.07295 0 P 0 ;0
L 1.42791998 -2.07295 1.42731998 -2.08241004 0 P 0 ;0
L 1.42731998 -2.08241004 1.42701004 -2.08708002 0 P 0 ;0
L 1.42701004 -2.08708002 1.42658002 -2.09353996 0 P 0 ;0
L 1.42658002 -2.09353996 1.4261 -2.10055 0 P 0 ;0
L 1.4261 -2.10055 1.42566998 -2.10706004 0 P 0 ;0
L 1.42566998 -2.10706004 1.42525 -2.11306004 0 P 0 ;0
L 1.42525 -2.11306004 1.42491998 -2.11851998 0 P 0 ;0
L 1.42491998 -2.11851998 1.42466004 -2.1231 0 P 0 ;0
L 1.42466004 -2.1231 1.42461004 -2.12471004 0 P 0 ;0
L 1.42461004 -2.12471004 1.4246 -2.12716004 0 P 0 ;0
L 1.4246 -2.12716004 1.47893002 -2.12716004 0 P 0 ;0
L 1.47893002 -2.12716004 1.47893002 -2.11358002 0 P 0 ;0
L 1.47893002 -2.11358002 1.47905 -2.10616998 0 P 0 ;0
L 1.47905 -2.10616998 1.47943996 -2.09385 0 P 0 ;0
L 1.47943996 -2.09385 1.48 -2.07968996 0 P 0 ;0
L 1.48 -2.07968996 1.48066004 -2.0655 0 P 0 ;0
L 1.48066004 -2.0655 1.4813 -2.05168996 0 P 0 ;0
L 1.4813 -2.05168996 1.48175 -2.03873996 0 P 0 ;0
L 1.48175 -2.03873996 1.48201998 -2.02785 0 P 0 ;0
L 1.48201998 -2.02785 1.48191998 -2.02286004 0 P 0 ;0
L 1.48191998 -2.02286004 1.48165 -2.01995 0 P 0 ;0
L 1.48165 -2.01995 1.48115 -2.01708002 0 P 0 ;0
L 1.48115 -2.01708002 1.48043996 -2.01425 0 P 0 ;0
L 1.48043996 -2.01425 1.47951004 -2.01146998 0 P 0 ;0
L 1.47951004 -2.01146998 1.47866998 -2.00946998 0 P 0 ;0
L 1.47866998 -2.00946998 1.47768002 -2.00753996 0 P 0 ;0
L 1.47768002 -2.00753996 1.47655 -2.00568002 0 P 0 ;0
L 1.47655 -2.00568002 1.47528002 -2.00391998 0 P 0 ;0
L 1.47528002 -2.00391998 1.47388002 -2.00225 0 P 0 ;0
L 1.47388002 -2.00225 1.47228996 -2.00063002 0 P 0 ;0
L 1.47228996 -2.00063002 1.4706 -1.99911998 0 P 0 ;0
L 1.4706 -1.99911998 1.4688 -1.99773002 0 P 0 ;0
L 1.4688 -1.99773002 1.46691004 -1.99648002 0 P 0 ;0
L 1.46691004 -1.99648002 1.46491998 -1.99535 0 P 0 ;0
L 1.46491998 -1.99535 1.46098996 -1.99351004 0 P 0 ;0
L 1.46098996 -1.99351004 1.45693002 -1.99196998 0 P 0 ;0
L 1.45693002 -1.99196998 1.45276004 -1.99076004 0 P 0 ;0
L 1.45276004 -1.99076004 1.44953996 -1.99006004 0 P 0 ;0
L 1.44953996 -1.99006004 1.44628996 -1.98956004 0 P 0 ;0
L 1.44628996 -1.98956004 1.44298002 -1.98923996 0 P 0 ;0
L 1.44298002 -1.98923996 1.42695 -1.98856998 0 P 0 ;0
L 1.42695 -1.98856998 1.41038996 -1.98865 0 P 0 ;0
L 1.41038996 -1.98865 1.4042 -1.98901004 0 P 0 ;0
L 1.4042 -1.98901004 1.39798996 -1.98971998 0 P 0 ;0
L 1.35778996 -2.11545 1.4153 -2.11545 0 P 0 ;0
L 1.35688996 -2.11445 1.41558996 -2.11445 0 P 0 ;0
L 1.35608002 -2.11345 1.41588002 -2.11345 0 P 0 ;0
L 1.35533002 -2.11245 1.41616998 -2.11245 0 P 0 ;0
L 1.35463996 -2.11145 1.41646004 -2.11145 0 P 0 ;0
L 1.35401004 -2.11045 1.41675 -2.11045 0 P 0 ;0
L 1.35341004 -2.10945 1.41703996 -2.10945 0 P 0 ;0
L 1.3529 -2.10845 1.41733002 -2.10845 0 P 0 ;0
L 1.35238002 -2.10745 1.41761998 -2.10745 0 P 0 ;0
L 1.35195 -2.10645 1.41788002 -2.10645 0 P 0 ;0
L 1.35155 -2.10545 1.41816004 -2.10545 0 P 0 ;0
L 1.3512 -2.10445 1.41841998 -2.10445 0 P 0 ;0
L 1.35091004 -2.10345 1.41868996 -2.10345 0 P 0 ;0
L 1.35066004 -2.10245 1.41896004 -2.10245 0 P 0 ;0
L 1.35046998 -2.10145 1.41923002 -2.10145 0 P 0 ;0
L 1.35033996 -2.10045 1.41948996 -2.10045 0 P 0 ;0
L 1.35021998 -2.09945 1.40141004 -2.09945 0 P 0 ;0
L 1.35016004 -2.09845 1.39791004 -2.09845 0 P 0 ;0
L 1.3501 -2.09745 1.39616004 -2.09745 0 P 0 ;0
L 1.35008002 -2.09645 1.39496004 -2.09645 0 P 0 ;0
L 1.35006998 -2.09545 1.39406004 -2.09545 0 P 0 ;0
L 1.35005 -2.09445 1.39338002 -2.09445 0 P 0 ;0
L 1.35003996 -2.09345 1.39288002 -2.09345 0 P 0 ;0
L 1.35001998 -2.09245 1.39253002 -2.09245 0 P 0 ;0
L 1.35001004 -2.09145 1.3923 -2.09145 0 P 0 ;0
L 1.35001998 -2.09045 1.3922 -2.09045 0 P 0 ;0
L 1.35003002 -2.08945 1.3922 -2.08945 0 P 0 ;0
L 1.35005 -2.08845 1.39231998 -2.08845 0 P 0 ;0
L 1.35006998 -2.08745 1.39256004 -2.08745 0 P 0 ;0
L 1.35008002 -2.08645 1.39293002 -2.08645 0 P 0 ;0
L 1.3501 -2.08545 1.39343002 -2.08545 0 P 0 ;0
L 1.35011004 -2.08445 1.39408996 -2.08445 0 P 0 ;0
L 1.39438002 -2.12845 1.3883 -2.12836004 0 P 0 ;0
L 1.3883 -2.12836004 1.38426998 -2.128 0 P 0 ;0
L 1.38426998 -2.128 1.38028002 -2.12733002 0 P 0 ;0
L 1.38028002 -2.12733002 1.37635 -2.12636004 0 P 0 ;0
L 1.37635 -2.12636004 1.37248996 -2.12508002 0 P 0 ;0
L 1.37248996 -2.12508002 1.36983996 -2.12398002 0 P 0 ;0
L 1.36983996 -2.12398002 1.36728996 -2.1227 0 P 0 ;0
L 1.36728996 -2.1227 1.36481998 -2.12123996 0 P 0 ;0
L 1.36481998 -2.12123996 1.36246004 -2.11961004 0 P 0 ;0
L 1.36246004 -2.11961004 1.36023002 -2.11781998 0 P 0 ;0
L 1.36023002 -2.11781998 1.35828996 -2.116 0 P 0 ;0
L 1.35828996 -2.116 1.35651998 -2.11403002 0 P 0 ;0
L 1.35651998 -2.11403002 1.35493002 -2.11191004 0 P 0 ;0
L 1.35493002 -2.11191004 1.35353002 -2.10966998 0 P 0 ;0
L 1.35353002 -2.10966998 1.35231004 -2.10731004 0 P 0 ;0
L 1.35231004 -2.10731004 1.35166998 -2.10576998 0 P 0 ;0
L 1.35166998 -2.10576998 1.35111004 -2.1042 0 P 0 ;0
L 1.35111004 -2.1042 1.35071998 -2.10276004 0 P 0 ;0
L 1.35071998 -2.10276004 1.35045 -2.1013 0 P 0 ;0
L 1.35045 -2.1013 1.35021998 -2.09943002 0 P 0 ;0
L 1.35021998 -2.09943002 1.3501 -2.09753002 0 P 0 ;0
L 1.3501 -2.09753002 1.35001004 -2.09128002 0 P 0 ;0
L 1.35001004 -2.09128002 1.35011998 -2.0844 0 P 0 ;0
L 1.35011998 -2.0844 1.35023996 -2.08258996 0 P 0 ;0
L 1.35023996 -2.08258996 1.3505 -2.08083996 0 P 0 ;0
L 1.3505 -2.08083996 1.35071998 -2.07985 0 P 0 ;0
L 1.35071998 -2.07985 1.35101004 -2.07888002 0 P 0 ;0
L 1.35101004 -2.07888002 1.35136004 -2.07793002 0 P 0 ;0
L 1.35136004 -2.07793002 1.35335 -2.07351998 0 P 0 ;0
L 1.35335 -2.07351998 1.35491998 -2.07065 0 P 0 ;0
L 1.35491998 -2.07065 1.35683002 -2.0677 0 P 0 ;0
L 1.35683002 -2.0677 1.35876998 -2.06511004 0 P 0 ;0
L 1.35876998 -2.06511004 1.35948996 -2.0643 0 P 0 ;0
L 1.35948996 -2.0643 1.36026998 -2.06356004 0 P 0 ;0
L 1.36026998 -2.06356004 1.3624 -2.06181998 0 P 0 ;0
L 1.3624 -2.06181998 1.36465 -2.06023996 0 P 0 ;0
L 1.36465 -2.06023996 1.36701004 -2.05883002 0 P 0 ;0
L 1.36701004 -2.05883002 1.37173002 -2.05641004 0 P 0 ;0
L 1.37173002 -2.05641004 1.37656004 -2.05426998 0 P 0 ;0
L 1.37656004 -2.05426998 1.38243002 -2.05203996 0 P 0 ;0
L 1.38243002 -2.05203996 1.38836004 -2.0501 0 P 0 ;0
L 1.38836004 -2.0501 1.4023 -2.04645 0 P 0 ;0
L 1.4023 -2.04645 1.41148996 -2.044 0 P 0 ;0
L 1.41148996 -2.044 1.42016998 -2.04095 0 P 0 ;0
L 1.42016998 -2.04095 1.42016998 -2.04093996 0 P 0 ;0
L 1.42016998 -2.04093996 1.42021004 -2.04093996 0 P 0 ;0
L 1.42021004 -2.04093996 1.42023996 -2.04093002 0 P 0 ;0
L 1.42023996 -2.04093002 1.42746998 -2.03776004 0 P 0 ;0
L 1.42746998 -2.03776004 1.42753002 -2.03773002 0 P 0 ;0
L 1.42753002 -2.03773002 1.42796998 -2.03748996 0 P 0 ;0
L 1.42796998 -2.03748996 1.42846004 -2.03718996 0 P 0 ;0
L 1.42846004 -2.03718996 1.42891998 -2.03683996 0 P 0 ;0
L 1.42891998 -2.03683996 1.42935 -2.03646004 0 P 0 ;0
L 1.42935 -2.03646004 1.42975 -2.03603996 0 P 0 ;0
L 1.42975 -2.03603996 1.43011004 -2.0356 0 P 0 ;0
L 1.43011004 -2.0356 1.43016004 -2.03553002 0 P 0 ;0
L 1.43016004 -2.03553002 1.4299 -2.03535 0 P 0 ;0
L 1.4299 -2.03535 1.43028002 -2.03535 0 P 0 ;0
L 1.43028002 -2.03535 1.43043996 -2.03513002 0 P 0 ;0
L 1.43043996 -2.03513002 1.43048002 -2.03506004 0 P 0 ;0
L 1.43048002 -2.03506004 1.43041998 -2.03501998 0 P 0 ;0
L 1.43041998 -2.03501998 1.4305 -2.03501998 0 P 0 ;0
L 1.4305 -2.03501998 1.43073002 -2.03463002 0 P 0 ;0
L 1.43073002 -2.03463002 1.43096004 -2.03415 0 P 0 ;0
L 1.43096004 -2.03415 1.43115 -2.03365 0 P 0 ;0
L 1.43115 -2.03365 1.4313 -2.03313002 0 P 0 ;0
L 1.4313 -2.03313002 1.4314 -2.03261004 0 P 0 ;0
L 1.4314 -2.03261004 1.43146004 -2.03208002 0 P 0 ;0
L 1.43146004 -2.03208002 1.43146998 -2.03155 0 P 0 ;0
L 1.43146998 -2.03155 1.43143996 -2.03101004 0 P 0 ;0
L 1.43143996 -2.03101004 1.43143002 -2.03093002 0 P 0 ;0
L 1.43143002 -2.03093002 1.43136004 -2.03048996 0 P 0 ;0
L 1.43136004 -2.03048996 1.43125 -2.02996998 0 P 0 ;0
L 1.43125 -2.02996998 1.43108002 -2.02946004 0 P 0 ;0
L 1.43108002 -2.02946004 1.43086998 -2.02896004 0 P 0 ;0
L 1.43086998 -2.02896004 1.43063002 -2.02848996 0 P 0 ;0
L 1.43063002 -2.02848996 1.43033996 -2.02803996 0 P 0 ;0
L 1.43033996 -2.02803996 1.43001998 -2.02761004 0 P 0 ;0
L 1.43001998 -2.02761004 1.42966004 -2.02721004 0 P 0 ;0
L 1.42966004 -2.02721004 1.42928002 -2.02685 0 P 0 ;0
L 1.42928002 -2.02685 1.42886004 -2.02651998 0 P 0 ;0
L 1.42886004 -2.02651998 1.42841998 -2.02623002 0 P 0 ;0
L 1.42841998 -2.02623002 1.42795 -2.02596998 0 P 0 ;0
L 1.42795 -2.02596998 1.42746004 -2.02575 0 P 0 ;0
L 1.42746004 -2.02575 1.42583002 -2.02518002 0 P 0 ;0
L 1.42583002 -2.02518002 1.42416004 -2.02476004 0 P 0 ;0
L 1.42416004 -2.02476004 1.42245 -2.02448002 0 P 0 ;0
L 1.42245 -2.02448002 1.42075 -2.02435 0 P 0 ;0
L 1.42075 -2.02435 1.41565 -2.02428002 0 P 0 ;0
L 1.41565 -2.02428002 1.4156 -2.02428002 0 P 0 ;0
L 1.4156 -2.02428002 1.41055 -2.02445 0 P 0 ;0
L 1.41055 -2.02445 1.41048002 -2.02445 0 P 0 ;0
L 1.41048002 -2.02445 1.40128996 -2.02533996 0 P 0 ;0
L 1.40128996 -2.02533996 1.39208996 -2.02696998 0 P 0 ;0
L 1.39208996 -2.02696998 1.38288002 -2.02936004 0 P 0 ;0
L 1.38288002 -2.02936004 1.37363002 -2.03251998 0 P 0 ;0
L 1.37363002 -2.03251998 1.37076998 -2.03356004 0 P 0 ;0
L 1.37076998 -2.03356004 1.36865 -2.03426998 0 P 0 ;0
L 1.36865 -2.03426998 1.36906004 -2.03066998 0 P 0 ;0
L 1.36906004 -2.03066998 1.36988996 -2.02383996 0 P 0 ;0
L 1.36988996 -2.02383996 1.37095 -2.01581004 0 P 0 ;0
L 1.37095 -2.01581004 1.37358996 -1.99631998 0 P 0 ;0
L 1.37358996 -1.99631998 1.37988002 -1.99491998 0 P 0 ;0
L 1.37988002 -1.99491998 1.38353996 -1.99416998 0 P 0 ;0
L 1.38353996 -1.99416998 1.38841998 -1.99326998 0 P 0 ;0
L 1.38841998 -1.99326998 1.39358002 -1.9924 0 P 0 ;0
L 1.39358002 -1.9924 1.39825 -1.9917 0 P 0 ;0
L 1.39825 -1.9917 1.40436998 -1.991 0 P 0 ;0
L 1.40436998 -1.991 1.41045 -1.99065 0 P 0 ;0
L 1.41045 -1.99065 1.42691004 -1.99056998 0 P 0 ;0
L 1.42691004 -1.99056998 1.44283996 -1.99123996 0 P 0 ;0
L 1.44283996 -1.99123996 1.44603996 -1.99153996 0 P 0 ;0
L 1.44603996 -1.99153996 1.44918002 -1.99203002 0 P 0 ;0
L 1.44918002 -1.99203002 1.45226004 -1.9927 0 P 0 ;0
L 1.45226004 -1.9927 1.4563 -1.99386998 0 P 0 ;0
L 1.4563 -1.99386998 1.46021004 -1.99535 0 P 0 ;0
L 1.46021004 -1.99535 1.464 -1.99713002 0 P 0 ;0
L 1.464 -1.99713002 1.46586004 -1.99818996 0 P 0 ;0
L 1.46586004 -1.99818996 1.46763996 -1.99936004 0 P 0 ;0
L 1.46763996 -1.99936004 1.46931998 -2.00066004 0 P 0 ;0
L 1.46931998 -2.00066004 1.47091004 -2.00206998 0 P 0 ;0
L 1.47091004 -2.00206998 1.47238996 -2.00358996 0 P 0 ;0
L 1.47238996 -2.00358996 1.4737 -2.00515 0 P 0 ;0
L 1.4737 -2.00515 1.47488002 -2.00678996 0 P 0 ;0
L 1.47488002 -2.00678996 1.47593996 -2.00851004 0 P 0 ;0
L 1.47593996 -2.00851004 1.47686004 -2.01031004 0 P 0 ;0
L 1.47686004 -2.01031004 1.47763996 -2.01216998 0 P 0 ;0
L 1.47763996 -2.01216998 1.47851998 -2.01481004 0 P 0 ;0
L 1.47851998 -2.01481004 1.47918996 -2.01748996 0 P 0 ;0
L 1.47918996 -2.01748996 1.47966004 -2.02021998 0 P 0 ;0
L 1.47966004 -2.02021998 1.47993002 -2.02296998 0 P 0 ;0
L 1.47993002 -2.02296998 1.48001998 -2.02783996 0 P 0 ;0
L 1.48001998 -2.02783996 1.47975 -2.03868996 0 P 0 ;0
L 1.47975 -2.03868996 1.4793 -2.05161004 0 P 0 ;0
L 1.4793 -2.05161004 1.47866004 -2.06543002 0 P 0 ;0
L 1.47866004 -2.06543002 1.47801004 -2.07961004 0 P 0 ;0
L 1.47801004 -2.07961004 1.47743996 -2.09378996 0 P 0 ;0
L 1.47743996 -2.09378996 1.47705 -2.10613002 0 P 0 ;0
L 1.47705 -2.10613002 1.47693002 -2.11356004 0 P 0 ;0
L 1.47693002 -2.11356004 1.47693002 -2.12516004 0 P 0 ;0
L 1.47693002 -2.12516004 1.42661004 -2.12516004 0 P 0 ;0
L 1.42661004 -2.12516004 1.42661004 -2.12473996 0 P 0 ;0
L 1.42661004 -2.12473996 1.42666004 -2.12318002 0 P 0 ;0
L 1.42666004 -2.12318002 1.42691004 -2.11863996 0 P 0 ;0
L 1.42691004 -2.11863996 1.42725 -2.1132 0 P 0 ;0
L 1.42725 -2.1132 1.42766004 -2.1072 0 P 0 ;0
L 1.42766004 -2.1072 1.42766004 -2.10718996 0 P 0 ;0
L 1.42766004 -2.10718996 1.4281 -2.10068996 0 P 0 ;0
L 1.4281 -2.10068996 1.42858002 -2.09368002 0 P 0 ;0
L 1.42858002 -2.09368002 1.42901004 -2.08721004 0 P 0 ;0
L 1.42901004 -2.08721004 1.42901004 -2.0872 0 P 0 ;0
L 1.42901004 -2.0872 1.42931004 -2.08256004 0 P 0 ;0
L 1.42931004 -2.08256004 1.42991998 -2.07308002 0 P 0 ;0
L 1.42991998 -2.07308002 1.42916004 -2.07136998 0 P 0 ;0
L 1.42916004 -2.07136998 1.42731998 -2.07105 0 P 0 ;0
L 1.42731998 -2.07105 1.42105 -2.07303996 0 P 0 ;0
L 1.42105 -2.07303996 1.41815 -2.07393002 0 P 0 ;0
L 1.41815 -2.07393002 1.41451004 -2.075 0 P 0 ;0
L 1.41451004 -2.075 1.41076004 -2.07603002 0 P 0 ;0
L 1.41076004 -2.07603002 1.40748002 -2.0769 0 P 0 ;0
L 1.40748002 -2.0769 1.40438996 -2.07781004 0 P 0 ;0
L 1.40438996 -2.07781004 1.40431998 -2.07783996 0 P 0 ;0
L 1.40431998 -2.07783996 1.40133996 -2.07896998 0 P 0 ;0
L 1.40133996 -2.07896998 1.40005 -2.07956998 0 P 0 ;0
L 1.40005 -2.07956998 1.39881998 -2.08026004 0 P 0 ;0
L 1.39881998 -2.08026004 1.39763996 -2.08103002 0 P 0 ;0
L 1.39763996 -2.08103002 1.39651998 -2.08188002 0 P 0 ;0
L 1.39651998 -2.08188002 1.39578996 -2.08251004 0 P 0 ;0
L 1.39578996 -2.08251004 1.39573996 -2.08256004 0 P 0 ;0
L 1.39573996 -2.08256004 1.3951 -2.08318996 0 P 0 ;0
L 1.3951 -2.08318996 1.39446998 -2.08393002 0 P 0 ;0
L 1.39446998 -2.08393002 1.3939 -2.08471004 0 P 0 ;0
L 1.3939 -2.08471004 1.39336998 -2.08553996 0 P 0 ;0
L 1.39336998 -2.08553996 1.39301004 -2.08623996 0 P 0 ;0
L 1.39301004 -2.08623996 1.39271004 -2.08696998 0 P 0 ;0
L 1.39271004 -2.08696998 1.39248002 -2.08771998 0 P 0 ;0
L 1.39248002 -2.08771998 1.39231004 -2.08848996 0 P 0 ;0
L 1.39231004 -2.08848996 1.39221004 -2.08926004 0 P 0 ;0
L 1.39221004 -2.08926004 1.39218002 -2.09003996 0 P 0 ;0
L 1.39218002 -2.09003996 1.39221004 -2.0908 0 P 0 ;0
L 1.39221004 -2.0908 1.39231004 -2.09153002 0 P 0 ;0
L 1.39231004 -2.09153002 1.39246998 -2.09226004 0 P 0 ;0
L 1.39246998 -2.09226004 1.39268996 -2.09296998 0 P 0 ;0
L 1.39268996 -2.09296998 1.39296004 -2.09365 0 P 0 ;0
L 1.39296004 -2.09365 1.3933 -2.09431004 0 P 0 ;0
L 1.3933 -2.09431004 1.39368996 -2.09493996 0 P 0 ;0
L 1.39368996 -2.09493996 1.39411998 -2.09553996 0 P 0 ;0
L 1.39411998 -2.09553996 1.39468996 -2.09618002 0 P 0 ;0
L 1.39468996 -2.09618002 1.3953 -2.09678002 0 P 0 ;0
L 1.3953 -2.09678002 1.39596004 -2.09731998 0 P 0 ;0
L 1.39596004 -2.09731998 1.39666998 -2.0978 0 P 0 ;0
L 1.39666998 -2.0978 1.39673996 -2.09783996 0 P 0 ;0
L 1.39673996 -2.09783996 1.39741004 -2.09821998 0 P 0 ;0
L 1.39741004 -2.09821998 1.39748996 -2.09825 0 P 0 ;0
L 1.39748996 -2.09825 1.39818996 -2.09856998 0 P 0 ;0
L 1.39818996 -2.09856998 1.39898996 -2.09886004 0 P 0 ;0
L 1.39898996 -2.09886004 1.39906998 -2.09888002 0 P 0 ;0
L 1.39906998 -2.09888002 1.40043996 -2.09888002 0 P 0 ;0
L 1.40043996 -2.09888002 1.40033996 -2.09923002 0 P 0 ;0
L 1.40033996 -2.09923002 1.40041998 -2.09925 0 P 0 ;0
L 1.40041998 -2.09925 1.40186004 -2.09953002 0 P 0 ;0
L 1.40186004 -2.09953002 1.40331004 -2.09971004 0 P 0 ;0
L 1.40331004 -2.09971004 1.40478002 -2.09978002 0 P 0 ;0
L 1.40478002 -2.09978002 1.40625 -2.09975 0 P 0 ;0
L 1.40625 -2.09975 1.41096004 -2.09931004 0 P 0 ;0
L 1.41096004 -2.09931004 1.41556998 -2.09855 0 P 0 ;0
L 1.41556998 -2.09855 1.41791998 -2.09813002 0 P 0 ;0
L 1.41791998 -2.09813002 1.41995 -2.09791004 0 P 0 ;0
L 1.41995 -2.09791004 1.4201 -2.0979 0 P 0 ;0
L 1.4201 -2.0979 1.41941004 -2.10078002 0 P 0 ;0
L 1.41941004 -2.10078002 1.41761004 -2.10745 0 P 0 ;0
L 1.41761004 -2.10745 1.41391004 -2.12025 0 P 0 ;0
L 1.41391004 -2.12025 1.41215 -2.12626998 0 P 0 ;0
L 1.41215 -2.12626998 1.40655 -2.12725 0 P 0 ;0
L 1.40655 -2.12725 1.40046004 -2.12808002 0 P 0 ;0
L 1.40046004 -2.12808002 1.39438002 -2.12845 0 P 0 ;0
L 1.15303002 -2.08283002 1.20788996 -2.08283002 0 P 0 ;0
L 1.15398996 -2.08183002 1.20795 -2.08183002 0 P 0 ;0
L 1.15483002 -2.08083002 1.208 -2.08083002 0 P 0 ;0
L 1.15555 -2.07983002 1.20805 -2.07983002 0 P 0 ;0
L 1.15621998 -2.07883002 1.2081 -2.07883002 0 P 0 ;0
L 1.15681998 -2.07783002 1.20816004 -2.07783002 0 P 0 ;0
L 1.15733002 -2.07683002 1.20821004 -2.07683002 0 P 0 ;0
L 1.15778996 -2.07583002 1.20826004 -2.07583002 0 P 0 ;0
L 1.15818002 -2.07483002 1.20831004 -2.07483002 0 P 0 ;0
L 1.15853996 -2.07383002 1.20836998 -2.07383002 0 P 0 ;0
L 1.15881998 -2.07283002 1.20841998 -2.07283002 0 P 0 ;0
L 1.1591 -2.07183002 1.20846998 -2.07183002 0 P 0 ;0
L 1.15938002 -2.07083002 1.20853002 -2.07083002 0 P 0 ;0
L 1.1596 -2.06983002 1.20858002 -2.06983002 0 P 0 ;0
L 1.15981004 -2.06883002 1.20863996 -2.06883002 0 P 0 ;0
L 1.16001004 -2.06783002 1.20868996 -2.06783002 0 P 0 ;0
L 1.1602 -2.06683002 1.20875 -2.06683002 0 P 0 ;0
L 1.16033996 -2.06583002 1.2088 -2.06583002 0 P 0 ;0
L 1.16048996 -2.06483002 1.20886004 -2.06483002 0 P 0 ;0
L 1.16063996 -2.06383002 1.20891998 -2.06383002 0 P 0 ;0
L 1.16078002 -2.06283002 1.20896998 -2.06283002 0 P 0 ;0
L 1.16088996 -2.06183002 1.20903002 -2.06183002 0 P 0 ;0
L 1.16098996 -2.06083002 1.20908002 -2.06083002 0 P 0 ;0
L 1.16108996 -2.05983002 1.20913996 -2.05983002 0 P 0 ;0
L 1.16118002 -2.05883002 1.20918996 -2.05883002 0 P 0 ;0
L 1.16128002 -2.05783002 1.20925 -2.05783002 0 P 0 ;0
L 1.16133996 -2.05683002 1.2093 -2.05683002 0 P 0 ;0
L 1.1614 -2.05583002 1.20936004 -2.05583002 0 P 0 ;0
L 1.16146004 -2.05483002 1.20941004 -2.05483002 0 P 0 ;0
L 1.16151998 -2.05383002 1.20946998 -2.05383002 0 P 0 ;0
L 1.16158002 -2.05283002 1.20951998 -2.05283002 0 P 0 ;0
L 1.16163996 -2.05183002 1.20958002 -2.05183002 0 P 0 ;0
L 1.1617 -2.05083002 1.20963996 -2.05083002 0 P 0 ;0
L 1.16175 -2.04983002 1.2097 -2.04983002 0 P 0 ;0
L 1.16181004 -2.04883002 1.20975 -2.04883002 0 P 0 ;0
L 1.16186998 -2.04783002 1.20981004 -2.04783002 0 P 0 ;0
L 1.16193002 -2.04683002 1.20986998 -2.04683002 0 P 0 ;0
L 1.16198996 -2.04583002 1.20993002 -2.04583002 0 P 0 ;0
L 1.16205 -2.04483002 1.20998996 -2.04483002 0 P 0 ;0
L 1.16211004 -2.04383002 1.21005 -2.04383002 0 P 0 ;0
L 1.16215 -2.04283002 1.2101 -2.04283002 0 P 0 ;0
L 1.1622 -2.04183002 1.21016004 -2.04183002 0 P 0 ;0
L 1.16225 -2.04083002 1.21021998 -2.04083002 0 P 0 ;0
L 1.16228996 -2.03983002 1.21028002 -2.03983002 0 P 0 ;0
L 1.16233996 -2.03883002 1.21033996 -2.03883002 0 P 0 ;0
L 1.16238002 -2.03783002 1.2104 -2.03783002 0 P 0 ;0
L 1.16243002 -2.03683002 1.21046004 -2.03683002 0 P 0 ;0
L 1.16246998 -2.03583002 1.21051004 -2.03583002 0 P 0 ;0
L 1.16251998 -2.03483002 1.21056998 -2.03483002 0 P 0 ;0
L 1.16256998 -2.03383002 1.21063996 -2.03383002 0 P 0 ;0
L 1.16261004 -2.03283002 1.2107 -2.03283002 0 P 0 ;0
L 1.16266004 -2.03183002 1.21076004 -2.03183002 0 P 0 ;0
L 1.1627 -2.03083002 1.21083002 -2.03083002 0 P 0 ;0
L 1.16015 -1.97631004 1.17066004 -1.97631004 0 P 0 ;0
L 1.15961998 -1.97531004 1.17026004 -1.97531004 0 P 0 ;0
L 1.1591 -1.97431004 1.16986998 -1.97431004 0 P 0 ;0
L 1.15856998 -1.97331004 1.16946998 -1.97331004 0 P 0 ;0
L 1.15803996 -1.97231004 1.16903002 -1.97231004 0 P 0 ;0
L 1.15746998 -1.97131004 1.16858996 -1.97131004 0 P 0 ;0
L 1.1569 -1.97031004 1.16815 -1.97031004 0 P 0 ;0
L 1.15631998 -1.96931004 1.16771004 -1.96931004 0 P 0 ;0
L 1.15573996 -1.96831004 1.16726998 -1.96831004 0 P 0 ;0
L 1.15516004 -1.96731004 1.16681998 -1.96731004 0 P 0 ;0
L 1.15458996 -1.96631004 1.16638002 -1.96631004 0 P 0 ;0
L 1.15398002 -1.96531004 1.16593996 -1.96531004 0 P 0 ;0
L 1.1533 -1.96431004 1.16548996 -1.96431004 0 P 0 ;0
L 1.15261998 -1.96331004 1.16503002 -1.96331004 0 P 0 ;0
L 1.15193996 -1.96231004 1.16448002 -1.96231004 0 P 0 ;0
L 1.15126004 -1.96131004 1.16393002 -1.96131004 0 P 0 ;0
L 1.15058002 -1.96031004 1.16338002 -1.96031004 0 P 0 ;0
L 1.1499 -1.95931004 1.16283002 -1.95931004 0 P 0 ;0
L 1.1491 -1.95831004 1.16228996 -1.95831004 0 P 0 ;0
L 1.14831004 -1.95731004 1.16173996 -1.95731004 0 P 0 ;0
L 1.14751004 -1.95631004 1.16118996 -1.95631004 0 P 0 ;0
L 1.14671004 -1.95531004 1.16063996 -1.95531004 0 P 0 ;0
L 1.14591998 -1.95431004 1.16008996 -1.95431004 0 P 0 ;0
L 1.14511998 -1.95331004 1.15943996 -1.95331004 0 P 0 ;0
L 1.1442 -1.95231004 1.15878002 -1.95231004 0 P 0 ;0
L 1.14326998 -1.95131004 1.15811004 -1.95131004 0 P 0 ;0
L 1.14233996 -1.95031004 1.15745 -1.95031004 0 P 0 ;0
L 1.14141004 -1.94931004 1.15678002 -1.94931004 0 P 0 ;0
L 1.14048996 -1.94831004 1.15611998 -1.94831004 0 P 0 ;0
L 1.1395 -1.94731004 1.15545 -1.94731004 0 P 0 ;0
L 1.13843002 -1.94631004 1.15478996 -1.94631004 0 P 0 ;0
L 1.13736004 -1.94531004 1.15411998 -1.94531004 0 P 0 ;0
L 1.13628996 -1.94431004 1.15333002 -1.94431004 0 P 0 ;0
L 1.13521004 -1.94331004 1.15253002 -1.94331004 0 P 0 ;0
L 1.13413996 -1.94231004 1.15173996 -1.94231004 0 P 0 ;0
L 1.13306998 -1.94131004 1.15093996 -1.94131004 0 P 0 ;0
L 1.132 -1.94031004 1.15013996 -1.94031004 0 P 0 ;0
L 1.13081004 -1.93931004 1.14935 -1.93931004 0 P 0 ;0
L 1.12958002 -1.93831004 1.14855 -1.93831004 0 P 0 ;0
L 1.12833996 -1.93731004 1.14775 -1.93731004 0 P 0 ;0
L 1.1271 -1.93631004 1.14688996 -1.93631004 0 P 0 ;0
L 1.12586004 -1.93531004 1.14593996 -1.93531004 0 P 0 ;0
L 1.12461998 -1.93431004 1.14498996 -1.93431004 0 P 0 ;0
L 1.12338002 -1.93331004 1.14405 -1.93331004 0 P 0 ;0
L 1.12203002 -1.93231004 1.1431 -1.93231004 0 P 0 ;0
L 1.1206 -1.93131004 1.14216004 -1.93131004 0 P 0 ;0
L 1.11916004 -1.93031004 1.14121004 -1.93031004 0 P 0 ;0
L 1.11771998 -1.92931004 1.14026998 -1.92931004 0 P 0 ;0
L 1.11628996 -1.92831004 1.13931998 -1.92831004 0 P 0 ;0
L 1.11483996 -1.92731004 1.13838002 -1.92731004 0 P 0 ;0
L 1.11338996 -1.92631004 1.13743002 -1.92631004 0 P 0 ;0
L 1.11171998 -1.92531004 1.13648996 -1.92531004 0 P 0 ;0
L 1.11005 -1.92431004 1.13538002 -1.92431004 0 P 0 ;0
L 1.10838002 -1.92331004 1.13426998 -1.92331004 0 P 0 ;0
L 1.1067 -1.92231004 1.13315 -1.92231004 0 P 0 ;0
L 1.10503002 -1.92131004 1.13203002 -1.92131004 0 P 0 ;0
L 1.10336004 -1.92031004 1.13091998 -1.92031004 0 P 0 ;0
L 1.1015 -1.91931004 1.1298 -1.91931004 0 P 0 ;0
L 1.09955 -1.91831004 1.12868002 -1.91831004 0 P 0 ;0
L 1.16275 -2.02983002 1.21088996 -2.02983002 0 P 0 ;0
L 1.16278996 -2.02883002 1.21095 -2.02883002 0 P 0 ;0
L 1.16283996 -2.02783002 1.21101004 -2.02783002 0 P 0 ;0
L 1.16226998 -2.02683002 1.21108002 -2.02683002 0 P 0 ;0
L 1.16153996 -2.02583002 1.21113996 -2.02583002 0 P 0 ;0
L 1.15846004 -2.02483002 1.2112 -2.02483002 0 P 0 ;0
L 1.10036004 -2.00383002 1.21255 -2.00383002 0 P 0 ;0
L 1.10226004 -2.00283002 1.2126 -2.00283002 0 P 0 ;0
L 1.10433996 -2.00183002 1.21266998 -2.00183002 0 P 0 ;0
L 1.1065 -2.00083002 1.21273002 -2.00083002 0 P 0 ;0
L 1.10886998 -1.99983002 1.21278996 -1.99983002 0 P 0 ;0
L 1.11138002 -1.99883002 1.21285 -1.99883002 0 P 0 ;0
L 1.11436998 -1.99783002 1.21288002 -1.99783002 0 P 0 ;0
L 1.11748996 -1.99683002 1.21255 -1.99683002 0 P 0 ;0
L 1.12061998 -1.99583002 1.2089 -1.99583002 0 P 0 ;0
L 1.12433996 -1.99483002 1.2036 -1.99483002 0 P 0 ;0
L 1.12863996 -1.99383002 1.19728002 -1.99383002 0 P 0 ;0
L 1.13295 -1.99283002 1.19096998 -1.99283002 0 P 0 ;0
L 1.13985 -1.99183002 1.18111998 -1.99183002 0 P 0 ;0
L 1.14948002 -1.99083002 1.1651 -1.99083002 0 P 0 ;0
L 1.24218002 -2.08316004 1.29143996 -2.08316004 0 P 0 ;0
L 1.24223002 -2.08216004 1.29151004 -2.08216004 0 P 0 ;0
L 1.24228002 -2.08116004 1.29158996 -2.08116004 0 P 0 ;0
L 1.24233996 -2.08016004 1.29166004 -2.08016004 0 P 0 ;0
L 1.24238996 -2.07916004 1.29173002 -2.07916004 0 P 0 ;0
L 1.24245 -2.07816004 1.29181004 -2.07816004 0 P 0 ;0
L 1.2425 -2.07716004 1.29188002 -2.07716004 0 P 0 ;0
L 1.24256004 -2.07616004 1.29195 -2.07616004 0 P 0 ;0
L 1.24261004 -2.07516004 1.29203002 -2.07516004 0 P 0 ;0
L 1.24266998 -2.07416004 1.2921 -2.07416004 0 P 0 ;0
L 1.24271998 -2.07316004 1.29216998 -2.07316004 0 P 0 ;0
L 1.24278002 -2.07216004 1.29223996 -2.07216004 0 P 0 ;0
L 1.24283002 -2.07116004 1.29231998 -2.07116004 0 P 0 ;0
L 1.24288002 -2.07016004 1.29238996 -2.07016004 0 P 0 ;0
L 1.24293002 -2.06916004 1.29246004 -2.06916004 0 P 0 ;0
L 1.24296998 -2.06816004 1.29253002 -2.06816004 0 P 0 ;0
L 1.24301998 -2.06716004 1.29261004 -2.06716004 0 P 0 ;0
L 1.24306004 -2.06616004 1.2927 -2.06616004 0 P 0 ;0
L 1.24311004 -2.06516004 1.29281004 -2.06516004 0 P 0 ;0
L 1.24315 -2.06416004 1.29291998 -2.06416004 0 P 0 ;0
L 1.2432 -2.06316004 1.29303002 -2.06316004 0 P 0 ;0
L 1.24323996 -2.06216004 1.29315 -2.06216004 0 P 0 ;0
L 1.24328996 -2.06116004 1.29331998 -2.06116004 0 P 0 ;0
L 1.24333002 -2.06016004 1.2935 -2.06016004 0 P 0 ;0
L 1.24338002 -2.05916004 1.29366998 -2.05916004 0 P 0 ;0
L 1.24341998 -2.05816004 1.29385 -2.05816004 0 P 0 ;0
L 1.24346998 -2.05716004 1.29408996 -2.05716004 0 P 0 ;0
L 1.24351004 -2.05616004 1.29433996 -2.05616004 0 P 0 ;0
L 1.24355 -2.05516004 1.29458996 -2.05516004 0 P 0 ;0
L 1.2436 -2.05416004 1.29485 -2.05416004 0 P 0 ;0
L 1.24363996 -2.05316004 1.29516998 -2.05316004 0 P 0 ;0
L 1.24368996 -2.05216004 1.29551998 -2.05216004 0 P 0 ;0
L 1.24373002 -2.05116004 1.29586004 -2.05116004 0 P 0 ;0
L 1.24378002 -2.05016004 1.29621004 -2.05016004 0 P 0 ;0
L 1.24383002 -2.04916004 1.29663996 -2.04916004 0 P 0 ;0
L 1.24386998 -2.04816004 1.29708002 -2.04816004 0 P 0 ;0
L 1.24391004 -2.04716004 1.29753002 -2.04716004 0 P 0 ;0
L 1.24396004 -2.04616004 1.29796998 -2.04616004 0 P 0 ;0
L 1.244 -2.04516004 1.29851004 -2.04516004 0 P 0 ;0
L 1.24405 -2.04416004 1.2991 -2.04416004 0 P 0 ;0
L 1.24408996 -2.04316004 1.29975 -2.04316004 0 P 0 ;0
L 1.24413996 -2.04216004 1.3005 -2.04216004 0 P 0 ;0
L 1.24418002 -2.04116004 1.30131998 -2.04116004 0 P 0 ;0
L 1.24423002 -2.04016004 1.30223002 -2.04016004 0 P 0 ;0
L 1.24426998 -2.03916004 1.30326998 -2.03916004 0 P 0 ;0
L 1.24431998 -2.03816004 1.30446004 -2.03816004 0 P 0 ;0
L 1.24436004 -2.03716004 1.30581998 -2.03716004 0 P 0 ;0
L 1.24441004 -2.03616004 1.30738002 -2.03616004 0 P 0 ;0
L 1.24445 -2.03516004 1.30923002 -2.03516004 0 P 0 ;0
L 1.24448996 -2.03416004 1.31156004 -2.03416004 0 P 0 ;0
L 1.24453996 -2.03316004 1.31478996 -2.03316004 0 P 0 ;0
L 1.24458996 -2.03216004 1.32013002 -2.03216004 0 P 0 ;0
L 1.24461998 -2.03116004 1.33481004 -2.03116004 0 P 0 ;0
L 1.24463996 -2.03016004 1.33478002 -2.03016004 0 P 0 ;0
L 1.24466004 -2.02916004 1.33473996 -2.02916004 0 P 0 ;0
L 1.24468002 -2.02816004 1.33471004 -2.02816004 0 P 0 ;0
L 1.2447 -2.02716004 1.33468002 -2.02716004 0 P 0 ;0
L 1.24471998 -2.02616004 1.33463996 -2.02616004 0 P 0 ;0
L 1.24473996 -2.02516004 1.3346 -2.02516004 0 P 0 ;0
L 1.24476004 -2.02416004 1.33456998 -2.02416004 0 P 0 ;0
L 1.24478002 -2.02316004 1.33453002 -2.02316004 0 P 0 ;0
L 1.2448 -2.02216004 1.3345 -2.02216004 0 P 0 ;0
L 1.24481998 -2.02116004 1.33446998 -2.02116004 0 P 0 ;0
L 1.24483996 -2.02016004 1.33443002 -2.02016004 0 P 0 ;0
L 1.24486004 -2.01916004 1.3344 -2.01916004 0 P 0 ;0
L 1.24488002 -2.01816004 1.33436004 -2.01816004 0 P 0 ;0
L 1.2449 -2.01716004 1.33433002 -2.01716004 0 P 0 ;0
L 1.24491998 -2.01616004 1.33428996 -2.01616004 0 P 0 ;0
L 1.24493996 -2.01516004 1.33426004 -2.01516004 0 P 0 ;0
L 1.24496004 -2.01416004 1.33421998 -2.01416004 0 P 0 ;0
L 1.24498002 -2.01316004 1.33418996 -2.01316004 0 P 0 ;0
L 1.245 -2.01216004 1.33415 -2.01216004 0 P 0 ;0
L 1.24501998 -2.01116004 1.33411998 -2.01116004 0 P 0 ;0
L 1.24503996 -2.01016004 1.33408002 -2.01016004 0 P 0 ;0
L 1.24506004 -2.00916004 1.33403996 -2.00916004 0 P 0 ;0
L 1.24508002 -2.00816004 1.334 -2.00816004 0 P 0 ;0
L 1.2451 -2.00716004 1.33396004 -2.00716004 0 P 0 ;0
L 1.24511998 -2.00616004 1.33393002 -2.00616004 0 P 0 ;0
L 1.24513996 -2.00516004 1.29098996 -2.00516004 0 P 0 ;0
L 1.24513996 -2.00416004 1.29033002 -2.00416004 0 P 0 ;0
L 1.24513996 -2.00316004 1.29005 -2.00316004 0 P 0 ;0
L 1.24513996 -2.00216004 1.29005 -2.00216004 0 P 0 ;0
L 1.24513996 -2.00116004 1.29005 -2.00116004 0 P 0 ;0
L 1.24515 -2.00016004 1.29005 -2.00016004 0 P 0 ;0
L 1.24515 -1.99916004 1.29005 -1.99916004 0 P 0 ;0
L 1.24515 -1.99816004 1.29005 -1.99816004 0 P 0 ;0
L 1.24515 -1.99716004 1.29005 -1.99716004 0 P 0 ;0
L 1.24515 -1.99616004 1.29005 -1.99616004 0 P 0 ;0
L 1.24515 -1.99516004 1.29005 -1.99516004 0 P 0 ;0
L 1.16085 -2.02753002 1.1601 -2.04393002 0 P 0 ;0
L 1.1601 -2.04393002 1.15928996 -2.05771998 0 P 0 ;0
L 1.15928996 -2.05771998 1.15883996 -2.06228002 0 P 0 ;0
L 1.15883996 -2.06228002 1.15818002 -2.06681998 0 P 0 ;0
L 1.15818002 -2.06681998 1.15751004 -2.07006998 0 P 0 ;0
L 1.15751004 -2.07006998 1.15661004 -2.07328996 0 P 0 ;0
L 1.15661004 -2.07328996 1.15616004 -2.07453996 0 P 0 ;0
L 1.15616004 -2.07453996 1.15563002 -2.07576998 0 P 0 ;0
L 1.15563002 -2.07576998 1.15501998 -2.07696004 0 P 0 ;0
L 1.15501998 -2.07696004 1.15433002 -2.0781 0 P 0 ;0
L 1.15433002 -2.0781 1.1534 -2.07941998 0 P 0 ;0
L 1.1534 -2.07941998 1.15236004 -2.08066004 0 P 0 ;0
L 1.15236004 -2.08066004 1.15123002 -2.08181998 0 P 0 ;0
L 1.15123002 -2.08181998 1.15001004 -2.08286998 0 P 0 ;0
L 1.15001004 -2.08286998 1.14871004 -2.08383002 0 P 0 ;0
L 1.14871004 -2.08383002 1.14733002 -2.08468002 0 P 0 ;0
L 1.14733002 -2.08468002 1.14591004 -2.0854 0 P 0 ;0
L 1.14591004 -2.0854 1.14443996 -2.086 0 P 0 ;0
L 1.14443996 -2.086 1.14291004 -2.08648002 0 P 0 ;0
L 1.14291004 -2.08648002 1.14136004 -2.08683002 0 P 0 ;0
L 1.14136004 -2.08683002 1.13976998 -2.08703996 0 P 0 ;0
L 1.13976998 -2.08703996 1.13816004 -2.08713002 0 P 0 ;0
L 1.13816004 -2.08713002 1.13656998 -2.08708002 0 P 0 ;0
L 1.13656998 -2.08708002 1.13498996 -2.0869 0 P 0 ;0
L 1.13498996 -2.0869 1.13341998 -2.08658996 0 P 0 ;0
L 1.13341998 -2.08658996 1.13188996 -2.08615 0 P 0 ;0
L 1.13188996 -2.08615 1.1304 -2.08558996 0 P 0 ;0
L 1.1304 -2.08558996 1.12895 -2.08488996 0 P 0 ;0
L 1.12895 -2.08488996 1.12756998 -2.08408002 0 P 0 ;0
L 1.12756998 -2.08408002 1.12625 -2.08315 0 P 0 ;0
L 1.12625 -2.08315 1.12501004 -2.08211998 0 P 0 ;0
L 1.12501004 -2.08211998 1.12386004 -2.081 0 P 0 ;0
L 1.12386004 -2.081 1.12281004 -2.07978002 0 P 0 ;0
L 1.12281004 -2.07978002 1.12183996 -2.07846998 0 P 0 ;0
L 1.12183996 -2.07846998 1.1211 -2.07726004 0 P 0 ;0
L 1.1211 -2.07726004 1.12046998 -2.07598996 0 P 0 ;0
L 1.12046998 -2.07598996 1.11996004 -2.07466998 0 P 0 ;0
L 1.11996004 -2.07466998 1.11955 -2.07331004 0 P 0 ;0
L 1.11955 -2.07331004 1.11926998 -2.07191004 0 P 0 ;0
L 1.11926998 -2.07191004 1.11868002 -2.06693996 0 P 0 ;0
L 1.11868002 -2.06693996 1.11848002 -2.06191004 0 P 0 ;0
L 1.11848002 -2.06191004 1.11871004 -2.05668002 0 P 0 ;0
L 1.11871004 -2.05668002 1.11936004 -2.05148002 0 P 0 ;0
L 1.11936004 -2.05148002 1.11978996 -2.04936998 0 P 0 ;0
L 1.11978996 -2.04936998 1.12036998 -2.0473 0 P 0 ;0
L 1.12036998 -2.0473 1.12108996 -2.04528002 0 P 0 ;0
L 1.12108996 -2.04528002 1.12196004 -2.04331998 0 P 0 ;0
L 1.12196004 -2.04331998 1.1229 -2.04153996 0 P 0 ;0
L 1.1229 -2.04153996 1.12396998 -2.03985 0 P 0 ;0
L 1.12396998 -2.03985 1.12516998 -2.03823002 0 P 0 ;0
L 1.12516998 -2.03823002 1.12735 -2.03573996 0 P 0 ;0
L 1.12735 -2.03573996 1.12973002 -2.03345 0 P 0 ;0
L 1.12973002 -2.03345 1.13223996 -2.03141998 0 P 0 ;0
L 1.13223996 -2.03141998 1.13491998 -2.02961004 0 P 0 ;0
L 1.13491998 -2.02961004 1.13611004 -2.02893002 0 P 0 ;0
L 1.13611004 -2.02893002 1.13735 -2.02833996 0 P 0 ;0
L 1.13735 -2.02833996 1.13861998 -2.02781998 0 P 0 ;0
L 1.13861998 -2.02781998 1.13993996 -2.0274 0 P 0 ;0
L 1.13993996 -2.0274 1.14191004 -2.02693002 0 P 0 ;0
L 1.14191004 -2.02693002 1.14391004 -2.02663002 0 P 0 ;0
L 1.14391004 -2.02663002 1.14935 -2.02626004 0 P 0 ;0
L 1.14935 -2.02626004 1.15471004 -2.0263 0 P 0 ;0
L 1.15471004 -2.0263 1.15591004 -2.02638996 0 P 0 ;0
L 1.15591004 -2.02638996 1.1571 -2.02656998 0 P 0 ;0
L 1.1571 -2.02656998 1.15828002 -2.02683996 0 P 0 ;0
L 1.15828002 -2.02683996 1.16085 -2.02753002 0 P 0 ;0
L 1.13876998 -2.14783002 1.20233002 -2.14783002 0 P 0 ;0
L 1.14236998 -2.14683002 1.20266004 -2.14683002 0 P 0 ;0
L 1.14481004 -2.14583002 1.20296004 -2.14583002 0 P 0 ;0
L 1.1467 -2.14483002 1.20325 -2.14483002 0 P 0 ;0
L 1.14826004 -2.14383002 1.20353002 -2.14383002 0 P 0 ;0
L 1.1496 -2.14283002 1.20373996 -2.14283002 0 P 0 ;0
L 1.15078996 -2.14183002 1.20395 -2.14183002 0 P 0 ;0
L 1.15186004 -2.14083002 1.20415 -2.14083002 0 P 0 ;0
L 1.15278996 -2.13983002 1.20431998 -2.13983002 0 P 0 ;0
L 1.15361998 -2.13883002 1.20446004 -2.13883002 0 P 0 ;0
L 1.15436004 -2.13783002 1.20458002 -2.13783002 0 P 0 ;0
L 1.155 -2.13683002 1.20466998 -2.13683002 0 P 0 ;0
L 1.15556998 -2.13583002 1.20475 -2.13583002 0 P 0 ;0
L 1.15608996 -2.13483002 1.20481998 -2.13483002 0 P 0 ;0
L 1.15653996 -2.13383002 1.20488996 -2.13383002 0 P 0 ;0
L 1.15691004 -2.13283002 1.20496004 -2.13283002 0 P 0 ;0
L 1.15723996 -2.13183002 1.20503002 -2.13183002 0 P 0 ;0
L 1.15751998 -2.13083002 1.2051 -2.13083002 0 P 0 ;0
L 1.15773002 -2.12983002 1.20516004 -2.12983002 0 P 0 ;0
L 1.15793002 -2.12883002 1.20523002 -2.12883002 0 P 0 ;0
L 1.15806004 -2.12783002 1.2053 -2.12783002 0 P 0 ;0
L 1.15816998 -2.12683002 1.20536998 -2.12683002 0 P 0 ;0
L 1.15821004 -2.12583002 1.20543996 -2.12583002 0 P 0 ;0
L 1.11716004 -2.12483002 1.12726004 -2.12483002 0 P 0 ;0
L 1.15823996 -2.12483002 1.20551004 -2.12483002 0 P 0 ;0
L 1.10911998 -2.12383002 1.1352 -2.12383002 0 P 0 ;0
L 1.15821998 -2.12383002 1.20556998 -2.12383002 0 P 0 ;0
L 1.10468996 -2.12283002 1.14018996 -2.12283002 0 P 0 ;0
L 1.1582 -2.12283002 1.20563996 -2.12283002 0 P 0 ;0
L 1.10131004 -2.12183002 1.14366998 -2.12183002 0 P 0 ;0
L 1.15818002 -2.12183002 1.2057 -2.12183002 0 P 0 ;0
L 1.15808996 -2.12083002 1.20576004 -2.12083002 0 P 0 ;0
L 1.15781004 -2.11983002 1.20583002 -2.11983002 0 P 0 ;0
L 1.15721004 -2.11883002 1.20588002 -2.11883002 0 P 0 ;0
L 1.14146004 -2.08883002 1.20758002 -2.08883002 0 P 0 ;0
L 1.14525 -2.08783002 1.20763002 -2.08783002 0 P 0 ;0
L 1.14751004 -2.08683002 1.20768002 -2.08683002 0 P 0 ;0
L 1.14928002 -2.08583002 1.20773002 -2.08583002 0 P 0 ;0
L 1.15073002 -2.08483002 1.20778996 -2.08483002 0 P 0 ;0
L 1.15196004 -2.08383002 1.20783996 -2.08383002 0 P 0 ;0
L 1.13818996 -2.08913002 1.13826998 -2.08913002 0 P 0 ;0
L 1.13826998 -2.08913002 1.13988002 -2.08903996 0 P 0 ;0
L 1.13988002 -2.08903996 1.13996004 -2.08903996 0 P 0 ;0
L 1.13996004 -2.08903996 1.14001004 -2.08903002 0 P 0 ;0
L 1.14001004 -2.08903002 1.14005 -2.08901998 0 P 0 ;0
L 1.14005 -2.08901998 1.14163002 -2.08881004 0 P 0 ;0
L 1.14163002 -2.08881004 1.14166998 -2.0888 0 P 0 ;0
L 1.14166998 -2.0888 1.14171004 -2.0888 0 P 0 ;0
L 1.14171004 -2.0888 1.14178996 -2.08878002 0 P 0 ;0
L 1.14178996 -2.08878002 1.14335 -2.08843002 0 P 0 ;0
L 1.14335 -2.08843002 1.14351004 -2.08838996 0 P 0 ;0
L 1.14351004 -2.08838996 1.14503002 -2.08791004 0 P 0 ;0
L 1.14503002 -2.08791004 1.14511004 -2.08788996 0 P 0 ;0
L 1.14511004 -2.08788996 1.14515 -2.08786998 0 P 0 ;0
L 1.14515 -2.08786998 1.14518996 -2.08786004 0 P 0 ;0
L 1.14518996 -2.08786004 1.14666004 -2.08725 0 P 0 ;0
L 1.14666004 -2.08725 1.14673996 -2.08721998 0 P 0 ;0
L 1.14673996 -2.08721998 1.14678002 -2.0872 0 P 0 ;0
L 1.14678002 -2.0872 1.14681998 -2.08718996 0 P 0 ;0
L 1.14681998 -2.08718996 1.14823996 -2.08646998 0 P 0 ;0
L 1.14823996 -2.08646998 1.14826998 -2.08645 0 P 0 ;0
L 1.14826998 -2.08645 1.14835 -2.08641004 0 P 0 ;0
L 1.14835 -2.08641004 1.14838002 -2.08638002 0 P 0 ;0
L 1.14838002 -2.08638002 1.14976004 -2.08553002 0 P 0 ;0
L 1.14976004 -2.08553002 1.14978996 -2.08551004 0 P 0 ;0
L 1.14978996 -2.08551004 1.14983002 -2.08548996 0 P 0 ;0
L 1.14983002 -2.08548996 1.14988996 -2.08543996 0 P 0 ;0
L 1.14988996 -2.08543996 1.1512 -2.08448996 0 P 0 ;0
L 1.1512 -2.08448996 1.15126004 -2.08443996 0 P 0 ;0
L 1.15126004 -2.08443996 1.15128996 -2.08441004 0 P 0 ;0
L 1.15128996 -2.08441004 1.15131998 -2.08438996 0 P 0 ;0
L 1.15131998 -2.08438996 1.15253996 -2.08333002 0 P 0 ;0
L 1.15253996 -2.08333002 1.15256998 -2.0833 0 P 0 ;0
L 1.15256998 -2.0833 1.1526 -2.08328002 0 P 0 ;0
L 1.1526 -2.08328002 1.15263002 -2.08323996 0 P 0 ;0
L 1.15263002 -2.08323996 1.15266004 -2.08321998 0 P 0 ;0
L 1.15266004 -2.08321998 1.15378996 -2.08206004 0 P 0 ;0
L 1.15378996 -2.08206004 1.15376004 -2.08203996 0 P 0 ;0
L 1.15376004 -2.08203996 1.15381998 -2.08203996 0 P 0 ;0
L 1.15381998 -2.08203996 1.15383996 -2.082 0 P 0 ;0
L 1.15383996 -2.082 1.15386998 -2.08196998 0 P 0 ;0
L 1.15386998 -2.08196998 1.1539 -2.08195 0 P 0 ;0
L 1.1539 -2.08195 1.15493002 -2.08071004 0 P 0 ;0
L 1.15493002 -2.08071004 1.15493002 -2.0807 0 P 0 ;0
L 1.15493002 -2.0807 1.15496004 -2.08066998 0 P 0 ;0
L 1.15496004 -2.08066998 1.15498002 -2.08063996 0 P 0 ;0
L 1.15498002 -2.08063996 1.15501004 -2.08061004 0 P 0 ;0
L 1.15501004 -2.08061004 1.15503002 -2.08058002 0 P 0 ;0
L 1.15503002 -2.08058002 1.15596004 -2.07926004 0 P 0 ;0
L 1.15596004 -2.07926004 1.15603996 -2.07913996 0 P 0 ;0
L 1.15603996 -2.07913996 1.15673002 -2.07798996 0 P 0 ;0
L 1.15673002 -2.07798996 1.15676998 -2.07793002 0 P 0 ;0
L 1.15676998 -2.07793002 1.15678996 -2.07786998 0 P 0 ;0
L 1.15678996 -2.07786998 1.15741004 -2.07668996 0 P 0 ;0
L 1.15741004 -2.07668996 1.15743996 -2.07663002 0 P 0 ;0
L 1.15743996 -2.07663002 1.15746004 -2.07656998 0 P 0 ;0
L 1.15746004 -2.07656998 1.15746998 -2.07656998 0 P 0 ;0
L 1.15746998 -2.07656998 1.158 -2.07533996 0 P 0 ;0
L 1.158 -2.07533996 1.15801004 -2.07531004 0 P 0 ;0
L 1.15801004 -2.07531004 1.15803002 -2.07528002 0 P 0 ;0
L 1.15803002 -2.07528002 1.15805 -2.07521998 0 P 0 ;0
L 1.15805 -2.07521998 1.15848996 -2.07396004 0 P 0 ;0
L 1.15848996 -2.07396004 1.15841004 -2.07393002 0 P 0 ;0
L 1.15841004 -2.07393002 1.15851004 -2.07393002 0 P 0 ;0
L 1.15851004 -2.07393002 1.15851998 -2.0739 0 P 0 ;0
L 1.15851998 -2.0739 1.15853002 -2.07386004 0 P 0 ;0
L 1.15853002 -2.07386004 1.15853996 -2.07383002 0 P 0 ;0
L 1.15853996 -2.07383002 1.15943996 -2.07061004 0 P 0 ;0
L 1.15943996 -2.07061004 1.15945 -2.07058002 0 P 0 ;0
L 1.15945 -2.07058002 1.15946004 -2.07053996 0 P 0 ;0
L 1.15946004 -2.07053996 1.15946998 -2.07051004 0 P 0 ;0
L 1.15946998 -2.07051004 1.15946998 -2.07046998 0 P 0 ;0
L 1.15946998 -2.07046998 1.16013996 -2.06723002 0 P 0 ;0
L 1.16013996 -2.06723002 1.16013996 -2.0672 0 P 0 ;0
L 1.16013996 -2.0672 1.16016004 -2.06713996 0 P 0 ;0
L 1.16016004 -2.06713996 1.16016004 -2.06711004 0 P 0 ;0
L 1.16016004 -2.06711004 1.16081998 -2.06256004 0 P 0 ;0
L 1.16081998 -2.06256004 1.16081998 -2.06253996 0 P 0 ;0
L 1.16081998 -2.06253996 1.16083002 -2.0625 0 P 0 ;0
L 1.16083002 -2.0625 1.16083002 -2.06246998 0 P 0 ;0
L 1.16083002 -2.06246998 1.16126998 -2.05791004 0 P 0 ;0
L 1.16126998 -2.05791004 1.16128002 -2.0579 0 P 0 ;0
L 1.16128002 -2.0579 1.16128002 -2.05783996 0 P 0 ;0
L 1.16128002 -2.05783996 1.1621 -2.04405 0 P 0 ;0
L 1.1621 -2.04405 1.1621 -2.04401998 0 P 0 ;0
L 1.1621 -2.04401998 1.16285 -2.02761998 0 P 0 ;0
L 1.16285 -2.02761998 1.16136998 -2.0256 0 P 0 ;0
L 1.16136998 -2.0256 1.15878996 -2.02491004 0 P 0 ;0
L 1.15878996 -2.02491004 1.15878002 -2.0249 0 P 0 ;0
L 1.15878002 -2.0249 1.15871998 -2.02488996 0 P 0 ;0
L 1.15871998 -2.02488996 1.15755 -2.02461998 0 P 0 ;0
L 1.15755 -2.02461998 1.15746998 -2.0246 0 P 0 ;0
L 1.15746998 -2.0246 1.1574 -2.0246 0 P 0 ;0
L 1.1574 -2.0246 1.15621004 -2.02441004 0 P 0 ;0
L 1.15621004 -2.02441004 1.15616998 -2.02441004 0 P 0 ;0
L 1.15616998 -2.02441004 1.1561 -2.0244 0 P 0 ;0
L 1.1561 -2.0244 1.15606004 -2.02438996 0 P 0 ;0
L 1.15606004 -2.02438996 1.15486004 -2.0243 0 P 0 ;0
L 1.15486004 -2.0243 1.15471998 -2.0243 0 P 0 ;0
L 1.15471998 -2.0243 1.14936004 -2.02426004 0 P 0 ;0
L 1.14936004 -2.02426004 1.14928996 -2.02426004 0 P 0 ;0
L 1.14928996 -2.02426004 1.14925 -2.02426998 0 P 0 ;0
L 1.14925 -2.02426998 1.14921004 -2.02426998 0 P 0 ;0
L 1.14921004 -2.02426998 1.14376998 -2.02463996 0 P 0 ;0
L 1.14376998 -2.02463996 1.1437 -2.02463996 0 P 0 ;0
L 1.1437 -2.02463996 1.14365 -2.02465 0 P 0 ;0
L 1.14365 -2.02465 1.14361004 -2.02465 0 P 0 ;0
L 1.14361004 -2.02465 1.14161998 -2.02495 0 P 0 ;0
L 1.14161998 -2.02495 1.14161004 -2.02495 0 P 0 ;0
L 1.14161004 -2.02495 1.14153002 -2.02496998 0 P 0 ;0
L 1.14153002 -2.02496998 1.14148996 -2.02496998 0 P 0 ;0
L 1.14148996 -2.02496998 1.14143996 -2.02498996 0 P 0 ;0
L 1.14143996 -2.02498996 1.13946998 -2.02545 0 P 0 ;0
L 1.13946998 -2.02545 1.13943996 -2.02546998 0 P 0 ;0
L 1.13943996 -2.02546998 1.1394 -2.02546998 0 P 0 ;0
L 1.1394 -2.02546998 1.13933002 -2.0255 0 P 0 ;0
L 1.13933002 -2.0255 1.13801004 -2.02591998 0 P 0 ;0
L 1.13801004 -2.02591998 1.13798002 -2.02593002 0 P 0 ;0
L 1.13798002 -2.02593002 1.13793996 -2.02593996 0 P 0 ;0
L 1.13793996 -2.02593996 1.13788002 -2.02596998 0 P 0 ;0
L 1.13788002 -2.02596998 1.1366 -2.02648002 0 P 0 ;0
L 1.1366 -2.02648002 1.13653996 -2.0265 0 P 0 ;0
L 1.13653996 -2.0265 1.13648002 -2.02653002 0 P 0 ;0
L 1.13648002 -2.02653002 1.13523996 -2.02713002 0 P 0 ;0
L 1.13523996 -2.02713002 1.13518002 -2.02716004 0 P 0 ;0
L 1.13518002 -2.02716004 1.13515 -2.02716998 0 P 0 ;0
L 1.13515 -2.02716998 1.13511998 -2.02718996 0 P 0 ;0
L 1.13511998 -2.02718996 1.13393002 -2.02786998 0 P 0 ;0
L 1.13393002 -2.02786998 1.13388996 -2.02788996 0 P 0 ;0
L 1.13388996 -2.02788996 1.1338 -2.02795 0 P 0 ;0
L 1.1338 -2.02795 1.13111998 -2.02976004 0 P 0 ;0
L 1.13111998 -2.02976004 1.13105 -2.02981004 0 P 0 ;0
L 1.13105 -2.02981004 1.13101004 -2.02983996 0 P 0 ;0
L 1.13101004 -2.02983996 1.13098002 -2.02986004 0 P 0 ;0
L 1.13098002 -2.02986004 1.12846998 -2.03188996 0 P 0 ;0
L 1.12846998 -2.03188996 1.12838002 -2.03198002 0 P 0 ;0
L 1.12838002 -2.03198002 1.12833996 -2.03201004 0 P 0 ;0
L 1.12833996 -2.03201004 1.12596004 -2.0343 0 P 0 ;0
L 1.12596004 -2.0343 1.12593996 -2.03433002 0 P 0 ;0
L 1.12593996 -2.03433002 1.1259 -2.03436004 0 P 0 ;0
L 1.1259 -2.03436004 1.12588002 -2.03438996 0 P 0 ;0
L 1.12588002 -2.03438996 1.12585 -2.03443002 0 P 0 ;0
L 1.12585 -2.03443002 1.12366998 -2.03691004 0 P 0 ;0
L 1.12366998 -2.03691004 1.12363996 -2.03695 0 P 0 ;0
L 1.12363996 -2.03695 1.12361998 -2.03698002 0 P 0 ;0
L 1.12361998 -2.03698002 1.12358996 -2.03701004 0 P 0 ;0
L 1.12358996 -2.03701004 1.12356998 -2.03703996 0 P 0 ;0
L 1.12356998 -2.03703996 1.12236998 -2.03865 0 P 0 ;0
L 1.12236998 -2.03865 1.12233996 -2.03868996 0 P 0 ;0
L 1.12233996 -2.03868996 1.12233002 -2.03871004 0 P 0 ;0
L 1.12233002 -2.03871004 1.12228996 -2.03878002 0 P 0 ;0
L 1.12228996 -2.03878002 1.12121004 -2.04046998 0 P 0 ;0
L 1.12121004 -2.04046998 1.12118996 -2.0405 0 P 0 ;0
L 1.12118996 -2.0405 1.12116998 -2.04053996 0 P 0 ;0
L 1.12116998 -2.04053996 1.12115 -2.04056998 0 P 0 ;0
L 1.12115 -2.04056998 1.12113996 -2.04061004 0 P 0 ;0
L 1.12113996 -2.04061004 1.12018996 -2.04238002 0 P 0 ;0
L 1.12018996 -2.04238002 1.12016004 -2.04245 0 P 0 ;0
L 1.12016004 -2.04245 1.12013996 -2.04248002 0 P 0 ;0
L 1.12013996 -2.04248002 1.12013002 -2.04251004 0 P 0 ;0
L 1.12013002 -2.04251004 1.11926004 -2.04446998 0 P 0 ;0
L 1.11926004 -2.04446998 1.11925 -2.0445 0 P 0 ;0
L 1.11925 -2.0445 1.11923002 -2.04453996 0 P 0 ;0
L 1.11923002 -2.04453996 1.11921998 -2.04458002 0 P 0 ;0
L 1.11921998 -2.04458002 1.11921004 -2.04461004 0 P 0 ;0
L 1.11921004 -2.04461004 1.11848002 -2.04663002 0 P 0 ;0
L 1.11848002 -2.04663002 1.11846998 -2.04666004 0 P 0 ;0
L 1.11846998 -2.04666004 1.11846004 -2.0467 0 P 0 ;0
L 1.11846004 -2.0467 1.11843996 -2.04676998 0 P 0 ;0
L 1.11843996 -2.04676998 1.11786004 -2.04883996 0 P 0 ;0
L 1.11786004 -2.04883996 1.11785 -2.04886998 0 P 0 ;0
L 1.11785 -2.04886998 1.11783996 -2.04891004 0 P 0 ;0
L 1.11783996 -2.04891004 1.11783996 -2.04893996 0 P 0 ;0
L 1.11783996 -2.04893996 1.11783002 -2.04896998 0 P 0 ;0
L 1.11783002 -2.04896998 1.11783002 -2.04898002 0 P 0 ;0
L 1.11783002 -2.04898002 1.1174 -2.05108002 0 P 0 ;0
L 1.1174 -2.05108002 1.1174 -2.05111998 0 P 0 ;0
L 1.1174 -2.05111998 1.11738996 -2.05116004 0 P 0 ;0
L 1.11738996 -2.05116004 1.11738002 -2.05118996 0 P 0 ;0
L 1.11738002 -2.05118996 1.11738002 -2.05123002 0 P 0 ;0
L 1.11738002 -2.05123002 1.11673002 -2.05643002 0 P 0 ;0
L 1.11673002 -2.05643002 1.11671998 -2.05646998 0 P 0 ;0
L 1.11671998 -2.05646998 1.11671998 -2.05655 0 P 0 ;0
L 1.11671998 -2.05655 1.11671004 -2.05658996 0 P 0 ;0
L 1.11671004 -2.05658996 1.11648996 -2.06181998 0 P 0 ;0
L 1.11648996 -2.06181998 1.11648002 -2.06186998 0 P 0 ;0
L 1.11648002 -2.06186998 1.11648002 -2.06195 0 P 0 ;0
L 1.11648002 -2.06195 1.11648996 -2.06198996 0 P 0 ;0
L 1.11648996 -2.06198996 1.11668002 -2.06696998 0 P 0 ;0
L 1.11668002 -2.06696998 1.11768002 -2.06696998 0 P 0 ;0
L 1.11768002 -2.06696998 1.11668002 -2.06701004 0 P 0 ;0
L 1.11668002 -2.06701004 1.11668002 -2.06713002 0 P 0 ;0
L 1.11668002 -2.06713002 1.11668996 -2.06716998 0 P 0 ;0
L 1.11668996 -2.06716998 1.11728002 -2.07215 0 P 0 ;0
L 1.11728002 -2.07215 1.11728996 -2.07218996 0 P 0 ;0
L 1.11728996 -2.07218996 1.11728996 -2.07223002 0 P 0 ;0
L 1.11728996 -2.07223002 1.11731004 -2.07231004 0 P 0 ;0
L 1.11731004 -2.07231004 1.11758996 -2.07371004 0 P 0 ;0
L 1.11758996 -2.07371004 1.1176 -2.07375 0 P 0 ;0
L 1.1176 -2.07375 1.11761004 -2.0738 0 P 0 ;0
L 1.11761004 -2.0738 1.11761998 -2.07383996 0 P 0 ;0
L 1.11761998 -2.07383996 1.11763996 -2.07388002 0 P 0 ;0
L 1.11763996 -2.07388002 1.11803996 -2.07523996 0 P 0 ;0
L 1.11803996 -2.07523996 1.11806004 -2.07531998 0 P 0 ;0
L 1.11806004 -2.07531998 1.11808002 -2.07536004 0 P 0 ;0
L 1.11808002 -2.07536004 1.11808996 -2.07541004 0 P 0 ;0
L 1.11808996 -2.07541004 1.11861004 -2.07673002 0 P 0 ;0
L 1.11861004 -2.07673002 1.11863996 -2.07681004 0 P 0 ;0
L 1.11863996 -2.07681004 1.11866004 -2.07683996 0 P 0 ;0
L 1.11866004 -2.07683996 1.11868002 -2.07688002 0 P 0 ;0
L 1.11868002 -2.07688002 1.11931004 -2.07815 0 P 0 ;0
L 1.11931004 -2.07815 1.11935 -2.07823002 0 P 0 ;0
L 1.11935 -2.07823002 1.1194 -2.0783 0 P 0 ;0
L 1.1194 -2.0783 1.12013996 -2.07951998 0 P 0 ;0
L 1.12013996 -2.07951998 1.12021004 -2.07961998 0 P 0 ;0
L 1.12021004 -2.07961998 1.12023002 -2.07965 0 P 0 ;0
L 1.12023002 -2.07965 1.12023002 -2.07966004 0 P 0 ;0
L 1.12023002 -2.07966004 1.1212 -2.08096998 0 P 0 ;0
L 1.1212 -2.08096998 1.12123996 -2.08103002 0 P 0 ;0
L 1.12123996 -2.08103002 1.12126998 -2.08106004 0 P 0 ;0
L 1.12126998 -2.08106004 1.12128996 -2.08108996 0 P 0 ;0
L 1.12128996 -2.08108996 1.12235 -2.08231004 0 P 0 ;0
L 1.12235 -2.08231004 1.12238002 -2.08233996 0 P 0 ;0
L 1.12238002 -2.08233996 1.1224 -2.08236998 0 P 0 ;0
L 1.1224 -2.08236998 1.12246004 -2.08243002 0 P 0 ;0
L 1.12246004 -2.08243002 1.12361004 -2.08355 0 P 0 ;0
L 1.12361004 -2.08355 1.12366998 -2.08361004 0 P 0 ;0
L 1.12366998 -2.08361004 1.1237 -2.08363002 0 P 0 ;0
L 1.1237 -2.08363002 1.12373002 -2.08366004 0 P 0 ;0
L 1.12373002 -2.08366004 1.12496998 -2.08468996 0 P 0 ;0
L 1.12496998 -2.08468996 1.125 -2.08471004 0 P 0 ;0
L 1.125 -2.08471004 1.12503002 -2.08473996 0 P 0 ;0
L 1.12503002 -2.08473996 1.12506998 -2.08476004 0 P 0 ;0
L 1.12506998 -2.08476004 1.1251 -2.08478996 0 P 0 ;0
L 1.1251 -2.08478996 1.12641998 -2.08571004 0 P 0 ;0
L 1.12641998 -2.08571004 1.12645 -2.08573002 0 P 0 ;0
L 1.12645 -2.08573002 1.12648002 -2.08576004 0 P 0 ;0
L 1.12648002 -2.08576004 1.12651004 -2.08578002 0 P 0 ;0
L 1.12651004 -2.08578002 1.12655 -2.0858 0 P 0 ;0
L 1.12655 -2.0858 1.12793996 -2.08661004 0 P 0 ;0
L 1.12793996 -2.08661004 1.12801004 -2.08665 0 P 0 ;0
L 1.12801004 -2.08665 1.12805 -2.08666998 0 P 0 ;0
L 1.12805 -2.08666998 1.12808002 -2.08668996 0 P 0 ;0
L 1.12808002 -2.08668996 1.12808996 -2.08668996 0 P 0 ;0
L 1.12808996 -2.08668996 1.12953996 -2.08738996 0 P 0 ;0
L 1.12953996 -2.08738996 1.12961998 -2.08743002 0 P 0 ;0
L 1.12961998 -2.08743002 1.12965 -2.08743996 0 P 0 ;0
L 1.12965 -2.08743996 1.1297 -2.08746004 0 P 0 ;0
L 1.1297 -2.08746004 1.13118002 -2.08801998 0 P 0 ;0
L 1.13118002 -2.08801998 1.13133996 -2.08808002 0 P 0 ;0
L 1.13133996 -2.08808002 1.13286998 -2.08851004 0 P 0 ;0
L 1.13286998 -2.08851004 1.13295 -2.08853996 0 P 0 ;0
L 1.13295 -2.08853996 1.13303996 -2.08855 0 P 0 ;0
L 1.13303996 -2.08855 1.1346 -2.08886004 0 P 0 ;0
L 1.1346 -2.08886004 1.13471998 -2.08888996 0 P 0 ;0
L 1.13471998 -2.08888996 1.13476004 -2.08888996 0 P 0 ;0
L 1.13476004 -2.08888996 1.13633996 -2.08906998 0 P 0 ;0
L 1.13633996 -2.08906998 1.13638996 -2.08908002 0 P 0 ;0
L 1.13638996 -2.08908002 1.13651004 -2.08908002 0 P 0 ;0
L 1.13651004 -2.08908002 1.1381 -2.08913002 0 P 0 ;0
L 1.1381 -2.08913002 1.13818996 -2.08913002 0 P 0 ;0
L 1.31623996 -1.98923996 1.3135 -1.98988002 0 P 0 ;0
L 1.3135 -1.98988002 1.31078996 -1.99071004 0 P 0 ;0
L 1.31078996 -1.99071004 1.30813002 -1.99175 0 P 0 ;0
L 1.30813002 -1.99175 1.30553996 -1.99296998 0 P 0 ;0
L 1.30553996 -1.99296998 1.30308996 -1.99431998 0 P 0 ;0
L 1.30308996 -1.99431998 1.30073996 -1.99585 0 P 0 ;0
L 1.30073996 -1.99585 1.29863996 -1.99746004 0 P 0 ;0
L 1.29863996 -1.99746004 1.29666004 -1.99923996 0 P 0 ;0
L 1.29666004 -1.99923996 1.29205 -2.00375 0 P 0 ;0
L 1.29205 -2.00375 1.29205 -1.99243996 0 P 0 ;0
L 1.29205 -1.99243996 1.24316004 -1.99243996 0 P 0 ;0
L 1.24316004 -1.99243996 1.24313996 -2.00521004 0 P 0 ;0
L 1.24313996 -2.00521004 1.24261004 -2.03151004 0 P 0 ;0
L 1.24261004 -2.03151004 1.24086998 -2.07046004 0 P 0 ;0
L 1.24086998 -2.07046004 1.23873996 -2.10921004 0 P 0 ;0
L 1.23873996 -2.10921004 1.23811998 -2.11641998 0 P 0 ;0
L 1.23811998 -2.11641998 1.23711998 -2.12361998 0 P 0 ;0
L 1.23711998 -2.12361998 1.23655 -2.12716004 0 P 0 ;0
L 1.23655 -2.12716004 1.29205 -2.12716004 0 P 0 ;0
L 1.29205 -2.12716004 1.29206998 -2.11766004 0 P 0 ;0
L 1.29206998 -2.11766004 1.29238996 -2.10283996 0 P 0 ;0
L 1.29238996 -2.10283996 1.29336004 -2.08431004 0 P 0 ;0
L 1.29336004 -2.08431004 1.29463996 -2.06673002 0 P 0 ;0
L 1.29463996 -2.06673002 1.29511004 -2.06253002 0 P 0 ;0
L 1.29511004 -2.06253002 1.29583996 -2.05836004 0 P 0 ;0
L 1.29583996 -2.05836004 1.29683002 -2.05446998 0 P 0 ;0
L 1.29683002 -2.05446998 1.29813996 -2.05068996 0 P 0 ;0
L 1.29813996 -2.05068996 1.29978002 -2.04701998 0 P 0 ;0
L 1.29978002 -2.04701998 1.30056998 -2.04556998 0 P 0 ;0
L 1.30056998 -2.04556998 1.30146998 -2.04418996 0 P 0 ;0
L 1.30146998 -2.04418996 1.30246998 -2.04288002 0 P 0 ;0
L 1.30246998 -2.04288002 1.30356998 -2.04165 0 P 0 ;0
L 1.30356998 -2.04165 1.30475 -2.0405 0 P 0 ;0
L 1.30475 -2.0405 1.30603996 -2.03945 0 P 0 ;0
L 1.30603996 -2.03945 1.30773996 -2.03826004 0 P 0 ;0
L 1.30773996 -2.03826004 1.30953002 -2.03723002 0 P 0 ;0
L 1.30953002 -2.03723002 1.31141004 -2.03635 0 P 0 ;0
L 1.31141004 -2.03635 1.31335 -2.03563002 0 P 0 ;0
L 1.31335 -2.03563002 1.31535 -2.03508002 0 P 0 ;0
L 1.31535 -2.03508002 1.31973996 -2.03423002 0 P 0 ;0
L 1.31973996 -2.03423002 1.32416004 -2.03366998 0 P 0 ;0
L 1.32416004 -2.03366998 1.32863002 -2.0334 0 P 0 ;0
L 1.32863002 -2.0334 1.33688002 -2.03318002 0 P 0 ;0
L 1.33688002 -2.03318002 1.33613002 -2.01151004 0 P 0 ;0
L 1.33613002 -2.01151004 1.33581004 -2.00315 0 P 0 ;0
L 1.33581004 -2.00315 1.33543996 -1.99596004 0 P 0 ;0
L 1.33543996 -1.99596004 1.33508002 -1.98971004 0 P 0 ;0
L 1.33508002 -1.98971004 1.33503996 -1.98945 0 P 0 ;0
L 1.33503996 -1.98945 1.335 -1.98931998 0 P 0 ;0
L 1.335 -1.98931998 1.33496004 -1.9892 0 P 0 ;0
L 1.33496004 -1.9892 1.3349 -1.98908002 0 P 0 ;0
L 1.3349 -1.98908002 1.33483996 -1.98896998 0 P 0 ;0
L 1.33483996 -1.98896998 1.33476998 -1.98886004 0 P 0 ;0
L 1.33476998 -1.98886004 1.33468996 -1.98876004 0 P 0 ;0
L 1.33468996 -1.98876004 1.3346 -1.98866998 0 P 0 ;0
L 1.3346 -1.98866998 1.33451004 -1.98858996 0 P 0 ;0
L 1.33451004 -1.98858996 1.3344 -1.98851998 0 P 0 ;0
L 1.3344 -1.98851998 1.3343 -1.98845 0 P 0 ;0
L 1.3343 -1.98845 1.33418002 -1.98838996 0 P 0 ;0
L 1.33418002 -1.98838996 1.33406998 -1.98833996 0 P 0 ;0
L 1.33406998 -1.98833996 1.33395 -1.9883 0 P 0 ;0
L 1.33395 -1.9883 1.33383002 -1.98828002 0 P 0 ;0
L 1.33383002 -1.98828002 1.3337 -1.98826004 0 P 0 ;0
L 1.3337 -1.98826004 1.33356998 -1.98825 0 P 0 ;0
L 1.33356998 -1.98825 1.32756998 -1.98823002 0 P 0 ;0
L 1.32756998 -1.98823002 1.32135 -1.98853996 0 P 0 ;0
L 1.32135 -1.98853996 1.31878996 -1.98881998 0 P 0 ;0
L 1.31878996 -1.98881998 1.31623996 -1.98923996 0 P 0 ;0
L 1.2389 -2.12516004 1.29006004 -2.12516004 0 P 0 ;0
L 1.23906998 -2.12416004 1.29006004 -2.12416004 0 P 0 ;0
L 1.23921004 -2.12316004 1.29006004 -2.12316004 0 P 0 ;0
L 1.23933996 -2.12216004 1.29006004 -2.12216004 0 P 0 ;0
L 1.23948996 -2.12116004 1.29006004 -2.12116004 0 P 0 ;0
L 1.23961998 -2.12016004 1.29006998 -2.12016004 0 P 0 ;0
L 1.23976004 -2.11916004 1.29006998 -2.11916004 0 P 0 ;0
L 1.2399 -2.11816004 1.29006998 -2.11816004 0 P 0 ;0
L 1.24003996 -2.11716004 1.29008002 -2.11716004 0 P 0 ;0
L 1.24015 -2.11616004 1.2901 -2.11616004 0 P 0 ;0
L 1.24023996 -2.11516004 1.29011998 -2.11516004 0 P 0 ;0
L 1.24033002 -2.11416004 1.29013996 -2.11416004 0 P 0 ;0
L 1.24041004 -2.11316004 1.29016004 -2.11316004 0 P 0 ;0
L 1.24048996 -2.11216004 1.29018996 -2.11216004 0 P 0 ;0
L 1.24058002 -2.11116004 1.29021004 -2.11116004 0 P 0 ;0
L 1.24066998 -2.11016004 1.29023002 -2.11016004 0 P 0 ;0
L 1.24075 -2.10916004 1.29025 -2.10916004 0 P 0 ;0
L 1.2408 -2.10816004 1.29026998 -2.10816004 0 P 0 ;0
L 1.24086004 -2.10716004 1.29028996 -2.10716004 0 P 0 ;0
L 1.24091004 -2.10616004 1.29031998 -2.10616004 0 P 0 ;0
L 1.24096998 -2.10516004 1.29033996 -2.10516004 0 P 0 ;0
L 1.24101998 -2.10416004 1.29036004 -2.10416004 0 P 0 ;0
L 1.24108002 -2.10316004 1.29038002 -2.10316004 0 P 0 ;0
L 1.24113002 -2.10216004 1.29041998 -2.10216004 0 P 0 ;0
L 1.24118002 -2.10116004 1.29046998 -2.10116004 0 P 0 ;0
L 1.24123996 -2.10016004 1.29053002 -2.10016004 0 P 0 ;0
L 1.24128996 -2.09916004 1.29058002 -2.09916004 0 P 0 ;0
L 1.24135 -2.09816004 1.29063002 -2.09816004 0 P 0 ;0
L 1.2414 -2.09716004 1.29068002 -2.09716004 0 P 0 ;0
L 1.24146004 -2.09616004 1.29073996 -2.09616004 0 P 0 ;0
L 1.24151004 -2.09516004 1.29078996 -2.09516004 0 P 0 ;0
L 1.24156998 -2.09416004 1.29083996 -2.09416004 0 P 0 ;0
L 1.24161998 -2.09316004 1.2909 -2.09316004 0 P 0 ;0
L 1.24168002 -2.09216004 1.29095 -2.09216004 0 P 0 ;0
L 1.24173002 -2.09116004 1.291 -2.09116004 0 P 0 ;0
L 1.24178996 -2.09016004 1.29105 -2.09016004 0 P 0 ;0
L 1.24183996 -2.08916004 1.2911 -2.08916004 0 P 0 ;0
L 1.2419 -2.08816004 1.29116004 -2.08816004 0 P 0 ;0
L 1.24196004 -2.08716004 1.29121004 -2.08716004 0 P 0 ;0
L 1.24201004 -2.08616004 1.29126998 -2.08616004 0 P 0 ;0
L 1.24206998 -2.08516004 1.29131998 -2.08516004 0 P 0 ;0
L 1.24211998 -2.08416004 1.29136998 -2.08416004 0 P 0 ;0
L 1.2389 -2.12516004 1.2391 -2.12393002 0 P 0 ;0
L 1.2391 -2.12393002 1.2391 -2.1239 0 P 0 ;0
L 1.2391 -2.1239 1.24011004 -2.11665 0 P 0 ;0
L 1.24011004 -2.11665 1.24073002 -2.10935 0 P 0 ;0
L 1.24073002 -2.10935 1.24073996 -2.10931998 0 P 0 ;0
L 1.24073996 -2.10931998 1.24286004 -2.07056004 0 P 0 ;0
L 1.24286004 -2.07056004 1.24461004 -2.03158002 0 P 0 ;0
L 1.24461004 -2.03158002 1.24513996 -2.00523002 0 P 0 ;0
L 1.24513996 -2.00523002 1.24515 -1.99443996 0 P 0 ;0
L 1.24515 -1.99443996 1.29005 -1.99443996 0 P 0 ;0
L 1.29005 -1.99443996 1.29005 -2.00375 0 P 0 ;0
L 1.29005 -2.00375 1.29128002 -2.0056 0 P 0 ;0
L 1.29128002 -2.0056 1.29345 -2.00518002 0 P 0 ;0
L 1.29345 -2.00518002 1.29803002 -2.0007 0 P 0 ;0
L 1.29803002 -2.0007 1.29991998 -1.999 0 P 0 ;0
L 1.29991998 -1.999 1.30188996 -1.99748996 0 P 0 ;0
L 1.30188996 -1.99748996 1.30411998 -1.99603996 0 P 0 ;0
L 1.30411998 -1.99603996 1.30645 -1.99475 0 P 0 ;0
L 1.30645 -1.99475 1.30891998 -1.99358996 0 P 0 ;0
L 1.30891998 -1.99358996 1.31145 -1.9926 0 P 0 ;0
L 1.31145 -1.9926 1.31401998 -1.99181004 0 P 0 ;0
L 1.31401998 -1.99181004 1.31663996 -1.9912 0 P 0 ;0
L 1.31663996 -1.9912 1.31906004 -1.9908 0 P 0 ;0
L 1.31906004 -1.9908 1.32151004 -1.99053002 0 P 0 ;0
L 1.32151004 -1.99053002 1.32761998 -1.99023002 0 P 0 ;0
L 1.32761998 -1.99023002 1.3331 -1.99025 0 P 0 ;0
L 1.3331 -1.99025 1.33345 -1.99608002 0 P 0 ;0
L 1.33345 -1.99608002 1.33381004 -2.00323002 0 P 0 ;0
L 1.33381004 -2.00323002 1.33413002 -2.01158996 0 P 0 ;0
L 1.33413002 -2.01158996 1.33413002 -2.0116 0 P 0 ;0
L 1.33413002 -2.0116 1.33481998 -2.03123002 0 P 0 ;0
L 1.33481998 -2.03123002 1.32853996 -2.0314 0 P 0 ;0
L 1.32853996 -2.0314 1.32398002 -2.03166998 0 P 0 ;0
L 1.32398002 -2.03166998 1.31941998 -2.03225 0 P 0 ;0
L 1.31941998 -2.03225 1.31488996 -2.03313002 0 P 0 ;0
L 1.31488996 -2.03313002 1.31273996 -2.03373002 0 P 0 ;0
L 1.31273996 -2.03373002 1.31063996 -2.0345 0 P 0 ;0
L 1.31063996 -2.0345 1.3086 -2.03545 0 P 0 ;0
L 1.3086 -2.03545 1.30666004 -2.03656998 0 P 0 ;0
L 1.30666004 -2.03656998 1.30658996 -2.03661998 0 P 0 ;0
L 1.30658996 -2.03661998 1.30483002 -2.03786004 0 P 0 ;0
L 1.30483002 -2.03786004 1.30341998 -2.03901004 0 P 0 ;0
L 1.30341998 -2.03901004 1.30336998 -2.03906004 0 P 0 ;0
L 1.30336998 -2.03906004 1.30211998 -2.04026004 0 P 0 ;0
L 1.30211998 -2.04026004 1.30093002 -2.0416 0 P 0 ;0
L 1.30093002 -2.0416 1.29983002 -2.04303996 0 P 0 ;0
L 1.29983002 -2.04303996 1.29978996 -2.0431 0 P 0 ;0
L 1.29978996 -2.0431 1.29885 -2.04453996 0 P 0 ;0
L 1.29885 -2.04453996 1.29798996 -2.04613002 0 P 0 ;0
L 1.29798996 -2.04613002 1.29631998 -2.04986998 0 P 0 ;0
L 1.29631998 -2.04986998 1.29628002 -2.04995 0 P 0 ;0
L 1.29628002 -2.04995 1.29625 -2.05003002 0 P 0 ;0
L 1.29625 -2.05003002 1.29491998 -2.0539 0 P 0 ;0
L 1.29491998 -2.0539 1.29388996 -2.05793996 0 P 0 ;0
L 1.29388996 -2.05793996 1.29386998 -2.05801998 0 P 0 ;0
L 1.29386998 -2.05801998 1.29313996 -2.06221004 0 P 0 ;0
L 1.29313996 -2.06221004 1.29313002 -2.06223996 0 P 0 ;0
L 1.29313002 -2.06223996 1.29311998 -2.0623 0 P 0 ;0
L 1.29311998 -2.0623 1.29265 -2.06655 0 P 0 ;0
L 1.29265 -2.06655 1.29136998 -2.08418996 0 P 0 ;0
L 1.29136998 -2.08418996 1.29038996 -2.10276998 0 P 0 ;0
L 1.29038996 -2.10276998 1.29006998 -2.11763002 0 P 0 ;0
L 1.29006998 -2.11763002 1.29006004 -2.12516004 0 P 0 ;0
L 1.29006004 -2.12516004 1.2389 -2.12516004 0 P 0 ;0
L 1.09846998 -2.00483002 1.21248002 -2.00483002 0 P 0 ;0
L 1.09838002 -2.12083002 1.14708002 -2.12083002 0 P 0 ;0
L 1.11933002 -2.18283002 1.15161998 -2.18283002 0 P 0 ;0
L 1.11001998 -2.18183002 1.15838002 -2.18183002 0 P 0 ;0
L 1.10246998 -2.18083002 1.16333996 -2.18083002 0 P 0 ;0
L 1.04061004 -1.89731004 1.09978002 -1.89731004 0 P 0 ;0
L 1.03565 -1.89631004 1.09821004 -1.89631004 0 P 0 ;0
L 1.03068996 -1.89531004 1.09661004 -1.89531004 0 P 0 ;0
L 1.02573002 -1.89431004 1.09475 -1.89431004 0 P 0 ;0
L 1.019 -1.89331004 1.09288002 -1.89331004 0 P 0 ;0
L 1.01163996 -1.89231004 1.09101998 -1.89231004 0 P 0 ;0
L 0.99518996 -1.89131004 1.08916004 -1.89131004 0 P 0 ;0
L 0.87011998 -1.88331004 1.07278996 -1.88331004 0 P 0 ;0
L 0.86963996 -1.88231004 1.07053002 -1.88231004 0 P 0 ;0
L 0.86916004 -1.88131004 1.06828002 -1.88131004 0 P 0 ;0
L 0.86863002 -1.88031004 1.06603002 -1.88031004 0 P 0 ;0
L 0.86806998 -1.87931004 1.06351004 -1.87931004 0 P 0 ;0
L 0.8675 -1.87831004 1.06076998 -1.87831004 0 P 0 ;0
L 0.86693002 -1.87731004 1.05803996 -1.87731004 0 P 0 ;0
L 0.86631004 -1.87631004 1.05531004 -1.87631004 0 P 0 ;0
L 0.86563996 -1.87531004 1.05256998 -1.87531004 0 P 0 ;0
L 0.86498002 -1.87431004 1.04983996 -1.87431004 0 P 0 ;0
L 0.86431998 -1.87331004 1.0471 -1.87331004 0 P 0 ;0
L 0.86356004 -1.87231004 1.04376004 -1.87231004 0 P 0 ;0
L 0.86278996 -1.87131004 1.04041998 -1.87131004 0 P 0 ;0
L 0.86203002 -1.87031004 1.03708002 -1.87031004 0 P 0 ;0
L 0.86118996 -1.86931004 1.03373996 -1.86931004 0 P 0 ;0
L 0.8603 -1.86831004 1.0304 -1.86831004 0 P 0 ;0
L 0.85941004 -1.86731004 1.02656998 -1.86731004 0 P 0 ;0
L 0.8585 -1.86631004 1.02231998 -1.86631004 0 P 0 ;0
L 0.85756998 -1.86531004 1.01806998 -1.86531004 0 P 0 ;0
L 0.85663002 -1.86431004 1.01381998 -1.86431004 0 P 0 ;0
L 0.85568996 -1.86331004 1.00931998 -1.86331004 0 P 0 ;0
L 0.85481004 -1.86231004 1.00335 -1.86231004 0 P 0 ;0
L 0.85916998 -1.86131004 0.99738002 -1.86131004 0 P 0 ;0
L 0.86716998 -1.86031004 0.99141998 -1.86031004 0 P 0 ;0
L 0.87476998 -1.89731004 0.89943002 -1.89731004 0 P 0 ;0
L 0.87453996 -1.89631004 0.90426004 -1.89631004 0 P 0 ;0
L 0.87431004 -1.89531004 0.9097 -1.89531004 0 P 0 ;0
L 0.87406998 -1.89431004 0.91608002 -1.89431004 0 P 0 ;0
L 0.87383002 -1.89331004 0.92246004 -1.89331004 0 P 0 ;0
L 0.87355 -1.89231004 0.93086004 -1.89231004 0 P 0 ;0
L 0.87323002 -1.89131004 0.95553002 -1.89131004 0 P 0 ;0
L 0.87291004 -1.89031004 1.08728996 -1.89031004 0 P 0 ;0
L 0.87258996 -1.88931004 1.08543002 -1.88931004 0 P 0 ;0
L 0.87223002 -1.88831004 1.08356998 -1.88831004 0 P 0 ;0
L 0.87183002 -1.88731004 1.0817 -1.88731004 0 P 0 ;0
L 0.87143002 -1.88631004 1.07955 -1.88631004 0 P 0 ;0
L 0.87103002 -1.88531004 1.07728996 -1.88531004 0 P 0 ;0
L 0.8706 -1.88431004 1.07503996 -1.88431004 0 P 0 ;0
L 0.87525 -1.85931004 0.98545 -1.85931004 0 P 0 ;0
L 0.88421004 -1.85831004 0.97621004 -1.85831004 0 P 0 ;0
L 0.89393002 -1.85731004 0.96606998 -1.85731004 0 P 0 ;0
L 0.9106 -1.85631004 0.95203002 -1.85631004 0 P 0 ;0
L 1.08716004 -1.91231004 1.12151004 -1.91231004 0 P 0 ;0
L 1.08486004 -1.91131004 1.12018996 -1.91131004 0 P 0 ;0
L 1.08256004 -1.91031004 1.11886004 -1.91031004 0 P 0 ;0
L 1.08023002 -1.90931004 1.11753996 -1.90931004 0 P 0 ;0
L 1.07738002 -1.90831004 1.11621004 -1.90831004 0 P 0 ;0
L 1.07453002 -1.90731004 1.11488996 -1.90731004 0 P 0 ;0
L 1.07168996 -1.90631004 1.11356998 -1.90631004 0 P 0 ;0
L 1.06883996 -1.90531004 1.11223996 -1.90531004 0 P 0 ;0
L 1.066 -1.90431004 1.11076998 -1.90431004 0 P 0 ;0
L 1.06315 -1.90331004 1.1092 -1.90331004 0 P 0 ;0
L 1.0599 -1.90231004 1.10763002 -1.90231004 0 P 0 ;0
L 1.05611998 -1.90131004 1.10606004 -1.90131004 0 P 0 ;0
L 1.05235 -1.90031004 1.10448996 -1.90031004 0 P 0 ;0
L 1.04856998 -1.89931004 1.10291998 -1.89931004 0 P 0 ;0
L 1.04478996 -1.89831004 1.10135 -1.89831004 0 P 0 ;0
L 0.98815 -2.08316004 1.03726998 -2.08316004 0 P 0 ;0
L 0.98818002 -2.08216004 1.03731004 -2.08216004 0 P 0 ;0
L 0.98821998 -2.08116004 1.03735 -2.08116004 0 P 0 ;0
L 0.98825 -2.08016004 1.03738996 -2.08016004 0 P 0 ;0
L 0.98828002 -2.07916004 1.03743002 -2.07916004 0 P 0 ;0
L 0.98831998 -2.07816004 1.03746998 -2.07816004 0 P 0 ;0
L 0.98835 -2.07716004 1.03751004 -2.07716004 0 P 0 ;0
L 0.98838002 -2.07616004 1.03755 -2.07616004 0 P 0 ;0
L 0.98841998 -2.07516004 1.03758002 -2.07516004 0 P 0 ;0
L 0.98845 -2.07416004 1.03761004 -2.07416004 0 P 0 ;0
L 0.98848002 -2.07316004 1.03763996 -2.07316004 0 P 0 ;0
L 0.98851004 -2.07216004 1.03768002 -2.07216004 0 P 0 ;0
L 0.98855 -2.07116004 1.03771004 -2.07116004 0 P 0 ;0
L 0.98858002 -2.07016004 1.03773996 -2.07016004 0 P 0 ;0
L 0.98858996 -2.06916004 1.03776998 -2.06916004 0 P 0 ;0
L 0.98858996 -2.06816004 1.0378 -2.06816004 0 P 0 ;0
L 0.98858996 -2.06716004 1.03783002 -2.06716004 0 P 0 ;0
L 0.98858002 -2.06616004 1.03786004 -2.06616004 0 P 0 ;0
L 0.98856998 -2.06516004 1.0379 -2.06516004 0 P 0 ;0
L 0.98856998 -2.06416004 1.03793002 -2.06416004 0 P 0 ;0
L 0.98856998 -2.06316004 1.03796004 -2.06316004 0 P 0 ;0
L 0.98856004 -2.06216004 1.03798996 -2.06216004 0 P 0 ;0
L 0.98855 -2.06116004 1.03801998 -2.06116004 0 P 0 ;0
L 0.98855 -2.06016004 1.03805 -2.06016004 0 P 0 ;0
L 0.98853996 -2.05916004 1.03808002 -2.05916004 0 P 0 ;0
L 0.98853996 -2.05816004 1.0381 -2.05816004 0 P 0 ;0
L 0.98853002 -2.05716004 1.03811998 -2.05716004 0 P 0 ;0
L 0.98848002 -2.05616004 1.03815 -2.05616004 0 P 0 ;0
L 0.98841004 -2.05516004 1.03818002 -2.05516004 0 P 0 ;0
L 0.98835 -2.05416004 1.0382 -2.05416004 0 P 0 ;0
L 0.98828002 -2.05316004 1.03821998 -2.05316004 0 P 0 ;0
L 0.98821004 -2.05216004 1.03825 -2.05216004 0 P 0 ;0
L 0.98815 -2.05116004 1.03826998 -2.05116004 0 P 0 ;0
L 0.98808996 -2.05016004 1.03828996 -2.05016004 0 P 0 ;0
L 0.98801998 -2.04916004 1.03831998 -2.04916004 0 P 0 ;0
L 0.98796004 -2.04816004 1.03833996 -2.04816004 0 P 0 ;0
L 0.98788996 -2.04716004 1.03836004 -2.04716004 0 P 0 ;0
L 0.98783002 -2.04616004 1.03838996 -2.04616004 0 P 0 ;0
L 0.98768996 -2.04516004 1.0384 -2.04516004 0 P 0 ;0
L 0.98756004 -2.04416004 1.03841004 -2.04416004 0 P 0 ;0
L 0.98738002 -2.04316004 1.03841998 -2.04316004 0 P 0 ;0
L 0.98716004 -2.04216004 1.03843002 -2.04216004 0 P 0 ;0
L 0.98691998 -2.04116004 1.03843996 -2.04116004 0 P 0 ;0
L 0.98661998 -2.04016004 1.03845 -2.04016004 0 P 0 ;0
L 0.98631998 -2.03916004 1.03846004 -2.03916004 0 P 0 ;0
L 0.98593996 -2.03816004 1.03846998 -2.03816004 0 P 0 ;0
L 0.98546998 -2.03716004 1.03848002 -2.03716004 0 P 0 ;0
L 0.98491004 -2.03616004 1.03846998 -2.03616004 0 P 0 ;0
L 0.98425 -2.03516004 1.03846004 -2.03516004 0 P 0 ;0
L 0.98346004 -2.03416004 1.03846004 -2.03416004 0 P 0 ;0
L 0.98251998 -2.03316004 1.03843996 -2.03316004 0 P 0 ;0
L 0.98138002 -2.03216004 1.03843002 -2.03216004 0 P 0 ;0
L 0.97998996 -2.03116004 1.03841998 -2.03116004 0 P 0 ;0
L 0.97813996 -2.03016004 1.03841004 -2.03016004 0 P 0 ;0
L 0.97491004 -2.02916004 1.0384 -2.02916004 0 P 0 ;0
L 0.94763996 -2.00716004 1.03293996 -2.00716004 0 P 0 ;0
L 0.94978996 -2.00616004 1.03231998 -2.00616004 0 P 0 ;0
L 0.95081004 -2.00516004 1.0317 -2.00516004 0 P 0 ;0
L 0.95183002 -2.00416004 1.03098002 -2.00416004 0 P 0 ;0
L 0.95285 -2.00316004 1.03023002 -2.00316004 0 P 0 ;0
L 0.95388996 -2.00216004 1.02936004 -2.00216004 0 P 0 ;0
L 0.95498002 -2.00116004 1.02841998 -2.00116004 0 P 0 ;0
L 0.95621998 -2.00016004 1.02738996 -2.00016004 0 P 0 ;0
L 0.95761998 -1.99916004 1.0262 -1.99916004 0 P 0 ;0
L 0.9592 -1.99816004 1.02486004 -1.99816004 0 P 0 ;0
L 0.96083996 -1.99716004 1.02335 -1.99716004 0 P 0 ;0
L 0.9627 -1.99616004 1.02161004 -1.99616004 0 P 0 ;0
L 0.96468996 -1.99516004 1.01951998 -1.99516004 0 P 0 ;0
L 0.96685 -1.99416004 1.01683002 -1.99416004 0 P 0 ;0
L 0.96936998 -1.99316004 1.01378002 -1.99316004 0 P 0 ;0
L 0.97236998 -1.99216004 1.00981004 -1.99216004 0 P 0 ;0
L 0.97676004 -1.99116004 1.00456998 -1.99116004 0 P 0 ;0
L 1.06713996 -2.08283002 1.12288002 -2.08283002 0 P 0 ;0
L 1.06698996 -2.08183002 1.12193996 -2.08183002 0 P 0 ;0
L 1.06686004 -2.08083002 1.12108996 -2.08083002 0 P 0 ;0
L 1.06673996 -2.07983002 1.12036004 -2.07983002 0 P 0 ;0
L 1.06661998 -2.07883002 1.11971998 -2.07883002 0 P 0 ;0
L 1.06653002 -2.07783002 1.11916004 -2.07783002 0 P 0 ;0
L 1.06648002 -2.07683002 1.11866004 -2.07683002 0 P 0 ;0
L 1.06641998 -2.07583002 1.11826004 -2.07583002 0 P 0 ;0
L 1.06636998 -2.07483002 1.11791998 -2.07483002 0 P 0 ;0
L 1.06631998 -2.07383002 1.11761998 -2.07383002 0 P 0 ;0
L 1.06626004 -2.07283002 1.11741998 -2.07283002 0 P 0 ;0
L 1.06621004 -2.07183002 1.11723996 -2.07183002 0 P 0 ;0
L 1.06616004 -2.07083002 1.11711998 -2.07083002 0 P 0 ;0
L 1.06616004 -2.06983002 1.11701004 -2.06983002 0 P 0 ;0
L 1.06616004 -2.06883002 1.11688996 -2.06883002 0 P 0 ;0
L 1.06616998 -2.06783002 1.11676998 -2.06783002 0 P 0 ;0
L 1.06618002 -2.06683002 1.11666998 -2.06683002 0 P 0 ;0
L 1.06618996 -2.06583002 1.11663002 -2.06583002 0 P 0 ;0
L 1.0662 -2.06483002 1.11658996 -2.06483002 0 P 0 ;0
L 1.06621004 -2.06383002 1.11656004 -2.06383002 0 P 0 ;0
L 1.06623002 -2.06283002 1.11651998 -2.06283002 0 P 0 ;0
L 1.06631004 -2.06183002 1.11648996 -2.06183002 0 P 0 ;0
L 1.06638002 -2.06083002 1.11653002 -2.06083002 0 P 0 ;0
L 1.06645 -2.05983002 1.11656998 -2.05983002 0 P 0 ;0
L 1.06651998 -2.05883002 1.11661998 -2.05883002 0 P 0 ;0
L 1.06658996 -2.05783002 1.11666004 -2.05783002 0 P 0 ;0
L 1.06666998 -2.05683002 1.11671004 -2.05683002 0 P 0 ;0
L 1.06673996 -2.05583002 1.11681004 -2.05583002 0 P 0 ;0
L 1.06686004 -2.05483002 1.11693002 -2.05483002 0 P 0 ;0
L 1.067 -2.05383002 1.11705 -2.05383002 0 P 0 ;0
L 1.06713996 -2.05283002 1.11718002 -2.05283002 0 P 0 ;0
L 1.06728002 -2.05183002 1.11731004 -2.05183002 0 P 0 ;0
L 1.06741998 -2.05083002 1.11746004 -2.05083002 0 P 0 ;0
L 1.06756004 -2.04983002 1.11766004 -2.04983002 0 P 0 ;0
L 1.0677 -2.04883002 1.11786004 -2.04883002 0 P 0 ;0
L 1.06786004 -2.04783002 1.11813996 -2.04783002 0 P 0 ;0
L 1.06806998 -2.04683002 1.11841998 -2.04683002 0 P 0 ;0
L 1.06828002 -2.04583002 1.11876998 -2.04583002 0 P 0 ;0
L 1.06848996 -2.04483002 1.11913002 -2.04483002 0 P 0 ;0
L 1.06871004 -2.04383002 1.11955 -2.04383002 0 P 0 ;0
L 1.06898996 -2.04283002 1.11998996 -2.04283002 0 P 0 ;0
L 1.06928002 -2.04183002 1.12048002 -2.04183002 0 P 0 ;0
L 1.06956004 -2.04083002 1.12101004 -2.04083002 0 P 0 ;0
L 1.06985 -2.03983002 1.12161998 -2.03983002 0 P 0 ;0
L 1.07021004 -2.03883002 1.12225 -2.03883002 0 P 0 ;0
L 1.07056998 -2.03783002 1.12298002 -2.03783002 0 P 0 ;0
L 1.07093002 -2.03683002 1.12373996 -2.03683002 0 P 0 ;0
L 1.07128996 -2.03583002 1.12461998 -2.03583002 0 P 0 ;0
L 1.07173002 -2.03483002 1.12548996 -2.03483002 0 P 0 ;0
L 1.07216998 -2.03383002 1.12646004 -2.03383002 0 P 0 ;0
L 1.07261998 -2.03283002 1.12748996 -2.03283002 0 P 0 ;0
L 1.07308002 -2.03183002 1.12855 -2.03183002 0 P 0 ;0
L 1.07361998 -2.03083002 1.12978996 -2.03083002 0 P 0 ;0
L 1.09761004 -1.91731004 1.12756998 -1.91731004 0 P 0 ;0
L 1.09566004 -1.91631004 1.12645 -1.91631004 0 P 0 ;0
L 1.09371004 -1.91531004 1.12533002 -1.91531004 0 P 0 ;0
L 1.09176004 -1.91431004 1.12416004 -1.91431004 0 P 0 ;0
L 1.08946004 -1.91331004 1.12283996 -1.91331004 0 P 0 ;0
L 1.07415 -2.02983002 1.13101998 -2.02983002 0 P 0 ;0
L 1.07468996 -2.02883002 1.13248996 -2.02883002 0 P 0 ;0
L 1.07528996 -2.02783002 1.134 -2.02783002 0 P 0 ;0
L 1.07591998 -2.02683002 1.13586004 -2.02683002 0 P 0 ;0
L 1.07656004 -2.02583002 1.13828996 -2.02583002 0 P 0 ;0
L 1.07721004 -2.02483002 1.14243002 -2.02483002 0 P 0 ;0
L 1.07795 -2.02383002 1.21126998 -2.02383002 0 P 0 ;0
L 1.07868002 -2.02283002 1.21133002 -2.02283002 0 P 0 ;0
L 1.07941998 -2.02183002 1.2114 -2.02183002 0 P 0 ;0
L 1.08021004 -2.02083002 1.21146004 -2.02083002 0 P 0 ;0
L 1.08103996 -2.01983002 1.21153002 -2.01983002 0 P 0 ;0
L 1.08186998 -2.01883002 1.2116 -2.01883002 0 P 0 ;0
L 1.08273002 -2.01783002 1.21166004 -2.01783002 0 P 0 ;0
L 1.08366998 -2.01683002 1.21173002 -2.01683002 0 P 0 ;0
L 1.0846 -2.01583002 1.2118 -2.01583002 0 P 0 ;0
L 1.08555 -2.01483002 1.21186004 -2.01483002 0 P 0 ;0
L 1.08661004 -2.01383002 1.21193002 -2.01383002 0 P 0 ;0
L 1.08766998 -2.01283002 1.21198996 -2.01283002 0 P 0 ;0
L 1.08873002 -2.01183002 1.21205 -2.01183002 0 P 0 ;0
L 1.0898 -2.01083002 1.21211998 -2.01083002 0 P 0 ;0
L 1.09098996 -2.00983002 1.21218002 -2.00983002 0 P 0 ;0
L 1.09225 -2.00883002 1.21223996 -2.00883002 0 P 0 ;0
L 1.09358996 -2.00783002 1.2123 -2.00783002 0 P 0 ;0
L 1.09506998 -2.00683002 1.21236004 -2.00683002 0 P 0 ;0
L 1.09668996 -2.00583002 1.21241998 -2.00583002 0 P 0 ;0
L 0.98546998 -2.12516004 1.03548996 -2.12516004 0 P 0 ;0
L 0.98558996 -2.12416004 1.03553996 -2.12416004 0 P 0 ;0
L 0.9857 -2.12316004 1.03558002 -2.12316004 0 P 0 ;0
L 0.98581004 -2.12216004 1.03561998 -2.12216004 0 P 0 ;0
L 0.98591004 -2.12116004 1.03566998 -2.12116004 0 P 0 ;0
L 0.98598996 -2.12016004 1.03571004 -2.12016004 0 P 0 ;0
L 0.98608002 -2.11916004 1.03575 -2.11916004 0 P 0 ;0
L 0.98616998 -2.11816004 1.0358 -2.11816004 0 P 0 ;0
L 0.98625 -2.11716004 1.03583996 -2.11716004 0 P 0 ;0
L 0.98633996 -2.11616004 1.03588002 -2.11616004 0 P 0 ;0
L 0.98641998 -2.11516004 1.03593002 -2.11516004 0 P 0 ;0
L 0.98651004 -2.11416004 1.03596998 -2.11416004 0 P 0 ;0
L 0.9866 -2.11316004 1.03601004 -2.11316004 0 P 0 ;0
L 0.98668002 -2.11216004 1.03605 -2.11216004 0 P 0 ;0
L 0.98676998 -2.11116004 1.0361 -2.11116004 0 P 0 ;0
L 0.98685 -2.11016004 1.03613996 -2.11016004 0 P 0 ;0
L 0.98693996 -2.10916004 1.03618002 -2.10916004 0 P 0 ;0
L 0.987 -2.10816004 1.03623002 -2.10816004 0 P 0 ;0
L 0.98705 -2.10716004 1.03626998 -2.10716004 0 P 0 ;0
L 0.9871 -2.10616004 1.03631004 -2.10616004 0 P 0 ;0
L 0.98716004 -2.10516004 1.03636004 -2.10516004 0 P 0 ;0
L 0.9872 -2.10416004 1.0364 -2.10416004 0 P 0 ;0
L 0.98725 -2.10316004 1.03643996 -2.10316004 0 P 0 ;0
L 0.98731004 -2.10216004 1.03648002 -2.10216004 0 P 0 ;0
L 0.98735 -2.10116004 1.03653002 -2.10116004 0 P 0 ;0
L 0.9874 -2.10016004 1.03656998 -2.10016004 0 P 0 ;0
L 0.98746004 -2.09916004 1.03661004 -2.09916004 0 P 0 ;0
L 0.98751004 -2.09816004 1.03666004 -2.09816004 0 P 0 ;0
L 0.98755 -2.09716004 1.0367 -2.09716004 0 P 0 ;0
L 0.9876 -2.09616004 1.03673996 -2.09616004 0 P 0 ;0
L 0.98766004 -2.09516004 1.03678996 -2.09516004 0 P 0 ;0
L 0.9877 -2.09416004 1.03683002 -2.09416004 0 P 0 ;0
L 0.98775 -2.09316004 1.03686998 -2.09316004 0 P 0 ;0
L 0.98781004 -2.09216004 1.03691998 -2.09216004 0 P 0 ;0
L 0.98785 -2.09116004 1.03696004 -2.09116004 0 P 0 ;0
L 0.9879 -2.09016004 1.037 -2.09016004 0 P 0 ;0
L 0.98796004 -2.08916004 1.03703996 -2.08916004 0 P 0 ;0
L 0.98798996 -2.08816004 1.03706998 -2.08816004 0 P 0 ;0
L 0.98801998 -2.08716004 1.03711004 -2.08716004 0 P 0 ;0
L 0.98805 -2.08616004 1.03715 -2.08616004 0 P 0 ;0
L 0.98808996 -2.08516004 1.03718996 -2.08516004 0 P 0 ;0
L 0.98811998 -2.08416004 1.03723002 -2.08416004 0 P 0 ;0
L 1.08216998 -2.15683002 1.19803996 -2.15683002 0 P 0 ;0
L 1.0821 -2.15583002 1.19861004 -2.15583002 0 P 0 ;0
L 1.08201998 -2.15483002 1.19918002 -2.15483002 0 P 0 ;0
L 1.08195 -2.15383002 1.1997 -2.15383002 0 P 0 ;0
L 1.08188996 -2.15283002 1.20018002 -2.15283002 0 P 0 ;0
L 1.08183002 -2.15183002 1.20066004 -2.15183002 0 P 0 ;0
L 1.08176998 -2.15083002 1.20113996 -2.15083002 0 P 0 ;0
L 1.08171998 -2.14983002 1.20153996 -2.14983002 0 P 0 ;0
L 1.08166004 -2.14883002 1.20193002 -2.14883002 0 P 0 ;0
L 1.0816 -2.14783002 1.11538996 -2.14783002 0 P 0 ;0
L 1.08155 -2.14683002 1.10903002 -2.14683002 0 P 0 ;0
L 1.0815 -2.14583002 1.10415 -2.14583002 0 P 0 ;0
L 1.08146004 -2.14483002 1.09953002 -2.14483002 0 P 0 ;0
L 1.08141004 -2.14383002 1.09563996 -2.14383002 0 P 0 ;0
L 1.08136004 -2.14283002 1.09183996 -2.14283002 0 P 0 ;0
L 1.08131004 -2.14183002 1.08821004 -2.14183002 0 P 0 ;0
L 1.08133002 -2.14083002 1.08471998 -2.14083002 0 P 0 ;0
L 1.09586998 -2.11983002 1.14965 -2.11983002 0 P 0 ;0
L 1.09361998 -2.11883002 1.15221998 -2.11883002 0 P 0 ;0
L 1.09158996 -2.11783002 1.20595 -2.11783002 0 P 0 ;0
L 1.08988002 -2.11683002 1.20601004 -2.11683002 0 P 0 ;0
L 1.08823996 -2.11583002 1.20606998 -2.11583002 0 P 0 ;0
L 1.08678996 -2.11483002 1.20613002 -2.11483002 0 P 0 ;0
L 1.08541004 -2.11383002 1.20618996 -2.11383002 0 P 0 ;0
L 1.08416998 -2.11283002 1.20625 -2.11283002 0 P 0 ;0
L 1.08295 -2.11183002 1.20631004 -2.11183002 0 P 0 ;0
L 1.08188002 -2.11083002 1.20638002 -2.11083002 0 P 0 ;0
L 1.08081998 -2.10983002 1.20643996 -2.10983002 0 P 0 ;0
L 1.07986004 -2.10883002 1.2065 -2.10883002 0 P 0 ;0
L 1.07895 -2.10783002 1.20656004 -2.10783002 0 P 0 ;0
L 1.07803002 -2.10683002 1.20661998 -2.10683002 0 P 0 ;0
L 1.07723996 -2.10583002 1.20666998 -2.10583002 0 P 0 ;0
L 1.07646004 -2.10483002 1.20671998 -2.10483002 0 P 0 ;0
L 1.07568002 -2.10383002 1.20678002 -2.10383002 0 P 0 ;0
L 1.075 -2.10283002 1.20683002 -2.10283002 0 P 0 ;0
L 1.07433002 -2.10183002 1.20688002 -2.10183002 0 P 0 ;0
L 1.07366998 -2.10083002 1.20693996 -2.10083002 0 P 0 ;0
L 1.07308996 -2.09983002 1.20698996 -2.09983002 0 P 0 ;0
L 1.07253002 -2.09883002 1.20705 -2.09883002 0 P 0 ;0
L 1.07198002 -2.09783002 1.2071 -2.09783002 0 P 0 ;0
L 1.07146998 -2.09683002 1.20715 -2.09683002 0 P 0 ;0
L 1.07101998 -2.09583002 1.2072 -2.09583002 0 P 0 ;0
L 1.07056998 -2.09483002 1.20726004 -2.09483002 0 P 0 ;0
L 1.07013002 -2.09383002 1.20731004 -2.09383002 0 P 0 ;0
L 1.06976998 -2.09283002 1.20736004 -2.09283002 0 P 0 ;0
L 1.06941998 -2.09183002 1.20741998 -2.09183002 0 P 0 ;0
L 1.06906004 -2.09083002 1.20746998 -2.09083002 0 P 0 ;0
L 1.06876004 -2.08983002 1.20753002 -2.08983002 0 P 0 ;0
L 1.06848996 -2.08883002 1.13443002 -2.08883002 0 P 0 ;0
L 1.06821998 -2.08783002 1.13068002 -2.08783002 0 P 0 ;0
L 1.06795 -2.08683002 1.12836998 -2.08683002 0 P 0 ;0
L 1.06771998 -2.08583002 1.1266 -2.08583002 0 P 0 ;0
L 1.06753002 -2.08483002 1.12516004 -2.08483002 0 P 0 ;0
L 1.06733002 -2.08383002 1.12393996 -2.08383002 0 P 0 ;0
L 0.90273996 -1.85456998 0.89068996 -1.85558002 0 P 0 ;0
L 0.89068996 -1.85558002 0.87421004 -1.85741998 0 P 0 ;0
L 0.87421004 -1.85741998 0.85783002 -1.85946998 0 P 0 ;0
L 0.85783002 -1.85946998 0.85526998 -1.8599 0 P 0 ;0
L 0.85526998 -1.8599 0.85276004 -1.86055 0 P 0 ;0
L 0.85276004 -1.86055 0.85255 -1.86063996 0 P 0 ;0
L 0.85255 -1.86063996 0.85248996 -1.86068996 0 P 0 ;0
L 0.85248996 -1.86068996 0.85243002 -1.86073002 0 P 0 ;0
L 0.85243002 -1.86073002 0.85238002 -1.86078002 0 P 0 ;0
L 0.85238002 -1.86078002 0.85233002 -1.86083996 0 P 0 ;0
L 0.85233002 -1.86083996 0.85225 -1.86096004 0 P 0 ;0
L 0.85225 -1.86096004 0.85218002 -1.8611 0 P 0 ;0
L 0.85218002 -1.8611 0.85216004 -1.86116998 0 P 0 ;0
L 0.85216004 -1.86116998 0.85215 -1.86123996 0 P 0 ;0
L 0.85215 -1.86123996 0.85213996 -1.86136998 0 P 0 ;0
L 0.85213996 -1.86136998 0.85213002 -1.86148996 0 P 0 ;0
L 0.85213002 -1.86148996 0.85213996 -1.86161998 0 P 0 ;0
L 0.85213996 -1.86161998 0.85215 -1.86173996 0 P 0 ;0
L 0.85215 -1.86173996 0.85218002 -1.86186998 0 P 0 ;0
L 0.85218002 -1.86186998 0.85221004 -1.86198996 0 P 0 ;0
L 0.85221004 -1.86198996 0.85225 -1.8621 0 P 0 ;0
L 0.85225 -1.8621 0.85231004 -1.86221998 0 P 0 ;0
L 0.85231004 -1.86221998 0.85236998 -1.86233002 0 P 0 ;0
L 0.85236998 -1.86233002 0.85281998 -1.863 0 P 0 ;0
L 0.85281998 -1.863 0.8533 -1.86363996 0 P 0 ;0
L 0.8533 -1.86363996 0.85383002 -1.86425 0 P 0 ;0
L 0.85383002 -1.86425 0.85736004 -1.86801998 0 P 0 ;0
L 0.85736004 -1.86801998 0.86013002 -1.87113002 0 P 0 ;0
L 0.86013002 -1.87113002 0.86266004 -1.87443002 0 P 0 ;0
L 0.86266004 -1.87443002 0.86501004 -1.87798996 0 P 0 ;0
L 0.86501004 -1.87798996 0.86711998 -1.88171004 0 P 0 ;0
L 0.86711998 -1.88171004 0.86896998 -1.88553996 0 P 0 ;0
L 0.86896998 -1.88553996 0.87055 -1.8895 0 P 0 ;0
L 0.87055 -1.8895 0.8718 -1.89343002 0 P 0 ;0
L 0.8718 -1.89343002 0.87276004 -1.89745 0 P 0 ;0
L 0.87276004 -1.89745 0.87371004 -1.90195 0 P 0 ;0
L 0.87371004 -1.90195 0.87383002 -1.90236004 0 P 0 ;0
L 0.87383002 -1.90236004 0.87396998 -1.90276004 0 P 0 ;0
L 0.87396998 -1.90276004 0.87416004 -1.90313996 0 P 0 ;0
L 0.87416004 -1.90313996 0.87436998 -1.90351004 0 P 0 ;0
L 0.87436998 -1.90351004 0.87443002 -1.9036 0 P 0 ;0
L 0.87443002 -1.9036 0.87456998 -1.90376004 0 P 0 ;0
L 0.87456998 -1.90376004 0.87465 -1.90381998 0 P 0 ;0
L 0.87465 -1.90381998 0.87473002 -1.90388996 0 P 0 ;0
L 0.87473002 -1.90388996 0.87481998 -1.90393996 0 P 0 ;0
L 0.87481998 -1.90393996 0.87491998 -1.90398996 0 P 0 ;0
L 0.87491998 -1.90398996 0.87501004 -1.90403002 0 P 0 ;0
L 0.87501004 -1.90403002 0.87521004 -1.90408996 0 P 0 ;0
L 0.87521004 -1.90408996 0.87531998 -1.9041 0 P 0 ;0
L 0.87531998 -1.9041 0.87573002 -1.90413002 0 P 0 ;0
L 0.87573002 -1.90413002 0.87613996 -1.90411998 0 P 0 ;0
L 0.87613996 -1.90411998 0.87653996 -1.90408002 0 P 0 ;0
L 0.87653996 -1.90408002 0.87695 -1.90401004 0 P 0 ;0
L 0.87695 -1.90401004 0.90756004 -1.89766998 0 P 0 ;0
L 0.90756004 -1.89766998 0.92603996 -1.89478002 0 P 0 ;0
L 0.92603996 -1.89478002 0.93486004 -1.89393996 0 P 0 ;0
L 0.93486004 -1.89393996 0.94371004 -1.8935 0 P 0 ;0
L 0.94371004 -1.8935 0.97045 -1.89308002 0 P 0 ;0
L 0.97045 -1.89308002 0.99468996 -1.89328996 0 P 0 ;0
L 0.99468996 -1.89328996 1.01021004 -1.89413996 0 P 0 ;0
L 1.01021004 -1.89413996 1.0241 -1.89601998 0 P 0 ;0
L 1.0241 -1.89601998 1.04188002 -1.89961004 0 P 0 ;0
L 1.04188002 -1.89961004 1.06095 -1.90466004 0 P 0 ;0
L 1.06095 -1.90466004 1.07963996 -1.91123002 0 P 0 ;0
L 1.07963996 -1.91123002 1.09093996 -1.91613002 0 P 0 ;0
L 1.09093996 -1.91613002 1.10186998 -1.92175 0 P 0 ;0
L 1.10186998 -1.92175 1.11243996 -1.92806998 0 P 0 ;0
L 1.11243996 -1.92806998 1.12163002 -1.93446998 0 P 0 ;0
L 1.12163002 -1.93446998 1.13033002 -1.94148996 0 P 0 ;0
L 1.13033002 -1.94148996 1.1385 -1.94911004 0 P 0 ;0
L 1.1385 -1.94911004 1.14358996 -1.9546 0 P 0 ;0
L 1.14358996 -1.9546 1.14825 -1.96045 0 P 0 ;0
L 1.14825 -1.96045 1.15246998 -1.96663002 0 P 0 ;0
L 1.15246998 -1.96663002 1.15623002 -1.97316004 0 P 0 ;0
L 1.15623002 -1.97316004 1.15895 -1.97831004 0 P 0 ;0
L 1.15895 -1.97831004 1.17358996 -1.97831004 0 P 0 ;0
L 1.17358996 -1.97831004 1.17135 -1.9726 0 P 0 ;0
L 1.17135 -1.9726 1.16696004 -1.96266998 0 P 0 ;0
L 1.16696004 -1.96266998 1.16171998 -1.95313002 0 P 0 ;0
L 1.16171998 -1.95313002 1.1557 -1.94406998 0 P 0 ;0
L 1.1557 -1.94406998 1.14885 -1.93548002 0 P 0 ;0
L 1.14885 -1.93548002 1.13778996 -1.92378002 0 P 0 ;0
L 1.13778996 -1.92378002 1.12576998 -1.91301998 0 P 0 ;0
L 1.12576998 -1.91301998 1.11283996 -1.90326004 0 P 0 ;0
L 1.11283996 -1.90326004 1.09783002 -1.89368996 0 P 0 ;0
L 1.09783002 -1.89368996 1.08213002 -1.88526998 0 P 0 ;0
L 1.08213002 -1.88526998 1.06576998 -1.87801004 0 P 0 ;0
L 1.06576998 -1.87801004 1.04776004 -1.87141998 0 P 0 ;0
L 1.04776004 -1.87141998 1.02938002 -1.86591998 0 P 0 ;0
L 1.02938002 -1.86591998 1.01058002 -1.8615 0 P 0 ;0
L 1.01058002 -1.8615 0.98441998 -1.85711004 0 P 0 ;0
L 0.98441998 -1.85711004 0.95781004 -1.85448996 0 P 0 ;0
L 0.95781004 -1.85448996 0.93061004 -1.85366004 0 P 0 ;0
L 0.93061004 -1.85366004 0.90273996 -1.85456998 0 P 0 ;0
L 1.16015 -1.97631004 1.15798002 -1.97218996 0 P 0 ;0
L 1.15798002 -1.97218996 1.15796004 -1.97216004 0 P 0 ;0
L 1.15796004 -1.97216004 1.15416004 -1.96556998 0 P 0 ;0
L 1.15416004 -1.96556998 1.15411998 -1.96551004 0 P 0 ;0
L 1.15411998 -1.96551004 1.14986004 -1.95926004 0 P 0 ;0
L 1.14986004 -1.95926004 1.14981998 -1.95921004 0 P 0 ;0
L 1.14981998 -1.95921004 1.14511004 -1.9533 0 P 0 ;0
L 1.14511004 -1.9533 1.13991998 -1.9477 0 P 0 ;0
L 1.13991998 -1.9477 1.13986004 -1.94765 0 P 0 ;0
L 1.13986004 -1.94765 1.13163996 -1.93998002 0 P 0 ;0
L 1.13163996 -1.93998002 1.12283002 -1.93286004 0 P 0 ;0
L 1.12283002 -1.93286004 1.11351998 -1.92638996 0 P 0 ;0
L 1.11351998 -1.92638996 1.10283996 -1.92 0 P 0 ;0
L 1.10283996 -1.92 1.0918 -1.91433002 0 P 0 ;0
L 1.0918 -1.91433002 1.08036998 -1.90936004 0 P 0 ;0
L 1.08036998 -1.90936004 1.06153002 -1.90273996 0 P 0 ;0
L 1.06153002 -1.90273996 1.06146004 -1.90273002 0 P 0 ;0
L 1.06146004 -1.90273002 1.04233002 -1.89766004 0 P 0 ;0
L 1.04233002 -1.89766004 1.02443002 -1.89405 0 P 0 ;0
L 1.02443002 -1.89405 1.0104 -1.89213996 0 P 0 ;0
L 1.0104 -1.89213996 0.99475 -1.89128996 0 P 0 ;0
L 0.99475 -1.89128996 0.97045 -1.89108002 0 P 0 ;0
L 0.97045 -1.89108002 0.94365 -1.8915 0 P 0 ;0
L 0.94365 -1.8915 0.94361998 -1.8915 0 P 0 ;0
L 0.94361998 -1.8915 0.93471998 -1.89195 0 P 0 ;0
L 0.93471998 -1.89195 0.92578996 -1.89278996 0 P 0 ;0
L 0.92578996 -1.89278996 0.9072 -1.89571004 0 P 0 ;0
L 0.9072 -1.89571004 0.87656998 -1.90203996 0 P 0 ;0
L 0.87656998 -1.90203996 0.87626998 -1.9021 0 P 0 ;0
L 0.87626998 -1.9021 0.87601998 -1.90211998 0 P 0 ;0
L 0.87601998 -1.90211998 0.87588996 -1.90213002 0 P 0 ;0
L 0.87588996 -1.90213002 0.87583002 -1.90198996 0 P 0 ;0
L 0.87583002 -1.90198996 0.87573002 -1.90175 0 P 0 ;0
L 0.87573002 -1.90175 0.87566004 -1.90146998 0 P 0 ;0
L 0.87566004 -1.90146998 0.87471004 -1.89701004 0 P 0 ;0
L 0.87471004 -1.89701004 0.8747 -1.89698996 0 P 0 ;0
L 0.8747 -1.89698996 0.87373002 -1.89288996 0 P 0 ;0
L 0.87373002 -1.89288996 0.87243002 -1.88881998 0 P 0 ;0
L 0.87243002 -1.88881998 0.8724 -1.88876004 0 P 0 ;0
L 0.8724 -1.88876004 0.8708 -1.88473996 0 P 0 ;0
L 0.8708 -1.88473996 0.8689 -1.88078002 0 P 0 ;0
L 0.8689 -1.88078002 0.86671998 -1.87693996 0 P 0 ;0
L 0.86671998 -1.87693996 0.86428996 -1.87326004 0 P 0 ;0
L 0.86428996 -1.87326004 0.86166998 -1.86985 0 P 0 ;0
L 0.86166998 -1.86985 0.85883996 -1.86668002 0 P 0 ;0
L 0.85883996 -1.86668002 0.85883002 -1.86666004 0 P 0 ;0
L 0.85883002 -1.86666004 0.85531998 -1.86291004 0 P 0 ;0
L 0.85531998 -1.86291004 0.85486004 -1.86238002 0 P 0 ;0
L 0.85486004 -1.86238002 0.85466004 -1.86211998 0 P 0 ;0
L 0.85466004 -1.86211998 0.8557 -1.86186004 0 P 0 ;0
L 0.8557 -1.86186004 0.85811998 -1.86145 0 P 0 ;0
L 0.85811998 -1.86145 0.87443996 -1.85941004 0 P 0 ;0
L 0.87443996 -1.85941004 0.89088996 -1.85756998 0 P 0 ;0
L 0.89088996 -1.85756998 0.90286004 -1.85656998 0 P 0 ;0
L 0.90286004 -1.85656998 0.93061004 -1.85566004 0 P 0 ;0
L 0.93061004 -1.85566004 0.95768002 -1.85648996 0 P 0 ;0
L 0.95768002 -1.85648996 0.98416004 -1.8591 0 P 0 ;0
L 0.98416004 -1.8591 1.01018996 -1.86346004 0 P 0 ;0
L 1.01018996 -1.86346004 1.02886004 -1.86785 0 P 0 ;0
L 1.02886004 -1.86785 1.04711998 -1.87331998 0 P 0 ;0
L 1.04711998 -1.87331998 1.06501004 -1.87986004 0 P 0 ;0
L 1.06501004 -1.87986004 1.08125 -1.88706998 0 P 0 ;0
L 1.08125 -1.88706998 1.09681004 -1.89541998 0 P 0 ;0
L 1.09681004 -1.89541998 1.1117 -1.9049 0 P 0 ;0
L 1.1117 -1.9049 1.1245 -1.91456998 0 P 0 ;0
L 1.1245 -1.91456998 1.13638996 -1.92521004 0 P 0 ;0
L 1.13638996 -1.92521004 1.14733996 -1.93678996 0 P 0 ;0
L 1.14733996 -1.93678996 1.15408002 -1.94525 0 P 0 ;0
L 1.15408002 -1.94525 1.16001004 -1.95416998 0 P 0 ;0
L 1.16001004 -1.95416998 1.16516004 -1.96355 0 P 0 ;0
L 1.16516004 -1.96355 1.1695 -1.97336998 0 P 0 ;0
L 1.1695 -1.97336998 1.17066004 -1.97631004 0 P 0 ;0
L 1.17066004 -1.97631004 1.16015 -1.97631004 0 P 0 ;0
L 0.87563002 -1.90131004 0.8801 -1.90131004 0 P 0 ;0
L 0.87541004 -1.90031004 0.88493996 -1.90031004 0 P 0 ;0
L 0.8752 -1.89931004 0.88976998 -1.89931004 0 P 0 ;0
L 0.87498996 -1.89831004 0.8946 -1.89831004 0 P 0 ;0
L 0.89423002 -2.08316004 0.94355 -2.08316004 0 P 0 ;0
L 0.89428996 -2.08216004 0.9436 -2.08216004 0 P 0 ;0
L 0.89435 -2.08116004 0.94365 -2.08116004 0 P 0 ;0
L 0.89441004 -2.08016004 0.9437 -2.08016004 0 P 0 ;0
L 0.89446004 -2.07916004 0.94375 -2.07916004 0 P 0 ;0
L 0.89451998 -2.07816004 0.94378996 -2.07816004 0 P 0 ;0
L 0.89458002 -2.07716004 0.94383996 -2.07716004 0 P 0 ;0
L 0.89463996 -2.07616004 0.94388996 -2.07616004 0 P 0 ;0
L 0.8947 -2.07516004 0.94393996 -2.07516004 0 P 0 ;0
L 0.89475 -2.07416004 0.94398002 -2.07416004 0 P 0 ;0
L 0.89481004 -2.07316004 0.94403002 -2.07316004 0 P 0 ;0
L 0.89486998 -2.07216004 0.94408002 -2.07216004 0 P 0 ;0
L 0.89493002 -2.07116004 0.94415 -2.07116004 0 P 0 ;0
L 0.89498996 -2.07016004 0.94426004 -2.07016004 0 P 0 ;0
L 0.89505 -2.06916004 0.94436998 -2.06916004 0 P 0 ;0
L 0.8951 -2.06816004 0.94448002 -2.06816004 0 P 0 ;0
L 0.89516004 -2.06716004 0.94458996 -2.06716004 0 P 0 ;0
L 0.89521998 -2.06616004 0.9447 -2.06616004 0 P 0 ;0
L 0.89526998 -2.06516004 0.94481004 -2.06516004 0 P 0 ;0
L 0.89531004 -2.06416004 0.94491998 -2.06416004 0 P 0 ;0
L 0.89535 -2.06316004 0.94503002 -2.06316004 0 P 0 ;0
L 0.8954 -2.06216004 0.94513996 -2.06216004 0 P 0 ;0
L 0.89543996 -2.06116004 0.94531998 -2.06116004 0 P 0 ;0
L 0.89548996 -2.06016004 0.94551004 -2.06016004 0 P 0 ;0
L 0.89553002 -2.05916004 0.9457 -2.05916004 0 P 0 ;0
L 0.89558002 -2.05816004 0.94588996 -2.05816004 0 P 0 ;0
L 0.89561998 -2.05716004 0.94608002 -2.05716004 0 P 0 ;0
L 0.89566998 -2.05616004 0.94626998 -2.05616004 0 P 0 ;0
L 0.89571004 -2.05516004 0.94646998 -2.05516004 0 P 0 ;0
L 0.89575 -2.05416004 0.94666004 -2.05416004 0 P 0 ;0
L 0.8958 -2.05316004 0.94685 -2.05316004 0 P 0 ;0
L 0.89583996 -2.05216004 0.94708002 -2.05216004 0 P 0 ;0
L 0.89588996 -2.05116004 0.94735 -2.05116004 0 P 0 ;0
L 0.89593996 -2.05016004 0.94761998 -2.05016004 0 P 0 ;0
L 0.89598002 -2.04916004 0.9479 -2.04916004 0 P 0 ;0
L 0.89601998 -2.04816004 0.94825 -2.04816004 0 P 0 ;0
L 0.89606998 -2.04716004 0.94858996 -2.04716004 0 P 0 ;0
L 0.89611004 -2.04616004 0.94893002 -2.04616004 0 P 0 ;0
L 0.89616004 -2.04516004 0.94935 -2.04516004 0 P 0 ;0
L 0.8962 -2.04416004 0.94976998 -2.04416004 0 P 0 ;0
L 0.89625 -2.04316004 0.9502 -2.04316004 0 P 0 ;0
L 0.89628002 -2.04216004 0.95068996 -2.04216004 0 P 0 ;0
L 0.89631004 -2.04116004 0.95118996 -2.04116004 0 P 0 ;0
L 0.89633996 -2.04016004 0.95168996 -2.04016004 0 P 0 ;0
L 0.89638002 -2.03916004 0.95228002 -2.03916004 0 P 0 ;0
L 0.89641004 -2.03816004 0.95291004 -2.03816004 0 P 0 ;0
L 0.89643996 -2.03716004 0.95363002 -2.03716004 0 P 0 ;0
L 0.89646998 -2.03616004 0.95445 -2.03616004 0 P 0 ;0
L 0.89651004 -2.03516004 0.95535 -2.03516004 0 P 0 ;0
L 0.89653996 -2.03416004 0.95636998 -2.03416004 0 P 0 ;0
L 0.89656998 -2.03316004 0.95756998 -2.03316004 0 P 0 ;0
L 0.8966 -2.03216004 0.95893996 -2.03216004 0 P 0 ;0
L 0.89663996 -2.03116004 0.96055 -2.03116004 0 P 0 ;0
L 0.89666998 -2.03016004 0.96278002 -2.03016004 0 P 0 ;0
L 0.8967 -2.02916004 0.96676004 -2.02916004 0 P 0 ;0
L 0.89673996 -2.02816004 1.03838996 -2.02816004 0 P 0 ;0
L 0.89676998 -2.02716004 1.03838002 -2.02716004 0 P 0 ;0
L 0.8968 -2.02616004 1.03833996 -2.02616004 0 P 0 ;0
L 0.89683996 -2.02516004 1.03828996 -2.02516004 0 P 0 ;0
L 0.89686998 -2.02416004 1.03823002 -2.02416004 0 P 0 ;0
L 0.8969 -2.02316004 1.03816004 -2.02316004 0 P 0 ;0
L 0.89693996 -2.02216004 1.0381 -2.02216004 0 P 0 ;0
L 0.89696998 -2.02116004 1.03803996 -2.02116004 0 P 0 ;0
L 0.897 -2.02016004 1.0379 -2.02016004 0 P 0 ;0
L 0.89703002 -2.01916004 1.03773996 -2.01916004 0 P 0 ;0
L 0.89706004 -2.01816004 1.03751998 -2.01816004 0 P 0 ;0
L 0.89708996 -2.01716004 1.03728002 -2.01716004 0 P 0 ;0
L 0.89711998 -2.01616004 1.03698996 -2.01616004 0 P 0 ;0
L 0.89713996 -2.01516004 1.03668002 -2.01516004 0 P 0 ;0
L 0.89716998 -2.01416004 1.03631004 -2.01416004 0 P 0 ;0
L 0.8972 -2.01316004 1.03591998 -2.01316004 0 P 0 ;0
L 0.89721998 -2.01216004 1.03548996 -2.01216004 0 P 0 ;0
L 0.89725 -2.01116004 1.03505 -2.01116004 0 P 0 ;0
L 0.89726998 -2.01016004 1.03458002 -2.01016004 0 P 0 ;0
L 0.8973 -2.00916004 1.03405 -2.00916004 0 P 0 ;0
L 0.89733002 -2.00816004 1.03351998 -2.00816004 0 P 0 ;0
L 0.89736004 -2.00716004 0.94676004 -2.00716004 0 P 0 ;0
L 0.89738002 -2.00616004 0.9461 -2.00616004 0 P 0 ;0
L 0.89741004 -2.00516004 0.94563996 -2.00516004 0 P 0 ;0
L 0.89743996 -2.00416004 0.94563996 -2.00416004 0 P 0 ;0
L 0.89746004 -2.00316004 0.94563996 -2.00316004 0 P 0 ;0
L 0.89748996 -2.00216004 0.94563996 -2.00216004 0 P 0 ;0
L 0.89751004 -2.00116004 0.94563996 -2.00116004 0 P 0 ;0
L 0.89753996 -2.00016004 0.94563996 -2.00016004 0 P 0 ;0
L 0.89756998 -1.99916004 0.94563996 -1.99916004 0 P 0 ;0
L 0.8976 -1.99816004 0.94563996 -1.99816004 0 P 0 ;0
L 0.89761998 -1.99716004 0.94563996 -1.99716004 0 P 0 ;0
L 0.89765 -1.99616004 0.94563996 -1.99616004 0 P 0 ;0
L 0.89768002 -1.99516004 0.94563996 -1.99516004 0 P 0 ;0
L 0.97546998 -1.98933996 0.97236998 -1.99006004 0 P 0 ;0
L 0.97236998 -1.99006004 0.96931998 -1.99103002 0 P 0 ;0
L 0.96931998 -1.99103002 0.96603002 -1.99233002 0 P 0 ;0
L 0.96603002 -1.99233002 0.96281004 -1.99383002 0 P 0 ;0
L 0.96281004 -1.99383002 0.95976004 -1.99546998 0 P 0 ;0
L 0.95976004 -1.99546998 0.95681004 -1.99728996 0 P 0 ;0
L 0.95681004 -1.99728996 0.95521004 -1.99841004 0 P 0 ;0
L 0.95521004 -1.99841004 0.95368996 -1.99963002 0 P 0 ;0
L 0.95368996 -1.99963002 0.95223996 -2.00095 0 P 0 ;0
L 0.95223996 -2.00095 0.94763996 -2.00546998 0 P 0 ;0
L 0.94763996 -2.00546998 0.94763996 -1.99243996 0 P 0 ;0
L 0.94763996 -1.99243996 0.89575 -1.99243996 0 P 0 ;0
L 0.89575 -1.99243996 0.89505 -2.01878002 0 P 0 ;0
L 0.89505 -2.01878002 0.89423996 -2.04316004 0 P 0 ;0
L 0.89423996 -2.04316004 0.89321998 -2.0661 0 P 0 ;0
L 0.89321998 -2.0661 0.89198996 -2.08728996 0 P 0 ;0
L 0.89198996 -2.08728996 0.89055 -2.1063 0 P 0 ;0
L 0.89055 -2.1063 0.88993996 -2.11358002 0 P 0 ;0
L 0.88993996 -2.11358002 0.88943002 -2.11988002 0 P 0 ;0
L 0.88943002 -2.11988002 0.88898996 -2.12533996 0 P 0 ;0
L 0.88898996 -2.12533996 0.88896004 -2.12613002 0 P 0 ;0
L 0.88896004 -2.12613002 0.88896998 -2.12621004 0 P 0 ;0
L 0.88896998 -2.12621004 0.88898002 -2.12625 0 P 0 ;0
L 0.88898002 -2.12625 0.88898996 -2.12628002 0 P 0 ;0
L 0.88898996 -2.12628002 0.88901998 -2.12636004 0 P 0 ;0
L 0.88901998 -2.12636004 0.88903996 -2.12638996 0 P 0 ;0
L 0.88903996 -2.12638996 0.88906998 -2.12641998 0 P 0 ;0
L 0.88906998 -2.12641998 0.88908996 -2.12645 0 P 0 ;0
L 0.88908996 -2.12645 0.88911998 -2.12646998 0 P 0 ;0
L 0.88911998 -2.12646998 0.88915 -2.1265 0 P 0 ;0
L 0.88915 -2.1265 0.88921004 -2.12653996 0 P 0 ;0
L 0.88921004 -2.12653996 0.88925 -2.12655 0 P 0 ;0
L 0.88925 -2.12655 0.88928002 -2.12656004 0 P 0 ;0
L 0.88928002 -2.12656004 0.88931998 -2.12658002 0 P 0 ;0
L 0.88931998 -2.12658002 0.8894 -2.12658002 0 P 0 ;0
L 0.8894 -2.12658002 0.89648002 -2.12686998 0 P 0 ;0
L 0.89648002 -2.12686998 0.90518996 -2.1271 0 P 0 ;0
L 0.90518996 -2.1271 0.9165 -2.12716004 0 P 0 ;0
L 0.9165 -2.12716004 0.94403996 -2.12716004 0 P 0 ;0
L 0.94403996 -2.12716004 0.94468996 -2.10135 0 P 0 ;0
L 0.94468996 -2.10135 0.9461 -2.07171998 0 P 0 ;0
L 0.9461 -2.07171998 0.94713002 -2.06233002 0 P 0 ;0
L 0.94713002 -2.06233002 0.9489 -2.05308002 0 P 0 ;0
L 0.9489 -2.05308002 0.94975 -2.04995 0 P 0 ;0
L 0.94975 -2.04995 0.9508 -2.04688996 0 P 0 ;0
L 0.9508 -2.04688996 0.95205 -2.0439 0 P 0 ;0
L 0.95205 -2.0439 0.95351004 -2.041 0 P 0 ;0
L 0.95351004 -2.041 0.9544 -2.03951004 0 P 0 ;0
L 0.9544 -2.03951004 0.95541998 -2.03811004 0 P 0 ;0
L 0.95541998 -2.03811004 0.95655 -2.03678996 0 P 0 ;0
L 0.95655 -2.03678996 0.95778996 -2.03556998 0 P 0 ;0
L 0.95778996 -2.03556998 0.95911998 -2.03446998 0 P 0 ;0
L 0.95911998 -2.03446998 0.96056998 -2.03346998 0 P 0 ;0
L 0.96056998 -2.03346998 0.96151004 -2.03291004 0 P 0 ;0
L 0.96151004 -2.03291004 0.96248996 -2.03243002 0 P 0 ;0
L 0.96248996 -2.03243002 0.96351004 -2.03201998 0 P 0 ;0
L 0.96351004 -2.03201998 0.96455 -2.03168996 0 P 0 ;0
L 0.96455 -2.03168996 0.96613002 -2.0313 0 P 0 ;0
L 0.96613002 -2.0313 0.96773002 -2.03101998 0 P 0 ;0
L 0.96773002 -2.03101998 0.96935 -2.03086004 0 P 0 ;0
L 0.96935 -2.03086004 0.97095 -2.03081004 0 P 0 ;0
L 0.97095 -2.03081004 0.97255 -2.03086998 0 P 0 ;0
L 0.97255 -2.03086998 0.97413002 -2.03105 0 P 0 ;0
L 0.97413002 -2.03105 0.97513002 -2.03123996 0 P 0 ;0
L 0.97513002 -2.03123996 0.9761 -2.03151004 0 P 0 ;0
L 0.9761 -2.03151004 0.97706004 -2.03186004 0 P 0 ;0
L 0.97706004 -2.03186004 0.97796998 -2.0323 0 P 0 ;0
L 0.97796998 -2.0323 0.97885 -2.0328 0 P 0 ;0
L 0.97885 -2.0328 0.97968002 -2.03336998 0 P 0 ;0
L 0.97968002 -2.03336998 0.98046998 -2.03398996 0 P 0 ;0
L 0.98046998 -2.03398996 0.98121998 -2.03468002 0 P 0 ;0
L 0.98121998 -2.03468002 0.98191004 -2.03541998 0 P 0 ;0
L 0.98191004 -2.03541998 0.98253996 -2.0362 0 P 0 ;0
L 0.98253996 -2.0362 0.9831 -2.03703002 0 P 0 ;0
L 0.9831 -2.03703002 0.9836 -2.03788996 0 P 0 ;0
L 0.9836 -2.03788996 0.98403996 -2.0388 0 P 0 ;0
L 0.98403996 -2.0388 0.9844 -2.03973996 0 P 0 ;0
L 0.9844 -2.03973996 0.98505 -2.04188996 0 P 0 ;0
L 0.98505 -2.04188996 0.98553002 -2.04408002 0 P 0 ;0
L 0.98553002 -2.04408002 0.98583002 -2.0463 0 P 0 ;0
L 0.98583002 -2.0463 0.98653002 -2.05705 0 P 0 ;0
L 0.98653002 -2.05705 0.9866 -2.06961004 0 P 0 ;0
L 0.9866 -2.06961004 0.98596004 -2.08908002 0 P 0 ;0
L 0.98596004 -2.08908002 0.98498002 -2.10858002 0 P 0 ;0
L 0.98498002 -2.10858002 0.98388002 -2.12146998 0 P 0 ;0
L 0.98388002 -2.12146998 0.98323002 -2.12716004 0 P 0 ;0
L 0.98323002 -2.12716004 1.03741004 -2.12716004 0 P 0 ;0
L 1.03741004 -2.12716004 1.03896004 -2.09103002 0 P 0 ;0
L 1.03896004 -2.09103002 1.03956004 -2.0759 0 P 0 ;0
L 1.03956004 -2.0759 1.04005 -2.06025 0 P 0 ;0
L 1.04005 -2.06025 1.04038996 -2.04626004 0 P 0 ;0
L 1.04038996 -2.04626004 1.04048002 -2.03698996 0 P 0 ;0
L 1.04048002 -2.03698996 1.04036998 -2.02651998 0 P 0 ;0
L 1.04036998 -2.02651998 1.04003996 -2.02096998 0 P 0 ;0
L 1.04003996 -2.02096998 1.03975 -2.01895 0 P 0 ;0
L 1.03975 -2.01895 1.0393 -2.01693996 0 P 0 ;0
L 1.0393 -2.01693996 1.03868996 -2.01483996 0 P 0 ;0
L 1.03868996 -2.01483996 1.03793996 -2.01278002 0 P 0 ;0
L 1.03793996 -2.01278002 1.03658996 -2.00968002 0 P 0 ;0
L 1.03658996 -2.00968002 1.03501004 -2.00668996 0 P 0 ;0
L 1.03501004 -2.00668996 1.0332 -2.0038 0 P 0 ;0
L 1.0332 -2.0038 1.03186998 -2.002 0 P 0 ;0
L 1.03186998 -2.002 1.0304 -2.0003 0 P 0 ;0
L 1.0304 -2.0003 1.0288 -1.99873002 0 P 0 ;0
L 1.0288 -1.99873002 1.02708002 -1.99728996 0 P 0 ;0
L 1.02708002 -1.99728996 1.02518002 -1.99593002 0 P 0 ;0
L 1.02518002 -1.99593002 1.02318002 -1.99471998 0 P 0 ;0
L 1.02318002 -1.99471998 1.0211 -1.99365 0 P 0 ;0
L 1.0211 -1.99365 1.01893002 -1.99273996 0 P 0 ;0
L 1.01893002 -1.99273996 1.01358996 -1.99098996 0 P 0 ;0
L 1.01358996 -1.99098996 1.0081 -1.98971004 0 P 0 ;0
L 1.0081 -1.98971004 1.00428996 -1.98908996 0 P 0 ;0
L 1.00428996 -1.98908996 1.00043996 -1.98868002 0 P 0 ;0
L 1.00043996 -1.98868002 0.99138002 -1.98826004 0 P 0 ;0
L 0.99138002 -1.98826004 0.98251998 -1.98846998 0 P 0 ;0
L 0.98251998 -1.98846998 0.97898996 -1.98878996 0 P 0 ;0
L 0.97898996 -1.98878996 0.97546998 -1.98933996 0 P 0 ;0
L 0.91651004 -2.12516004 0.94208996 -2.12516004 0 P 0 ;0
L 0.8911 -2.12416004 0.94211004 -2.12416004 0 P 0 ;0
L 0.89118002 -2.12316004 0.94213996 -2.12316004 0 P 0 ;0
L 0.89125 -2.12216004 0.94216004 -2.12216004 0 P 0 ;0
L 0.89133002 -2.12116004 0.94218996 -2.12116004 0 P 0 ;0
L 0.89141004 -2.12016004 0.94221004 -2.12016004 0 P 0 ;0
L 0.89148996 -2.11916004 0.94223996 -2.11916004 0 P 0 ;0
L 0.89156998 -2.11816004 0.94226998 -2.11816004 0 P 0 ;0
L 0.89166004 -2.11716004 0.94228996 -2.11716004 0 P 0 ;0
L 0.89173996 -2.11616004 0.94231004 -2.11616004 0 P 0 ;0
L 0.89181998 -2.11516004 0.94233996 -2.11516004 0 P 0 ;0
L 0.8919 -2.11416004 0.94236004 -2.11416004 0 P 0 ;0
L 0.89198002 -2.11316004 0.94238996 -2.11316004 0 P 0 ;0
L 0.89206998 -2.11216004 0.94241998 -2.11216004 0 P 0 ;0
L 0.89215 -2.11116004 0.94243996 -2.11116004 0 P 0 ;0
L 0.89223002 -2.11016004 0.94246998 -2.11016004 0 P 0 ;0
L 0.89231998 -2.10916004 0.94248996 -2.10916004 0 P 0 ;0
L 0.8924 -2.10816004 0.94251998 -2.10816004 0 P 0 ;0
L 0.89248002 -2.10716004 0.94255 -2.10716004 0 P 0 ;0
L 0.89256998 -2.10616004 0.94256998 -2.10616004 0 P 0 ;0
L 0.89263996 -2.10516004 0.94258996 -2.10516004 0 P 0 ;0
L 0.89271004 -2.10416004 0.94261998 -2.10416004 0 P 0 ;0
L 0.89278996 -2.10316004 0.94263996 -2.10316004 0 P 0 ;0
L 0.89286998 -2.10216004 0.94266998 -2.10216004 0 P 0 ;0
L 0.89293996 -2.10116004 0.9427 -2.10116004 0 P 0 ;0
L 0.89301998 -2.10016004 0.94275 -2.10016004 0 P 0 ;0
L 0.89308996 -2.09916004 0.94278996 -2.09916004 0 P 0 ;0
L 0.89316998 -2.09816004 0.94283996 -2.09816004 0 P 0 ;0
L 0.89325 -2.09716004 0.94288996 -2.09716004 0 P 0 ;0
L 0.89331998 -2.09616004 0.94293996 -2.09616004 0 P 0 ;0
L 0.8934 -2.09516004 0.94298002 -2.09516004 0 P 0 ;0
L 0.89346998 -2.09416004 0.94303002 -2.09416004 0 P 0 ;0
L 0.89355 -2.09316004 0.94308002 -2.09316004 0 P 0 ;0
L 0.89361998 -2.09216004 0.94313002 -2.09216004 0 P 0 ;0
L 0.8937 -2.09116004 0.94318002 -2.09116004 0 P 0 ;0
L 0.89378002 -2.09016004 0.94321998 -2.09016004 0 P 0 ;0
L 0.89385 -2.08916004 0.94326998 -2.08916004 0 P 0 ;0
L 0.89393002 -2.08816004 0.94331998 -2.08816004 0 P 0 ;0
L 0.894 -2.08716004 0.94336004 -2.08716004 0 P 0 ;0
L 0.89406004 -2.08616004 0.94341004 -2.08616004 0 P 0 ;0
L 0.89411998 -2.08516004 0.94346004 -2.08516004 0 P 0 ;0
L 0.89418002 -2.08416004 0.94351004 -2.08416004 0 P 0 ;0
L 0.91651004 -2.12516004 0.90521998 -2.1251 0 P 0 ;0
L 0.90521998 -2.1251 0.89655 -2.12486998 0 P 0 ;0
L 0.89655 -2.12486998 0.89106004 -2.12465 0 P 0 ;0
L 0.89106004 -2.12465 0.89141998 -2.12003996 0 P 0 ;0
L 0.89141998 -2.12003996 0.89193996 -2.11373996 0 P 0 ;0
L 0.89193996 -2.11373996 0.89253996 -2.10645 0 P 0 ;0
L 0.89253996 -2.10645 0.89398002 -2.08741998 0 P 0 ;0
L 0.89398002 -2.08741998 0.89521998 -2.06621998 0 P 0 ;0
L 0.89521998 -2.06621998 0.89521998 -2.06618996 0 P 0 ;0
L 0.89521998 -2.06618996 0.89623996 -2.04323002 0 P 0 ;0
L 0.89623996 -2.04323002 0.89703996 -2.01883002 0 P 0 ;0
L 0.89703996 -2.01883002 0.8977 -1.99443996 0 P 0 ;0
L 0.8977 -1.99443996 0.94563996 -1.99443996 0 P 0 ;0
L 0.94563996 -1.99443996 0.94563996 -2.00546998 0 P 0 ;0
L 0.94563996 -2.00546998 0.94686004 -2.00731004 0 P 0 ;0
L 0.94686004 -2.00731004 0.94903002 -2.00688996 0 P 0 ;0
L 0.94903002 -2.00688996 0.95361998 -2.00241004 0 P 0 ;0
L 0.95361998 -2.00241004 0.95498996 -2.00115 0 P 0 ;0
L 0.95498996 -2.00115 0.95641998 -2.00001004 0 P 0 ;0
L 0.95641998 -2.00001004 0.9579 -1.99896004 0 P 0 ;0
L 0.9579 -1.99896004 0.96076004 -1.9972 0 P 0 ;0
L 0.96076004 -1.9972 0.9637 -1.99561998 0 P 0 ;0
L 0.9637 -1.99561998 0.96683002 -1.99416998 0 P 0 ;0
L 0.96683002 -1.99416998 0.96998996 -1.99291998 0 P 0 ;0
L 0.96998996 -1.99291998 0.9729 -1.99198996 0 P 0 ;0
L 0.9729 -1.99198996 0.97586004 -1.9913 0 P 0 ;0
L 0.97586004 -1.9913 0.97923002 -1.99076998 0 P 0 ;0
L 0.97923002 -1.99076998 0.98263002 -1.99046998 0 P 0 ;0
L 0.98263002 -1.99046998 0.99136004 -1.99026004 0 P 0 ;0
L 0.99136004 -1.99026004 1.00028996 -1.99066998 0 P 0 ;0
L 1.00028996 -1.99066998 1.00403002 -1.99108002 0 P 0 ;0
L 1.00403002 -1.99108002 1.00771004 -1.99166998 0 P 0 ;0
L 1.00771004 -1.99166998 1.01305 -1.99291998 0 P 0 ;0
L 1.01305 -1.99291998 1.01823002 -1.99461998 0 P 0 ;0
L 1.01823002 -1.99461998 1.02026004 -1.99546998 0 P 0 ;0
L 1.02026004 -1.99546998 1.02221004 -1.99646998 0 P 0 ;0
L 1.02221004 -1.99646998 1.02408002 -1.9976 0 P 0 ;0
L 1.02408002 -1.9976 1.02585 -1.99886998 0 P 0 ;0
L 1.02585 -1.99886998 1.02746004 -2.00021004 0 P 0 ;0
L 1.02746004 -2.00021004 1.02893996 -2.00166998 0 P 0 ;0
L 1.02893996 -2.00166998 1.03031004 -2.00325 0 P 0 ;0
L 1.03031004 -2.00325 1.03155 -2.00493002 0 P 0 ;0
L 1.03155 -2.00493002 1.03326998 -2.00768002 0 P 0 ;0
L 1.03326998 -2.00768002 1.03478002 -2.01055 0 P 0 ;0
L 1.03478002 -2.01055 1.03608002 -2.01351998 0 P 0 ;0
L 1.03608002 -2.01351998 1.03678996 -2.01546998 0 P 0 ;0
L 1.03678996 -2.01546998 1.03736004 -2.01743002 0 P 0 ;0
L 1.03736004 -2.01743002 1.03778002 -2.0193 0 P 0 ;0
L 1.03778002 -2.0193 1.03805 -2.02116998 0 P 0 ;0
L 1.03805 -2.02116998 1.03836998 -2.02658996 0 P 0 ;0
L 1.03836998 -2.02658996 1.03848002 -2.03698996 0 P 0 ;0
L 1.03848002 -2.03698996 1.03838996 -2.04623002 0 P 0 ;0
L 1.03838996 -2.04623002 1.03805 -2.06018996 0 P 0 ;0
L 1.03805 -2.06018996 1.03756004 -2.07583002 0 P 0 ;0
L 1.03756004 -2.07583002 1.03696998 -2.09095 0 P 0 ;0
L 1.03696998 -2.09095 1.03548996 -2.12516004 0 P 0 ;0
L 1.03548996 -2.12516004 0.98546998 -2.12516004 0 P 0 ;0
L 0.98546998 -2.12516004 0.98586998 -2.12166004 0 P 0 ;0
L 0.98586998 -2.12166004 0.98696998 -2.10871998 0 P 0 ;0
L 0.98696998 -2.10871998 0.98796004 -2.08916004 0 P 0 ;0
L 0.98796004 -2.08916004 0.9886 -2.06963002 0 P 0 ;0
L 0.9886 -2.06963002 0.98853002 -2.05698002 0 P 0 ;0
L 0.98853002 -2.05698002 0.98781998 -2.0461 0 P 0 ;0
L 0.98781998 -2.0461 0.9875 -2.04373002 0 P 0 ;0
L 0.9875 -2.04373002 0.98748002 -2.04365 0 P 0 ;0
L 0.98748002 -2.04365 0.98698996 -2.04138996 0 P 0 ;0
L 0.98698996 -2.04138996 0.9863 -2.03908002 0 P 0 ;0
L 0.9863 -2.03908002 0.98588002 -2.038 0 P 0 ;0
L 0.98588002 -2.038 0.98538002 -2.03696004 0 P 0 ;0
L 0.98538002 -2.03696004 0.9848 -2.03596004 0 P 0 ;0
L 0.9848 -2.03596004 0.98413996 -2.03501004 0 P 0 ;0
L 0.98413996 -2.03501004 0.98341998 -2.03411004 0 P 0 ;0
L 0.98341998 -2.03411004 0.98336998 -2.03405 0 P 0 ;0
L 0.98336998 -2.03405 0.98263002 -2.03326004 0 P 0 ;0
L 0.98263002 -2.03326004 0.98176998 -2.03246998 0 P 0 ;0
L 0.98176998 -2.03246998 0.98086998 -2.03175 0 P 0 ;0
L 0.98086998 -2.03175 0.97991004 -2.0311 0 P 0 ;0
L 0.97991004 -2.0311 0.9789 -2.03051998 0 P 0 ;0
L 0.9789 -2.03051998 0.97783002 -2.03001998 0 P 0 ;0
L 0.97783002 -2.03001998 0.97673002 -2.02961004 0 P 0 ;0
L 0.97673002 -2.02961004 0.97663996 -2.02958002 0 P 0 ;0
L 0.97663996 -2.02958002 0.97558996 -2.02928996 0 P 0 ;0
L 0.97558996 -2.02928996 0.97443002 -2.02906998 0 P 0 ;0
L 0.97443002 -2.02906998 0.9727 -2.02888002 0 P 0 ;0
L 0.9727 -2.02888002 0.97261998 -2.02886998 0 P 0 ;0
L 0.97261998 -2.02886998 0.97096004 -2.02881004 0 P 0 ;0
L 0.97096004 -2.02881004 0.96921004 -2.02886004 0 P 0 ;0
L 0.96921004 -2.02886004 0.96745 -2.02903996 0 P 0 ;0
L 0.96745 -2.02903996 0.96571004 -2.02933996 0 P 0 ;0
L 0.96571004 -2.02933996 0.964 -2.02976004 0 P 0 ;0
L 0.964 -2.02976004 0.96283002 -2.03013996 0 P 0 ;0
L 0.96283002 -2.03013996 0.96168002 -2.0306 0 P 0 ;0
L 0.96168002 -2.0306 0.96056998 -2.03115 0 P 0 ;0
L 0.96056998 -2.03115 0.95948996 -2.03178002 0 P 0 ;0
L 0.95948996 -2.03178002 0.95791004 -2.03286998 0 P 0 ;0
L 0.95791004 -2.03286998 0.95645 -2.03408996 0 P 0 ;0
L 0.95645 -2.03408996 0.95508996 -2.03541998 0 P 0 ;0
L 0.95508996 -2.03541998 0.95383996 -2.03686998 0 P 0 ;0
L 0.95383996 -2.03686998 0.9538 -2.03693002 0 P 0 ;0
L 0.9538 -2.03693002 0.95273002 -2.03841004 0 P 0 ;0
L 0.95273002 -2.03841004 0.95175 -2.04003996 0 P 0 ;0
L 0.95175 -2.04003996 0.95023002 -2.04306004 0 P 0 ;0
L 0.95023002 -2.04306004 0.94896004 -2.04611004 0 P 0 ;0
L 0.94896004 -2.04611004 0.94893002 -2.04616998 0 P 0 ;0
L 0.94893002 -2.04616998 0.94783002 -2.04936004 0 P 0 ;0
L 0.94783002 -2.04936004 0.94695 -2.05263002 0 P 0 ;0
L 0.94695 -2.05263002 0.94515 -2.06203002 0 P 0 ;0
L 0.94515 -2.06203002 0.9441 -2.07156004 0 P 0 ;0
L 0.9441 -2.07156004 0.9427 -2.10128002 0 P 0 ;0
L 0.9427 -2.10128002 0.94208996 -2.12516004 0 P 0 ;0
L 0.94208996 -2.12516004 0.91651004 -2.12516004 0 P 0 ;0
L 0.93143002 -2.21261998 1.00578996 -2.21261998 0 P 0 ;0
L 0.94051004 -2.21161998 1.00803002 -2.21161998 0 P 0 ;0
L 0.94941998 -2.21061998 1.01026004 -2.21061998 0 P 0 ;0
L 0.9555 -2.20961998 1.0125 -2.20961998 0 P 0 ;0
L 0.96158002 -2.20861998 1.01473996 -2.20861998 0 P 0 ;0
L 0.96766004 -2.20761998 1.01696998 -2.20761998 0 P 0 ;0
L 0.97373002 -2.20661998 1.01921004 -2.20661998 0 P 0 ;0
L 0.97981004 -2.20561998 1.02145 -2.20561998 0 P 0 ;0
L 0.98498996 -2.20461998 1.02368996 -2.20461998 0 P 0 ;0
L 0.98973996 -2.20361998 1.02591998 -2.20361998 0 P 0 ;0
L 0.99448996 -2.20261998 1.02816004 -2.20261998 0 P 0 ;0
L 0.99923996 -2.20161998 1.0304 -2.20161998 0 P 0 ;0
L 1.00398996 -2.20061998 1.03243996 -2.20061998 0 P 0 ;0
L 1.00875 -2.19961998 1.0344 -2.19961998 0 P 0 ;0
L 1.01348996 -2.19861998 1.03636998 -2.19861998 0 P 0 ;0
L 1.0178 -2.19761998 1.03833996 -2.19761998 0 P 0 ;0
L 1.02168996 -2.19661998 1.04031004 -2.19661998 0 P 0 ;0
L 1.02558002 -2.19561998 1.04228002 -2.19561998 0 P 0 ;0
L 1.02946998 -2.19461998 1.04415 -2.19461998 0 P 0 ;0
L 1.03336004 -2.19361998 1.04596998 -2.19361998 0 P 0 ;0
L 1.03725 -2.19261998 1.04778996 -2.19261998 0 P 0 ;0
L 1.04113996 -2.19161998 1.0496 -2.19161998 0 P 0 ;0
L 1.14356998 -1.98926998 1.13261004 -1.99086004 0 P 0 ;0
L 1.13261004 -1.99086004 1.12165 -1.9934 0 P 0 ;0
L 1.12165 -1.9934 1.11125 -1.99673002 0 P 0 ;0
L 1.11125 -1.99673002 1.10658002 -1.99858996 0 P 0 ;0
L 1.10658002 -1.99858996 1.10198996 -2.00071004 0 P 0 ;0
L 1.10198996 -2.00071004 1.09653002 -2.00358996 0 P 0 ;0
L 1.09653002 -2.00358996 1.09436998 -2.00488996 0 P 0 ;0
L 1.09436998 -2.00488996 1.09226004 -2.00631004 0 P 0 ;0
L 1.09226004 -2.00631004 1.09028002 -2.00781004 0 P 0 ;0
L 1.09028002 -2.00781004 1.08836998 -2.00941998 0 P 0 ;0
L 1.08836998 -2.00941998 1.08405 -2.0135 0 P 0 ;0
L 1.08405 -2.0135 1.08096998 -2.01678996 0 P 0 ;0
L 1.08096998 -2.01678996 1.07808002 -2.02026998 0 P 0 ;0
L 1.07808002 -2.02026998 1.0754 -2.02393002 0 P 0 ;0
L 1.0754 -2.02393002 1.07313996 -2.02748002 0 P 0 ;0
L 1.07313996 -2.02748002 1.07116004 -2.03118996 0 P 0 ;0
L 1.07116004 -2.03118996 1.06943996 -2.03505 0 P 0 ;0
L 1.06943996 -2.03505 1.06795 -2.03918996 0 P 0 ;0
L 1.06795 -2.03918996 1.06673996 -2.04343996 0 P 0 ;0
L 1.06673996 -2.04343996 1.06583002 -2.04778002 0 P 0 ;0
L 1.06583002 -2.04778002 1.06476998 -2.05538996 0 P 0 ;0
L 1.06476998 -2.05538996 1.06421004 -2.06306004 0 P 0 ;0
L 1.06421004 -2.06306004 1.06415 -2.07076004 0 P 0 ;0
L 1.06415 -2.07076004 1.06456998 -2.0785 0 P 0 ;0
L 1.06456998 -2.0785 1.06508996 -2.08276004 0 P 0 ;0
L 1.06508996 -2.08276004 1.06591004 -2.08696004 0 P 0 ;0
L 1.06591004 -2.08696004 1.06703002 -2.09108002 0 P 0 ;0
L 1.06703002 -2.09108002 1.06833002 -2.09473002 0 P 0 ;0
L 1.06833002 -2.09473002 1.06991998 -2.09823996 0 P 0 ;0
L 1.06991998 -2.09823996 1.0718 -2.10161998 0 P 0 ;0
L 1.0718 -2.10161998 1.07398002 -2.10491998 0 P 0 ;0
L 1.07398002 -2.10491998 1.07641998 -2.10803002 0 P 0 ;0
L 1.07641998 -2.10803002 1.07908996 -2.11095 0 P 0 ;0
L 1.07908996 -2.11095 1.08175 -2.11345 0 P 0 ;0
L 1.08175 -2.11345 1.08458996 -2.11573996 0 P 0 ;0
L 1.08458996 -2.11573996 1.08758996 -2.1178 0 P 0 ;0
L 1.08758996 -2.1178 1.09073002 -2.11963996 0 P 0 ;0
L 1.09073002 -2.11963996 1.094 -2.12123996 0 P 0 ;0
L 1.094 -2.12123996 1.0986 -2.12306998 0 P 0 ;0
L 1.0986 -2.12306998 1.10331004 -2.12456004 0 P 0 ;0
L 1.10331004 -2.12456004 1.10811004 -2.12568996 0 P 0 ;0
L 1.10811004 -2.12568996 1.11298002 -2.12646998 0 P 0 ;0
L 1.11298002 -2.12646998 1.1182 -2.12693002 0 P 0 ;0
L 1.1182 -2.12693002 1.12343996 -2.12703002 0 P 0 ;0
L 1.12343996 -2.12703002 1.12866998 -2.12676004 0 P 0 ;0
L 1.12866998 -2.12676004 1.13388002 -2.12613002 0 P 0 ;0
L 1.13388002 -2.12613002 1.14086004 -2.12473996 0 P 0 ;0
L 1.14086004 -2.12473996 1.1477 -2.12273996 0 P 0 ;0
L 1.1477 -2.12273996 1.15433996 -2.12015 0 P 0 ;0
L 1.15433996 -2.12015 1.1545 -2.12008996 0 P 0 ;0
L 1.1545 -2.12008996 1.15466004 -2.12003996 0 P 0 ;0
L 1.15466004 -2.12003996 1.15483002 -2.12001004 0 P 0 ;0
L 1.15483002 -2.12001004 1.15498996 -2.11998996 0 P 0 ;0
L 1.15498996 -2.11998996 1.15533002 -2.11998996 0 P 0 ;0
L 1.15533002 -2.11998996 1.15538996 -2.12 0 P 0 ;0
L 1.15538996 -2.12 1.15545 -2.12001998 0 P 0 ;0
L 1.15545 -2.12001998 1.15551004 -2.12003002 0 P 0 ;0
L 1.15551004 -2.12003002 1.15556004 -2.12006004 0 P 0 ;0
L 1.15556004 -2.12006004 1.15561004 -2.12008002 0 P 0 ;0
L 1.15561004 -2.12008002 1.15566004 -2.12011004 0 P 0 ;0
L 1.15566004 -2.12011004 1.15571004 -2.12015 0 P 0 ;0
L 1.15571004 -2.12015 1.15575 -2.12018996 0 P 0 ;0
L 1.15575 -2.12018996 1.15578996 -2.12023996 0 P 0 ;0
L 1.15578996 -2.12023996 1.15583002 -2.12028002 0 P 0 ;0
L 1.15583002 -2.12028002 1.15586004 -2.12033996 0 P 0 ;0
L 1.15586004 -2.12033996 1.15588002 -2.12038996 0 P 0 ;0
L 1.15588002 -2.12038996 1.15591004 -2.12043996 0 P 0 ;0
L 1.15591004 -2.12043996 1.15601998 -2.12076004 0 P 0 ;0
L 1.15601998 -2.12076004 1.1561 -2.12108002 0 P 0 ;0
L 1.1561 -2.12108002 1.15616004 -2.12141998 0 P 0 ;0
L 1.15616004 -2.12141998 1.15618002 -2.12175 0 P 0 ;0
L 1.15618002 -2.12175 1.15623996 -2.12505 0 P 0 ;0
L 1.15623996 -2.12505 1.15616004 -2.12688002 0 P 0 ;0
L 1.15616004 -2.12688002 1.15593002 -2.12871004 0 P 0 ;0
L 1.15593002 -2.12871004 1.15553996 -2.13051998 0 P 0 ;0
L 1.15553996 -2.13051998 1.15516004 -2.1318 0 P 0 ;0
L 1.15516004 -2.1318 1.1547 -2.13305 0 P 0 ;0
L 1.1547 -2.13305 1.15415 -2.13426004 0 P 0 ;0
L 1.15415 -2.13426004 1.15351004 -2.13545 0 P 0 ;0
L 1.15351004 -2.13545 1.15278996 -2.1366 0 P 0 ;0
L 1.15278996 -2.1366 1.15198002 -2.13768996 0 P 0 ;0
L 1.15198002 -2.13768996 1.15111004 -2.13873002 0 P 0 ;0
L 1.15111004 -2.13873002 1.15016004 -2.13971004 0 P 0 ;0
L 1.15016004 -2.13971004 1.14876004 -2.14096004 0 P 0 ;0
L 1.14876004 -2.14096004 1.14726004 -2.1421 0 P 0 ;0
L 1.14726004 -2.1421 1.14566998 -2.14311004 0 P 0 ;0
L 1.14566998 -2.14311004 1.144 -2.144 0 P 0 ;0
L 1.144 -2.144 1.14226004 -2.14476004 0 P 0 ;0
L 1.14226004 -2.14476004 1.14046004 -2.14536998 0 P 0 ;0
L 1.14046004 -2.14536998 1.13863002 -2.14583002 0 P 0 ;0
L 1.13863002 -2.14583002 1.13676004 -2.14613996 0 P 0 ;0
L 1.13676004 -2.14613996 1.13041998 -2.14663996 0 P 0 ;0
L 1.13041998 -2.14663996 1.12403996 -2.1466 0 P 0 ;0
L 1.12403996 -2.1466 1.11621998 -2.14593996 0 P 0 ;0
L 1.11621998 -2.14593996 1.10843996 -2.14471004 0 P 0 ;0
L 1.10843996 -2.14471004 1.09946998 -2.14276998 0 P 0 ;0
L 1.09946998 -2.14276998 1.0905 -2.14041004 0 P 0 ;0
L 1.0905 -2.14041004 1.07963996 -2.13728996 0 P 0 ;0
L 1.07963996 -2.13728996 1.07936004 -2.1401 0 P 0 ;0
L 1.07936004 -2.1401 1.07931004 -2.14103996 0 P 0 ;0
L 1.07931004 -2.14103996 1.07931998 -2.14198002 0 P 0 ;0
L 1.07931998 -2.14198002 1.07956998 -2.14735 0 P 0 ;0
L 1.07956998 -2.14735 1.07993996 -2.15375 0 P 0 ;0
L 1.07993996 -2.15375 1.08045 -2.16081998 0 P 0 ;0
L 1.08045 -2.16081998 1.08181004 -2.17873002 0 P 0 ;0
L 1.08181004 -2.17873002 1.08996004 -2.18061004 0 P 0 ;0
L 1.08996004 -2.18061004 1.09951004 -2.18246004 0 P 0 ;0
L 1.09951004 -2.18246004 1.11243996 -2.18416998 0 P 0 ;0
L 1.11243996 -2.18416998 1.1254 -2.18543002 0 P 0 ;0
L 1.1254 -2.18543002 1.13508002 -2.18583002 0 P 0 ;0
L 1.13508002 -2.18583002 1.14765 -2.18528996 0 P 0 ;0
L 1.14765 -2.18528996 1.15368002 -2.18461004 0 P 0 ;0
L 1.15368002 -2.18461004 1.15971004 -2.18363996 0 P 0 ;0
L 1.15971004 -2.18363996 1.16521004 -2.18248002 0 P 0 ;0
L 1.16521004 -2.18248002 1.17063996 -2.18103002 0 P 0 ;0
L 1.17063996 -2.18103002 1.17528996 -2.17946998 0 P 0 ;0
L 1.17528996 -2.17946998 1.17978002 -2.17753996 0 P 0 ;0
L 1.17978002 -2.17753996 1.18216998 -2.1763 0 P 0 ;0
L 1.18216998 -2.1763 1.18446004 -2.17488996 0 P 0 ;0
L 1.18446004 -2.17488996 1.18663996 -2.17331004 0 P 0 ;0
L 1.18663996 -2.17331004 1.18871004 -2.17156004 0 P 0 ;0
L 1.18871004 -2.17156004 1.19161004 -2.16871998 0 P 0 ;0
L 1.19161004 -2.16871998 1.19431004 -2.16568996 0 P 0 ;0
L 1.19431004 -2.16568996 1.19678996 -2.16246998 0 P 0 ;0
L 1.19678996 -2.16246998 1.19908996 -2.15901998 0 P 0 ;0
L 1.19908996 -2.15901998 1.20113996 -2.15543996 0 P 0 ;0
L 1.20113996 -2.15543996 1.20295 -2.15171004 0 P 0 ;0
L 1.20295 -2.15171004 1.20435 -2.14815 0 P 0 ;0
L 1.20435 -2.14815 1.20543996 -2.14448996 0 P 0 ;0
L 1.20543996 -2.14448996 1.20621004 -2.14073996 0 P 0 ;0
L 1.20621004 -2.14073996 1.20651998 -2.13855 0 P 0 ;0
L 1.20651998 -2.13855 1.20671998 -2.13633996 0 P 0 ;0
L 1.20671998 -2.13633996 1.20761998 -2.12321004 0 P 0 ;0
L 1.20761998 -2.12321004 1.20858002 -2.10753996 0 P 0 ;0
L 1.20858002 -2.10753996 1.20951004 -2.09021998 0 P 0 ;0
L 1.20951004 -2.09021998 1.21048002 -2.07166004 0 P 0 ;0
L 1.21048002 -2.07166004 1.21156004 -2.05228002 0 P 0 ;0
L 1.21156004 -2.05228002 1.21258002 -2.03478996 0 P 0 ;0
L 1.21258002 -2.03478996 1.21333002 -2.02286004 0 P 0 ;0
L 1.21333002 -2.02286004 1.21393996 -2.01373996 0 P 0 ;0
L 1.21393996 -2.01373996 1.21443996 -2.00568996 0 P 0 ;0
L 1.21443996 -2.00568996 1.21485 -1.99883996 0 P 0 ;0
L 1.21485 -1.99883996 1.2149 -1.99721004 0 P 0 ;0
L 1.2149 -1.99721004 1.21488996 -1.99703996 0 P 0 ;0
L 1.21488996 -1.99703996 1.21486998 -1.99686004 0 P 0 ;0
L 1.21486998 -1.99686004 1.21483996 -1.99668996 0 P 0 ;0
L 1.21483996 -1.99668996 1.21478996 -1.99653002 0 P 0 ;0
L 1.21478996 -1.99653002 1.21473002 -1.99636998 0 P 0 ;0
L 1.21473002 -1.99636998 1.21466004 -1.99621004 0 P 0 ;0
L 1.21466004 -1.99621004 1.21458002 -1.99606004 0 P 0 ;0
L 1.21458002 -1.99606004 1.21448002 -1.99591004 0 P 0 ;0
L 1.21448002 -1.99591004 1.21433002 -1.99571998 0 P 0 ;0
L 1.21433002 -1.99571998 1.21416998 -1.99553996 0 P 0 ;0
L 1.21416998 -1.99553996 1.21398996 -1.99538002 0 P 0 ;0
L 1.21398996 -1.99538002 1.21378996 -1.99523996 0 P 0 ;0
L 1.21378996 -1.99523996 1.21358002 -1.99511004 0 P 0 ;0
L 1.21358002 -1.99511004 1.21336004 -1.995 0 P 0 ;0
L 1.21336004 -1.995 1.21261004 -1.99468996 0 P 0 ;0
L 1.21261004 -1.99468996 1.21183996 -1.99443996 0 P 0 ;0
L 1.21183996 -1.99443996 1.21105 -1.99423002 0 P 0 ;0
L 1.21105 -1.99423002 1.20593996 -1.99318002 0 P 0 ;0
L 1.20593996 -1.99318002 1.18996998 -1.99065 0 P 0 ;0
L 1.18996998 -1.99065 1.17318996 -1.98908002 0 P 0 ;0
L 1.17318996 -1.98908002 1.15718996 -1.98858002 0 P 0 ;0
L 1.15718996 -1.98858002 1.1504 -1.98876004 0 P 0 ;0
L 1.1504 -1.98876004 1.14356998 -1.98926998 0 P 0 ;0
L 1.04503996 -2.19061998 1.05141998 -2.19061998 0 P 0 ;0
L 1.04893002 -2.18961998 1.05323002 -2.18961998 0 P 0 ;0
L 1.05263002 -2.18861998 1.05503996 -2.18861998 0 P 0 ;0
L 1.05628996 -2.18761998 1.05676004 -2.18761998 0 P 0 ;0
L 1.09645 -2.17983002 1.16738002 -2.17983002 0 P 0 ;0
L 1.09126004 -2.17883002 1.17091004 -2.17883002 0 P 0 ;0
L 1.0868 -2.17783002 1.17386998 -2.17783002 0 P 0 ;0
L 1.08368002 -2.17683002 1.17636004 -2.17683002 0 P 0 ;0
L 1.0836 -2.17583002 1.1787 -2.17583002 0 P 0 ;0
L 1.08351998 -2.17483002 1.18066998 -2.17483002 0 P 0 ;0
L 1.08345 -2.17383002 1.18236998 -2.17383002 0 P 0 ;0
L 1.08336998 -2.17283002 1.1839 -2.17283002 0 P 0 ;0
L 1.08328996 -2.17183002 1.18526998 -2.17183002 0 P 0 ;0
L 1.08321998 -2.17083002 1.18646998 -2.17083002 0 P 0 ;0
L 1.08313996 -2.16983002 1.18761998 -2.16983002 0 P 0 ;0
L 1.08306998 -2.16883002 1.18863996 -2.16883002 0 P 0 ;0
L 1.08298996 -2.16783002 1.18966004 -2.16783002 0 P 0 ;0
L 1.08291998 -2.16683002 1.19061004 -2.16683002 0 P 0 ;0
L 1.08283996 -2.16583002 1.1915 -2.16583002 0 P 0 ;0
L 1.08276004 -2.16483002 1.19238996 -2.16483002 0 P 0 ;0
L 1.08268996 -2.16383002 1.19321004 -2.16383002 0 P 0 ;0
L 1.08261004 -2.16283002 1.19398002 -2.16283002 0 P 0 ;0
L 1.08253002 -2.16183002 1.19476004 -2.16183002 0 P 0 ;0
L 1.08246004 -2.16083002 1.19548002 -2.16083002 0 P 0 ;0
L 1.08238002 -2.15983002 1.19613996 -2.15983002 0 P 0 ;0
L 1.08231004 -2.15883002 1.19681004 -2.15883002 0 P 0 ;0
L 1.08223996 -2.15783002 1.19746004 -2.15783002 0 P 0 ;0
L 1.13506998 -2.18383002 1.12553002 -2.18343996 0 P 0 ;0
L 1.12553002 -2.18343996 1.11266004 -2.18218002 0 P 0 ;0
L 1.11266004 -2.18218002 1.09983002 -2.18048002 0 P 0 ;0
L 1.09983002 -2.18048002 1.09036998 -2.17866004 0 P 0 ;0
L 1.09036998 -2.17866004 1.0837 -2.17711004 0 P 0 ;0
L 1.0837 -2.17711004 1.08245 -2.16066998 0 P 0 ;0
L 1.08245 -2.16066998 1.08193996 -2.15361998 0 P 0 ;0
L 1.08193996 -2.15361998 1.08156998 -2.14726004 0 P 0 ;0
L 1.08156998 -2.14726004 1.08131998 -2.14191004 0 P 0 ;0
L 1.08131998 -2.14191004 1.08131004 -2.14108996 0 P 0 ;0
L 1.08131004 -2.14108996 1.08136004 -2.14026004 0 P 0 ;0
L 1.08136004 -2.14026004 1.0814 -2.13986998 0 P 0 ;0
L 1.0814 -2.13986998 1.08996004 -2.14233002 0 P 0 ;0
L 1.08996004 -2.14233002 1.08996998 -2.14233996 0 P 0 ;0
L 1.08996998 -2.14233996 1.08998996 -2.14233996 0 P 0 ;0
L 1.08998996 -2.14233996 1.099 -2.14471998 0 P 0 ;0
L 1.099 -2.14471998 1.10806998 -2.14668002 0 P 0 ;0
L 1.10806998 -2.14668002 1.11598002 -2.14791998 0 P 0 ;0
L 1.11598002 -2.14791998 1.12395 -2.1486 0 P 0 ;0
L 1.12395 -2.1486 1.13048996 -2.14863996 0 P 0 ;0
L 1.13048996 -2.14863996 1.137 -2.14811998 0 P 0 ;0
L 1.137 -2.14811998 1.13903002 -2.14778996 0 P 0 ;0
L 1.13903002 -2.14778996 1.14103002 -2.14728996 0 P 0 ;0
L 1.14103002 -2.14728996 1.14298002 -2.14661998 0 P 0 ;0
L 1.14298002 -2.14661998 1.14486998 -2.14581004 0 P 0 ;0
L 1.14486998 -2.14581004 1.14668002 -2.14483996 0 P 0 ;0
L 1.14668002 -2.14483996 1.1484 -2.14373996 0 P 0 ;0
L 1.1484 -2.14373996 1.15003002 -2.1425 0 P 0 ;0
L 1.15003002 -2.1425 1.15155 -2.14115 0 P 0 ;0
L 1.15155 -2.14115 1.1526 -2.14006998 0 P 0 ;0
L 1.1526 -2.14006998 1.15263996 -2.14001998 0 P 0 ;0
L 1.15263996 -2.14001998 1.15356004 -2.13893002 0 P 0 ;0
L 1.15356004 -2.13893002 1.15443996 -2.13771998 0 P 0 ;0
L 1.15443996 -2.13771998 1.15523002 -2.13646004 0 P 0 ;0
L 1.15523002 -2.13646004 1.15593996 -2.13515 0 P 0 ;0
L 1.15593996 -2.13515 1.15655 -2.13381004 0 P 0 ;0
L 1.15655 -2.13381004 1.15706004 -2.13243002 0 P 0 ;0
L 1.15706004 -2.13243002 1.15748002 -2.13101004 0 P 0 ;0
L 1.15748002 -2.13101004 1.1579 -2.12905 0 P 0 ;0
L 1.1579 -2.12905 1.15816004 -2.12706004 0 P 0 ;0
L 1.15816004 -2.12706004 1.15825 -2.12506998 0 P 0 ;0
L 1.15825 -2.12506998 1.15818002 -2.12165 0 P 0 ;0
L 1.15818002 -2.12165 1.15813996 -2.12118002 0 P 0 ;0
L 1.15813996 -2.12118002 1.15813002 -2.1211 0 P 0 ;0
L 1.15813002 -2.1211 1.15806004 -2.12068002 0 P 0 ;0
L 1.15806004 -2.12068002 1.15793996 -2.12018996 0 P 0 ;0
L 1.15793996 -2.12018996 1.15778002 -2.11973002 0 P 0 ;0
L 1.15778002 -2.11973002 1.1577 -2.11953002 0 P 0 ;0
L 1.1577 -2.11953002 1.15758996 -2.11933002 0 P 0 ;0
L 1.15758996 -2.11933002 1.15746998 -2.11913996 0 P 0 ;0
L 1.15746998 -2.11913996 1.15733002 -2.11895 0 P 0 ;0
L 1.15733002 -2.11895 1.15716998 -2.11878002 0 P 0 ;0
L 1.15716998 -2.11878002 1.157 -2.11863002 0 P 0 ;0
L 1.157 -2.11863002 1.15681998 -2.11848996 0 P 0 ;0
L 1.15681998 -2.11848996 1.15663002 -2.11836004 0 P 0 ;0
L 1.15663002 -2.11836004 1.15641998 -2.11825 0 P 0 ;0
L 1.15641998 -2.11825 1.15621004 -2.11816004 0 P 0 ;0
L 1.15621004 -2.11816004 1.15598996 -2.11808996 0 P 0 ;0
L 1.15598996 -2.11808996 1.15576998 -2.11803996 0 P 0 ;0
L 1.15576998 -2.11803996 1.15553002 -2.118 0 P 0 ;0
L 1.15553002 -2.118 1.15518002 -2.11798002 0 P 0 ;0
L 1.15518002 -2.11798002 1.15483996 -2.11798996 0 P 0 ;0
L 1.15483996 -2.11798996 1.15451004 -2.11803002 0 P 0 ;0
L 1.15451004 -2.11803002 1.15418002 -2.1181 0 P 0 ;0
L 1.15418002 -2.1181 1.15386004 -2.1182 0 P 0 ;0
L 1.15386004 -2.1182 1.15361004 -2.11828996 0 P 0 ;0
L 1.15361004 -2.11828996 1.14705 -2.12083996 0 P 0 ;0
L 1.14705 -2.12083996 1.14038996 -2.12278996 0 P 0 ;0
L 1.14038996 -2.12278996 1.13356004 -2.12416004 0 P 0 ;0
L 1.13356004 -2.12416004 1.1285 -2.12476998 0 P 0 ;0
L 1.1285 -2.12476998 1.12341004 -2.12501998 0 P 0 ;0
L 1.12341004 -2.12501998 1.11831004 -2.12493002 0 P 0 ;0
L 1.11831004 -2.12493002 1.11323002 -2.12448996 0 P 0 ;0
L 1.11323002 -2.12448996 1.10848996 -2.12373002 0 P 0 ;0
L 1.10848996 -2.12373002 1.10383996 -2.12263002 0 P 0 ;0
L 1.10383996 -2.12263002 1.09926998 -2.12118996 0 P 0 ;0
L 1.09926998 -2.12118996 1.09481004 -2.11941004 0 P 0 ;0
L 1.09481004 -2.11941004 1.09168002 -2.11788002 0 P 0 ;0
L 1.09168002 -2.11788002 1.08866004 -2.11611998 0 P 0 ;0
L 1.08866004 -2.11611998 1.08578002 -2.11413002 0 P 0 ;0
L 1.08578002 -2.11413002 1.08306998 -2.11193996 0 P 0 ;0
L 1.08306998 -2.11193996 1.08051998 -2.10955 0 P 0 ;0
L 1.08051998 -2.10955 1.07793996 -2.10673002 0 P 0 ;0
L 1.07793996 -2.10673002 1.07561004 -2.10373996 0 P 0 ;0
L 1.07561004 -2.10373996 1.07351004 -2.10058002 0 P 0 ;0
L 1.07351004 -2.10058002 1.07171004 -2.09733996 0 P 0 ;0
L 1.07171004 -2.09733996 1.07018002 -2.09396998 0 P 0 ;0
L 1.07018002 -2.09396998 1.06893996 -2.09048002 0 P 0 ;0
L 1.06893996 -2.09048002 1.06786004 -2.0865 0 P 0 ;0
L 1.06786004 -2.0865 1.06706004 -2.08243996 0 P 0 ;0
L 1.06706004 -2.08243996 1.06656004 -2.07833002 0 P 0 ;0
L 1.06656004 -2.07833002 1.06615 -2.07071004 0 P 0 ;0
L 1.06615 -2.07071004 1.06621004 -2.06313996 0 P 0 ;0
L 1.06621004 -2.06313996 1.06675 -2.0556 0 P 0 ;0
L 1.06675 -2.0556 1.0678 -2.04813002 0 P 0 ;0
L 1.0678 -2.04813002 1.06868996 -2.04391998 0 P 0 ;0
L 1.06868996 -2.04391998 1.06985 -2.03981004 0 P 0 ;0
L 1.06985 -2.03981004 1.0713 -2.03578996 0 P 0 ;0
L 1.0713 -2.03578996 1.07296004 -2.03206998 0 P 0 ;0
L 1.07296004 -2.03206998 1.07486998 -2.02848996 0 P 0 ;0
L 1.07486998 -2.02848996 1.07705 -2.02506004 0 P 0 ;0
L 1.07705 -2.02506004 1.07966004 -2.0215 0 P 0 ;0
L 1.07966004 -2.0215 1.08246998 -2.01811004 0 P 0 ;0
L 1.08246998 -2.01811004 1.08546998 -2.01491004 0 P 0 ;0
L 1.08546998 -2.01491004 1.0897 -2.01091004 0 P 0 ;0
L 1.0897 -2.01091004 1.09153002 -2.00936998 0 P 0 ;0
L 1.09153002 -2.00936998 1.09341998 -2.00793996 0 P 0 ;0
L 1.09341998 -2.00793996 1.09545 -2.00658002 0 P 0 ;0
L 1.09545 -2.00658002 1.09751004 -2.00533996 0 P 0 ;0
L 1.09751004 -2.00533996 1.10288002 -2.0025 0 P 0 ;0
L 1.10288002 -2.0025 1.10736998 -2.00043002 0 P 0 ;0
L 1.10736998 -2.00043002 1.11193002 -1.99861004 0 P 0 ;0
L 1.11193002 -1.99861004 1.12218002 -1.99533002 0 P 0 ;0
L 1.12218002 -1.99533002 1.13298002 -1.99281998 0 P 0 ;0
L 1.13298002 -1.99281998 1.14378996 -1.99126004 0 P 0 ;0
L 1.14378996 -1.99126004 1.1505 -1.99075 0 P 0 ;0
L 1.1505 -1.99075 1.15718002 -1.99058996 0 P 0 ;0
L 1.15718002 -1.99058996 1.17306998 -1.99108002 0 P 0 ;0
L 1.17306998 -1.99108002 1.18971998 -1.99263002 0 P 0 ;0
L 1.18971998 -1.99263002 1.20558002 -1.99515 0 P 0 ;0
L 1.20558002 -1.99515 1.21058996 -1.99618002 0 P 0 ;0
L 1.21058996 -1.99618002 1.21126998 -1.99636004 0 P 0 ;0
L 1.21126998 -1.99636004 1.21191998 -1.99656998 0 P 0 ;0
L 1.21191998 -1.99656998 1.21253002 -1.99681998 0 P 0 ;0
L 1.21253002 -1.99681998 1.21261004 -1.99686004 0 P 0 ;0
L 1.21261004 -1.99686004 1.21266004 -1.99688996 0 P 0 ;0
L 1.21266004 -1.99688996 1.21271998 -1.99693002 0 P 0 ;0
L 1.21271998 -1.99693002 1.21281998 -1.99703002 0 P 0 ;0
L 1.21281998 -1.99703002 1.21286004 -1.99708996 0 P 0 ;0
L 1.21286004 -1.99708996 1.21288002 -1.99711004 0 P 0 ;0
L 1.21288002 -1.99711004 1.21288002 -1.99711998 0 P 0 ;0
L 1.21288002 -1.99711998 1.21288996 -1.99715 0 P 0 ;0
L 1.21288996 -1.99715 1.2129 -1.99716998 0 P 0 ;0
L 1.2129 -1.99716998 1.2129 -1.99721998 0 P 0 ;0
L 1.2129 -1.99721998 1.21285 -1.99875 0 P 0 ;0
L 1.21285 -1.99875 1.21243996 -2.00556998 0 P 0 ;0
L 1.21243996 -2.00556998 1.21193996 -2.01361004 0 P 0 ;0
L 1.21193996 -2.01361004 1.21133996 -2.02273002 0 P 0 ;0
L 1.21133996 -2.02273002 1.21133996 -2.02273996 0 P 0 ;0
L 1.21133996 -2.02273996 1.21058996 -2.03468002 0 P 0 ;0
L 1.21058996 -2.03468002 1.20956004 -2.05216998 0 P 0 ;0
L 1.20956004 -2.05216998 1.20848996 -2.07156004 0 P 0 ;0
L 1.20848996 -2.07156004 1.20848996 -2.07156998 0 P 0 ;0
L 1.20848996 -2.07156998 1.20751004 -2.09011004 0 P 0 ;0
L 1.20751004 -2.09011004 1.20658996 -2.10743996 0 P 0 ;0
L 1.20658996 -2.10743996 1.20561998 -2.12308996 0 P 0 ;0
L 1.20561998 -2.12308996 1.20473002 -2.13618996 0 P 0 ;0
L 1.20473002 -2.13618996 1.20453002 -2.13831998 0 P 0 ;0
L 1.20453002 -2.13831998 1.20423996 -2.14041004 0 P 0 ;0
L 1.20423996 -2.14041004 1.2035 -2.144 0 P 0 ;0
L 1.2035 -2.144 1.20246004 -2.1475 0 P 0 ;0
L 1.20246004 -2.1475 1.20111998 -2.1509 0 P 0 ;0
L 1.20111998 -2.1509 1.19936998 -2.1545 0 P 0 ;0
L 1.19936998 -2.1545 1.19738002 -2.15796998 0 P 0 ;0
L 1.19738002 -2.15796998 1.19516004 -2.1613 0 P 0 ;0
L 1.19516004 -2.1613 1.19276998 -2.16441004 0 P 0 ;0
L 1.19276998 -2.16441004 1.19016004 -2.16733996 0 P 0 ;0
L 1.19016004 -2.16733996 1.18736004 -2.17008002 0 P 0 ;0
L 1.18736004 -2.17008002 1.1854 -2.17173996 0 P 0 ;0
L 1.1854 -2.17173996 1.18335 -2.17323002 0 P 0 ;0
L 1.18335 -2.17323002 1.18118002 -2.17456004 0 P 0 ;0
L 1.18118002 -2.17456004 1.17893002 -2.17573002 0 P 0 ;0
L 1.17893002 -2.17573002 1.17456998 -2.1776 0 P 0 ;0
L 1.17456998 -2.1776 1.17006998 -2.17911998 0 P 0 ;0
L 1.17006998 -2.17911998 1.16473996 -2.18053002 0 P 0 ;0
L 1.16473996 -2.18053002 1.15935 -2.18166998 0 P 0 ;0
L 1.15935 -2.18166998 1.15341998 -2.18263002 0 P 0 ;0
L 1.15341998 -2.18263002 1.1475 -2.18328996 0 P 0 ;0
L 1.1475 -2.18328996 1.13506998 -2.18383002 0 P 0 ;0
L 0.90491998 -2.21461998 1.00131004 -2.21461998 0 P 0 ;0
L 0.92235 -2.21361998 1.00355 -2.21361998 0 P 0 ;0
L 0.76925 -1.8965 0.85586998 -1.8965 0 P 0 ;0
L 0.76958996 -1.8955 0.85556004 -1.8955 0 P 0 ;0
L 0.76995 -1.8945 0.85521004 -1.8945 0 P 0 ;0
L 0.77031004 -1.8935 0.85486004 -1.8935 0 P 0 ;0
L 0.77071004 -1.8925 0.85443996 -1.8925 0 P 0 ;0
L 0.77115 -1.8915 0.85401004 -1.8915 0 P 0 ;0
L 0.7716 -1.8905 0.85355 -1.8905 0 P 0 ;0
L 0.77206004 -1.8895 0.85303002 -1.8895 0 P 0 ;0
L 0.7726 -1.8885 0.85251004 -1.8885 0 P 0 ;0
L 0.77313996 -1.8875 0.85198996 -1.8875 0 P 0 ;0
L 0.77368996 -1.8865 0.85138002 -1.8865 0 P 0 ;0
L 0.77433002 -1.8855 0.85073996 -1.8855 0 P 0 ;0
L 0.77496004 -1.8845 0.85011004 -1.8845 0 P 0 ;0
L 0.77561998 -1.8835 0.84943002 -1.8835 0 P 0 ;0
L 0.77636004 -1.8825 0.84866998 -1.8825 0 P 0 ;0
L 0.77711004 -1.8815 0.84791004 -1.8815 0 P 0 ;0
L 0.7779 -1.8805 0.84713002 -1.8805 0 P 0 ;0
L 0.77876998 -1.8795 0.84623002 -1.8795 0 P 0 ;0
L 0.77963996 -1.8785 0.84533002 -1.8785 0 P 0 ;0
L 0.7806 -1.8775 0.8444 -1.8775 0 P 0 ;0
L 0.78161004 -1.8765 0.84335 -1.8765 0 P 0 ;0
L 0.78265 -1.8755 0.84228996 -1.8755 0 P 0 ;0
L 0.78381998 -1.8745 0.84108996 -1.8745 0 P 0 ;0
L 0.78498996 -1.8735 0.83986998 -1.8735 0 P 0 ;0
L 0.78635 -1.8725 0.83848002 -1.8725 0 P 0 ;0
L 0.78773002 -1.8715 0.83706004 -1.8715 0 P 0 ;0
L 0.78933002 -1.8705 0.83541998 -1.8705 0 P 0 ;0
L 0.791 -1.8695 0.83366004 -1.8695 0 P 0 ;0
L 0.793 -1.8685 0.83171998 -1.8685 0 P 0 ;0
L 0.79525 -1.8675 0.82941998 -1.8675 0 P 0 ;0
L 0.79791998 -1.8665 0.82671004 -1.8665 0 P 0 ;0
L 0.80143996 -1.8655 0.82328996 -1.8655 0 P 0 ;0
L 0.80705 -1.8645 0.81776004 -1.8645 0 P 0 ;0
L 0.74543002 -1.89661998 0.75033002 -1.89661998 0 P 0 ;0
L 0.74751004 -1.89561998 0.75058996 -1.89561998 0 P 0 ;0
L 0.74958996 -1.89461998 0.75086004 -1.89461998 0 P 0 ;0
L 0.76733996 -1.9125 0.85751998 -1.9125 0 P 0 ;0
L 0.76728996 -1.9115 0.85756004 -1.9115 0 P 0 ;0
L 0.76723996 -1.9105 0.85758996 -1.9105 0 P 0 ;0
L 0.76721998 -1.9095 0.85763002 -1.9095 0 P 0 ;0
L 0.76725 -1.9085 0.85761004 -1.9085 0 P 0 ;0
L 0.76728002 -1.9075 0.85756998 -1.9075 0 P 0 ;0
L 0.76731004 -1.9065 0.85753002 -1.9065 0 P 0 ;0
L 0.76741998 -1.9055 0.85748996 -1.9055 0 P 0 ;0
L 0.76753996 -1.9045 0.85738002 -1.9045 0 P 0 ;0
L 0.76766004 -1.9035 0.85726004 -1.9035 0 P 0 ;0
L 0.76781998 -1.9025 0.85713996 -1.9025 0 P 0 ;0
L 0.76801998 -1.9015 0.85701004 -1.9015 0 P 0 ;0
L 0.76821004 -1.9005 0.85683002 -1.9005 0 P 0 ;0
L 0.76841998 -1.8995 0.85661998 -1.8995 0 P 0 ;0
L 0.7687 -1.8985 0.85641004 -1.8985 0 P 0 ;0
L 0.76896998 -1.8975 0.85613996 -1.8975 0 P 0 ;0
L 0.76751004 -2.08325 0.8416 -2.08325 0 P 0 ;0
L 0.76761998 -2.08225 0.84161998 -2.08225 0 P 0 ;0
L 0.76773996 -2.08125 0.84166998 -2.08125 0 P 0 ;0
L 0.76786004 -2.08025 0.84171998 -2.08025 0 P 0 ;0
L 0.76796998 -2.07925 0.84176998 -2.07925 0 P 0 ;0
L 0.76808002 -2.07825 0.84181004 -2.07825 0 P 0 ;0
L 0.76818002 -2.07725 0.84186004 -2.07725 0 P 0 ;0
L 0.76828996 -2.07625 0.8419 -2.07625 0 P 0 ;0
L 0.76838996 -2.07525 0.84195 -2.07525 0 P 0 ;0
L 0.76848996 -2.07425 0.842 -2.07425 0 P 0 ;0
L 0.7686 -2.07325 0.84205 -2.07325 0 P 0 ;0
L 0.7687 -2.07225 0.84208996 -2.07225 0 P 0 ;0
L 0.7688 -2.07125 0.84213996 -2.07125 0 P 0 ;0
L 0.7689 -2.07025 0.84218002 -2.07025 0 P 0 ;0
L 0.76901004 -2.06925 0.84223002 -2.06925 0 P 0 ;0
L 0.76911004 -2.06825 0.84228002 -2.06825 0 P 0 ;0
L 0.76921004 -2.06725 0.84233002 -2.06725 0 P 0 ;0
L 0.76931998 -2.06625 0.84236998 -2.06625 0 P 0 ;0
L 0.76941998 -2.06525 0.84241998 -2.06525 0 P 0 ;0
L 0.76948996 -2.06425 0.84246004 -2.06425 0 P 0 ;0
L 0.76956004 -2.06325 0.84251004 -2.06325 0 P 0 ;0
L 0.76963002 -2.06225 0.84256004 -2.06225 0 P 0 ;0
L 0.7697 -2.06125 0.8426 -2.06125 0 P 0 ;0
L 0.76976998 -2.06025 0.84265 -2.06025 0 P 0 ;0
L 0.76983996 -2.05925 0.8427 -2.05925 0 P 0 ;0
L 0.76991004 -2.05825 0.84273996 -2.05825 0 P 0 ;0
L 0.76996998 -2.05725 0.84278996 -2.05725 0 P 0 ;0
L 0.77001004 -2.05625 0.84283996 -2.05625 0 P 0 ;0
L 0.77003996 -2.05525 0.84288002 -2.05525 0 P 0 ;0
L 0.77008002 -2.05425 0.84295 -2.05425 0 P 0 ;0
L 0.77011998 -2.05325 0.84303996 -2.05325 0 P 0 ;0
L 0.77016004 -2.05225 0.84311998 -2.05225 0 P 0 ;0
L 0.77018996 -2.05125 0.84321004 -2.05125 0 P 0 ;0
L 0.77023002 -2.05025 0.8433 -2.05025 0 P 0 ;0
L 0.77026998 -2.04925 0.84338002 -2.04925 0 P 0 ;0
L 0.77031004 -2.04825 0.84346998 -2.04825 0 P 0 ;0
L 0.77033996 -2.04725 0.84356004 -2.04725 0 P 0 ;0
L 0.77038002 -2.04625 0.84363996 -2.04625 0 P 0 ;0
L 0.77041004 -2.04525 0.84373002 -2.04525 0 P 0 ;0
L 0.77043996 -2.04425 0.84381004 -2.04425 0 P 0 ;0
L 0.77046004 -2.04325 0.8439 -2.04325 0 P 0 ;0
L 0.77048002 -2.04225 0.84398996 -2.04225 0 P 0 ;0
L 0.77051004 -2.04125 0.84406998 -2.04125 0 P 0 ;0
L 0.77053002 -2.04025 0.84416004 -2.04025 0 P 0 ;0
L 0.77055 -2.03925 0.84425 -2.03925 0 P 0 ;0
L 0.77058002 -2.03825 0.84433002 -2.03825 0 P 0 ;0
L 0.7706 -2.03725 0.84441998 -2.03725 0 P 0 ;0
L 0.77061998 -2.03625 0.84451004 -2.03625 0 P 0 ;0
L 0.77065 -2.03525 0.84458996 -2.03525 0 P 0 ;0
L 0.77066998 -2.03425 0.84468002 -2.03425 0 P 0 ;0
L 0.7707 -2.03325 0.84476998 -2.03325 0 P 0 ;0
L 0.77071998 -2.03225 0.84485 -2.03225 0 P 0 ;0
L 0.77073002 -2.03125 0.84493996 -2.03125 0 P 0 ;0
L 0.77073996 -2.03025 0.84503002 -2.03025 0 P 0 ;0
L 0.79986004 -1.8638 0.79643996 -1.86486998 0 P 0 ;0
L 0.79643996 -1.86486998 0.79311998 -1.86621004 0 P 0 ;0
L 0.79311998 -1.86621004 0.78991004 -1.86781004 0 P 0 ;0
L 0.78991004 -1.86781004 0.78683996 -1.86966998 0 P 0 ;0
L 0.78683996 -1.86966998 0.78391998 -1.87178002 0 P 0 ;0
L 0.78391998 -1.87178002 0.78111998 -1.87416998 0 P 0 ;0
L 0.78111998 -1.87416998 0.7785 -1.87676004 0 P 0 ;0
L 0.7785 -1.87676004 0.77608002 -1.87953996 0 P 0 ;0
L 0.77608002 -1.87953996 0.77386998 -1.8825 0 P 0 ;0
L 0.77386998 -1.8825 0.77188002 -1.88561998 0 P 0 ;0
L 0.77188002 -1.88561998 0.77013996 -1.88886004 0 P 0 ;0
L 0.77013996 -1.88886004 0.76863996 -1.89221004 0 P 0 ;0
L 0.76863996 -1.89221004 0.7674 -1.89566998 0 P 0 ;0
L 0.7674 -1.89566998 0.76643002 -1.89921004 0 P 0 ;0
L 0.76643002 -1.89921004 0.76571004 -1.90283996 0 P 0 ;0
L 0.76571004 -1.90283996 0.76531004 -1.90636004 0 P 0 ;0
L 0.76531004 -1.90636004 0.7652 -1.90991004 0 P 0 ;0
L 0.7652 -1.90991004 0.76538996 -1.91345 0 P 0 ;0
L 0.76538996 -1.91345 0.76586998 -1.91696998 0 P 0 ;0
L 0.76586998 -1.91696998 0.76663996 -1.92046004 0 P 0 ;0
L 0.76663996 -1.92046004 0.76803002 -1.92493996 0 P 0 ;0
L 0.76803002 -1.92493996 0.76978002 -1.9293 0 P 0 ;0
L 0.76978002 -1.9293 0.77106998 -1.93193996 0 P 0 ;0
L 0.77106998 -1.93193996 0.77253002 -1.93448002 0 P 0 ;0
L 0.77253002 -1.93448002 0.77416004 -1.93693996 0 P 0 ;0
L 0.77416004 -1.93693996 0.77593002 -1.93923002 0 P 0 ;0
L 0.77593002 -1.93923002 0.77783996 -1.94141004 0 P 0 ;0
L 0.77783996 -1.94141004 0.77988996 -1.94345 0 P 0 ;0
L 0.77988996 -1.94345 0.78216004 -1.94545 0 P 0 ;0
L 0.78216004 -1.94545 0.78453996 -1.9473 0 P 0 ;0
L 0.78453996 -1.9473 0.78703002 -1.94901998 0 P 0 ;0
L 0.78703002 -1.94901998 0.79016998 -1.95088002 0 P 0 ;0
L 0.79016998 -1.95088002 0.79343996 -1.95248996 0 P 0 ;0
L 0.79343996 -1.95248996 0.79683002 -1.95383996 0 P 0 ;0
L 0.79683002 -1.95383996 0.80031998 -1.95491998 0 P 0 ;0
L 0.80031998 -1.95491998 0.80391004 -1.95573996 0 P 0 ;0
L 0.80391004 -1.95573996 0.80751998 -1.95626004 0 P 0 ;0
L 0.80751998 -1.95626004 0.81116004 -1.9565 0 P 0 ;0
L 0.81116004 -1.9565 0.81481004 -1.95646004 0 P 0 ;0
L 0.81481004 -1.95646004 0.81843996 -1.95613002 0 P 0 ;0
L 0.81843996 -1.95613002 0.82205 -1.95551004 0 P 0 ;0
L 0.82205 -1.95551004 0.82561998 -1.95461004 0 P 0 ;0
L 0.82561998 -1.95461004 0.82911004 -1.95345 0 P 0 ;0
L 0.82911004 -1.95345 0.83248996 -1.95201004 0 P 0 ;0
L 0.83248996 -1.95201004 0.83576004 -1.95031998 0 P 0 ;0
L 0.83576004 -1.95031998 0.83891998 -1.94836004 0 P 0 ;0
L 0.83891998 -1.94836004 0.84191998 -1.94616998 0 P 0 ;0
L 0.84191998 -1.94616998 0.84475 -1.94375 0 P 0 ;0
L 0.84475 -1.94375 0.84738996 -1.94113996 0 P 0 ;0
L 0.84738996 -1.94113996 0.84983002 -1.93833996 0 P 0 ;0
L 0.84983002 -1.93833996 0.85206998 -1.93533996 0 P 0 ;0
L 0.85206998 -1.93533996 0.8536 -1.93291998 0 P 0 ;0
L 0.8536 -1.93291998 0.85496004 -1.93041004 0 P 0 ;0
L 0.85496004 -1.93041004 0.85613996 -1.9278 0 P 0 ;0
L 0.85613996 -1.9278 0.85711998 -1.92511004 0 P 0 ;0
L 0.85711998 -1.92511004 0.85823002 -1.92123002 0 P 0 ;0
L 0.85823002 -1.92123002 0.85901998 -1.91726998 0 P 0 ;0
L 0.85901998 -1.91726998 0.85948996 -1.91323996 0 P 0 ;0
L 0.85948996 -1.91323996 0.85963996 -1.90918002 0 P 0 ;0
L 0.85963996 -1.90918002 0.85946998 -1.90513002 0 P 0 ;0
L 0.85946998 -1.90513002 0.85898002 -1.9011 0 P 0 ;0
L 0.85898002 -1.9011 0.85841998 -1.89826004 0 P 0 ;0
L 0.85841998 -1.89826004 0.85766004 -1.89546004 0 P 0 ;0
L 0.85766004 -1.89546004 0.85671004 -1.89273002 0 P 0 ;0
L 0.85671004 -1.89273002 0.85556998 -1.89006004 0 P 0 ;0
L 0.85556998 -1.89006004 0.85361998 -1.88631004 0 P 0 ;0
L 0.85361998 -1.88631004 0.85136004 -1.88273996 0 P 0 ;0
L 0.85136004 -1.88273996 0.84881004 -1.87938002 0 P 0 ;0
L 0.84881004 -1.87938002 0.84596998 -1.87623002 0 P 0 ;0
L 0.84596998 -1.87623002 0.84355 -1.87393996 0 P 0 ;0
L 0.84355 -1.87393996 0.84096998 -1.87181998 0 P 0 ;0
L 0.84096998 -1.87181998 0.83826004 -1.86988996 0 P 0 ;0
L 0.83826004 -1.86988996 0.83541004 -1.86815 0 P 0 ;0
L 0.83541004 -1.86815 0.83243996 -1.86661004 0 P 0 ;0
L 0.83243996 -1.86661004 0.82938996 -1.86531004 0 P 0 ;0
L 0.82938996 -1.86531004 0.82625 -1.86423002 0 P 0 ;0
L 0.82625 -1.86423002 0.82303996 -1.86336004 0 P 0 ;0
L 0.82303996 -1.86336004 0.81978002 -1.86273002 0 P 0 ;0
L 0.81978002 -1.86273002 0.81646998 -1.86233002 0 P 0 ;0
L 0.81646998 -1.86233002 0.81228996 -1.86215 0 P 0 ;0
L 0.81228996 -1.86215 0.80811004 -1.86233996 0 P 0 ;0
L 0.80811004 -1.86233996 0.80396004 -1.86288996 0 P 0 ;0
L 0.80396004 -1.86288996 0.79986004 -1.8638 0 P 0 ;0
L 0.80308996 -1.9535 0.82186004 -1.9535 0 P 0 ;0
L 0.79926004 -1.9525 0.82563996 -1.9525 0 P 0 ;0
L 0.79636004 -1.9515 0.82856998 -1.9515 0 P 0 ;0
L 0.79393002 -1.9505 0.83093996 -1.9505 0 P 0 ;0
L 0.7919 -1.9495 0.83298996 -1.9495 0 P 0 ;0
L 0.79008002 -1.9485 0.8349 -1.9485 0 P 0 ;0
L 0.78838996 -1.9475 0.83651004 -1.9475 0 P 0 ;0
L 0.7869 -1.9465 0.83806998 -1.9465 0 P 0 ;0
L 0.78548002 -1.9455 0.83943996 -1.9455 0 P 0 ;0
L 0.7842 -1.9445 0.84078996 -1.9445 0 P 0 ;0
L 0.78298002 -1.9435 0.84196998 -1.9435 0 P 0 ;0
L 0.78183996 -1.9425 0.84313996 -1.9425 0 P 0 ;0
L 0.78076998 -1.9415 0.84418996 -1.9415 0 P 0 ;0
L 0.77976004 -1.9405 0.8452 -1.9405 0 P 0 ;0
L 0.77883002 -1.9395 0.84616998 -1.9395 0 P 0 ;0
L 0.77793996 -1.9385 0.84703996 -1.9385 0 P 0 ;0
L 0.77711998 -1.9375 0.84791004 -1.9375 0 P 0 ;0
L 0.77635 -1.9365 0.84871004 -1.9365 0 P 0 ;0
L 0.77561004 -1.9355 0.84945 -1.9355 0 P 0 ;0
L 0.77493996 -1.9345 0.8502 -1.9345 0 P 0 ;0
L 0.77428002 -1.9335 0.85086998 -1.9335 0 P 0 ;0
L 0.7737 -1.9325 0.8515 -1.9325 0 P 0 ;0
L 0.77311998 -1.9315 0.8521 -1.9315 0 P 0 ;0
L 0.77258996 -1.9305 0.85263996 -1.9305 0 P 0 ;0
L 0.7721 -1.9295 0.85318002 -1.9295 0 P 0 ;0
L 0.77161004 -1.9285 0.85363002 -1.9285 0 P 0 ;0
L 0.77121004 -1.9275 0.85408002 -1.9275 0 P 0 ;0
L 0.77081004 -1.9265 0.85448002 -1.9265 0 P 0 ;0
L 0.77041004 -1.9255 0.85485 -1.9255 0 P 0 ;0
L 0.77001004 -1.9245 0.85521998 -1.9245 0 P 0 ;0
L 0.76968002 -1.9235 0.8555 -1.9235 0 P 0 ;0
L 0.76936998 -1.9225 0.85578996 -1.9225 0 P 0 ;0
L 0.76906004 -1.9215 0.85606998 -1.9215 0 P 0 ;0
L 0.76875 -1.9205 0.85633002 -1.9205 0 P 0 ;0
L 0.76848002 -1.9195 0.85653002 -1.9195 0 P 0 ;0
L 0.76826004 -1.9185 0.85673002 -1.9185 0 P 0 ;0
L 0.76803002 -1.9175 0.85693002 -1.9175 0 P 0 ;0
L 0.76783002 -1.9165 0.85708996 -1.9165 0 P 0 ;0
L 0.76768996 -1.9155 0.85721004 -1.9155 0 P 0 ;0
L 0.76755 -1.9145 0.85733002 -1.9145 0 P 0 ;0
L 0.76741998 -1.9135 0.85745 -1.9135 0 P 0 ;0
L 0.81121004 -1.9545 0.80773002 -1.95426998 0 P 0 ;0
L 0.80773002 -1.95426998 0.80426998 -1.95376998 0 P 0 ;0
L 0.80426998 -1.95376998 0.80083996 -1.95298996 0 P 0 ;0
L 0.80083996 -1.95298996 0.7975 -1.95195 0 P 0 ;0
L 0.7975 -1.95195 0.79426004 -1.95066004 0 P 0 ;0
L 0.79426004 -1.95066004 0.79111998 -1.94911998 0 P 0 ;0
L 0.79111998 -1.94911998 0.78811004 -1.94733002 0 P 0 ;0
L 0.78811004 -1.94733002 0.78573002 -1.94568996 0 P 0 ;0
L 0.78573002 -1.94568996 0.78343996 -1.9439 0 P 0 ;0
L 0.78343996 -1.9439 0.78126004 -1.94198996 0 P 0 ;0
L 0.78126004 -1.94198996 0.7793 -1.94003996 0 P 0 ;0
L 0.7793 -1.94003996 0.77746998 -1.93796004 0 P 0 ;0
L 0.77746998 -1.93796004 0.77578996 -1.93576998 0 P 0 ;0
L 0.77578996 -1.93576998 0.77423002 -1.93343002 0 P 0 ;0
L 0.77423002 -1.93343002 0.77283996 -1.931 0 P 0 ;0
L 0.77283996 -1.931 0.77161004 -1.92848996 0 P 0 ;0
L 0.77161004 -1.92848996 0.76991998 -1.92426998 0 P 0 ;0
L 0.76991998 -1.92426998 0.76858002 -1.91993996 0 P 0 ;0
L 0.76858002 -1.91993996 0.76783996 -1.91661998 0 P 0 ;0
L 0.76783996 -1.91661998 0.76738002 -1.91326998 0 P 0 ;0
L 0.76738002 -1.91326998 0.76721004 -1.90988996 0 P 0 ;0
L 0.76721004 -1.90988996 0.76731004 -1.90651004 0 P 0 ;0
L 0.76731004 -1.90651004 0.7677 -1.90315 0 P 0 ;0
L 0.7677 -1.90315 0.76838002 -1.89966998 0 P 0 ;0
L 0.76838002 -1.89966998 0.76931004 -1.89626998 0 P 0 ;0
L 0.76931004 -1.89626998 0.7705 -1.89296004 0 P 0 ;0
L 0.7705 -1.89296004 0.77193996 -1.88973996 0 P 0 ;0
L 0.77193996 -1.88973996 0.7736 -1.88663996 0 P 0 ;0
L 0.7736 -1.88663996 0.77551004 -1.88363996 0 P 0 ;0
L 0.77551004 -1.88363996 0.77763002 -1.8808 0 P 0 ;0
L 0.77763002 -1.8808 0.77996004 -1.87813002 0 P 0 ;0
L 0.77996004 -1.87813002 0.78246998 -1.87565 0 P 0 ;0
L 0.78246998 -1.87565 0.78516004 -1.87336004 0 P 0 ;0
L 0.78516004 -1.87336004 0.78795 -1.87133996 0 P 0 ;0
L 0.78795 -1.87133996 0.79088002 -1.86956004 0 P 0 ;0
L 0.79088002 -1.86956004 0.79393996 -1.86803002 0 P 0 ;0
L 0.79393996 -1.86803002 0.79711004 -1.86675 0 P 0 ;0
L 0.79711004 -1.86675 0.80038002 -1.86573002 0 P 0 ;0
L 0.80038002 -1.86573002 0.80431004 -1.86486004 0 P 0 ;0
L 0.80431004 -1.86486004 0.80828996 -1.86433996 0 P 0 ;0
L 0.80828996 -1.86433996 0.8123 -1.86416004 0 P 0 ;0
L 0.8123 -1.86416004 0.81631004 -1.86431998 0 P 0 ;0
L 0.81631004 -1.86431998 0.81946998 -1.86471004 0 P 0 ;0
L 0.81946998 -1.86471004 0.82258996 -1.86531004 0 P 0 ;0
L 0.82258996 -1.86531004 0.82566004 -1.86613996 0 P 0 ;0
L 0.82566004 -1.86613996 0.82866998 -1.86718002 0 P 0 ;0
L 0.82866998 -1.86718002 0.83158996 -1.86843002 0 P 0 ;0
L 0.83158996 -1.86843002 0.83443002 -1.86988996 0 P 0 ;0
L 0.83443002 -1.86988996 0.83716004 -1.87156004 0 P 0 ;0
L 0.83716004 -1.87156004 0.83976004 -1.87341004 0 P 0 ;0
L 0.83976004 -1.87341004 0.84223002 -1.87543996 0 P 0 ;0
L 0.84223002 -1.87543996 0.84453996 -1.87763002 0 P 0 ;0
L 0.84453996 -1.87763002 0.84726998 -1.88065 0 P 0 ;0
L 0.84726998 -1.88065 0.84971998 -1.88388002 0 P 0 ;0
L 0.84971998 -1.88388002 0.85188996 -1.88731004 0 P 0 ;0
L 0.85188996 -1.88731004 0.85376004 -1.89091004 0 P 0 ;0
L 0.85376004 -1.89091004 0.85483996 -1.89345 0 P 0 ;0
L 0.85483996 -1.89345 0.85575 -1.89605 0 P 0 ;0
L 0.85575 -1.89605 0.85646998 -1.89871004 0 P 0 ;0
L 0.85646998 -1.89871004 0.857 -1.90141004 0 P 0 ;0
L 0.857 -1.90141004 0.85748002 -1.9053 0 P 0 ;0
L 0.85748002 -1.9053 0.85763996 -1.90918996 0 P 0 ;0
L 0.85763996 -1.90918996 0.8575 -1.91308002 0 P 0 ;0
L 0.8575 -1.91308002 0.85703996 -1.91696004 0 P 0 ;0
L 0.85703996 -1.91696004 0.85628002 -1.92076004 0 P 0 ;0
L 0.85628002 -1.92076004 0.85521998 -1.92448996 0 P 0 ;0
L 0.85521998 -1.92448996 0.85428002 -1.92705 0 P 0 ;0
L 0.85428002 -1.92705 0.85316998 -1.92951998 0 P 0 ;0
L 0.85316998 -1.92951998 0.85188002 -1.93191004 0 P 0 ;0
L 0.85188002 -1.93191004 0.85041998 -1.9342 0 P 0 ;0
L 0.85041998 -1.9342 0.84826998 -1.93708002 0 P 0 ;0
L 0.84826998 -1.93708002 0.84593002 -1.93976998 0 P 0 ;0
L 0.84593002 -1.93976998 0.8434 -1.94228002 0 P 0 ;0
L 0.8434 -1.94228002 0.84068002 -1.9446 0 P 0 ;0
L 0.84068002 -1.9446 0.8378 -1.9467 0 P 0 ;0
L 0.8378 -1.9467 0.83476998 -1.94858002 0 P 0 ;0
L 0.83476998 -1.94858002 0.83163996 -1.9502 0 P 0 ;0
L 0.83163996 -1.9502 0.8284 -1.95158002 0 P 0 ;0
L 0.8284 -1.95158002 0.82506004 -1.95268996 0 P 0 ;0
L 0.82506004 -1.95268996 0.82163996 -1.95356004 0 P 0 ;0
L 0.82163996 -1.95356004 0.81818002 -1.95413996 0 P 0 ;0
L 0.81818002 -1.95413996 0.8147 -1.95446004 0 P 0 ;0
L 0.8147 -1.95446004 0.81121004 -1.9545 0 P 0 ;0
L 0.77075 -2.02925 0.84511004 -2.02925 0 P 0 ;0
L 0.77076004 -2.02825 0.8452 -2.02825 0 P 0 ;0
L 0.77076998 -2.02725 0.84528996 -2.02725 0 P 0 ;0
L 0.77078002 -2.02625 0.84536998 -2.02625 0 P 0 ;0
L 0.77078996 -2.02525 0.84548996 -2.02525 0 P 0 ;0
L 0.7708 -2.02425 0.84561998 -2.02425 0 P 0 ;0
L 0.77081004 -2.02325 0.84575 -2.02325 0 P 0 ;0
L 0.77081998 -2.02225 0.84588002 -2.02225 0 P 0 ;0
L 0.77083002 -2.02125 0.84601004 -2.02125 0 P 0 ;0
L 0.77083996 -2.02025 0.84613996 -2.02025 0 P 0 ;0
L 0.77085 -2.01925 0.84626004 -2.01925 0 P 0 ;0
L 0.77085 -2.01825 0.84638996 -2.01825 0 P 0 ;0
L 0.77085 -2.01725 0.84651998 -2.01725 0 P 0 ;0
L 0.77086004 -2.01625 0.84663996 -2.01625 0 P 0 ;0
L 0.77086004 -2.01525 0.84676998 -2.01525 0 P 0 ;0
L 0.77086004 -2.01425 0.8469 -2.01425 0 P 0 ;0
L 0.77086004 -2.01325 0.84703002 -2.01325 0 P 0 ;0
L 0.77086004 -2.01225 0.84716004 -2.01225 0 P 0 ;0
L 0.77086004 -2.01125 0.84728996 -2.01125 0 P 0 ;0
L 0.77086004 -2.01025 0.84741004 -2.01025 0 P 0 ;0
L 0.77086998 -2.00925 0.84753996 -2.00925 0 P 0 ;0
L 0.77086998 -2.00825 0.84766998 -2.00825 0 P 0 ;0
L 0.77086998 -2.00725 0.84778996 -2.00725 0 P 0 ;0
L 0.77086998 -2.00625 0.84791998 -2.00625 0 P 0 ;0
L 0.77086998 -2.00525 0.84805 -2.00525 0 P 0 ;0
L 0.77086998 -2.00425 0.84818002 -2.00425 0 P 0 ;0
L 0.77088002 -2.00325 0.84831004 -2.00325 0 P 0 ;0
L 0.77088002 -2.00225 0.84843996 -2.00225 0 P 0 ;0
L 0.77088002 -2.00125 0.84856004 -2.00125 0 P 0 ;0
L 0.77088002 -2.00025 0.84868996 -2.00025 0 P 0 ;0
L 0.77088002 -1.99925 0.84881998 -1.99925 0 P 0 ;0
L 0.77088002 -1.99825 0.84896004 -1.99825 0 P 0 ;0
L 0.77088002 -1.99725 0.84911004 -1.99725 0 P 0 ;0
L 0.77088996 -1.99625 0.84926998 -1.99625 0 P 0 ;0
L 0.77088996 -1.99525 0.84941998 -1.99525 0 P 0 ;0
L 0.77088996 -1.99425 0.84956998 -1.99425 0 P 0 ;0
L 0.77088996 -1.99325 0.84971998 -1.99325 0 P 0 ;0
L 0.77088996 -1.99225 0.84986998 -1.99225 0 P 0 ;0
L 0.77088996 -1.99125 0.85003002 -1.99125 0 P 0 ;0
L 0.7709 -1.99025 0.85018002 -1.99025 0 P 0 ;0
L 0.7709 -1.98925 0.85033002 -1.98925 0 P 0 ;0
L 0.76885 -2.01878002 0.76871998 -2.03201998 0 P 0 ;0
L 0.76871998 -2.03201998 0.7684 -2.04553996 0 P 0 ;0
L 0.7684 -2.04553996 0.76796004 -2.05751004 0 P 0 ;0
L 0.76796004 -2.05751004 0.76741004 -2.06523002 0 P 0 ;0
L 0.76741004 -2.06523002 0.76596004 -2.07933996 0 P 0 ;0
L 0.76596004 -2.07933996 0.7636 -2.09918002 0 P 0 ;0
L 0.7636 -2.09918002 0.76116004 -2.119 0 P 0 ;0
L 0.76116004 -2.119 0.76011998 -2.12526004 0 P 0 ;0
L 0.76011998 -2.12526004 0.75948996 -2.12825 0 P 0 ;0
L 0.75948996 -2.12825 0.84418002 -2.12825 0 P 0 ;0
L 0.84418002 -2.12825 0.84361998 -2.10788002 0 P 0 ;0
L 0.84361998 -2.10788002 0.8436 -2.08276004 0 P 0 ;0
L 0.8436 -2.08276004 0.8449 -2.05491998 0 P 0 ;0
L 0.8449 -2.05491998 0.84736004 -2.02641004 0 P 0 ;0
L 0.84736004 -2.02641004 0.85083996 -1.99923002 0 P 0 ;0
L 0.85083996 -1.99923002 0.85268996 -1.987 0 P 0 ;0
L 0.85268996 -1.987 0.7689 -1.987 0 P 0 ;0
L 0.7689 -1.987 0.76885 -2.01878002 0 P 0 ;0
L 0.76195 -2.12625 0.84211998 -2.12625 0 P 0 ;0
L 0.76213996 -2.12525 0.8421 -2.12525 0 P 0 ;0
L 0.76231004 -2.12425 0.84206998 -2.12425 0 P 0 ;0
L 0.76248002 -2.12325 0.84203996 -2.12325 0 P 0 ;0
L 0.76263996 -2.12225 0.84201004 -2.12225 0 P 0 ;0
L 0.76281004 -2.12125 0.84198996 -2.12125 0 P 0 ;0
L 0.76296998 -2.12025 0.84196004 -2.12025 0 P 0 ;0
L 0.76313996 -2.11925 0.84193002 -2.11925 0 P 0 ;0
L 0.76326998 -2.11825 0.8419 -2.11825 0 P 0 ;0
L 0.76338996 -2.11725 0.84188002 -2.11725 0 P 0 ;0
L 0.76351004 -2.11625 0.84185 -2.11625 0 P 0 ;0
L 0.76363996 -2.11525 0.84181998 -2.11525 0 P 0 ;0
L 0.76376004 -2.11425 0.84178996 -2.11425 0 P 0 ;0
L 0.76388002 -2.11325 0.84176998 -2.11325 0 P 0 ;0
L 0.76401004 -2.11225 0.84173996 -2.11225 0 P 0 ;0
L 0.76413002 -2.11125 0.84171004 -2.11125 0 P 0 ;0
L 0.76425 -2.11025 0.84168002 -2.11025 0 P 0 ;0
L 0.76438002 -2.10925 0.84166004 -2.10925 0 P 0 ;0
L 0.7645 -2.10825 0.84163002 -2.10825 0 P 0 ;0
L 0.76461998 -2.10725 0.84161998 -2.10725 0 P 0 ;0
L 0.76475 -2.10625 0.84161998 -2.10625 0 P 0 ;0
L 0.76486998 -2.10525 0.84161998 -2.10525 0 P 0 ;0
L 0.76498996 -2.10425 0.84161998 -2.10425 0 P 0 ;0
L 0.76511998 -2.10325 0.84161998 -2.10325 0 P 0 ;0
L 0.76523996 -2.10225 0.84161998 -2.10225 0 P 0 ;0
L 0.76536004 -2.10125 0.84161998 -2.10125 0 P 0 ;0
L 0.76548996 -2.10025 0.84161998 -2.10025 0 P 0 ;0
L 0.76561004 -2.09925 0.84161998 -2.09925 0 P 0 ;0
L 0.76573002 -2.09825 0.84161004 -2.09825 0 P 0 ;0
L 0.76583996 -2.09725 0.84161004 -2.09725 0 P 0 ;0
L 0.76596998 -2.09625 0.84161004 -2.09625 0 P 0 ;0
L 0.76608996 -2.09525 0.84161004 -2.09525 0 P 0 ;0
L 0.7662 -2.09425 0.84161004 -2.09425 0 P 0 ;0
L 0.76631998 -2.09325 0.84161004 -2.09325 0 P 0 ;0
L 0.76643996 -2.09225 0.84161004 -2.09225 0 P 0 ;0
L 0.76656004 -2.09125 0.84161004 -2.09125 0 P 0 ;0
L 0.76668002 -2.09025 0.84161004 -2.09025 0 P 0 ;0
L 0.76678996 -2.08925 0.84161004 -2.08925 0 P 0 ;0
L 0.76691998 -2.08825 0.84161004 -2.08825 0 P 0 ;0
L 0.76703002 -2.08725 0.84161004 -2.08725 0 P 0 ;0
L 0.76715 -2.08625 0.8416 -2.08625 0 P 0 ;0
L 0.76726998 -2.08525 0.8416 -2.08525 0 P 0 ;0
L 0.76738996 -2.08425 0.8416 -2.08425 0 P 0 ;0
L 0.76195 -2.12625 0.76208002 -2.12561998 0 P 0 ;0
L 0.76208002 -2.12561998 0.76313996 -2.11928996 0 P 0 ;0
L 0.76313996 -2.11928996 0.76558996 -2.09941998 0 P 0 ;0
L 0.76558996 -2.09941998 0.76558996 -2.09941004 0 P 0 ;0
L 0.76558996 -2.09941004 0.76793996 -2.07956004 0 P 0 ;0
L 0.76793996 -2.07956004 0.7694 -2.0654 0 P 0 ;0
L 0.7694 -2.0654 0.76941004 -2.06536004 0 P 0 ;0
L 0.76941004 -2.06536004 0.76996004 -2.05761998 0 P 0 ;0
L 0.76996004 -2.05761998 0.76996004 -2.05758996 0 P 0 ;0
L 0.76996004 -2.05758996 0.7704 -2.0456 0 P 0 ;0
L 0.7704 -2.0456 0.77071998 -2.03206004 0 P 0 ;0
L 0.77071998 -2.03206004 0.77085 -2.01878002 0 P 0 ;0
L 0.77085 -2.01878002 0.7709 -1.989 0 P 0 ;0
L 0.7709 -1.989 0.85036004 -1.989 0 P 0 ;0
L 0.85036004 -1.989 0.84886004 -1.99895 0 P 0 ;0
L 0.84886004 -1.99895 0.84538002 -2.02618996 0 P 0 ;0
L 0.84538002 -2.02618996 0.8429 -2.05478996 0 P 0 ;0
L 0.8429 -2.05478996 0.8416 -2.08271004 0 P 0 ;0
L 0.8416 -2.08271004 0.84161998 -2.10791004 0 P 0 ;0
L 0.84161998 -2.10791004 0.84211998 -2.12625 0 P 0 ;0
L 0.84211998 -2.12625 0.76195 -2.12625 0 P 0 ;0
L 0.71628996 -1.91261998 0.74938002 -1.91261998 0 P 0 ;0
L 0.71783002 -1.91161998 0.74933002 -1.91161998 0 P 0 ;0
L 0.71953002 -1.91061998 0.74931004 -1.91061998 0 P 0 ;0
L 0.72133002 -1.90961998 0.74928996 -1.90961998 0 P 0 ;0
L 0.72313996 -1.90861998 0.74926998 -1.90861998 0 P 0 ;0
L 0.72493996 -1.90761998 0.74928996 -1.90761998 0 P 0 ;0
L 0.72673996 -1.90661998 0.74931998 -1.90661998 0 P 0 ;0
L 0.72855 -1.90561998 0.74935 -1.90561998 0 P 0 ;0
L 0.73035 -1.90461998 0.74938996 -1.90461998 0 P 0 ;0
L 0.73215 -1.90361998 0.74946998 -1.90361998 0 P 0 ;0
L 0.73396004 -1.90261998 0.74953996 -1.90261998 0 P 0 ;0
L 0.73576004 -1.90161998 0.74961998 -1.90161998 0 P 0 ;0
L 0.73756998 -1.90061998 0.74973996 -1.90061998 0 P 0 ;0
L 0.73943002 -1.89961998 0.74986004 -1.89961998 0 P 0 ;0
L 0.74141998 -1.89861998 0.74998996 -1.89861998 0 P 0 ;0
L 0.74341004 -1.89761998 0.75015 -1.89761998 0 P 0 ;0
L 0.59843002 -2.08361998 0.6754 -2.08361998 0 P 0 ;0
L 0.59846004 -2.08261998 0.67538996 -2.08261998 0 P 0 ;0
L 0.59848002 -2.08161998 0.67538002 -2.08161998 0 P 0 ;0
L 0.59851004 -2.08061998 0.67538002 -2.08061998 0 P 0 ;0
L 0.59853002 -2.07961998 0.67546004 -2.07961998 0 P 0 ;0
L 0.59856004 -2.07861998 0.67553996 -2.07861998 0 P 0 ;0
L 0.59861998 -2.07761998 0.67561004 -2.07761998 0 P 0 ;0
L 0.5987 -2.07661998 0.67568996 -2.07661998 0 P 0 ;0
L 0.59878002 -2.07561998 0.67576004 -2.07561998 0 P 0 ;0
L 0.59885 -2.07461998 0.67583996 -2.07461998 0 P 0 ;0
L 0.59893002 -2.07361998 0.67591998 -2.07361998 0 P 0 ;0
L 0.59901004 -2.07261998 0.67598996 -2.07261998 0 P 0 ;0
L 0.59908002 -2.07161998 0.67606998 -2.07161998 0 P 0 ;0
L 0.59916004 -2.07061998 0.67613996 -2.07061998 0 P 0 ;0
L 0.59923002 -2.06961998 0.67621004 -2.06961998 0 P 0 ;0
L 0.59936004 -2.06861998 0.6763 -2.06861998 0 P 0 ;0
L 0.59948996 -2.06761998 0.67645 -2.06761998 0 P 0 ;0
L 0.59963002 -2.06661998 0.6766 -2.06661998 0 P 0 ;0
L 0.59976998 -2.06561998 0.67676004 -2.06561998 0 P 0 ;0
L 0.5999 -2.06461998 0.67691998 -2.06461998 0 P 0 ;0
L 0.60003002 -2.06361998 0.67706998 -2.06361998 0 P 0 ;0
L 0.60016998 -2.06261998 0.6773 -2.06261998 0 P 0 ;0
L 0.60031004 -2.06161998 0.67753002 -2.06161998 0 P 0 ;0
L 0.60051004 -2.06061998 0.67776004 -2.06061998 0 P 0 ;0
L 0.60071004 -2.05961998 0.67798996 -2.05961998 0 P 0 ;0
L 0.60091998 -2.05861998 0.67823002 -2.05861998 0 P 0 ;0
L 0.60111998 -2.05761998 0.67853002 -2.05761998 0 P 0 ;0
L 0.60133002 -2.05661998 0.67883996 -2.05661998 0 P 0 ;0
L 0.60153996 -2.05561998 0.67913996 -2.05561998 0 P 0 ;0
L 0.60173996 -2.05461998 0.67945 -2.05461998 0 P 0 ;0
L 0.60195 -2.05361998 0.67975 -2.05361998 0 P 0 ;0
L 0.60223002 -2.05261998 0.68006004 -2.05261998 0 P 0 ;0
L 0.60251004 -2.05161998 0.68036004 -2.05161998 0 P 0 ;0
L 0.60278996 -2.05061998 0.68066998 -2.05061998 0 P 0 ;0
L 0.60306004 -2.04961998 0.68096998 -2.04961998 0 P 0 ;0
L 0.60333996 -2.04861998 0.68135 -2.04861998 0 P 0 ;0
L 0.60361998 -2.04761998 0.68173002 -2.04761998 0 P 0 ;0
L 0.6039 -2.04661998 0.68211004 -2.04661998 0 P 0 ;0
L 0.60418002 -2.04561998 0.68248996 -2.04561998 0 P 0 ;0
L 0.60453002 -2.04461998 0.68288002 -2.04461998 0 P 0 ;0
L 0.60488002 -2.04361998 0.68326004 -2.04361998 0 P 0 ;0
L 0.60523002 -2.04261998 0.68363996 -2.04261998 0 P 0 ;0
L 0.60556998 -2.04161998 0.68401998 -2.04161998 0 P 0 ;0
L 0.60591998 -2.04061998 0.6844 -2.04061998 0 P 0 ;0
L 0.60626998 -2.03961998 0.68486004 -2.03961998 0 P 0 ;0
L 0.60661998 -2.03861998 0.68531998 -2.03861998 0 P 0 ;0
L 0.60698996 -2.03761998 0.68578002 -2.03761998 0 P 0 ;0
L 0.60743002 -2.03661998 0.68623996 -2.03661998 0 P 0 ;0
L 0.60786004 -2.03561998 0.6867 -2.03561998 0 P 0 ;0
L 0.60828996 -2.03461998 0.68716004 -2.03461998 0 P 0 ;0
L 0.60873002 -2.03361998 0.68761998 -2.03361998 0 P 0 ;0
L 0.60916004 -2.03261998 0.68808996 -2.03261998 0 P 0 ;0
L 0.60958996 -2.03161998 0.68856998 -2.03161998 0 P 0 ;0
L 0.61003002 -2.03061998 0.68911004 -2.03061998 0 P 0 ;0
L 0.61046004 -2.02961998 0.68965 -2.02961998 0 P 0 ;0
L 0.61088996 -2.02861998 0.69018996 -2.02861998 0 P 0 ;0
L 0.61133002 -2.02761998 0.69073002 -2.02761998 0 P 0 ;0
L 0.61176004 -2.02661998 0.69126998 -2.02661998 0 P 0 ;0
L 0.6122 -2.02561998 0.69181004 -2.02561998 0 P 0 ;0
L 0.61263002 -2.02461998 0.69235 -2.02461998 0 P 0 ;0
L 0.61306004 -2.02361998 0.69288002 -2.02361998 0 P 0 ;0
L 0.61348996 -2.02261998 0.69346998 -2.02261998 0 P 0 ;0
L 0.61393002 -2.02161998 0.69408996 -2.02161998 0 P 0 ;0
L 0.61436004 -2.02061998 0.6947 -2.02061998 0 P 0 ;0
L 0.61478996 -2.01961998 0.69531998 -2.01961998 0 P 0 ;0
L 0.61531004 -2.01861998 0.69593996 -2.01861998 0 P 0 ;0
L 0.61583996 -2.01761998 0.69656004 -2.01761998 0 P 0 ;0
L 0.61636004 -2.01661998 0.69718002 -2.01661998 0 P 0 ;0
L 0.61688002 -2.01561998 0.69778996 -2.01561998 0 P 0 ;0
L 0.6174 -2.01461998 0.69841998 -2.01461998 0 P 0 ;0
L 0.61791998 -2.01361998 0.69911998 -2.01361998 0 P 0 ;0
L 0.61843996 -2.01261998 0.69981998 -2.01261998 0 P 0 ;0
L 0.61896004 -2.01161998 0.70051998 -2.01161998 0 P 0 ;0
L 0.61948002 -2.01061998 0.70123002 -2.01061998 0 P 0 ;0
L 0.62 -2.00961998 0.70193002 -2.00961998 0 P 0 ;0
L 0.62051998 -2.00861998 0.70263002 -2.00861998 0 P 0 ;0
L 0.62103996 -2.00761998 0.70333002 -2.00761998 0 P 0 ;0
L 0.62163996 -2.00661998 0.70403996 -2.00661998 0 P 0 ;0
L 0.62225 -2.00561998 0.70483002 -2.00561998 0 P 0 ;0
L 0.62285 -2.00461998 0.70565 -2.00461998 0 P 0 ;0
L 0.62346004 -2.00361998 0.70646004 -2.00361998 0 P 0 ;0
L 0.62406004 -2.00261998 0.70726998 -2.00261998 0 P 0 ;0
L 0.62466004 -2.00161998 0.70808996 -2.00161998 0 P 0 ;0
L 0.62526998 -2.00061998 0.7089 -2.00061998 0 P 0 ;0
L 0.62586998 -1.99961998 0.70971004 -1.99961998 0 P 0 ;0
L 0.62648002 -1.99861998 0.71053002 -1.99861998 0 P 0 ;0
L 0.62708002 -1.99761998 0.71133996 -1.99761998 0 P 0 ;0
L 0.62768996 -1.99661998 0.71216004 -1.99661998 0 P 0 ;0
L 0.62831998 -1.99561998 0.71296998 -1.99561998 0 P 0 ;0
L 0.62901004 -1.99461998 0.71378996 -1.99461998 0 P 0 ;0
L 0.62971004 -1.99361998 0.71466004 -1.99361998 0 P 0 ;0
L 0.6304 -1.99261998 0.71561004 -1.99261998 0 P 0 ;0
L 0.6311 -1.99161998 0.71656998 -1.99161998 0 P 0 ;0
L 0.63178996 -1.99061998 0.71753002 -1.99061998 0 P 0 ;0
L 0.63248996 -1.98961998 0.71848996 -1.98961998 0 P 0 ;0
L 0.63318002 -1.98861998 0.71945 -1.98861998 0 P 0 ;0
L 0.63388002 -1.98761998 0.72041004 -1.98761998 0 P 0 ;0
L 0.63456998 -1.98661998 0.72136998 -1.98661998 0 P 0 ;0
L 0.63526998 -1.98561998 0.72233002 -1.98561998 0 P 0 ;0
L 0.63598002 -1.98461998 0.72328996 -1.98461998 0 P 0 ;0
L 0.63678996 -1.98361998 0.72425 -1.98361998 0 P 0 ;0
L 0.6376 -1.98261998 0.72521004 -1.98261998 0 P 0 ;0
L 0.63841004 -1.98161998 0.72628002 -1.98161998 0 P 0 ;0
L 0.63921998 -1.98061998 0.72738996 -1.98061998 0 P 0 ;0
L 0.64003002 -1.97961998 0.7285 -1.97961998 0 P 0 ;0
L 0.64083996 -1.97861998 0.72961004 -1.97861998 0 P 0 ;0
L 0.64165 -1.97761998 0.73071004 -1.97761998 0 P 0 ;0
L 0.64246004 -1.97661998 0.73181998 -1.97661998 0 P 0 ;0
L 0.64326998 -1.97561998 0.73293002 -1.97561998 0 P 0 ;0
L 0.64406998 -1.97461998 0.73403996 -1.97461998 0 P 0 ;0
L 0.64488002 -1.97361998 0.73515 -1.97361998 0 P 0 ;0
L 0.64568996 -1.97261998 0.73625 -1.97261998 0 P 0 ;0
L 0.6465 -1.97161998 0.73736004 -1.97161998 0 P 0 ;0
L 0.64731004 -1.97061998 0.73848002 -1.97061998 0 P 0 ;0
L 0.64811998 -1.96961998 0.73973002 -1.96961998 0 P 0 ;0
L 0.64893002 -1.96861998 0.74098996 -1.96861998 0 P 0 ;0
L 0.64981004 -1.96761998 0.74225 -1.96761998 0 P 0 ;0
L 0.65076004 -1.96661998 0.74351004 -1.96661998 0 P 0 ;0
L 0.65171004 -1.96561998 0.74476998 -1.96561998 0 P 0 ;0
L 0.65266998 -1.96461998 0.74603002 -1.96461998 0 P 0 ;0
L 0.65361998 -1.96361998 0.74728996 -1.96361998 0 P 0 ;0
L 0.65458002 -1.96261998 0.74855 -1.96261998 0 P 0 ;0
L 0.65553002 -1.96161998 0.74981004 -1.96161998 0 P 0 ;0
L 0.65648996 -1.96061998 0.75106004 -1.96061998 0 P 0 ;0
L 0.65743996 -1.95961998 0.75233996 -1.95961998 0 P 0 ;0
L 0.6584 -1.95861998 0.7537 -1.95861998 0 P 0 ;0
L 0.65935 -1.95761998 0.75506004 -1.95761998 0 P 0 ;0
L 0.66031004 -1.95661998 0.75641998 -1.95661998 0 P 0 ;0
L 0.66126004 -1.95561998 0.75778996 -1.95561998 0 P 0 ;0
L 0.66221004 -1.95461998 0.75916004 -1.95461998 0 P 0 ;0
L 0.66316998 -1.95361998 0.76053996 -1.95361998 0 P 0 ;0
L 0.66411998 -1.95261998 0.76193996 -1.95261998 0 P 0 ;0
L 0.66523002 -1.95161998 0.76333996 -1.95161998 0 P 0 ;0
L 0.66636004 -1.95061998 0.76406998 -1.95061998 0 P 0 ;0
L 0.66746998 -1.94961998 0.76355 -1.94961998 0 P 0 ;0
L 0.6686 -1.94861998 0.76291998 -1.94861998 0 P 0 ;0
L 0.66971004 -1.94761998 0.76226998 -1.94761998 0 P 0 ;0
L 0.67083996 -1.94661998 0.76161998 -1.94661998 0 P 0 ;0
L 0.67196004 -1.94561998 0.76096998 -1.94561998 0 P 0 ;0
L 0.67306998 -1.94461998 0.76033002 -1.94461998 0 P 0 ;0
L 0.6742 -1.94361998 0.75968996 -1.94361998 0 P 0 ;0
L 0.67531004 -1.94261998 0.75905 -1.94261998 0 P 0 ;0
L 0.67643996 -1.94161998 0.75846004 -1.94161998 0 P 0 ;0
L 0.67755 -1.94061998 0.75788996 -1.94061998 0 P 0 ;0
L 0.67868002 -1.93961998 0.75731998 -1.93961998 0 P 0 ;0
L 0.67978996 -1.93861998 0.75676998 -1.93861998 0 P 0 ;0
L 0.68091998 -1.93761998 0.75626998 -1.93761998 0 P 0 ;0
L 0.68221004 -1.93661998 0.75576998 -1.93661998 0 P 0 ;0
L 0.68353002 -1.93561998 0.75528002 -1.93561998 0 P 0 ;0
L 0.68483996 -1.93461998 0.75483996 -1.93461998 0 P 0 ;0
L 0.68616004 -1.93361998 0.75441004 -1.93361998 0 P 0 ;0
L 0.68746998 -1.93261998 0.75398002 -1.93261998 0 P 0 ;0
L 0.68878002 -1.93161998 0.7536 -1.93161998 0 P 0 ;0
L 0.6901 -1.93061998 0.75323996 -1.93061998 0 P 0 ;0
L 0.69141004 -1.92961998 0.75286998 -1.92961998 0 P 0 ;0
L 0.69271998 -1.92861998 0.75253996 -1.92861998 0 P 0 ;0
L 0.69403002 -1.92761998 0.75223002 -1.92761998 0 P 0 ;0
L 0.69535 -1.92661998 0.75193002 -1.92661998 0 P 0 ;0
L 0.69666004 -1.92561998 0.75163002 -1.92561998 0 P 0 ;0
L 0.69796998 -1.92461998 0.75138002 -1.92461998 0 P 0 ;0
L 0.69936998 -1.92361998 0.75113996 -1.92361998 0 P 0 ;0
L 0.70091004 -1.92261998 0.75088996 -1.92261998 0 P 0 ;0
L 0.70243996 -1.92161998 0.75066004 -1.92161998 0 P 0 ;0
L 0.70398002 -1.92061998 0.75046004 -1.92061998 0 P 0 ;0
L 0.70551998 -1.91961998 0.75026004 -1.91961998 0 P 0 ;0
L 0.70706004 -1.91861998 0.75006998 -1.91861998 0 P 0 ;0
L 0.7086 -1.91761998 0.7499 -1.91761998 0 P 0 ;0
L 0.71013996 -1.91661998 0.74976998 -1.91661998 0 P 0 ;0
L 0.71166998 -1.91561998 0.74961998 -1.91561998 0 P 0 ;0
L 0.71321004 -1.91461998 0.74951998 -1.91461998 0 P 0 ;0
L 0.71475 -1.91361998 0.74945 -1.91361998 0 P 0 ;0
L 0.61556998 -2.15661998 0.70655 -2.15661998 0 P 0 ;0
L 0.61503002 -2.15561998 0.7056 -2.15561998 0 P 0 ;0
L 0.61448996 -2.15461998 0.70465 -2.15461998 0 P 0 ;0
L 0.61395 -2.15361998 0.7037 -2.15361998 0 P 0 ;0
L 0.61341004 -2.15261998 0.70273996 -2.15261998 0 P 0 ;0
L 0.61286998 -2.15161998 0.70178996 -2.15161998 0 P 0 ;0
L 0.61233002 -2.15061998 0.70095 -2.15061998 0 P 0 ;0
L 0.61188002 -2.14961998 0.70015 -2.14961998 0 P 0 ;0
L 0.61143002 -2.14861998 0.69935 -2.14861998 0 P 0 ;0
L 0.61098002 -2.14761998 0.69855 -2.14761998 0 P 0 ;0
L 0.61053002 -2.14661998 0.69775 -2.14661998 0 P 0 ;0
L 0.61008002 -2.14561998 0.69695 -2.14561998 0 P 0 ;0
L 0.60963002 -2.14461998 0.69615 -2.14461998 0 P 0 ;0
L 0.60918002 -2.14361998 0.69535 -2.14361998 0 P 0 ;0
L 0.60873002 -2.14261998 0.69455 -2.14261998 0 P 0 ;0
L 0.60831004 -2.14161998 0.69381998 -2.14161998 0 P 0 ;0
L 0.60793996 -2.14061998 0.69315 -2.14061998 0 P 0 ;0
L 0.60756998 -2.13961998 0.69248002 -2.13961998 0 P 0 ;0
L 0.60721004 -2.13861998 0.69181004 -2.13861998 0 P 0 ;0
L 0.60683996 -2.13761998 0.69115 -2.13761998 0 P 0 ;0
L 0.60646998 -2.13661998 0.69048002 -2.13661998 0 P 0 ;0
L 0.60611004 -2.13561998 0.68981004 -2.13561998 0 P 0 ;0
L 0.60573996 -2.13461998 0.68918002 -2.13461998 0 P 0 ;0
L 0.60538002 -2.13361998 0.68863002 -2.13361998 0 P 0 ;0
L 0.60503996 -2.13261998 0.68808002 -2.13261998 0 P 0 ;0
L 0.60476004 -2.13161998 0.68753002 -2.13161998 0 P 0 ;0
L 0.60446998 -2.13061998 0.68698002 -2.13061998 0 P 0 ;0
L 0.60418002 -2.12961998 0.68643002 -2.12961998 0 P 0 ;0
L 0.6039 -2.12861998 0.68588002 -2.12861998 0 P 0 ;0
L 0.60361004 -2.12761998 0.68533002 -2.12761998 0 P 0 ;0
L 0.60331998 -2.12661998 0.68486004 -2.12661998 0 P 0 ;0
L 0.60303002 -2.12561998 0.68441998 -2.12561998 0 P 0 ;0
L 0.60275 -2.12461998 0.68396998 -2.12461998 0 P 0 ;0
L 0.60246004 -2.12361998 0.68353002 -2.12361998 0 P 0 ;0
L 0.60218002 -2.12261998 0.68308996 -2.12261998 0 P 0 ;0
L 0.60188996 -2.12161998 0.68263996 -2.12161998 0 P 0 ;0
L 0.60166998 -2.12061998 0.6822 -2.12061998 0 P 0 ;0
L 0.60145 -2.11961998 0.68176004 -2.11961998 0 P 0 ;0
L 0.60123002 -2.11861998 0.68138996 -2.11861998 0 P 0 ;0
L 0.60101004 -2.11761998 0.68105 -2.11761998 0 P 0 ;0
L 0.60078002 -2.11661998 0.68071004 -2.11661998 0 P 0 ;0
L 0.6006 -2.11561998 0.68036004 -2.11561998 0 P 0 ;0
L 0.60043002 -2.11461998 0.68001998 -2.11461998 0 P 0 ;0
L 0.60025 -2.11361998 0.67968002 -2.11361998 0 P 0 ;0
L 0.60008002 -2.11261998 0.67933002 -2.11261998 0 P 0 ;0
L 0.59991004 -2.11161998 0.67898996 -2.11161998 0 P 0 ;0
L 0.59976004 -2.11061998 0.6787 -2.11061998 0 P 0 ;0
L 0.59963996 -2.10961998 0.67845 -2.10961998 0 P 0 ;0
L 0.59951004 -2.10861998 0.6782 -2.10861998 0 P 0 ;0
L 0.59938002 -2.10761998 0.67795 -2.10761998 0 P 0 ;0
L 0.59925 -2.10661998 0.6777 -2.10661998 0 P 0 ;0
L 0.59913002 -2.10561998 0.67746004 -2.10561998 0 P 0 ;0
L 0.59905 -2.10461998 0.67721004 -2.10461998 0 P 0 ;0
L 0.59896998 -2.10361998 0.67696004 -2.10361998 0 P 0 ;0
L 0.59888002 -2.10261998 0.67671004 -2.10261998 0 P 0 ;0
L 0.5988 -2.10161998 0.67653996 -2.10161998 0 P 0 ;0
L 0.59871998 -2.10061998 0.67638002 -2.10061998 0 P 0 ;0
L 0.59866998 -2.09961998 0.67621004 -2.09961998 0 P 0 ;0
L 0.59863996 -2.09861998 0.67605 -2.09861998 0 P 0 ;0
L 0.59861004 -2.09761998 0.67588996 -2.09761998 0 P 0 ;0
L 0.59858996 -2.09661998 0.6758 -2.09661998 0 P 0 ;0
L 0.59856004 -2.09561998 0.67571004 -2.09561998 0 P 0 ;0
L 0.59853002 -2.09461998 0.67563002 -2.09461998 0 P 0 ;0
L 0.5985 -2.09361998 0.67553996 -2.09361998 0 P 0 ;0
L 0.59846998 -2.09261998 0.67546004 -2.09261998 0 P 0 ;0
L 0.59843996 -2.09161998 0.67546004 -2.09161998 0 P 0 ;0
L 0.59841998 -2.09061998 0.67545 -2.09061998 0 P 0 ;0
L 0.59838002 -2.08961998 0.67543996 -2.08961998 0 P 0 ;0
L 0.59836004 -2.08861998 0.67543002 -2.08861998 0 P 0 ;0
L 0.59833002 -2.08761998 0.67543002 -2.08761998 0 P 0 ;0
L 0.59835 -2.08661998 0.67541998 -2.08661998 0 P 0 ;0
L 0.59836998 -2.08561998 0.67541004 -2.08561998 0 P 0 ;0
L 0.5984 -2.08461998 0.67541004 -2.08461998 0 P 0 ;0
L 0.80005 -2.25161998 0.85543996 -2.25161998 0 P 0 ;0
L 0.78651998 -2.25061998 0.86596004 -2.25061998 0 P 0 ;0
L 0.77878996 -2.24961998 0.87636004 -2.24961998 0 P 0 ;0
L 0.77106004 -2.24861998 0.88285 -2.24861998 0 P 0 ;0
L 0.76398996 -2.24761998 0.88933996 -2.24761998 0 P 0 ;0
L 0.75891998 -2.24661998 0.89583996 -2.24661998 0 P 0 ;0
L 0.73781004 -1.8982 0.71738996 -1.90951998 0 P 0 ;0
L 0.71738996 -1.90951998 0.69766998 -1.92233996 0 P 0 ;0
L 0.69766998 -1.92233996 0.67971004 -1.93601998 0 P 0 ;0
L 0.67971004 -1.93601998 0.66278996 -1.95113002 0 P 0 ;0
L 0.66278996 -1.95113002 0.64786998 -1.96675 0 P 0 ;0
L 0.64786998 -1.96675 0.63423996 -1.98358996 0 P 0 ;0
L 0.63423996 -1.98358996 0.62643996 -1.99483002 0 P 0 ;0
L 0.62643996 -1.99483002 0.61933996 -2.00655 0 P 0 ;0
L 0.61933996 -2.00655 0.61298996 -2.01873996 0 P 0 ;0
L 0.61298996 -2.01873996 0.60503002 -2.03713002 0 P 0 ;0
L 0.60503002 -2.03713002 0.60225 -2.04506004 0 P 0 ;0
L 0.60225 -2.04506004 0.59998996 -2.05323002 0 P 0 ;0
L 0.59998996 -2.05323002 0.59833996 -2.0612 0 P 0 ;0
L 0.59833996 -2.0612 0.59725 -2.06928996 0 P 0 ;0
L 0.59725 -2.06928996 0.59656998 -2.07833996 0 P 0 ;0
L 0.59656998 -2.07833996 0.59633002 -2.0875 0 P 0 ;0
L 0.59633002 -2.0875 0.59668996 -2.10036998 0 P 0 ;0
L 0.59668996 -2.10036998 0.59715 -2.10596004 0 P 0 ;0
L 0.59715 -2.10596004 0.59786004 -2.11151004 0 P 0 ;0
L 0.59786004 -2.11151004 0.59878996 -2.11686998 0 P 0 ;0
L 0.59878996 -2.11686998 0.59996998 -2.1222 0 P 0 ;0
L 0.59996998 -2.1222 0.60326998 -2.13368996 0 P 0 ;0
L 0.60326998 -2.13368996 0.60656998 -2.1427 0 P 0 ;0
L 0.60656998 -2.1427 0.6105 -2.15143996 0 P 0 ;0
L 0.6105 -2.15143996 0.61505 -2.15988002 0 P 0 ;0
L 0.61505 -2.15988002 0.62023996 -2.16803996 0 P 0 ;0
L 0.62023996 -2.16803996 0.62828996 -2.17873002 0 P 0 ;0
L 0.62828996 -2.17873002 0.63718996 -2.18871004 0 P 0 ;0
L 0.63718996 -2.18871004 0.64693002 -2.19795 0 P 0 ;0
L 0.64693002 -2.19795 0.6582 -2.20701998 0 P 0 ;0
L 0.6582 -2.20701998 0.67011004 -2.21518996 0 P 0 ;0
L 0.67011004 -2.21518996 0.68261004 -2.22243002 0 P 0 ;0
L 0.68261004 -2.22243002 0.69673996 -2.22936004 0 P 0 ;0
L 0.69673996 -2.22936004 0.71123002 -2.23543996 0 P 0 ;0
L 0.71123002 -2.23543996 0.72611998 -2.24066998 0 P 0 ;0
L 0.72611998 -2.24066998 0.74536004 -2.24598996 0 P 0 ;0
L 0.74536004 -2.24598996 0.76493002 -2.24985 0 P 0 ;0
L 0.76493002 -2.24985 0.78671998 -2.25266998 0 P 0 ;0
L 0.78671998 -2.25266998 0.80863002 -2.25425 0 P 0 ;0
L 0.80863002 -2.25425 0.83146004 -2.25463002 0 P 0 ;0
L 0.83146004 -2.25463002 0.85418002 -2.25375 0 P 0 ;0
L 0.85418002 -2.25375 0.87641004 -2.25163996 0 P 0 ;0
L 0.87641004 -2.25163996 0.89853002 -2.24823002 0 P 0 ;0
L 0.89853002 -2.24823002 0.93045 -2.24101998 0 P 0 ;0
L 0.93045 -2.24101998 0.96466004 -2.23063002 0 P 0 ;0
L 0.96466004 -2.23063002 0.99911004 -2.2178 0 P 0 ;0
L 0.99911004 -2.2178 1.03183002 -2.20318002 0 P 0 ;0
L 1.03183002 -2.20318002 1.04391998 -2.19703002 0 P 0 ;0
L 1.04391998 -2.19703002 1.05581004 -2.19048996 0 P 0 ;0
L 1.05581004 -2.19048996 1.06676004 -2.18411998 0 P 0 ;0
L 1.06676004 -2.18411998 1.06681004 -2.18408996 0 P 0 ;0
L 1.06681004 -2.18408996 1.06685 -2.18405 0 P 0 ;0
L 1.06685 -2.18405 1.0669 -2.18401004 0 P 0 ;0
L 1.0669 -2.18401004 1.06693996 -2.18396998 0 P 0 ;0
L 1.06693996 -2.18396998 1.06696998 -2.18391998 0 P 0 ;0
L 1.06696998 -2.18391998 1.06701004 -2.18386998 0 P 0 ;0
L 1.06701004 -2.18386998 1.06703002 -2.18381998 0 P 0 ;0
L 1.06703002 -2.18381998 1.06706004 -2.18376004 0 P 0 ;0
L 1.06706004 -2.18376004 1.06706998 -2.18371004 0 P 0 ;0
L 1.06706998 -2.18371004 1.06708996 -2.18365 0 P 0 ;0
L 1.06708996 -2.18365 1.06708996 -2.18358996 0 P 0 ;0
L 1.06708996 -2.18358996 1.0671 -2.18353002 0 P 0 ;0
L 1.0671 -2.18353002 1.0671 -2.18346998 0 P 0 ;0
L 1.0671 -2.18346998 1.06708996 -2.18341004 0 P 0 ;0
L 1.06708996 -2.18341004 1.06706998 -2.18336004 0 P 0 ;0
L 1.06706998 -2.18336004 1.06706004 -2.1833 0 P 0 ;0
L 1.06706004 -2.1833 1.06703002 -2.18323996 0 P 0 ;0
L 1.06703002 -2.18323996 1.06701004 -2.18318996 0 P 0 ;0
L 1.06701004 -2.18318996 1.06696998 -2.18313996 0 P 0 ;0
L 1.06696998 -2.18313996 1.06693996 -2.18308996 0 P 0 ;0
L 1.06693996 -2.18308996 1.06688002 -2.18303002 0 P 0 ;0
L 1.06688002 -2.18303002 1.06678996 -2.18296998 0 P 0 ;0
L 1.06678996 -2.18296998 1.06673002 -2.18295 0 P 0 ;0
L 1.06673002 -2.18295 1.0667 -2.18295 0 P 0 ;0
L 1.0667 -2.18295 1.06666004 -2.18293996 0 P 0 ;0
L 1.06666004 -2.18293996 1.0666 -2.18293996 0 P 0 ;0
L 1.0666 -2.18293996 1.06656998 -2.18295 0 P 0 ;0
L 1.06656998 -2.18295 1.06653002 -2.18295 0 P 0 ;0
L 1.06653002 -2.18295 1.06153002 -2.1842 0 P 0 ;0
L 1.06153002 -2.1842 1.05583996 -2.18566998 0 P 0 ;0
L 1.05583996 -2.18566998 1.04916998 -2.1875 0 P 0 ;0
L 1.04916998 -2.1875 1.0153 -2.1962 0 P 0 ;0
L 1.0153 -2.1962 0.9814 -2.20333996 0 P 0 ;0
L 0.9814 -2.20333996 0.94881998 -2.2087 0 P 0 ;0
L 0.94881998 -2.2087 0.9189 -2.21198996 0 P 0 ;0
L 0.9189 -2.21198996 0.90113996 -2.21278996 0 P 0 ;0
L 0.90113996 -2.21278996 0.87738002 -2.21265 0 P 0 ;0
L 0.87738002 -2.21265 0.854 -2.21183002 0 P 0 ;0
L 0.854 -2.21183002 0.83788996 -2.21033996 0 P 0 ;0
L 0.83788996 -2.21033996 0.8174 -2.20693002 0 P 0 ;0
L 0.8174 -2.20693002 0.79708996 -2.2023 0 P 0 ;0
L 0.79708996 -2.2023 0.7769 -2.19641004 0 P 0 ;0
L 0.7769 -2.19641004 0.76433002 -2.19183996 0 P 0 ;0
L 0.76433002 -2.19183996 0.75208996 -2.18638002 0 P 0 ;0
L 0.75208996 -2.18638002 0.74026998 -2.18006998 0 P 0 ;0
L 0.74026998 -2.18006998 0.72886998 -2.17291004 0 P 0 ;0
L 0.72886998 -2.17291004 0.71961998 -2.16603002 0 P 0 ;0
L 0.71961998 -2.16603002 0.71098996 -2.15838996 0 P 0 ;0
L 0.71098996 -2.15838996 0.70303002 -2.15003002 0 P 0 ;0
L 0.70303002 -2.15003002 0.6958 -2.14098996 0 P 0 ;0
L 0.6958 -2.14098996 0.69106998 -2.1339 0 P 0 ;0
L 0.69106998 -2.1339 0.68696004 -2.12643002 0 P 0 ;0
L 0.68696004 -2.12643002 0.68351004 -2.11863002 0 P 0 ;0
L 0.68351004 -2.11863002 0.68073996 -2.11056004 0 P 0 ;0
L 0.68073996 -2.11056004 0.67866004 -2.10218996 0 P 0 ;0
L 0.67866004 -2.10218996 0.67788002 -2.09741998 0 P 0 ;0
L 0.67788002 -2.09741998 0.67746004 -2.0926 0 P 0 ;0
L 0.67746004 -2.0926 0.67738002 -2.08076004 0 P 0 ;0
L 0.67738002 -2.08076004 0.67828002 -2.06891004 0 P 0 ;0
L 0.67828002 -2.06891004 0.67903002 -2.06403996 0 P 0 ;0
L 0.67903002 -2.06403996 0.68013002 -2.05923996 0 P 0 ;0
L 0.68013002 -2.05923996 0.68288002 -2.05021998 0 P 0 ;0
L 0.68288002 -2.05021998 0.68623996 -2.04141004 0 P 0 ;0
L 0.68623996 -2.04141004 0.69018002 -2.03286004 0 P 0 ;0
L 0.69018002 -2.03286004 0.69486004 -2.02418002 0 P 0 ;0
L 0.69486004 -2.02418002 0.70003996 -2.0158 0 P 0 ;0
L 0.70003996 -2.0158 0.70573002 -2.00768996 0 P 0 ;0
L 0.70573002 -2.00768996 0.7158 -1.99531998 0 P 0 ;0
L 0.7158 -1.99531998 0.72681004 -1.98385 0 P 0 ;0
L 0.72681004 -1.98385 0.73971004 -1.9722 0 P 0 ;0
L 0.73971004 -1.9722 0.7533 -1.9614 0 P 0 ;0
L 0.7533 -1.9614 0.75753996 -1.95828002 0 P 0 ;0
L 0.75753996 -1.95828002 0.76138002 -1.95548002 0 P 0 ;0
L 0.76138002 -1.95548002 0.76463002 -1.95316004 0 P 0 ;0
L 0.76463002 -1.95316004 0.76516004 -1.95281004 0 P 0 ;0
L 0.76516004 -1.95281004 0.7657 -1.95248996 0 P 0 ;0
L 0.7657 -1.95248996 0.76578002 -1.95243996 0 P 0 ;0
L 0.76578002 -1.95243996 0.76586004 -1.95238002 0 P 0 ;0
L 0.76586004 -1.95238002 0.76593002 -1.95231998 0 P 0 ;0
L 0.76593002 -1.95231998 0.766 -1.95223996 0 P 0 ;0
L 0.766 -1.95223996 0.76606004 -1.95216998 0 P 0 ;0
L 0.76606004 -1.95216998 0.76616004 -1.95201004 0 P 0 ;0
L 0.76616004 -1.95201004 0.7662 -1.95191998 0 P 0 ;0
L 0.7662 -1.95191998 0.76626004 -1.95173996 0 P 0 ;0
L 0.76626004 -1.95173996 0.76628002 -1.95163996 0 P 0 ;0
L 0.76628002 -1.95163996 0.7663 -1.95143002 0 P 0 ;0
L 0.7663 -1.95143002 0.7663 -1.95121004 0 P 0 ;0
L 0.7663 -1.95121004 0.76628996 -1.951 0 P 0 ;0
L 0.76628996 -1.951 0.76625 -1.95078996 0 P 0 ;0
L 0.76625 -1.95078996 0.7662 -1.95058002 0 P 0 ;0
L 0.7662 -1.95058002 0.76613002 -1.95036998 0 P 0 ;0
L 0.76613002 -1.95036998 0.76583002 -1.94966998 0 P 0 ;0
L 0.76583002 -1.94966998 0.76548996 -1.94896998 0 P 0 ;0
L 0.76548996 -1.94896998 0.76508996 -1.9483 0 P 0 ;0
L 0.76508996 -1.9483 0.76253002 -1.94436004 0 P 0 ;0
L 0.76253002 -1.94436004 0.76056998 -1.94126998 0 P 0 ;0
L 0.76056998 -1.94126998 0.75871998 -1.93806004 0 P 0 ;0
L 0.75871998 -1.93806004 0.75716998 -1.93496998 0 P 0 ;0
L 0.75716998 -1.93496998 0.7558 -1.93178002 0 P 0 ;0
L 0.7558 -1.93178002 0.7546 -1.92853996 0 P 0 ;0
L 0.7546 -1.92853996 0.75358996 -1.92521004 0 P 0 ;0
L 0.75358996 -1.92521004 0.7527 -1.92161998 0 P 0 ;0
L 0.7527 -1.92161998 0.75196998 -1.91796004 0 P 0 ;0
L 0.75196998 -1.91796004 0.75155 -1.91496004 0 P 0 ;0
L 0.75155 -1.91496004 0.75133002 -1.91193002 0 P 0 ;0
L 0.75133002 -1.91193002 0.75126998 -1.9085 0 P 0 ;0
L 0.75126998 -1.9085 0.75136004 -1.90506004 0 P 0 ;0
L 0.75136004 -1.90506004 0.75161004 -1.90181998 0 P 0 ;0
L 0.75161004 -1.90181998 0.752 -1.8986 0 P 0 ;0
L 0.752 -1.8986 0.75228996 -1.89701998 0 P 0 ;0
L 0.75228996 -1.89701998 0.75268996 -1.89546998 0 P 0 ;0
L 0.75268996 -1.89546998 0.7532 -1.89395 0 P 0 ;0
L 0.7532 -1.89395 0.75358996 -1.89281998 0 P 0 ;0
L 0.75358996 -1.89281998 0.75373002 -1.89231998 0 P 0 ;0
L 0.75373002 -1.89231998 0.75383996 -1.8918 0 P 0 ;0
L 0.75383996 -1.8918 0.75391998 -1.89138996 0 P 0 ;0
L 0.75391998 -1.89138996 0.75396998 -1.89098996 0 P 0 ;0
L 0.75396998 -1.89098996 0.75396998 -1.89086004 0 P 0 ;0
L 0.75396998 -1.89086004 0.75393996 -1.89076998 0 P 0 ;0
L 0.75393996 -1.89076998 0.7539 -1.89071004 0 P 0 ;0
L 0.7539 -1.89071004 0.75386004 -1.89066998 0 P 0 ;0
L 0.75386004 -1.89066998 0.75381004 -1.89063002 0 P 0 ;0
L 0.75381004 -1.89063002 0.75378996 -1.89061004 0 P 0 ;0
L 0.75378996 -1.89061004 0.75373002 -1.89058996 0 P 0 ;0
L 0.75373002 -1.89058996 0.75368002 -1.89056998 0 P 0 ;0
L 0.75368002 -1.89056998 0.75356004 -1.89056998 0 P 0 ;0
L 0.75356004 -1.89056998 0.75346998 -1.8906 0 P 0 ;0
L 0.75346998 -1.8906 0.74898002 -1.8927 0 P 0 ;0
L 0.74898002 -1.8927 0.74383002 -1.89518002 0 P 0 ;0
L 0.74383002 -1.89518002 0.73781004 -1.8982 0 P 0 ;0
L 0.69776998 -2.22761998 0.96701004 -2.22761998 0 P 0 ;0
L 0.6957 -2.22661998 0.96968996 -2.22661998 0 P 0 ;0
L 0.69366998 -2.22561998 0.97238002 -2.22561998 0 P 0 ;0
L 0.69163002 -2.22461998 0.97506004 -2.22461998 0 P 0 ;0
L 0.68958996 -2.22361998 0.97775 -2.22361998 0 P 0 ;0
L 0.68756004 -2.22261998 0.98043002 -2.22261998 0 P 0 ;0
L 0.68551998 -2.22161998 0.98311004 -2.22161998 0 P 0 ;0
L 0.68348996 -2.22061998 0.9858 -2.22061998 0 P 0 ;0
L 0.68176998 -2.21961998 0.98848002 -2.21961998 0 P 0 ;0
L 0.68003996 -2.21861998 0.99116998 -2.21861998 0 P 0 ;0
L 0.67831004 -2.21761998 0.99385 -2.21761998 0 P 0 ;0
L 0.67658002 -2.21661998 0.99653996 -2.21661998 0 P 0 ;0
L 0.67485 -2.21561998 0.99908002 -2.21561998 0 P 0 ;0
L 0.67311998 -2.21461998 0.87665 -2.21461998 0 P 0 ;0
L 0.6714 -2.21361998 0.85166004 -2.21361998 0 P 0 ;0
L 0.6699 -2.21261998 0.84083002 -2.21261998 0 P 0 ;0
L 0.66845 -2.21161998 0.8334 -2.21161998 0 P 0 ;0
L 0.66698996 -2.21061998 0.8274 -2.21061998 0 P 0 ;0
L 0.66553002 -2.20961998 0.82138996 -2.20961998 0 P 0 ;0
L 0.66406998 -2.20861998 0.81583002 -2.20861998 0 P 0 ;0
L 0.66261998 -2.20761998 0.81143996 -2.20761998 0 P 0 ;0
L 0.66116004 -2.20661998 0.80706004 -2.20661998 0 P 0 ;0
L 0.6597 -2.20561998 0.80266998 -2.20561998 0 P 0 ;0
L 0.65841004 -2.20461998 0.79828996 -2.20461998 0 P 0 ;0
L 0.65716998 -2.20361998 0.79448996 -2.20361998 0 P 0 ;0
L 0.65593002 -2.20261998 0.79106004 -2.20261998 0 P 0 ;0
L 0.65468996 -2.20161998 0.78763996 -2.20161998 0 P 0 ;0
L 0.83143002 -2.25261998 0.80871998 -2.25225 0 P 0 ;0
L 0.80871998 -2.25225 0.78691998 -2.25066998 0 P 0 ;0
L 0.78691998 -2.25066998 0.76525 -2.24786998 0 P 0 ;0
L 0.76525 -2.24786998 0.74581998 -2.24403996 0 P 0 ;0
L 0.74581998 -2.24403996 0.72671004 -2.23876004 0 P 0 ;0
L 0.72671004 -2.23876004 0.71196004 -2.23356998 0 P 0 ;0
L 0.71196004 -2.23356998 0.69756998 -2.22753996 0 P 0 ;0
L 0.69756998 -2.22753996 0.68355 -2.22066004 0 P 0 ;0
L 0.68355 -2.22066004 0.67118002 -2.2135 0 P 0 ;0
L 0.67118002 -2.2135 0.65938996 -2.20541004 0 P 0 ;0
L 0.65938996 -2.20541004 0.64825 -2.19643996 0 P 0 ;0
L 0.64825 -2.19643996 0.63861998 -2.18731998 0 P 0 ;0
L 0.63861998 -2.18731998 0.62983002 -2.17746998 0 P 0 ;0
L 0.62983002 -2.17746998 0.62188996 -2.1669 0 P 0 ;0
L 0.62188996 -2.1669 0.61678002 -2.15886998 0 P 0 ;0
L 0.61678002 -2.15886998 0.6123 -2.15056004 0 P 0 ;0
L 0.6123 -2.15056004 0.60841998 -2.14193996 0 P 0 ;0
L 0.60841998 -2.14193996 0.60516998 -2.13306998 0 P 0 ;0
L 0.60516998 -2.13306998 0.60191004 -2.12171004 0 P 0 ;0
L 0.60191004 -2.12171004 0.60075 -2.11648002 0 P 0 ;0
L 0.60075 -2.11648002 0.59983996 -2.11121004 0 P 0 ;0
L 0.59983996 -2.11121004 0.59913996 -2.10576004 0 P 0 ;0
L 0.59913996 -2.10576004 0.59868996 -2.10026004 0 P 0 ;0
L 0.59868996 -2.10026004 0.59833002 -2.0875 0 P 0 ;0
L 0.59833002 -2.0875 0.59856998 -2.07843996 0 P 0 ;0
L 0.59856998 -2.07843996 0.59923996 -2.0695 0 P 0 ;0
L 0.59923996 -2.0695 0.60031998 -2.06153996 0 P 0 ;0
L 0.60031998 -2.06153996 0.60193002 -2.05368996 0 P 0 ;0
L 0.60193002 -2.05368996 0.60416004 -2.04566004 0 P 0 ;0
L 0.60416004 -2.04566004 0.60688996 -2.03786004 0 P 0 ;0
L 0.60688996 -2.03786004 0.6148 -2.01961004 0 P 0 ;0
L 0.6148 -2.01961004 0.62108996 -2.00753002 0 P 0 ;0
L 0.62108996 -2.00753002 0.62811998 -1.99591998 0 P 0 ;0
L 0.62811998 -1.99591998 0.63583996 -1.98478996 0 P 0 ;0
L 0.63583996 -1.98478996 0.64936998 -1.96808002 0 P 0 ;0
L 0.64936998 -1.96808002 0.66418002 -1.95256998 0 P 0 ;0
L 0.66418002 -1.95256998 0.68098002 -1.93756004 0 P 0 ;0
L 0.68098002 -1.93756004 0.69881998 -1.92398002 0 P 0 ;0
L 0.69881998 -1.92398002 0.71841998 -1.91123996 0 P 0 ;0
L 0.71841998 -1.91123996 0.73875 -1.89996998 0 P 0 ;0
L 0.73875 -1.89996998 0.74471004 -1.89696998 0 P 0 ;0
L 0.74471004 -1.89696998 0.74983002 -1.89451004 0 P 0 ;0
L 0.74983002 -1.89451004 0.7511 -1.89391004 0 P 0 ;0
L 0.7511 -1.89391004 0.75076998 -1.89488996 0 P 0 ;0
L 0.75076998 -1.89488996 0.75033996 -1.89658996 0 P 0 ;0
L 0.75033996 -1.89658996 0.75003002 -1.8983 0 P 0 ;0
L 0.75003002 -1.8983 0.74961998 -1.90161998 0 P 0 ;0
L 0.74961998 -1.90161998 0.74936004 -1.90496004 0 P 0 ;0
L 0.74936004 -1.90496004 0.74926998 -1.9085 0 P 0 ;0
L 0.74926998 -1.9085 0.74933002 -1.91201998 0 P 0 ;0
L 0.74933002 -1.91201998 0.74956004 -1.91516998 0 P 0 ;0
L 0.74956004 -1.91516998 0.75 -1.91828996 0 P 0 ;0
L 0.75 -1.91828996 0.75075 -1.92205 0 P 0 ;0
L 0.75075 -1.92205 0.75166004 -1.92573996 0 P 0 ;0
L 0.75166004 -1.92573996 0.7527 -1.92916998 0 P 0 ;0
L 0.7527 -1.92916998 0.75393996 -1.93253002 0 P 0 ;0
L 0.75393996 -1.93253002 0.75536004 -1.93581998 0 P 0 ;0
L 0.75536004 -1.93581998 0.75696004 -1.939 0 P 0 ;0
L 0.75696004 -1.939 0.75885 -1.94231004 0 P 0 ;0
L 0.75885 -1.94231004 0.76083996 -1.94543996 0 P 0 ;0
L 0.76083996 -1.94543996 0.76338996 -1.94933996 0 P 0 ;0
L 0.76338996 -1.94933996 0.76371998 -1.94991998 0 P 0 ;0
L 0.76371998 -1.94991998 0.76401004 -1.9505 0 P 0 ;0
L 0.76401004 -1.9505 0.76423996 -1.95103002 0 P 0 ;0
L 0.76423996 -1.95103002 0.76408996 -1.95111004 0 P 0 ;0
L 0.76408996 -1.95111004 0.76348996 -1.95151004 0 P 0 ;0
L 0.76348996 -1.95151004 0.76021004 -1.95386004 0 P 0 ;0
L 0.76021004 -1.95386004 0.7602 -1.95386998 0 P 0 ;0
L 0.7602 -1.95386998 0.75636998 -1.95666004 0 P 0 ;0
L 0.75636998 -1.95666004 0.75636004 -1.95666998 0 P 0 ;0
L 0.75636004 -1.95666998 0.75635 -1.95666998 0 P 0 ;0
L 0.75635 -1.95666998 0.75208996 -1.95981004 0 P 0 ;0
L 0.75208996 -1.95981004 0.73841004 -1.97066998 0 P 0 ;0
L 0.73841004 -1.97066998 0.72541004 -1.98241004 0 P 0 ;0
L 0.72541004 -1.98241004 0.7143 -1.994 0 P 0 ;0
L 0.7143 -1.994 0.71425 -1.99406004 0 P 0 ;0
L 0.71425 -1.99406004 0.70413996 -2.00648002 0 P 0 ;0
L 0.70413996 -2.00648002 0.69836998 -2.01468996 0 P 0 ;0
L 0.69836998 -2.01468996 0.69313002 -2.02318002 0 P 0 ;0
L 0.69313002 -2.02318002 0.68838996 -2.03196004 0 P 0 ;0
L 0.68838996 -2.03196004 0.68438996 -2.04063996 0 P 0 ;0
L 0.68438996 -2.04063996 0.68098996 -2.04958002 0 P 0 ;0
L 0.68098996 -2.04958002 0.6782 -2.05873002 0 P 0 ;0
L 0.6782 -2.05873002 0.67706004 -2.06366004 0 P 0 ;0
L 0.67706004 -2.06366004 0.67628996 -2.06866998 0 P 0 ;0
L 0.67628996 -2.06866998 0.67538002 -2.08068996 0 P 0 ;0
L 0.67538002 -2.08068996 0.67546004 -2.09268996 0 P 0 ;0
L 0.67546004 -2.09268996 0.67588996 -2.09766998 0 P 0 ;0
L 0.67588996 -2.09766998 0.6767 -2.10258996 0 P 0 ;0
L 0.6767 -2.10258996 0.67881998 -2.11111998 0 P 0 ;0
L 0.67881998 -2.11111998 0.68163996 -2.11936004 0 P 0 ;0
L 0.68163996 -2.11936004 0.68516004 -2.12731998 0 P 0 ;0
L 0.68516004 -2.12731998 0.68935 -2.13493996 0 P 0 ;0
L 0.68935 -2.13493996 0.69418002 -2.14216998 0 P 0 ;0
L 0.69418002 -2.14216998 0.70153002 -2.15135 0 P 0 ;0
L 0.70153002 -2.15135 0.7096 -2.15983002 0 P 0 ;0
L 0.7096 -2.15983002 0.71836004 -2.16758996 0 P 0 ;0
L 0.71836004 -2.16758996 0.71843002 -2.16763996 0 P 0 ;0
L 0.71843002 -2.16763996 0.72773996 -2.17456004 0 P 0 ;0
L 0.72773996 -2.17456004 0.73926998 -2.1818 0 P 0 ;0
L 0.73926998 -2.1818 0.75121004 -2.18818002 0 P 0 ;0
L 0.75121004 -2.18818002 0.75128002 -2.18821004 0 P 0 ;0
L 0.75128002 -2.18821004 0.76358002 -2.19368996 0 P 0 ;0
L 0.76358002 -2.19368996 0.77628002 -2.19831004 0 P 0 ;0
L 0.77628002 -2.19831004 0.79658996 -2.20423996 0 P 0 ;0
L 0.79658996 -2.20423996 0.81701004 -2.20888996 0 P 0 ;0
L 0.81701004 -2.20888996 0.83763996 -2.21233002 0 P 0 ;0
L 0.83763996 -2.21233002 0.85388002 -2.21383002 0 P 0 ;0
L 0.85388002 -2.21383002 0.87733996 -2.21465 0 P 0 ;0
L 0.87733996 -2.21465 0.90118002 -2.21478996 0 P 0 ;0
L 0.90118002 -2.21478996 0.91906004 -2.21398996 0 P 0 ;0
L 0.91906004 -2.21398996 0.94908996 -2.21068002 0 P 0 ;0
L 0.94908996 -2.21068002 0.98176998 -2.2053 0 P 0 ;0
L 0.98176998 -2.2053 1.01575 -2.19815 0 P 0 ;0
L 1.01575 -2.19815 1.04968002 -2.18943002 0 P 0 ;0
L 1.04968002 -2.18943002 1.05633996 -2.18761004 0 P 0 ;0
L 1.05633996 -2.18761004 1.05713996 -2.1874 0 P 0 ;0
L 1.05713996 -2.1874 1.05483002 -2.18875 0 P 0 ;0
L 1.05483002 -2.18875 1.04298996 -2.19526004 0 P 0 ;0
L 1.04298996 -2.19526004 1.03096998 -2.20136998 0 P 0 ;0
L 1.03096998 -2.20136998 0.99835 -2.21595 0 P 0 ;0
L 0.99835 -2.21595 0.96401998 -2.22873996 0 P 0 ;0
L 0.96401998 -2.22873996 0.92993996 -2.23908002 0 P 0 ;0
L 0.92993996 -2.23908002 0.89816004 -2.24626004 0 P 0 ;0
L 0.89816004 -2.24626004 0.87616004 -2.24965 0 P 0 ;0
L 0.87616004 -2.24965 0.85405 -2.25176004 0 P 0 ;0
L 0.85405 -2.25176004 0.83143002 -2.25261998 0 P 0 ;0
L 0.65345 -2.20061998 0.78421004 -2.20061998 0 P 0 ;0
L 0.65221004 -2.19961998 0.78078002 -2.19961998 0 P 0 ;0
L 0.65096004 -2.19861998 0.77735 -2.19861998 0 P 0 ;0
L 0.64971998 -2.19761998 0.77438996 -2.19761998 0 P 0 ;0
L 0.64848002 -2.19661998 0.77163996 -2.19661998 0 P 0 ;0
L 0.64738996 -2.19561998 0.76888996 -2.19561998 0 P 0 ;0
L 0.64633996 -2.19461998 0.76613996 -2.19461998 0 P 0 ;0
L 0.64528002 -2.19361998 0.76343002 -2.19361998 0 P 0 ;0
L 0.64421998 -2.19261998 0.76118996 -2.19261998 0 P 0 ;0
L 0.64316998 -2.19161998 0.75893996 -2.19161998 0 P 0 ;0
L 0.64211004 -2.19061998 0.7567 -2.19061998 0 P 0 ;0
L 0.64106004 -2.18961998 0.75446004 -2.18961998 0 P 0 ;0
L 0.64 -2.18861998 0.75221004 -2.18861998 0 P 0 ;0
L 0.63895 -2.18761998 0.75018002 -2.18761998 0 P 0 ;0
L 0.63801004 -2.18661998 0.74831004 -2.18661998 0 P 0 ;0
L 0.63711004 -2.18561998 0.74643002 -2.18561998 0 P 0 ;0
L 0.63621998 -2.18461998 0.74456004 -2.18461998 0 P 0 ;0
L 0.63533002 -2.18361998 0.74268002 -2.18361998 0 P 0 ;0
L 0.63443996 -2.18261998 0.74081004 -2.18261998 0 P 0 ;0
L 0.63353996 -2.18161998 0.73898996 -2.18161998 0 P 0 ;0
L 0.63265 -2.18061998 0.73738996 -2.18061998 0 P 0 ;0
L 0.63176004 -2.17961998 0.7358 -2.17961998 0 P 0 ;0
L 0.63086998 -2.17861998 0.73421004 -2.17861998 0 P 0 ;0
L 0.62996998 -2.17761998 0.73261998 -2.17761998 0 P 0 ;0
L 0.6292 -2.17661998 0.73103002 -2.17661998 0 P 0 ;0
L 0.62845 -2.17561998 0.72943996 -2.17561998 0 P 0 ;0
L 0.6277 -2.17461998 0.72783996 -2.17461998 0 P 0 ;0
L 0.62693996 -2.17361998 0.72648002 -2.17361998 0 P 0 ;0
L 0.62618996 -2.17261998 0.72513996 -2.17261998 0 P 0 ;0
L 0.62543996 -2.17161998 0.72378996 -2.17161998 0 P 0 ;0
L 0.62468996 -2.17061998 0.72245 -2.17061998 0 P 0 ;0
L 0.62393996 -2.16961998 0.7211 -2.16961998 0 P 0 ;0
L 0.62318002 -2.16861998 0.71976004 -2.16861998 0 P 0 ;0
L 0.62243996 -2.16761998 0.71841004 -2.16761998 0 P 0 ;0
L 0.62171004 -2.16661998 0.71726998 -2.16661998 0 P 0 ;0
L 0.62108002 -2.16561998 0.71613996 -2.16561998 0 P 0 ;0
L 0.62043996 -2.16461998 0.71501004 -2.16461998 0 P 0 ;0
L 0.61981004 -2.16361998 0.71388002 -2.16361998 0 P 0 ;0
L 0.61916998 -2.16261998 0.71276004 -2.16261998 0 P 0 ;0
L 0.61853002 -2.16161998 0.71163002 -2.16161998 0 P 0 ;0
L 0.6179 -2.16061998 0.7105 -2.16061998 0 P 0 ;0
L 0.61726004 -2.15961998 0.7094 -2.15961998 0 P 0 ;0
L 0.61665 -2.15861998 0.70845 -2.15861998 0 P 0 ;0
L 0.61611004 -2.15761998 0.7075 -2.15761998 0 P 0 ;0
L 0.75383996 -2.24561998 0.901 -2.24561998 0 P 0 ;0
L 0.74876998 -2.24461998 0.90541998 -2.24461998 0 P 0 ;0
L 0.74431004 -2.24361998 0.90985 -2.24361998 0 P 0 ;0
L 0.7407 -2.24261998 0.91426998 -2.24261998 0 P 0 ;0
L 0.73708002 -2.24161998 0.9187 -2.24161998 0 P 0 ;0
L 0.73346998 -2.24061998 0.92311998 -2.24061998 0 P 0 ;0
L 0.72986004 -2.23961998 0.92753996 -2.23961998 0 P 0 ;0
L 0.72633996 -2.23861998 0.93145 -2.23861998 0 P 0 ;0
L 0.72348996 -2.23761998 0.93473996 -2.23761998 0 P 0 ;0
L 0.72063996 -2.23661998 0.93803996 -2.23661998 0 P 0 ;0
L 0.7178 -2.23561998 0.94133002 -2.23561998 0 P 0 ;0
L 0.71495 -2.23461998 0.94461998 -2.23461998 0 P 0 ;0
L 0.7121 -2.23361998 0.94791998 -2.23361998 0 P 0 ;0
L 0.70968996 -2.23261998 0.95121004 -2.23261998 0 P 0 ;0
L 0.70731004 -2.23161998 0.95451004 -2.23161998 0 P 0 ;0
L 0.70491998 -2.23061998 0.9578 -2.23061998 0 P 0 ;0
L 0.70253996 -2.22961998 0.9611 -2.22961998 0 P 0 ;0
L 0.70015 -2.22861998 0.96431998 -2.22861998 0 P 0 ;0
L 8.45 3.66615 8.45 3.71615 6 P 0 
L 8.5 3.76615 8.5 3.81615 6 P 0 
L 8.45 3.81615 8.45 3.86615 6 P 0 
L 8.5 3.46615 8.5 3.51615 6 P 0 
L 8.45 3.41615 8.45 3.46615 6 P 0 
L 8.5 3.61615 8.5 3.66615 6 P 0 
L 8.45 3.26615 8.45 3.31615 6 P 0 
L 8.5 3.31615 8.5 3.36615 6 P 0 
L 8.2 3.66615 8.2 3.71615 6 P 0 
L 8.35 3.66615 8.35 3.71615 6 P 0 
L 8.4 3.76615 8.4 3.81615 6 P 0 
L 8.35 3.81615 8.35 3.86615 6 P 0 
L 8.2 3.81615 8.2 3.86615 6 P 0 
L 8.4 3.46615 8.4 3.51615 6 P 0 
L 8.35 3.41615 8.35 3.46615 6 P 0 
L 8.2 3.41615 8.2 3.46615 6 P 0 
L 8.4 3.61615 8.4 3.66615 6 P 0 
L 8.35 3.26615 8.35 3.31615 6 P 0 
L 8.4 3.31615 8.4 3.36615 6 P 0 
L 8.2 3.26615 8.2 3.31615 6 P 0 
L 8.25 2.86615 8.3 2.86615 6 P 0 
L 8.1 3.66615 8.1 3.71615 6 P 0 
L 8.15 3.76615 8.15 3.81615 6 P 0 
L 8.1 3.81615 8.1 3.86615 6 P 0 
L 8.05 3.76615 8.05 3.81615 6 P 0 
L 8.1 3.41615 8.1 3.46615 6 P 0 
L 8.15 3.46615 8.15 3.51615 6 P 0 
L 8 3.46615 8 3.51615 6 P 0 
L 8.05 3.61615 8.05 3.66615 6 P 0 
L 8.15 3.61615 8.15 3.66615 6 P 0 
L 8.1 3.26615 8.1 3.31615 6 P 0 
L 8.15 3.31615 8.15 3.36615 6 P 0 
L 8.05 3.31615 8.05 3.36615 6 P 0 
L 5.42048002 1.91835 5.42048002 1.87835 6 P 0 
L 5.57531004 1.8508 5.57531004 1.8108 6 P 0 
L 2.34606004 3.26615 2.34606004 3.31615 6 P 0 
L 2.39606004 3.31615 2.39606004 3.36615 6 P 0 
L 2.44606004 3.26615 2.44606004 3.31615 6 P 0 
L 2.49606004 3.31615 2.49606004 3.36615 6 P 0 
L 2.49606004 3.46615 2.49606004 3.51615 6 P 0 
L 2.44606004 3.41615 2.44606004 3.46615 6 P 0 
L 2.39606004 3.46615 2.39606004 3.51615 6 P 0 
L 2.34606004 3.41615 2.34606004 3.46615 6 P 0 
L 2.19606004 3.26615 2.19606004 3.31615 6 P 0 
L 2.09606004 3.26615 2.09606004 3.31615 6 P 0 
L 2.14606004 3.31615 2.14606004 3.36615 6 P 0 
L 2.19606004 3.41615 2.19606004 3.46615 6 P 0 
L 2.09606004 3.41615 2.09606004 3.46615 6 P 0 
L 2.04606004 3.31615 2.04606004 3.36615 6 P 0 
L 2.14606004 3.46615 2.14606004 3.51615 6 P 0 
L 1.99606004 3.46615 1.99606004 3.51615 6 P 0 
L 2.04606004 3.61615 2.04606004 3.66615 6 P 0 
L 2.09606004 3.66615 2.09606004 3.71615 6 P 0 
L 2.14606004 3.61615 2.14606004 3.66615 6 P 0 
L 2.19606004 3.66615 2.19606004 3.71615 6 P 0 
L 2.49606004 3.61615 2.49606004 3.66615 6 P 0 
L 2.34606004 3.66615 2.34606004 3.71615 6 P 0 
L 2.39606004 3.61615 2.39606004 3.66615 6 P 0 
L 2.44606004 3.66615 2.44606004 3.71615 6 P 0 
L 2.49606004 3.76615 2.49606004 3.81615 6 P 0 
L 2.44606004 3.81615 2.44606004 3.86615 6 P 0 
L 2.39606004 3.76615 2.39606004 3.81615 6 P 0 
L 2.34606004 3.81615 2.34606004 3.86615 6 P 0 
L 2.14606004 3.76615 2.14606004 3.81615 6 P 0 
L 2.19606004 3.81615 2.19606004 3.86615 6 P 0 
L 2.09606004 3.81615 2.09606004 3.86615 6 P 0 
L 2.04606004 3.76615 2.04606004 3.81615 6 P 0 
L 2.24606004 2.86615 2.29606004 2.86615 6 P 0 
L 5.42048002 1.6433 5.42048002 1.6033 6 P 0 
L 5.57531004 1.7118 5.57531004 1.6718 6 P 0 
L 5.42048002 1.7796 5.42048002 1.7396 6 P 0 
L 5.57531004 1.9869 5.57531004 1.9469 6 P 0 
L 5.42048002 2.0547 5.42048002 2.0147 6 P 0 
L 5.57531004 2.1278 5.57531004 2.0878 6 P 0 
L 5.42048002 2.1954 5.42048002 2.1554 6 P 0 
L 5.57531004 2.2632 5.57531004 2.2232 6 P 0 
L 5.42048002 2.3308 5.42048002 2.2908 6 P 0 
L 5.57531004 2.3986 5.57531004 2.3586 6 P 0 
L 5.42048002 2.4662 5.42048002 2.4262 6 P 0 
L 5.57531004 2.5378 5.57531004 2.4978 6 P 0 
L 5.57531004 2.673 5.57531004 2.633 6 P 0 
L 5.42048002 2.6054 5.42048002 2.5654 6 P 0 
L 10.09 2.73655 10.09 2.69655 6 P 0 
L 9.975 2.66445 9.975 2.62445 6 P 0 
L 9.975 2.5109 9.975 2.4709 6 P 0 
L 10.09 2.57845 10.09 2.53845 6 P 0 
L 10.09 2.44335 10.09 2.40335 6 P 0 
L 9.975 2.3758 9.975 2.3358 6 P 0 
L 10.09 2.30825 10.09 2.26825 6 P 0 
L 9.975 2.23955 9.975 2.19955 6 P 0 
L 10.09 2.17095 10.09 2.13095 6 P 0 
L 10.09 2.05655 10.09 2.01655 6 P 0 
L 10.225 1.96645 10.225 1.92645 6 P 0 
L 10.26025 1.86845 10.26025 1.82845 6 P 0 
L 10.26 1.70445 10.26 1.66445 6 P 0 
L 10.35543996 1.52156004 10.38371998 1.49328002 7 P 0 
L 10.46445 1.395 10.42445 1.395 6 P 0 
L 10.395 1.28555 10.395 1.32555 6 P 0 
L 11.53316004 1.412 11.53316004 1.452 6 P 0 
L 11.73316004 1.492 11.73316004 1.532 6 P 0 
L 11.53316004 1.572 11.53316004 1.612 6 P 0 
L 11.78316004 1.652 11.78316004 1.692 6 P 0 
L 11.53316004 1.732 11.53316004 1.772 6 P 0 
L 11.73316004 1.812 11.73316004 1.852 6 P 0 
L 11.53316004 1.892 11.53316004 1.932 6 P 0 
L 11.53316004 2.052 11.53316004 2.092 6 P 0 
L 11.73316004 1.972 11.73316004 2.012 6 P 0 
L 11.73316004 2.132 11.73316004 2.172 6 P 0 
L 11.83316004 2.212 11.83316004 2.252 6 P 0 
L 11.73316004 2.292 11.73316004 2.332 6 P 0 
L 11.53316004 2.372 11.53316004 2.412 6 P 0 
L 11.53316004 2.532 11.53316004 2.572 6 P 0 
L 11.73316004 2.452 11.73316004 2.492 6 P 0 
L 11.73316004 2.612 11.73316004 2.652 6 P 0 
L 8.98115 2.825 8.98115 2.865 6 P 0 
L 2.97721004 2.825 2.97721004 2.865 6 P 0 
L 11.03661004 2.46615 11.03661004 2.51615 6 P 0 
L 11.08661004 2.21615 11.08661004 2.26615 6 P 0 
L 10.98661004 2.21615 10.98661004 2.26615 6 P 0 
L 11.03661004 2.26615 11.03661004 2.31615 6 P 0 
L 10.93661004 2.26615 10.93661004 2.31615 6 P 0 
L 10.98661004 2.36615 10.98661004 2.41615 6 P 0 
L 10.93661004 2.41615 10.93661004 2.46615 6 P 0 
L 11.08661004 2.36615 11.08661004 2.41615 6 P 0 
L 10.93661004 2.01615 10.93661004 2.06615 6 P 0 
L 10.98661004 2.06615 10.98661004 2.11615 6 P 0 
L 11.03661004 2.01615 11.03661004 2.06615 6 P 0 
L 11.08661004 2.06615 11.08661004 2.11615 6 P 0 
L 10.93661004 1.86615 10.93661004 1.91615 6 P 0 
L 11.03661004 1.86615 11.03661004 1.91615 6 P 0 
L 10.98661004 1.91615 10.98661004 1.96615 6 P 0 
L 11.08661004 1.91615 11.08661004 1.96615 6 P 0 
L 10.73661004 2.46615 10.73661004 2.41615 6 P 0 
L 10.68661004 2.41615 10.68661004 2.36615 6 P 0 
L 10.68661004 2.26615 10.68661004 2.21615 6 P 0 
L 10.73661004 2.31615 10.73661004 2.26615 6 P 0 
L 10.68661004 2.11615 10.68661004 2.06615 6 P 0 
L 10.83661004 2.16615 10.88661004 2.16615 6 P 0 
L 10.73661004 2.01615 10.73661004 2.06615 6 P 0 
L 10.68661004 1.91615 10.68661004 1.96615 6 P 0 
L 10.73661004 1.86615 10.73661004 1.91615 6 P 0 
L 10.63661004 2.46615 10.63661004 2.41615 6 P 0 
L 10.58661004 2.41615 10.58661004 2.36615 6 P 0 
L 10.63661004 2.31615 10.63661004 2.26615 6 P 0 
L 10.58661004 2.26615 10.58661004 2.21615 6 P 0 
L 10.58661004 2.11615 10.58661004 2.06615 6 P 0 
L 10.63661004 2.01615 10.63661004 2.06615 6 P 0 
L 10.58661004 1.91615 10.58661004 1.96615 6 P 0 
L 10.63661004 1.86615 10.63661004 1.91615 6 P 0 
L 0.69348996 1.86611998 0.69348996 1.90611998 6 P 0 
L 5.03268002 2.46615 5.03268002 2.51615 6 P 0 
L 5.08268002 2.36615 5.08268002 2.41615 6 P 0 
L 4.93268002 2.41615 4.93268002 2.46615 6 P 0 
L 4.98268002 2.36615 4.98268002 2.41615 6 P 0 
L 4.93268002 2.26615 4.93268002 2.31615 6 P 0 
L 5.03268002 2.26615 5.03268002 2.31615 6 P 0 
L 4.98268002 2.21615 4.98268002 2.26615 6 P 0 
L 5.08268002 2.21615 5.08268002 2.26615 6 P 0 
L 5.08268002 2.06615 5.08268002 2.11615 6 P 0 
L 5.03268002 2.01615 5.03268002 2.06615 6 P 0 
L 4.98268002 2.06615 4.98268002 2.11615 6 P 0 
L 4.93268002 2.01615 4.93268002 2.06615 6 P 0 
L 5.08268002 1.91615 5.08268002 1.96615 6 P 0 
L 4.98268002 1.91615 4.98268002 1.96615 6 P 0 
L 5.03268002 1.86615 5.03268002 1.91615 6 P 0 
L 4.93268002 1.86615 4.93268002 1.91615 6 P 0 
L 4.73268002 1.86615 4.73268002 1.91615 6 P 0 
L 4.63268002 1.86615 4.63268002 1.91615 6 P 0 
L 4.68268002 1.91615 4.68268002 1.96615 6 P 0 
L 4.58268002 1.91615 4.58268002 1.96615 6 P 0 
L 4.63268002 2.01615 4.63268002 2.06615 6 P 0 
L 4.73268002 2.01615 4.73268002 2.06615 6 P 0 
L 4.83268002 2.16615 4.88268002 2.16615 6 P 0 
L 4.58268002 2.11615 4.58268002 2.06615 6 P 0 
L 4.68268002 2.11615 4.68268002 2.06615 6 P 0 
L 4.73268002 2.31615 4.73268002 2.26615 6 P 0 
L 4.68268002 2.26615 4.68268002 2.21615 6 P 0 
L 4.58268002 2.26615 4.58268002 2.21615 6 P 0 
L 4.63268002 2.31615 4.63268002 2.26615 6 P 0 
L 4.58268002 2.41615 4.58268002 2.36615 6 P 0 
L 4.68268002 2.41615 4.68268002 2.36615 6 P 0 
L 4.63268002 2.46615 4.63268002 2.41615 6 P 0 
L 4.73268002 2.46615 4.73268002 2.41615 6 P 0 
A 12.75476004 4.52361998 12.75476004 4.52361998 12.73621004 4.52361998 3 P 0 N
A 12.8335 4.48425 12.8335 4.48425 12.81495 4.48425 3 P 0 N
L 12.73621004 4.52361998 12.81495 4.48425 9 P 0 
L 12.73621004 4.36613996 12.81495 4.32676998 9 P 0 
A 12.8335 4.32676998 12.8335 4.32676998 12.81495 4.32676998 3 P 0 N
A 12.75476004 4.36613996 12.75476004 4.36613996 12.73621004 4.36613996 3 P 0 N
L 12.73621004 4.20866004 12.81495 4.16928996 9 P 0 
A 12.8335 4.16928996 12.8335 4.16928996 12.81495 4.16928996 3 P 0 N
A 12.75476004 4.20866004 12.75476004 4.20866004 12.73621004 4.20866004 3 P 0 N
L 12.73621004 4.05118002 12.81495 4.01181004 9 P 0 
A 12.8335 4.01181004 12.8335 4.01181004 12.81495 4.01181004 3 P 0 N
A 12.75476004 4.05118002 12.75476004 4.05118002 12.73621004 4.05118002 3 P 0 N
L 12.73621004 3.8937 12.81495 3.85433002 9 P 0 
A 12.8335 3.85433002 12.8335 3.85433002 12.81495 3.85433002 3 P 0 N
A 12.75476004 3.8937 12.75476004 3.8937 12.73621004 3.8937 3 P 0 N
A 12.75476004 3.73621998 12.75476004 3.73621998 12.73621004 3.73621998 3 P 0 N
L 12.73621004 3.73621998 12.81495 3.69685 9 P 0 
A 12.8335 3.69685 12.8335 3.69685 12.81495 3.69685 3 P 0 N
L 12.73621004 3.57873996 12.81495 3.53936998 9 P 0 
A 12.8335 3.53936998 12.8335 3.53936998 12.81495 3.53936998 3 P 0 N
A 12.75476004 3.57873996 12.75476004 3.57873996 12.73621004 3.57873996 3 P 0 N
L 12.73621004 3.42126004 12.81495 3.38188996 9 P 0 
A 12.8335 3.38188996 12.8335 3.38188996 12.81495 3.38188996 3 P 0 N
A 12.75476004 3.42126004 12.75476004 3.42126004 12.73621004 3.42126004 3 P 0 N
A 12.8335 3.22441004 12.8335 3.22441004 12.81495 3.22441004 3 P 0 N
L 12.73621004 3.02756004 12.81495 3.06693002 9 P 0 
A 12.8335 3.06693002 12.8335 3.06693002 12.81495 3.06693002 3 P 0 N
A 12.75476004 3.02756004 12.75476004 3.02756004 12.73621004 3.02756004 3 P 0 N
L 12.73621004 3.18503996 12.81495 3.22441004 9 P 0 
A 12.75476004 3.18503996 12.75476004 3.18503996 12.73621004 3.18503996 3 P 0 N
A 12.8335 2.75196998 12.8335 2.75196998 12.81495 2.75196998 3 P 0 N
L 12.73621004 2.87008002 12.81495 2.90945 9 P 0 
A 12.8335 2.90945 12.8335 2.90945 12.81495 2.90945 3 P 0 N
A 12.75476004 2.87008002 12.75476004 2.87008002 12.73621004 2.87008002 3 P 0 N
A 12.8335 2.51575 12.8335 2.51575 12.81495 2.51575 3 P 0 N
A 12.75476004 2.47638002 12.75476004 2.47638002 12.73621004 2.47638002 3 P 0 N
L 12.73621004 2.7126 12.81495 2.75196998 9 P 0 
A 12.75476004 2.7126 12.75476004 2.7126 12.73621004 2.7126 3 P 0 N
L 12.73621004 2.3189 12.81495 2.35826998 9 P 0 
A 12.8335 2.35826998 12.8335 2.35826998 12.81495 2.35826998 3 P 0 N
A 12.75476004 2.3189 12.75476004 2.3189 12.73621004 2.3189 3 P 0 N
L 12.73621004 2.47638002 12.81495 2.51575 9 P 0 
A 12.75476004 2.00393996 12.75476004 2.00393996 12.73621004 2.00393996 3 P 0 N
L 12.73621004 2.16141998 12.81495 2.20078996 9 P 0 
A 12.8335 2.20078996 12.8335 2.20078996 12.81495 2.20078996 3 P 0 N
A 12.75476004 2.16141998 12.75476004 2.16141998 12.73621004 2.16141998 3 P 0 N
L 12.73621004 2.00393996 12.81495 1.96456998 9 P 0 
A 12.8335 1.96456998 12.8335 1.96456998 12.81495 1.96456998 3 P 0 N
L 12.55905 4.563 12.63778996 4.60236998 9 P 0 
A 12.65633996 4.60236998 12.65633996 4.60236998 12.63778996 4.60236998 3 P 0 N
A 12.5776 4.563 12.5776 4.563 12.55905 4.563 3 P 0 N
L 12.55905 4.24803002 12.63778996 4.2874 9 P 0 
A 12.65633996 4.2874 12.65633996 4.2874 12.63778996 4.2874 3 P 0 N
A 12.5776 4.24803002 12.5776 4.24803002 12.55905 4.24803002 3 P 0 N
L 12.55905 4.40551004 12.63778996 4.44488002 9 P 0 
A 12.65633996 4.44488002 12.65633996 4.44488002 12.63778996 4.44488002 3 P 0 N
A 12.5776 4.40551004 12.5776 4.40551004 12.55905 4.40551004 3 P 0 N
A 12.65633996 3.97243996 12.65633996 3.97243996 12.63778996 3.97243996 3 P 0 N
L 12.55905 4.09055 12.63778996 4.12991998 9 P 0 
A 12.65633996 4.12991998 12.65633996 4.12991998 12.63778996 4.12991998 3 P 0 N
A 12.5776 4.09055 12.5776 4.09055 12.55905 4.09055 3 P 0 N
L 12.55905 3.77558996 12.63778996 3.81496004 9 P 0 
A 12.65633996 3.81496004 12.65633996 3.81496004 12.63778996 3.81496004 3 P 0 N
A 12.5776 3.77558996 12.5776 3.77558996 12.55905 3.77558996 3 P 0 N
L 12.55905 3.93306998 12.63778996 3.97243996 9 P 0 
A 12.5776 3.93306998 12.5776 3.93306998 12.55905 3.93306998 3 P 0 N
A 12.65633996 3.5 12.65633996 3.5 12.63778996 3.5 3 P 0 N
L 12.55905 3.61811004 12.63778996 3.65748002 9 P 0 
A 12.65633996 3.65748002 12.65633996 3.65748002 12.63778996 3.65748002 3 P 0 N
A 12.5776 3.61811004 12.5776 3.61811004 12.55905 3.61811004 3 P 0 N
L 12.55905 3.30315 12.63778996 3.26378002 9 P 0 
A 12.65633996 3.26378002 12.65633996 3.26378002 12.63778996 3.26378002 3 P 0 N
A 12.5776 3.30315 12.5776 3.30315 12.55905 3.30315 3 P 0 N
L 12.55905 3.46063002 12.63778996 3.5 9 P 0 
A 12.5776 3.46063002 12.5776 3.46063002 12.55905 3.46063002 3 P 0 N
L 12.55905 3.14566998 12.63778996 3.1063 9 P 0 
A 12.65633996 3.1063 12.65633996 3.1063 12.63778996 3.1063 3 P 0 N
A 12.5776 3.14566998 12.5776 3.14566998 12.55905 3.14566998 3 P 0 N
A 12.5776 2.98818996 12.5776 2.98818996 12.55905 2.98818996 3 P 0 N
L 12.55905 2.98818996 12.63778996 2.94881998 9 P 0 
A 12.65633996 2.94881998 12.65633996 2.94881998 12.63778996 2.94881998 3 P 0 N
L 12.55905 2.83071004 12.63778996 2.79133996 9 P 0 
A 12.65633996 2.79133996 12.65633996 2.79133996 12.63778996 2.79133996 3 P 0 N
A 12.5776 2.83071004 12.5776 2.83071004 12.55905 2.83071004 3 P 0 N
L 12.55905 2.59448996 12.63778996 2.55511998 9 P 0 
A 12.65633996 2.55511998 12.65633996 2.55511998 12.63778996 2.55511998 3 P 0 N
A 12.5776 2.59448996 12.5776 2.59448996 12.55905 2.59448996 3 P 0 N
L 12.55905 2.43701004 12.63778996 2.39763996 9 P 0 
A 12.65633996 2.39763996 12.65633996 2.39763996 12.63778996 2.39763996 3 P 0 N
A 12.5776 2.43701004 12.5776 2.43701004 12.55905 2.43701004 3 P 0 N
L 12.55905 2.27953002 12.63778996 2.24016004 9 P 0 
A 12.65633996 2.24016004 12.65633996 2.24016004 12.63778996 2.24016004 3 P 0 N
A 12.5776 2.27953002 12.5776 2.27953002 12.55905 2.27953002 3 P 0 N
A 12.5776 2.04331004 12.5776 2.04331004 12.55905 2.04331004 3 P 0 N
A 12.65633996 2.08268002 12.65633996 2.08268002 12.63778996 2.08268002 3 P 0 N
L 12.55905 2.04331004 12.63778996 2.08268002 9 P 0 
L 12.55905 1.96456998 12.63778996 1.9252 9 P 0 
A 12.65633996 1.9252 12.65633996 1.9252 12.63778996 1.9252 3 P 0 N
A 12.5776 1.96456998 12.5776 1.96456998 12.55905 1.96456998 3 P 0 N
A 0.11303996 4.52363002 0.11303996 4.52363002 0.09448996 4.52363002 3 P 0 N
A 0.19178002 4.563 0.19178002 4.563 0.17323002 4.563 3 P 0 N
L 0.09448996 4.52363002 0.17323002 4.563 9 P 0 
A 0.11303996 4.36613996 0.11303996 4.36613996 0.09448996 4.36613996 3 P 0 N
A 0.19178002 4.40551004 0.19178002 4.40551004 0.17323002 4.40551004 3 P 0 N
L 0.09448996 4.36613996 0.17323002 4.40551004 9 P 0 
A 0.11303996 4.20866004 0.11303996 4.20866004 0.09448996 4.20866004 3 P 0 N
A 0.19178002 4.24803002 0.19178002 4.24803002 0.17323002 4.24803002 3 P 0 N
L 0.09448996 4.20866004 0.17323002 4.24803002 9 P 0 
A 0.11303996 4.05118002 0.11303996 4.05118002 0.09448996 4.05118002 3 P 0 N
A 0.19178002 4.09055 0.19178002 4.09055 0.17323002 4.09055 3 P 0 N
L 0.09448996 4.05118002 0.17323002 4.09055 9 P 0 
A 0.11303996 3.8937 0.11303996 3.8937 0.09448996 3.8937 3 P 0 N
A 0.19178002 3.93306998 0.19178002 3.93306998 0.17323002 3.93306998 3 P 0 N
L 0.09448996 3.8937 0.17323002 3.93306998 9 P 0 
A 0.11303996 3.73621998 0.11303996 3.73621998 0.09448996 3.73621998 3 P 0 N
A 0.19178002 3.77558996 0.19178002 3.77558996 0.17323002 3.77558996 3 P 0 N
L 0.09448996 3.73621998 0.17323002 3.77558996 9 P 0 
A 0.11303996 3.57873996 0.11303996 3.57873996 0.09448996 3.57873996 3 P 0 N
A 0.19178002 3.61811004 0.19178002 3.61811004 0.17323002 3.61811004 3 P 0 N
L 0.09448996 3.57873996 0.17323002 3.61811004 9 P 0 
A 0.11303996 3.42126004 0.11303996 3.42126004 0.09448996 3.42126004 3 P 0 N
A 0.19178002 3.46063002 0.19178002 3.46063002 0.17323002 3.46063002 3 P 0 N
L 0.09448996 3.42126004 0.17323002 3.46063002 9 P 0 
A 0.2902 3.14566998 0.2902 3.14566998 0.27165 3.14566998 3 P 0 N
A 0.36893996 3.18503996 0.36893996 3.18503996 0.35038996 3.18503996 3 P 0 N
L 0.27165 3.14566998 0.35038996 3.18503996 9 P 0 
A 0.2902 2.98818996 0.2902 2.98818996 0.27165 2.98818996 3 P 0 N
A 0.36893996 3.02756004 0.36893996 3.02756004 0.35038996 3.02756004 3 P 0 N
L 0.27165 2.98818996 0.35038996 3.02756004 9 P 0 
A 0.2902 2.83071004 0.2902 2.83071004 0.27165 2.83071004 3 P 0 N
A 0.36893996 2.87008002 0.36893996 2.87008002 0.35038996 2.87008002 3 P 0 N
L 0.27165 2.83071004 0.35038996 2.87008002 9 P 0 
A 0.2902 2.67323002 0.2902 2.67323002 0.27165 2.67323002 3 P 0 N
A 0.36893996 2.7126 0.36893996 2.7126 0.35038996 2.7126 3 P 0 N
L 0.27165 2.67323002 0.35038996 2.7126 9 P 0 
A 0.2902 2.43701004 0.2902 2.43701004 0.27165 2.43701004 3 P 0 N
A 0.36893996 2.47638002 0.36893996 2.47638002 0.35038996 2.47638002 3 P 0 N
L 0.27165 2.43701004 0.35038996 2.47638002 9 P 0 
A 0.2902 2.27953002 0.2902 2.27953002 0.27165 2.27953002 3 P 0 N
A 0.36893996 2.3189 0.36893996 2.3189 0.35038996 2.3189 3 P 0 N
L 0.27165 2.27953002 0.35038996 2.3189 9 P 0 
A 0.2902 2.12205 0.2902 2.12205 0.27165 2.12205 3 P 0 N
A 0.36893996 2.16141998 0.36893996 2.16141998 0.35038996 2.16141998 3 P 0 N
L 0.27165 2.12205 0.35038996 2.16141998 9 P 0 
L 0.09448996 2.00393996 0.17323002 2.04331004 9 P 0 
A 0.19178002 2.04331004 0.19178002 2.04331004 0.17323002 2.04331004 3 P 0 N
A 0.11303996 2.00393996 0.11303996 2.00393996 0.09448996 2.00393996 3 P 0 N
A 0.2902 1.96456998 0.2902 1.96456998 0.27165 1.96456998 3 P 0 N
A 0.36893996 1.9252 0.36893996 1.9252 0.35038996 1.9252 3 P 0 N
L 0.27165 1.96456998 0.35038996 1.9252 8 P 0 
A 0.11303996 1.9252 0.11303996 1.9252 0.09448996 1.9252 3 P 0 N
A 0.19178002 1.88583002 0.19178002 1.88583002 0.17323002 1.88583002 3 P 0 N
L 0.09448996 1.9252 0.17323002 1.88583002 9 P 0 
A 0.11303996 2.24016004 0.11303996 2.24016004 0.09448996 2.24016004 3 P 0 N
A 0.19178002 2.20078996 0.19178002 2.20078996 0.17323002 2.20078996 3 P 0 N
L 0.09448996 2.24016004 0.17323002 2.20078996 9 P 0 
A 0.11303996 2.39763996 0.11303996 2.39763996 0.09448996 2.39763996 3 P 0 N
A 0.19178002 2.35826998 0.19178002 2.35826998 0.17323002 2.35826998 3 P 0 N
L 0.09448996 2.39763996 0.17323002 2.35826998 9 P 0 
A 0.11303996 2.55511998 0.11303996 2.55511998 0.09448996 2.55511998 3 P 0 N
A 0.19178002 2.51575 0.19178002 2.51575 0.17323002 2.51575 3 P 0 N
L 0.09448996 2.55511998 0.17323002 2.51575 9 P 0 
A 0.11303996 2.79133996 0.11303996 2.79133996 0.09448996 2.79133996 3 P 0 N
A 0.19178002 2.75196998 0.19178002 2.75196998 0.17323002 2.75196998 3 P 0 N
L 0.09448996 2.79133996 0.17323002 2.75196998 9 P 0 
A 0.11303996 2.94881998 0.11303996 2.94881998 0.09448996 2.94881998 3 P 0 N
A 0.19178002 2.90945 0.19178002 2.90945 0.17323002 2.90945 3 P 0 N
L 0.09448996 2.94881998 0.17323002 2.90945 9 P 0 
A 0.11303996 3.1063 0.11303996 3.1063 0.09448996 3.1063 3 P 0 N
A 0.19178002 3.06693002 0.19178002 3.06693002 0.17323002 3.06693002 3 P 0 N
L 0.09448996 3.1063 0.17323002 3.06693002 9 P 0 
A 0.11303996 3.26378002 0.11303996 3.26378002 0.09448996 3.26378002 3 P 0 N
A 0.19178002 3.22441004 0.19178002 3.22441004 0.17323002 3.22441004 3 P 0 N
L 0.09448996 3.26378002 0.17323002 3.22441004 9 P 0 
A 0.2902 3.38188996 0.2902 3.38188996 0.27165 3.38188996 3 P 0 N
A 0.36893996 3.34251998 0.36893996 3.34251998 0.35038996 3.34251998 3 P 0 N
L 0.27165 3.38188996 0.35038996 3.34251998 9 P 0 
A 0.2902 3.53936998 0.2902 3.53936998 0.27165 3.53936998 3 P 0 N
A 0.36893996 3.5 0.36893996 3.5 0.35038996 3.5 3 P 0 N
L 0.27165 3.53936998 0.35038996 3.5 9 P 0 
A 0.2902 3.69685 0.2902 3.69685 0.27165 3.69685 3 P 0 N
A 0.36893996 3.65748002 0.36893996 3.65748002 0.35038996 3.65748002 3 P 0 N
L 0.27165 3.69685 0.35038996 3.65748002 9 P 0 
A 0.2902 3.85433002 0.2902 3.85433002 0.27165 3.85433002 3 P 0 N
A 0.36893996 3.81496004 0.36893996 3.81496004 0.35038996 3.81496004 3 P 0 N
L 0.27165 3.85433002 0.35038996 3.81496004 9 P 0 
A 0.2902 4.01181004 0.2902 4.01181004 0.27165 4.01181004 3 P 0 N
A 0.36893996 3.97243996 0.36893996 3.97243996 0.35038996 3.97243996 3 P 0 N
L 0.27165 4.01181004 0.35038996 3.97243996 9 P 0 
A 0.2902 4.16928996 0.2902 4.16928996 0.27165 4.16928996 3 P 0 N
A 0.36893996 4.12991998 0.36893996 4.12991998 0.35038996 4.12991998 3 P 0 N
L 0.27165 4.16928996 0.35038996 4.12991998 9 P 0 
A 0.2902 4.32676998 0.2902 4.32676998 0.27165 4.32676998 3 P 0 N
A 0.36893996 4.2874 0.36893996 4.2874 0.35038996 4.2874 3 P 0 N
L 0.27165 4.32676998 0.35038996 4.2874 9 P 0 
L 0.27165 4.48425 0.35038996 4.44488002 9 P 0 
A 0.36893996 4.44488002 0.36893996 4.44488002 0.35038996 4.44488002 3 P 0 N
A 0.2902 4.48425 0.2902 4.48425 0.27165 4.48425 3 P 0 N
L 4.87 0.025 6.565 0.025 14 P 0 
L 4.885 0.085 6.53 0.085 14 P 0 
L 4.895 0.15 6.54 0.15 14 P 0 
L 4.89 0.215 6.555 0.215 14 P 0 
L 4.89 0.3 6.535 0.3 14 P 0 
L 4.895 0.37 6.54 0.37 14 P 0 
A 12.84646004 6.02361998 12.9252 5.94488002 12.84646004 5.94488002 9 P 0 Y
A 12.9252 0.07873996 12.84646004 0 12.84646004 0.07873996 9 P 0 Y
L 12.9252 5.94488002 12.9252 0.07873996 9 P 0 
L 12.84646004 0 6.66536004 0 9 P 0 
A 6.58661998 0.35433002 6.50788002 0.43306998 6.50788002 0.35433002 9 P 0 N
A 6.66536004 0 6.58661998 0.07873996 6.66535994 0.07873996 9 P 0 Y
L 6.58661998 0.07873996 6.58661998 0.35433002 9 P 0 
A 4.93308002 0.43306998 4.85433996 0.35433002 4.93307992 0.35433002 9 P 0 N
L 6.50788002 0.43306998 4.93308002 0.43306998 9 P 0 
L 4.85433996 0.35433002 4.85433996 0.07873996 9 P 0 
A 4.85433996 0.07873996 4.77558996 0 4.7755999 0.07873996 9 P 0 Y
A 0.07873996 0 0 0.07873996 0.07873996 0.07873996 9 P 0 Y
L 4.77558996 0 0.07873996 0 9 P 0 
L 0.07873996 6.02361998 12.84646004 6.02361998 9 P 0 
A 0 5.94488002 0.07873996 6.02361998 0.07873996 5.94488002 9 P 0 Y
L 0 0.07873996 0 5.94488002 9 P 0 
L 0 6.07011998 12.89 6.07011998 14 P 0 
L 0 -0.0465 12.89 -0.0465 14 P 0 
L 0.005 6.16 0.035 6.13 3 P 0 
L 12.91 6.15 12.88 6.12 3 P 0 
L 12.91 -0.13 12.88 -0.1 3 P 0 
L 0.005 -0.135 0.035 -0.105 3 P 0 
L 0 -0.41426004 0 -0.093 9 P 0 
A 0.07873996 -0.493 0 -0.41426004 0.07873996 -0.41426004 9 P 0 Y
L 12.84646004 -0.493 0.07873996 -0.493 9 P 0 
A 12.9252 -0.41426004 12.84646004 -0.493 12.84646004 -0.41426004 9 P 0 Y
L 12.9252 -0.093 12.9252 -0.41426004 9 P 0 
L 0 -0.093 12.9252 -0.093 9 P 0 
L 0 6.11661998 12.9252 6.11661998 9 P 0 
L 0 6.43788002 0 6.11661998 9 P 0 
A 0.07873996 6.51661998 0 6.43788002 0.07873996 6.43788002 9 P 0 N
L 12.84646004 6.51661998 0.07873996 6.51661998 9 P 0 
A 12.9252 6.43788002 12.84646004 6.51661998 12.84646004 6.43788002 9 P 0 N
L 12.9252 6.11661998 12.9252 6.43788002 9 P 0 
L 0.0349 -2.3038 0.0349 -1.0038 2 P 0 ;0
L 0.0349 -1.0038 4.5349 -1.0038 2 P 0 ;0
L 4.5349 -1.0038 4.5349 -2.3038 2 P 0 ;0
L 4.5349 -2.3038 0.0349 -2.3038 2 P 0 ;0
L 0.0349 -1.6038 4.5349 -1.6038 2 P 0 ;0
L 0.0349 -1.8038 4.5349 -1.8038 2 P 0 ;0
L 2.4349 -2.1038 4.0349 -2.1038 2 P 0 ;0
L 2.4349 -2.3038 2.4349 -1.8038 2 P 0 ;0
L 3.2349 -2.1038 3.2349 -1.8038 2 P 0 ;0
L 4.0349 -2.3038 4.0349 -1.8038 2 P 0 ;0
L 0.0723999 -1.6844687 0.07906663 -1.69030079 1 P 0 ;0
L 0.07906663 -1.69030079 0.08656654 -1.6938 1 P 0 ;0
L 0.08656654 -1.6938 0.09323337 -1.6938 1 P 0 ;0
L 0.09323337 -1.6938 0.0999001 -1.69030079 1 P 0 ;0
L 0.0999001 -1.69030079 0.10490059 -1.6844687 1 P 0 ;0
L 0.10490059 -1.6844687 0.1074 -1.67629951 1 P 0 ;0
L 0.1074 -1.67629951 0.10573376 -1.66813455 1 P 0 ;0
L 0.10573376 -1.66813455 0.10156644 -1.66113396 1 P 0 ;0
L 0.10156644 -1.66113396 0.09406654 -1.65646614 1 P 0 ;0
L 0.09406654 -1.65646614 0.08406713 -1.65413327 1 P 0 ;0
L 0.08406713 -1.65413327 0.07823346 -1.64946762 1 P 0 ;0
L 0.07823346 -1.64946762 0.07573248 -1.64130059 1 P 0 ;0
L 0.07573248 -1.64130059 0.0774003 -1.63313356 1 P 0 ;0
L 0.0774003 -1.63313356 0.08156614 -1.62730148 1 P 0 ;0
L 0.08156614 -1.62730148 0.0873997 -1.6238 1 P 0 ;0
L 0.0873997 -1.6238 0.09323337 -1.6238 1 P 8191 ;0
L 0.09323337 -1.6238 0.09906693 -1.62613287 1 P 0 ;0
L 0.09906693 -1.62613287 0.10406742 -1.63196713 1 P 0 ;0
L 0.1383999 -1.6938 0.1383999 -1.6238 1 P 0 ;0
L 0.1734 -1.6238 0.1734 -1.6938 1 P 0 ;0
L 0.1734 -1.65880108 0.1383999 -1.65880108 1 P 0 ;0
L 0.23856683 -1.6938 0.20523307 -1.6938 1 P 0 ;0
L 0.20523307 -1.6938 0.20523307 -1.6238 1 P 0 ;0
L 0.20523307 -1.6238 0.23856683 -1.6238 1 P 0 ;0
L 0.22523337 -1.65763258 0.20523307 -1.65763258 1 P 0 ;0
L 0.30456683 -1.6938 0.27123307 -1.6938 1 P 0 ;0
L 0.27123307 -1.6938 0.27123307 -1.6238 1 P 0 ;0
L 0.27123307 -1.6238 0.30456683 -1.6238 1 P 0 ;0
L 0.29123337 -1.65763258 0.27123307 -1.65763258 1 P 0 ;0
L 0.35389921 -1.6238 0.35389921 -1.6938 1 P 0 ;0
L 0.33473356 -1.6238 0.37306634 -1.6238 1 P 0 ;0
L 0.09489921 -1.7188 0.09489921 -1.7888 1 P 0 ;0
L 0.07573356 -1.7188 0.11406634 -1.7188 1 P 0 ;0
L 0.1508998 -1.7188 0.17089862 -1.7188 1 P 0 ;0
L 0.16089921 -1.7188 0.16089921 -1.7888 1 P 0 ;0
L 0.1508998 -1.7888 0.17089862 -1.7888 1 P 0 ;0
L 0.22689921 -1.7188 0.22689921 -1.7888 1 P 0 ;0
L 0.20773356 -1.7188 0.24606634 -1.7188 1 P 0 ;0
L 0.27623307 -1.7188 0.27623307 -1.7888 1 P 0 ;0
L 0.27623307 -1.7888 0.30956683 -1.7888 1 P 0 ;0
L 0.37556683 -1.7888 0.34223307 -1.7888 1 P 0 ;0
L 0.34223307 -1.7888 0.34223307 -1.7188 1 P 0 ;0
L 0.34223307 -1.7188 0.37556683 -1.7188 1 P 0 ;0
L 0.36223337 -1.75263258 0.34223307 -1.75263258 1 P 0 ;0
L 2.5438999 -1.96813563 2.5519 -1.97480089 1 P 0 ;0
L 2.5519 -1.97480089 2.5608999 -1.9788 1 P 0 ;0
L 2.5608999 -1.9788 2.5689 -1.9788 1 P 0 ;0
L 2.5689 -1.9788 2.5769001 -1.97480089 1 P 0 ;0
L 2.5769001 -1.97480089 2.58290069 -1.96813563 1 P 0 ;0
L 2.58290069 -1.96813563 2.5859 -1.95879941 1 P 0 ;0
L 2.5859 -1.95879941 2.58390049 -1.94946811 1 P 0 ;0
L 2.58390049 -1.94946811 2.5788997 -1.94146732 1 P 0 ;0
L 2.5788997 -1.94146732 2.5698998 -1.93613278 1 P 0 ;0
L 2.5698998 -1.93613278 2.55790049 -1.93346663 1 P 0 ;0
L 2.55790049 -1.93346663 2.5509002 -1.92813445 1 P 0 ;0
L 2.5509002 -1.92813445 2.54789902 -1.91880069 1 P 0 ;0
L 2.54789902 -1.91880069 2.54990039 -1.90946683 1 P 0 ;0
L 2.54990039 -1.90946683 2.55489931 -1.90280167 1 P 0 ;0
L 2.55489931 -1.90280167 2.5618997 -1.8988 1 P 0 ;0
L 2.5618997 -1.8988 2.5689 -1.8988 1 P 0 ;0
L 2.5689 -1.8988 2.57590039 -1.90146614 1 P 0 ;0
L 2.57590039 -1.90146614 2.58190089 -1.90813386 1 P 0 ;0
L 2.6648998 -1.90546772 2.65889931 -1.90146614 1 P 0 ;0
L 2.65889931 -1.90146614 2.65190079 -1.8988 1 P 0 ;0
L 2.65190079 -1.8988 2.64390069 -1.8988 1 P 0 ;0
L 2.64390069 -1.8988 2.63489892 -1.90280167 1 P 0 ;0
L 2.63489892 -1.90280167 2.62790039 -1.90946683 1 P 0 ;0
L 2.62790039 -1.90946683 2.62289961 -1.91746762 1 P 0 ;0
L 2.62289961 -1.91746762 2.61889862 -1.93080049 1 P 0 ;0
L 2.61889862 -1.93080049 2.61789892 -1.94280039 1 P 0 ;0
L 2.61789892 -1.94280039 2.6199003 -1.9548003 1 P 0 ;0
L 2.6199003 -1.9548003 2.62289961 -1.96280098 1 P 0 ;0
L 2.62289961 -1.96280098 2.6289002 -1.97080177 1 P 0 ;0
L 2.6289002 -1.97080177 2.63590049 -1.97613396 1 P 0 ;0
L 2.63590049 -1.97613396 2.64289902 -1.9788 1 P 0 ;0
L 2.64289902 -1.9788 2.64989941 -1.9788 1 P 0 ;0
L 2.64989941 -1.9788 2.6568997 -1.97613396 1 P 0 ;0
L 2.6568997 -1.97613396 2.6629003 -1.97213484 1 P 0 ;0
L 2.6629003 -1.97213484 2.66790098 -1.96680266 1 P 0 ;0
L 2.69589892 -1.9788 2.72089902 -1.8988 1 P 0 ;0
L 2.72089902 -1.8988 2.74590098 -1.9788 1 P 0 ;0
L 2.73689931 -1.95080118 2.70489882 -1.95080118 1 P 0 ;0
L 2.77889961 -1.8988 2.77889961 -1.9788 1 P 0 ;0
L 2.77889961 -1.9788 2.8189003 -1.9788 1 P 0 ;0
L 2.8969003 -1.9788 2.85689961 -1.9788 1 P 0 ;0
L 2.85689961 -1.9788 2.85689961 -1.8988 1 P 0 ;0
L 2.85689961 -1.8988 2.8969003 -1.8988 1 P 0 ;0
L 2.8809 -1.93746575 2.85689961 -1.93746575 1 P 0 ;0
L 3.03289902 -1.9788 3.03289902 -1.8988 1 P 0 ;0
L 3.03289902 -1.8988 3.0208998 -1.91479911 1 P 0 ;0
L 3.0208998 -1.9788 3.04489833 -1.9788 1 P 0 ;0
L 3.11089902 -1.98146604 3.10889951 -1.98013297 1 P 8191 ;0
L 3.10889951 -1.98013297 3.10889951 -1.97746703 1 P 8191 ;0
L 3.10889951 -1.97746703 3.11089902 -1.97613396 1 P 8191 ;0
L 3.11089902 -1.97613396 3.11290039 -1.97746703 1 P 8191 ;0
L 3.11290039 -1.97746703 3.11290039 -1.98013297 1 P 8191 ;0
L 3.11290039 -1.98013297 3.11089902 -1.98146604 1 P 8191 ;0
L 3.11089902 -1.945469 3.10889951 -1.94413346 1 P 8191 ;0
L 3.10889951 -1.94413346 3.10889951 -1.94146732 1 P 8191 ;0
L 3.10889951 -1.94146732 3.11089902 -1.94013435 1 P 8191 ;0
L 3.11089902 -1.94013435 3.11290039 -1.94146732 1 P 8191 ;0
L 3.11290039 -1.94146732 3.11290039 -1.94413346 1 P 8191 ;0
L 3.11290039 -1.94413346 3.11089902 -1.945469 1 P 8191 ;0
L 3.18889902 -1.9788 3.18889902 -1.8988 1 P 0 ;0
L 3.18889902 -1.8988 3.1768998 -1.91479911 1 P 0 ;0
L 3.1768998 -1.9788 3.20089833 -1.9788 1 P 0 ;0
L 2.5138999 -2.23313563 2.5219 -2.23980089 1 P 0 ;0
L 2.5219 -2.23980089 2.5308999 -2.2438 1 P 0 ;0
L 2.5308999 -2.2438 2.5389 -2.2438 1 P 0 ;0
L 2.5389 -2.2438 2.5469001 -2.23980089 1 P 0 ;0
L 2.5469001 -2.23980089 2.55290069 -2.23313563 1 P 0 ;0
L 2.55290069 -2.23313563 2.5559 -2.22379941 1 P 0 ;0
L 2.5559 -2.22379941 2.55390049 -2.21446811 1 P 0 ;0
L 2.55390049 -2.21446811 2.5488997 -2.20646732 1 P 0 ;0
L 2.5488997 -2.20646732 2.5398998 -2.20113278 1 P 0 ;0
L 2.5398998 -2.20113278 2.52790049 -2.19846663 1 P 0 ;0
L 2.52790049 -2.19846663 2.5209002 -2.19313445 1 P 0 ;0
L 2.5209002 -2.19313445 2.51789902 -2.18380069 1 P 0 ;0
L 2.51789902 -2.18380069 2.51990039 -2.17446683 1 P 0 ;0
L 2.51990039 -2.17446683 2.52489931 -2.16780167 1 P 0 ;0
L 2.52489931 -2.16780167 2.5318997 -2.1638 1 P 0 ;0
L 2.5318997 -2.1638 2.5389 -2.1638 1 P 0 ;0
L 2.5389 -2.1638 2.54590039 -2.16646614 1 P 0 ;0
L 2.54590039 -2.16646614 2.55190089 -2.17313386 1 P 0 ;0
L 2.5918999 -2.2438 2.5918999 -2.1638 1 P 0 ;0
L 2.6339 -2.1638 2.6339 -2.2438 1 P 0 ;0
L 2.6339 -2.20380128 2.5918999 -2.20380128 1 P 0 ;0
L 2.7109003 -2.2438 2.67089961 -2.2438 1 P 0 ;0
L 2.67089961 -2.2438 2.67089961 -2.1638 1 P 0 ;0
L 2.67089961 -2.1638 2.7109003 -2.1638 1 P 0 ;0
L 2.6949 -2.20246575 2.67089961 -2.20246575 1 P 0 ;0
L 2.7889003 -2.2438 2.74889961 -2.2438 1 P 0 ;0
L 2.74889961 -2.2438 2.74889961 -2.1638 1 P 0 ;0
L 2.74889961 -2.1638 2.7889003 -2.1638 1 P 0 ;0
L 2.7729 -2.20246575 2.74889961 -2.20246575 1 P 0 ;0
L 2.84689902 -2.1638 2.84689902 -2.2438 1 P 0 ;0
L 2.8239003 -2.1638 2.86989961 -2.1638 1 P 0 ;0
L 3.29489961 -1.9238 3.29489961 -2.0038 1 P 0 ;0
L 3.29489961 -2.0038 3.3349003 -2.0038 1 P 0 ;0
L 3.36789892 -2.0038 3.39289902 -1.9238 1 P 0 ;0
L 3.39289902 -1.9238 3.41790098 -2.0038 1 P 0 ;0
L 3.40889931 -1.97580118 3.37689882 -1.97580118 1 P 0 ;0
L 3.47089902 -2.0038 3.47089902 -1.96780039 1 P 0 ;0
L 3.47089902 -1.96780039 3.45089961 -1.9238 1 P 0 ;0
L 3.4909003 -1.9238 3.47089902 -1.96780039 1 P 0 ;0
L 3.5689003 -2.0038 3.52889961 -2.0038 1 P 0 ;0
L 3.52889961 -2.0038 3.52889961 -1.9238 1 P 0 ;0
L 3.52889961 -1.9238 3.5689003 -1.9238 1 P 0 ;0
L 3.5529 -1.96246575 3.52889961 -1.96246575 1 P 0 ;0
L 3.60689961 -2.0038 3.60689961 -1.9238 1 P 0 ;0
L 3.60689961 -1.9238 3.6318998 -1.9238 1 P 0 ;0
L 3.6318998 -1.9238 3.6398999 -1.92780167 1 P 0 ;0
L 3.6398999 -1.92780167 3.64490069 -1.93313386 1 P 0 ;0
L 3.64490069 -1.93313386 3.6469003 -1.94380069 1 P 0 ;0
L 3.6469003 -1.94380069 3.64490069 -1.95446752 1 P 0 ;0
L 3.64490069 -1.95446752 3.6389001 -1.96113278 1 P 0 ;0
L 3.6389001 -1.96113278 3.6318998 -1.96513435 1 P 0 ;0
L 3.6318998 -1.96513435 3.60689961 -1.96513435 1 P 0 ;0
L 3.6318998 -1.96513435 3.6469003 -2.0038 1 P 0 ;0
L 3.33989902 -2.2538 3.33189892 -2.25246703 1 P 0 ;0
L 3.33189892 -2.25246703 3.32490039 -2.24713484 1 P 0 ;0
L 3.32490039 -2.24713484 3.3188999 -2.23913406 1 P 0 ;0
L 3.3188999 -2.23913406 3.31489892 -2.2298003 1 P 0 ;0
L 3.31489892 -2.2298003 3.31289931 -2.21913346 1 P 0 ;0
L 3.31289931 -2.21913346 3.31289931 -2.20846663 1 P 0 ;0
L 3.31289931 -2.20846663 3.31489892 -2.1977998 1 P 0 ;0
L 3.31489892 -2.1977998 3.3188999 -2.18846604 1 P 0 ;0
L 3.3188999 -2.18846604 3.32490039 -2.18046772 1 P 0 ;0
L 3.32490039 -2.18046772 3.33189892 -2.17513307 1 P 0 ;0
L 3.33189892 -2.17513307 3.33989902 -2.1738 1 P 0 ;0
L 3.33989902 -2.1738 3.34789911 -2.17513307 1 P 0 ;0
L 3.34789911 -2.17513307 3.35489951 -2.18046772 1 P 0 ;0
L 3.35489951 -2.18046772 3.3609 -2.18846604 1 P 0 ;0
L 3.3609 -2.18846604 3.36490098 -2.1977998 1 P 0 ;0
L 3.36490098 -2.1977998 3.36690059 -2.20846663 1 P 0 ;0
L 3.36690059 -2.20846663 3.36690059 -2.21913346 1 P 0 ;0
L 3.36690059 -2.21913346 3.36490098 -2.2298003 1 P 0 ;0
L 3.36490098 -2.2298003 3.3609 -2.23913406 1 P 0 ;0
L 3.3609 -2.23913406 3.35489951 -2.24713484 1 P 0 ;0
L 3.35489951 -2.24713484 3.34789911 -2.25246703 1 P 0 ;0
L 3.34789911 -2.25246703 3.33989902 -2.2538 1 P 0 ;0
L 3.39889941 -2.2538 3.39889941 -2.1738 1 P 0 ;0
L 3.39889941 -2.1738 3.43690049 -2.1738 1 P 0 ;0
L 3.4228998 -2.21246575 3.39889941 -2.21246575 1 P 0 ;0
L 0.16489872 -1.0538 0.16489872 -1.1538 1 P 0 ;0
L 0.13423376 -1.0538 0.19556614 -1.0538 1 P 0 ;0
L 0.2588997 -1.0538 0.29089774 -1.0538 1 P 0 ;0
L 0.27489872 -1.0538 0.27489872 -1.1538 1 P 0 ;0
L 0.2588997 -1.1538 0.29089774 -1.1538 1 P 0 ;0
L 0.38489872 -1.0538 0.38489872 -1.1538 1 P 0 ;0
L 0.35423376 -1.0538 0.41556614 -1.0538 1 P 0 ;0
L 0.46823287 -1.0538 0.46823287 -1.1538 1 P 0 ;0
L 0.46823287 -1.1538 0.52156703 -1.1538 1 P 0 ;0
L 0.63156703 -1.1538 0.57823287 -1.1538 1 P 0 ;0
L 0.57823287 -1.1538 0.57823287 -1.0538 1 P 0 ;0
L 0.57823287 -1.0538 0.63156703 -1.0538 1 P 0 ;0
L 0.61023337 -1.10213219 0.57823287 -1.10213219 1 P 0 ;0
L 4.18989892 -1.9538 4.21489902 -1.8738 1 P 0 ;0
L 4.21489902 -1.8738 4.23990098 -1.9538 1 P 0 ;0
L 4.23089931 -1.92580118 4.19889882 -1.92580118 1 P 0 ;0
L 4.27289961 -1.9538 4.27289961 -1.8738 1 P 0 ;0
L 4.27289961 -1.8738 4.2978998 -1.8738 1 P 0 ;0
L 4.2978998 -1.8738 4.3058999 -1.87780167 1 P 0 ;0
L 4.3058999 -1.87780167 4.31090069 -1.88313386 1 P 0 ;0
L 4.31090069 -1.88313386 4.3129003 -1.89380069 1 P 0 ;0
L 4.3129003 -1.89380069 4.31090069 -1.90446752 1 P 0 ;0
L 4.31090069 -1.90446752 4.3049001 -1.91113278 1 P 0 ;0
L 4.3049001 -1.91113278 4.2978998 -1.91513435 1 P 0 ;0
L 4.2978998 -1.91513435 4.27289961 -1.91513435 1 P 0 ;0
L 4.2978998 -1.91513435 4.3129003 -1.9538 1 P 0 ;0
L 4.37089902 -1.8738 4.37089902 -1.9538 1 P 0 ;0
L 4.3479003 -1.8738 4.39389961 -1.8738 1 P 0 ;0
L 3.61989892 -2.2538 3.61989892 -2.1638 1 P 0 ;0
L 3.61989892 -2.1638 3.6058997 -2.18179892 1 P 0 ;0
L 3.6058997 -2.2538 3.63389803 -2.2538 1 P 0 ;0
L 3.68773268 -2.17879961 3.69473337 -2.16980148 1 P 0 ;0
L 3.69473337 -2.16980148 3.70290039 -2.1652997 1 P 0 ;0
L 3.70290039 -2.1652997 3.71223386 -2.1638 1 P 0 ;0
L 3.71223386 -2.1638 3.7239002 -2.16679941 1 P 0 ;0
L 3.7239002 -2.16679941 3.73206722 -2.17430059 1 P 0 ;0
L 3.73206722 -2.17430059 3.7344001 -2.18329862 1 P 0 ;0
L 3.7344001 -2.18329862 3.73323366 -2.19230217 1 P 0 ;0
L 3.73323366 -2.19230217 3.72856585 -2.19980059 1 P 0 ;0
L 3.72856585 -2.19980059 3.70523317 -2.2148001 1 P 0 ;0
L 3.70523317 -2.2148001 3.69473337 -2.22530069 1 P 0 ;0
L 3.69473337 -2.22530069 3.68773268 -2.24030295 1 P 0 ;0
L 3.68773268 -2.24030295 3.6853998 -2.2538 1 P 0 ;0
L 3.6853998 -2.2538 3.7344001 -2.2538 1 P 0 ;0
L 0.5058997 -1.6638 0.53389803 -1.6638 1 P 0 ;0
L 0.51989892 -1.6638 0.51989892 -1.7538 1 P 0 ;0
L 0.5058997 -1.7538 0.53389803 -1.7538 1 P 0 ;0
L 0.58306703 -1.7538 0.58306703 -1.6638 1 P 0 ;0
L 0.58306703 -1.6638 0.63673287 -1.7538 1 P 0 ;0
L 0.63673287 -1.7538 0.63673287 -1.6638 1 P 0 ;0
L 0.69989892 -1.6638 0.69989892 -1.7538 1 P 0 ;0
L 0.67306703 -1.6638 0.72673287 -1.6638 1 P 0 ;0
L 0.81323366 -1.7538 0.76656624 -1.7538 1 P 0 ;0
L 0.76656624 -1.7538 0.76656624 -1.6638 1 P 0 ;0
L 0.76656624 -1.6638 0.81323366 -1.6638 1 P 0 ;0
L 0.79456673 -1.70729902 0.76656624 -1.70729902 1 P 0 ;0
L 0.85656624 -1.7538 0.85656624 -1.6638 1 P 0 ;0
L 0.85656624 -1.6638 0.88573307 -1.6638 1 P 0 ;0
L 0.88573307 -1.6638 0.89506654 -1.66830187 1 P 0 ;0
L 0.89506654 -1.66830187 0.90090079 -1.67430059 1 P 0 ;0
L 0.90090079 -1.67430059 0.90323366 -1.68630069 1 P 0 ;0
L 0.90323366 -1.68630069 0.90090079 -1.69830089 1 P 0 ;0
L 0.90090079 -1.69830089 0.8939002 -1.70579931 1 P 0 ;0
L 0.8939002 -1.70579931 0.88573307 -1.71030108 1 P 0 ;0
L 0.88573307 -1.71030108 0.85656624 -1.71030108 1 P 0 ;0
L 0.88573307 -1.71030108 0.90323366 -1.7538 1 P 0 ;0
L 0.94306703 -1.7538 0.94306703 -1.6638 1 P 0 ;0
L 0.94306703 -1.6638 0.99673287 -1.7538 1 P 0 ;0
L 0.99673287 -1.7538 0.99673287 -1.6638 1 P 0 ;0
L 1.03073209 -1.7538 1.05989892 -1.6638 1 P 0 ;0
L 1.05989892 -1.6638 1.08906782 -1.7538 1 P 0 ;0
L 1.07856585 -1.72230128 1.04123189 -1.72230128 1 P 0 ;0
L 1.12656624 -1.6638 1.12656624 -1.7538 1 P 0 ;0
L 1.12656624 -1.7538 1.17323366 -1.7538 1 P 0 ;0
L 1.30656624 -1.6638 1.30656624 -1.7538 1 P 0 ;0
L 1.30656624 -1.7538 1.35323366 -1.7538 1 P 0 ;0
L 1.39073209 -1.7538 1.41989892 -1.6638 1 P 0 ;0
L 1.41989892 -1.6638 1.44906782 -1.7538 1 P 0 ;0
L 1.43856585 -1.72230128 1.40123189 -1.72230128 1 P 0 ;0
L 1.50989892 -1.7538 1.50989892 -1.71330049 1 P 0 ;0
L 1.50989892 -1.71330049 1.48656624 -1.6638 1 P 0 ;0
L 1.53323366 -1.6638 1.50989892 -1.71330049 1 P 0 ;0
L 1.62323366 -1.7538 1.57656624 -1.7538 1 P 0 ;0
L 1.57656624 -1.7538 1.57656624 -1.6638 1 P 0 ;0
L 1.57656624 -1.6638 1.62323366 -1.6638 1 P 0 ;0
L 1.60456673 -1.70729902 1.57656624 -1.70729902 1 P 0 ;0
L 1.66656624 -1.7538 1.66656624 -1.6638 1 P 0 ;0
L 1.66656624 -1.6638 1.69573307 -1.6638 1 P 0 ;0
L 1.69573307 -1.6638 1.70506654 -1.66830187 1 P 0 ;0
L 1.70506654 -1.66830187 1.71090079 -1.67430059 1 P 0 ;0
L 1.71090079 -1.67430059 1.71323366 -1.68630069 1 P 0 ;0
L 1.71323366 -1.68630069 1.71090079 -1.69830089 1 P 0 ;0
L 1.71090079 -1.69830089 1.7039002 -1.70579931 1 P 0 ;0
L 1.7039002 -1.70579931 1.69573307 -1.71030108 1 P 0 ;0
L 1.69573307 -1.71030108 1.66656624 -1.71030108 1 P 0 ;0
L 1.69573307 -1.71030108 1.71323366 -1.7538 1 P 0 ;0
L 1.84773268 -1.71630256 1.8558997 -1.70579931 1 P 0 ;0
L 1.8558997 -1.70579931 1.86290039 -1.69980059 1 P 0 ;0
L 1.86290039 -1.69980059 1.87223386 -1.69680128 1 P 0 ;0
L 1.87223386 -1.69680128 1.88040089 -1.69980059 1 P 0 ;0
L 1.88040089 -1.69980059 1.88623297 -1.70579931 1 P 0 ;0
L 1.88623297 -1.70579931 1.89090079 -1.7148001 1 P 0 ;0
L 1.89090079 -1.7148001 1.89206722 -1.72530069 1 P 0 ;0
L 1.89206722 -1.72530069 1.89090079 -1.73430148 1 P 0 ;0
L 1.89090079 -1.73430148 1.88623297 -1.74330226 1 P 0 ;0
L 1.88623297 -1.74330226 1.87923238 -1.75080069 1 P 0 ;0
L 1.87923238 -1.75080069 1.87106742 -1.7538 1 P 0 ;0
L 1.87106742 -1.7538 1.86173396 -1.75080069 1 P 0 ;0
L 1.86173396 -1.75080069 1.85356693 -1.74180266 1 P 0 ;0
L 1.85356693 -1.74180266 1.84889911 -1.7283 1 P 0 ;0
L 1.84889911 -1.7283 1.84773268 -1.71330049 1 P 0 ;0
L 1.84773268 -1.71330049 1.85006555 -1.69380187 1 P 0 ;0
L 1.85006555 -1.69380187 1.85356693 -1.68329862 1 P 0 ;0
L 1.85356693 -1.68329862 1.85939902 -1.67280089 1 P 0 ;0
L 1.85939902 -1.67280089 1.86756604 -1.6652997 1 P 0 ;0
L 1.86756604 -1.6652997 1.87573307 -1.6638 1 P 0 ;0
L 1.87573307 -1.6638 1.8839002 -1.66679941 1 P 0 ;0
L 1.8839002 -1.66679941 1.88973435 -1.67430059 1 P 0 ;0
L 3.79773268 -1.96630256 3.8058997 -1.95579931 1 P 0 ;0
L 3.8058997 -1.95579931 3.81290039 -1.94980059 1 P 0 ;0
L 3.81290039 -1.94980059 3.82223386 -1.94680128 1 P 0 ;0
L 3.82223386 -1.94680128 3.83040089 -1.94980059 1 P 0 ;0
L 3.83040089 -1.94980059 3.83623297 -1.95579931 1 P 0 ;0
L 3.83623297 -1.95579931 3.84090079 -1.9648001 1 P 0 ;0
L 3.84090079 -1.9648001 3.84206722 -1.97530069 1 P 0 ;0
L 3.84206722 -1.97530069 3.84090079 -1.98430148 1 P 0 ;0
L 3.84090079 -1.98430148 3.83623297 -1.99330226 1 P 0 ;0
L 3.83623297 -1.99330226 3.82923238 -2.00080069 1 P 0 ;0
L 3.82923238 -2.00080069 3.82106742 -2.0038 1 P 0 ;0
L 3.82106742 -2.0038 3.81173396 -2.00080069 1 P 0 ;0
L 3.81173396 -2.00080069 3.80356693 -1.99180266 1 P 0 ;0
L 3.80356693 -1.99180266 3.79889911 -1.9783 1 P 0 ;0
L 3.79889911 -1.9783 3.79773268 -1.96330049 1 P 0 ;0
L 3.79773268 -1.96330049 3.80006555 -1.94380187 1 P 0 ;0
L 3.80006555 -1.94380187 3.80356693 -1.93329862 1 P 0 ;0
L 3.80356693 -1.93329862 3.80939902 -1.92280089 1 P 0 ;0
L 3.80939902 -1.92280089 3.81756604 -1.9152997 1 P 0 ;0
L 3.81756604 -1.9152997 3.82573307 -1.9138 1 P 0 ;0
L 3.82573307 -1.9138 3.8339002 -1.91679941 1 P 0 ;0
L 3.8339002 -1.91679941 3.83973435 -1.92430059 1 P 0 ;0
L 3.04773268 -2.21630256 3.0558997 -2.20579931 1 P 0 ;0
L 3.0558997 -2.20579931 3.06290039 -2.19980059 1 P 0 ;0
L 3.06290039 -2.19980059 3.07223386 -2.19680128 1 P 0 ;0
L 3.07223386 -2.19680128 3.08040089 -2.19980059 1 P 0 ;0
L 3.08040089 -2.19980059 3.08623297 -2.20579931 1 P 0 ;0
L 3.08623297 -2.20579931 3.09090079 -2.2148001 1 P 0 ;0
L 3.09090079 -2.2148001 3.09206722 -2.22530069 1 P 0 ;0
L 3.09206722 -2.22530069 3.09090079 -2.23430148 1 P 0 ;0
L 3.09090079 -2.23430148 3.08623297 -2.24330226 1 P 0 ;0
L 3.08623297 -2.24330226 3.07923238 -2.25080069 1 P 0 ;0
L 3.07923238 -2.25080069 3.07106742 -2.2538 1 P 0 ;0
L 3.07106742 -2.2538 3.06173396 -2.25080069 1 P 0 ;0
L 3.06173396 -2.25080069 3.05356693 -2.24180266 1 P 0 ;0
L 3.05356693 -2.24180266 3.04889911 -2.2283 1 P 0 ;0
L 3.04889911 -2.2283 3.04773268 -2.21330049 1 P 0 ;0
L 3.04773268 -2.21330049 3.05006555 -2.19380187 1 P 0 ;0
L 3.05006555 -2.19380187 3.05356693 -2.18329862 1 P 0 ;0
L 3.05356693 -2.18329862 3.05939902 -2.17280089 1 P 0 ;0
L 3.05939902 -2.17280089 3.06756604 -2.1652997 1 P 0 ;0
L 3.06756604 -2.1652997 3.07573307 -2.1638 1 P 0 ;0
L 3.07573307 -2.1638 3.0839002 -2.16679941 1 P 0 ;0
L 3.0839002 -2.16679941 3.08973435 -2.17430059 1 P 0 ;0
L 0.59099833 -1.36499882 0.5990003 -1.35750039 1 P 0 ;0
L 0.5990003 -1.35750039 0.60499902 -1.34500315 1 P 0 ;0
L 0.60499902 -1.34500315 0.60900187 -1.32749764 1 P 0 ;0
L 0.60900187 -1.32749764 0.60499902 -1.31250089 1 P 0 ;0
L 0.60499902 -1.31250089 0.59700079 -1.30250305 1 P 0 ;0
L 0.59700079 -1.30250305 0.5830001 -1.295 1 P 0 ;0
L 0.5830001 -1.295 0.52900059 -1.295 1 P 0 ;0
L 0.52900059 -1.295 0.52900059 -1.445 1 P 0 ;0
L 0.52900059 -1.445 0.59500118 -1.445 1 P 0 ;0
L 0.59500118 -1.445 0.60900187 -1.43500217 1 P 0 ;0
L 0.60900187 -1.43500217 0.6170001 -1.42000079 1 P 0 ;0
L 0.6170001 -1.42000079 0.62099931 -1.4025 1 P 0 ;0
L 0.62099931 -1.4025 0.6170001 -1.38500374 1 P 0 ;0
L 0.6170001 -1.38500374 0.60499902 -1.37000236 1 P 0 ;0
L 0.60499902 -1.37000236 0.59099833 -1.36499882 1 P 0 ;0
L 0.59099833 -1.36499882 0.52900059 -1.36499882 1 P 0 ;0
L 0.77100138 -1.445 0.77100138 -1.34500315 1 P 0 ;0
L 0.77100138 -1.36249941 0.76299951 -1.35250148 1 P 0 ;0
L 0.76299951 -1.35250148 0.75099833 -1.34750256 1 P 0 ;0
L 0.75099833 -1.34750256 0.73700138 -1.34500315 1 P 0 ;0
L 0.73700138 -1.34500315 0.72300069 -1.35000207 1 P 0 ;0
L 0.72300069 -1.35000207 0.71099961 -1.3599999 1 P 0 ;0
L 0.71099961 -1.3599999 0.70299764 -1.37500128 1 P 0 ;0
L 0.70299764 -1.37500128 0.69899852 -1.39500157 1 P 0 ;0
L 0.69899852 -1.39500157 0.70299764 -1.41500187 1 P 0 ;0
L 0.70299764 -1.41500187 0.71099961 -1.43000325 1 P 0 ;0
L 0.71099961 -1.43000325 0.72300069 -1.44000108 1 P 0 ;0
L 0.72300069 -1.44000108 0.73700138 -1.445 1 P 0 ;0
L 0.73700138 -1.445 0.75099833 -1.44250059 1 P 0 ;0
L 0.75099833 -1.44250059 0.76299951 -1.43500217 1 P 0 ;0
L 0.76299951 -1.43500217 0.77100138 -1.42500433 1 P 0 ;0
L 0.86700039 -1.445 0.86700039 -1.34500315 1 P 0 ;0
L 0.86700039 -1.36499882 0.87699833 -1.35500098 1 P 0 ;0
L 0.87699833 -1.35500098 0.8869998 -1.34750256 1 P 0 ;0
L 0.8869998 -1.34750256 0.90100049 -1.34500315 1 P 0 ;0
L 0.90100049 -1.34500315 0.91099833 -1.34750256 1 P 0 ;0
L 0.91099833 -1.34750256 0.92299951 -1.35500098 1 P 0 ;0
L 1.02700039 -1.445 1.02700039 -1.34500315 1 P 0 ;0
L 1.02700039 -1.36499882 1.03699833 -1.35500098 1 P 0 ;0
L 1.03699833 -1.35500098 1.0469998 -1.34750256 1 P 0 ;0
L 1.0469998 -1.34750256 1.06100049 -1.34500315 1 P 0 ;0
L 1.06100049 -1.34500315 1.07099833 -1.34750256 1 P 0 ;0
L 1.07099833 -1.34750256 1.08299951 -1.35500098 1 P 0 ;0
L 1.18500089 -1.37750069 1.24900187 -1.37750069 1 P 0 ;0
L 1.24900187 -1.37750069 1.24299951 -1.3599999 1 P 0 ;0
L 1.24299951 -1.3599999 1.23300157 -1.35000207 1 P 0 ;0
L 1.23300157 -1.35000207 1.21900089 -1.34500315 1 P 0 ;0
L 1.21900089 -1.34500315 1.2050003 -1.34750256 1 P 0 ;0
L 1.2050003 -1.34750256 1.19299911 -1.35500098 1 P 0 ;0
L 1.19299911 -1.35500098 1.18500089 -1.37250177 1 P 0 ;0
L 1.18500089 -1.37250177 1.18099803 -1.38750315 1 P 0 ;0
L 1.18099803 -1.38750315 1.18099803 -1.4025 1 P 0 ;0
L 1.18099803 -1.4025 1.18500089 -1.41750138 1 P 0 ;0
L 1.18500089 -1.41750138 1.19499872 -1.43250276 1 P 0 ;0
L 1.19499872 -1.43250276 1.2069998 -1.44250059 1 P 0 ;0
L 1.2069998 -1.44250059 1.22100049 -1.445 1 P 0 ;0
L 1.22100049 -1.445 1.23500118 -1.44000108 1 P 0 ;0
L 1.23500118 -1.44000108 1.24900187 -1.42500433 1 P 0 ;0
L 1.37499813 -1.445 1.37499813 -1.295 1 P 0 ;0
L 1.50500089 -1.37750069 1.56900187 -1.37750069 1 P 0 ;0
L 1.56900187 -1.37750069 1.56299951 -1.3599999 1 P 0 ;0
L 1.56299951 -1.3599999 1.55300157 -1.35000207 1 P 0 ;0
L 1.55300157 -1.35000207 1.53900089 -1.34500315 1 P 0 ;0
L 1.53900089 -1.34500315 1.5250003 -1.34750256 1 P 0 ;0
L 1.5250003 -1.34750256 1.51299911 -1.35500098 1 P 0 ;0
L 1.51299911 -1.35500098 1.50500089 -1.37250177 1 P 0 ;0
L 1.50500089 -1.37250177 1.50099803 -1.38750315 1 P 0 ;0
L 1.50099803 -1.38750315 1.50099803 -1.4025 1 P 0 ;0
L 1.50099803 -1.4025 1.50500089 -1.41750138 1 P 0 ;0
L 1.50500089 -1.41750138 1.51499872 -1.43250276 1 P 0 ;0
L 1.51499872 -1.43250276 1.5269998 -1.44250059 1 P 0 ;0
L 1.5269998 -1.44250059 1.54100049 -1.445 1 P 0 ;0
L 1.54100049 -1.445 1.55500118 -1.44000108 1 P 0 ;0
L 1.55500118 -1.44000108 1.56900187 -1.42500433 1 P 0 ;0
L 1.6529998 -1.48999951 1.66500089 -1.49499843 1 P 0 ;0
L 1.66500089 -1.49499843 1.68100108 -1.48999951 1 P 0 ;0
L 1.68100108 -1.48999951 1.69099902 -1.48000167 1 P 0 ;0
L 1.69099902 -1.48000167 1.69900089 -1.4674997 1 P 0 ;0
L 1.69900089 -1.4674997 1.71099833 -1.42750374 1 P 0 ;0
L 1.71099833 -1.42750374 1.7370001 -1.34500315 1 P 0 ;0
L 1.67299911 -1.34500315 1.71099833 -1.42750374 1 P 0 ;0
L 1.82500089 -1.37750069 1.88900187 -1.37750069 1 P 0 ;0
L 1.88900187 -1.37750069 1.88299951 -1.3599999 1 P 0 ;0
L 1.88299951 -1.3599999 1.87300157 -1.35000207 1 P 0 ;0
L 1.87300157 -1.35000207 1.85900089 -1.34500315 1 P 0 ;0
L 1.85900089 -1.34500315 1.8450003 -1.34750256 1 P 0 ;0
L 1.8450003 -1.34750256 1.83299911 -1.35500098 1 P 0 ;0
L 1.83299911 -1.35500098 1.82500089 -1.37250177 1 P 0 ;0
L 1.82500089 -1.37250177 1.82099803 -1.38750315 1 P 0 ;0
L 1.82099803 -1.38750315 1.82099803 -1.4025 1 P 0 ;0
L 1.82099803 -1.4025 1.82500089 -1.41750138 1 P 0 ;0
L 1.82500089 -1.41750138 1.83499872 -1.43250276 1 P 0 ;0
L 1.83499872 -1.43250276 1.8469998 -1.44250059 1 P 0 ;0
L 1.8469998 -1.44250059 1.86100049 -1.445 1 P 0 ;0
L 1.86100049 -1.445 1.87500118 -1.44000108 1 P 0 ;0
L 1.87500118 -1.44000108 1.88900187 -1.42500433 1 P 0 ;0
L 2.18699921 -1.37000236 2.22700167 -1.37000236 1 P 0 ;0
L 2.22700167 -1.37000236 2.22700167 -1.41500187 1 P 0 ;0
L 2.22700167 -1.41500187 2.21500059 -1.43000325 1 P 0 ;0
L 2.21500059 -1.43000325 2.2009999 -1.44000108 1 P 0 ;0
L 2.2009999 -1.44000108 2.18100049 -1.445 1 P 0 ;0
L 2.18100049 -1.445 2.16100108 -1.44000108 1 P 0 ;0
L 2.16100108 -1.44000108 2.14700039 -1.43000325 1 P 0 ;0
L 2.14700039 -1.43000325 2.13499931 -1.41500187 1 P 0 ;0
L 2.13499931 -1.41500187 2.12699734 -1.39750108 1 P 0 ;0
L 2.12699734 -1.39750108 2.12299823 -1.37750069 1 P 0 ;0
L 2.12299823 -1.37750069 2.12299823 -1.3599999 1 P 0 ;0
L 2.12299823 -1.3599999 2.12699734 -1.34500315 1 P 0 ;0
L 2.12699734 -1.34500315 2.13499931 -1.32749764 1 P 0 ;0
L 2.13499931 -1.32749764 2.14700039 -1.31250089 1 P 0 ;0
L 2.14700039 -1.31250089 2.15899783 -1.30250305 1 P 0 ;0
L 2.15899783 -1.30250305 2.17499813 -1.295 1 P 0 ;0
L 2.17499813 -1.295 2.18899882 -1.295 1 P 0 ;0
L 2.18899882 -1.295 2.20499902 -1.29999902 1 P 0 ;0
L 2.20499902 -1.29999902 2.2170001 -1.31000138 1 P 0 ;0
L 2.29699892 -1.31999931 2.309 -1.30500246 1 P 0 ;0
L 2.309 -1.30500246 2.32300069 -1.29749951 1 P 0 ;0
L 2.32300069 -1.29749951 2.33900089 -1.295 1 P 0 ;0
L 2.33900089 -1.295 2.3590003 -1.29999902 1 P 0 ;0
L 2.3590003 -1.29999902 2.37300098 -1.31250089 1 P 0 ;0
L 2.37300098 -1.31250089 2.3770001 -1.32749764 1 P 0 ;0
L 2.3770001 -1.32749764 2.37500059 -1.34250364 1 P 0 ;0
L 2.37500059 -1.34250364 2.36699862 -1.35500098 1 P 0 ;0
L 2.36699862 -1.35500098 2.3269998 -1.3800002 1 P 0 ;0
L 2.3269998 -1.3800002 2.309 -1.39750108 1 P 0 ;0
L 2.309 -1.39750108 2.29699892 -1.42250482 1 P 0 ;0
L 2.29699892 -1.42250482 2.2929998 -1.445 1 P 0 ;0
L 2.2929998 -1.445 2.3770001 -1.445 1 P 0 ;0
L 2.6129998 -1.42500433 2.629 -1.43750167 1 P 0 ;0
L 2.629 -1.43750167 2.6469998 -1.445 1 P 0 ;0
L 2.6469998 -1.445 2.6630001 -1.445 1 P 0 ;0
L 2.6630001 -1.445 2.6790003 -1.43750167 1 P 0 ;0
L 2.6790003 -1.43750167 2.69100138 -1.42500433 1 P 0 ;0
L 2.69100138 -1.42500433 2.6970001 -1.40749892 1 P 0 ;0
L 2.6970001 -1.40749892 2.69300098 -1.39000266 1 P 0 ;0
L 2.69300098 -1.39000266 2.68299951 -1.37500128 1 P 0 ;0
L 2.68299951 -1.37500128 2.66499961 -1.36499882 1 P 0 ;0
L 2.66499961 -1.36499882 2.64100108 -1.3599999 1 P 0 ;0
L 2.64100108 -1.3599999 2.62700039 -1.35000207 1 P 0 ;0
L 2.62700039 -1.35000207 2.62099803 -1.33250118 1 P 0 ;0
L 2.62099803 -1.33250118 2.62500089 -1.31500039 1 P 0 ;0
L 2.62500089 -1.31500039 2.63499872 -1.30250305 1 P 0 ;0
L 2.63499872 -1.30250305 2.64899941 -1.295 1 P 0 ;0
L 2.64899941 -1.295 2.6630001 -1.295 1 P 0 ;0
L 2.6630001 -1.295 2.67700079 -1.29999902 1 P 0 ;0
L 2.67700079 -1.29999902 2.68900187 -1.31250089 1 P 0 ;0
L 2.7729998 -1.445 2.8570001 -1.295 1 P 0 ;0
L 2.7729998 -1.295 2.8570001 -1.445 1 P 0 ;0
L 2.92299823 -1.445 2.92299823 -1.295 1 P 0 ;0
L 2.92299823 -1.295 2.97499813 -1.42000079 1 P 0 ;0
L 2.97499813 -1.42000079 3.02700167 -1.295 1 P 0 ;0
L 3.02700167 -1.295 3.02700167 -1.445 1 P 0 ;0
L 3.09699892 -1.31999931 3.109 -1.30500246 1 P 0 ;0
L 3.109 -1.30500246 3.12300069 -1.29749951 1 P 0 ;0
L 3.12300069 -1.29749951 3.13900089 -1.295 1 P 0 ;0
L 3.13900089 -1.295 3.1590003 -1.29999902 1 P 0 ;0
L 3.1590003 -1.29999902 3.17300098 -1.31250089 1 P 0 ;0
L 3.17300098 -1.31250089 3.1770001 -1.32749764 1 P 0 ;0
L 3.1770001 -1.32749764 3.17500059 -1.34250364 1 P 0 ;0
L 3.17500059 -1.34250364 3.16699862 -1.35500098 1 P 0 ;0
L 3.16699862 -1.35500098 3.1269998 -1.3800002 1 P 0 ;0
L 3.1269998 -1.3800002 3.109 -1.39750108 1 P 0 ;0
L 3.109 -1.39750108 3.09699892 -1.42250482 1 P 0 ;0
L 3.09699892 -1.42250482 3.0929998 -1.445 1 P 0 ;0
L 3.0929998 -1.445 3.1770001 -1.445 1 P 0 ;0
L 3.269 -1.39500157 3.3209999 -1.39500157 1 P 0 ;0
L 3.41499931 -1.445 3.41499931 -1.295 1 P 0 ;0
L 3.41499931 -1.295 3.46499961 -1.295 1 P 0 ;0
L 3.46499961 -1.295 3.4809999 -1.30250305 1 P 0 ;0
L 3.4809999 -1.30250305 3.49100138 -1.31250089 1 P 0 ;0
L 3.49100138 -1.31250089 3.49500059 -1.33250118 1 P 0 ;0
L 3.49500059 -1.33250118 3.49100138 -1.35250148 1 P 0 ;0
L 3.49100138 -1.35250148 3.4790003 -1.36499882 1 P 0 ;0
L 3.4790003 -1.36499882 3.46499961 -1.37250177 1 P 0 ;0
L 3.46499961 -1.37250177 3.41499931 -1.37250177 1 P 0 ;0
L 3.46499961 -1.37250177 3.49500059 -1.445 1 P 0 ;0
L 3.61499813 -1.34500315 3.61499813 -1.445 1 P 0 ;0
L 3.61499813 -1.30500246 3.61099902 -1.30250305 1 P 8191 ;0
L 3.61099902 -1.30250305 3.61099902 -1.29749951 1 P 8191 ;0
L 3.61099902 -1.29749951 3.61499813 -1.295 1 P 8191 ;0
L 3.61499813 -1.295 3.61900089 -1.29749951 1 P 8191 ;0
L 3.61900089 -1.29749951 3.61900089 -1.30250305 1 P 8191 ;0
L 3.61900089 -1.30250305 3.61499813 -1.30500246 1 P 8191 ;0
L 3.74500089 -1.42750374 3.75499872 -1.43750167 1 P 0 ;0
L 3.75499872 -1.43750167 3.76899941 -1.445 1 P 0 ;0
L 3.76899941 -1.445 3.78100049 -1.445 1 P 0 ;0
L 3.78100049 -1.445 3.79300157 -1.44000108 1 P 0 ;0
L 3.79300157 -1.44000108 3.8009999 -1.43250276 1 P 0 ;0
L 3.8009999 -1.43250276 3.80499902 -1.42250482 1 P 0 ;0
L 3.80499902 -1.42250482 3.80299951 -1.40749892 1 P 0 ;0
L 3.80299951 -1.40749892 3.79500118 -1.40000049 1 P 0 ;0
L 3.79500118 -1.40000049 3.75899783 -1.38500374 1 P 0 ;0
L 3.75899783 -1.38500374 3.75099961 -1.36749833 1 P 0 ;0
L 3.75099961 -1.36749833 3.75499872 -1.35500098 1 P 0 ;0
L 3.75499872 -1.35500098 3.76300069 -1.34750256 1 P 0 ;0
L 3.76300069 -1.34750256 3.77499813 -1.34500315 1 P 0 ;0
L 3.77499813 -1.34500315 3.78699921 -1.34750256 1 P 0 ;0
L 3.78699921 -1.34750256 3.7990003 -1.35500098 1 P 0 ;0
L 3.90500089 -1.37750069 3.96900187 -1.37750069 1 P 0 ;0
L 3.96900187 -1.37750069 3.96299951 -1.3599999 1 P 0 ;0
L 3.96299951 -1.3599999 3.95300157 -1.35000207 1 P 0 ;0
L 3.95300157 -1.35000207 3.93900089 -1.34500315 1 P 0 ;0
L 3.93900089 -1.34500315 3.9250003 -1.34750256 1 P 0 ;0
L 3.9250003 -1.34750256 3.91299911 -1.35500098 1 P 0 ;0
L 3.91299911 -1.35500098 3.90500089 -1.37250177 1 P 0 ;0
L 3.90500089 -1.37250177 3.90099803 -1.38750315 1 P 0 ;0
L 3.90099803 -1.38750315 3.90099803 -1.4025 1 P 0 ;0
L 3.90099803 -1.4025 3.90500089 -1.41750138 1 P 0 ;0
L 3.90500089 -1.41750138 3.91499872 -1.43250276 1 P 0 ;0
L 3.91499872 -1.43250276 3.9269998 -1.44250059 1 P 0 ;0
L 3.9269998 -1.44250059 3.94100049 -1.445 1 P 0 ;0
L 3.94100049 -1.445 3.95500118 -1.44000108 1 P 0 ;0
L 3.95500118 -1.44000108 3.96900187 -1.42500433 1 P 0 ;0
L 4.06700039 -1.445 4.06700039 -1.34500315 1 P 0 ;0
L 4.06700039 -1.36499882 4.07699833 -1.35500098 1 P 0 ;0
L 4.07699833 -1.35500098 4.0869998 -1.34750256 1 P 0 ;0
L 4.0869998 -1.34750256 4.10100049 -1.34500315 1 P 0 ;0
L 4.10100049 -1.34500315 4.11099833 -1.34750256 1 P 0 ;0
L 4.11099833 -1.34750256 4.12299951 -1.35500098 1 P 0 ;0
L 4.16964783 -2.2038 4.21839813 -2.0478 1 P 0 ;0
L 4.21839813 -2.0478 4.26715207 -2.2038 1 P 0 ;0
L 4.24959862 -2.14920217 4.18719774 -2.14920217 1 P 0 ;0
L 4.37939813 -2.2038 4.37939813 -2.0478 1 P 0 ;0
L 4.37939813 -2.0478 4.35599961 -2.07899813 1 P 0 ;0
L 4.35599961 -2.2038 4.40279675 -2.2038 1 P 0 ;0
L 2.0009002 -0.9538 2.0009002 -0.8038 1 P 0 ;0
L 2.0009002 -0.8038 2.04089902 -0.8038 1 P 0 ;0
L 2.04089902 -0.8038 2.05689921 -0.81130305 1 P 0 ;0
L 2.05689921 -0.81130305 2.0689003 -0.82130089 1 P 0 ;0
L 2.0689003 -0.82130089 2.07890187 -0.83629764 1 P 0 ;0
L 2.07890187 -0.83629764 2.0869001 -0.85380315 1 P 0 ;0
L 2.0869001 -0.85380315 2.0888997 -0.87880236 1 P 0 ;0
L 2.0888997 -0.87880236 2.0869001 -0.90380157 1 P 0 ;0
L 2.0869001 -0.90380157 2.07890187 -0.92130246 1 P 0 ;0
L 2.07890187 -0.92130246 2.0689003 -0.93630374 1 P 0 ;0
L 2.0689003 -0.93630374 2.05689921 -0.94630167 1 P 0 ;0
L 2.05689921 -0.94630167 2.04089902 -0.9538 1 P 0 ;0
L 2.04089902 -0.9538 2.0009002 -0.9538 1 P 0 ;0
L 2.15489783 -0.9538 2.20489813 -0.8038 1 P 0 ;0
L 2.20489813 -0.8038 2.25490207 -0.9538 1 P 0 ;0
L 2.23689862 -0.90130207 2.17289764 -0.90130207 1 P 0 ;0
L 2.36489813 -0.8038 2.36489813 -0.9538 1 P 0 ;0
L 2.31890059 -0.8038 2.41089931 -0.8038 1 P 0 ;0
L 2.56490059 -0.9538 2.48489931 -0.9538 1 P 0 ;0
L 2.48489931 -0.9538 2.48489931 -0.8038 1 P 0 ;0
L 2.48489931 -0.8038 2.56490059 -0.8038 1 P 0 ;0
L 2.5329001 -0.87629833 2.48489931 -0.87629833 1 P 0 ;0
L 2.84489813 -0.9538 2.82889783 -0.95130059 1 P 0 ;0
L 2.82889783 -0.95130059 2.81490089 -0.94130276 1 P 0 ;0
L 2.81490089 -0.94130276 2.8028998 -0.92630138 1 P 0 ;0
L 2.8028998 -0.92630138 2.79489783 -0.90880049 1 P 0 ;0
L 2.79489783 -0.90880049 2.79089862 -0.8888002 1 P 0 ;0
L 2.79089862 -0.8888002 2.79089862 -0.8687999 1 P 0 ;0
L 2.79089862 -0.8687999 2.79489783 -0.84879961 1 P 0 ;0
L 2.79489783 -0.84879961 2.8028998 -0.83129872 1 P 0 ;0
L 2.8028998 -0.83129872 2.81490089 -0.81630197 1 P 0 ;0
L 2.81490089 -0.81630197 2.82889783 -0.80629951 1 P 0 ;0
L 2.82889783 -0.80629951 2.84489813 -0.8038 1 P 0 ;0
L 2.84489813 -0.8038 2.86089833 -0.80629951 1 P 0 ;0
L 2.86089833 -0.80629951 2.87489902 -0.81630197 1 P 0 ;0
L 2.87489902 -0.81630197 2.8869001 -0.83129872 1 P 0 ;0
L 2.8869001 -0.83129872 2.89490207 -0.84879961 1 P 0 ;0
L 2.89490207 -0.84879961 2.89890128 -0.8687999 1 P 0 ;0
L 2.89890128 -0.8687999 2.89890128 -0.8888002 1 P 0 ;0
L 2.89890128 -0.8888002 2.89490207 -0.90880049 1 P 0 ;0
L 2.89490207 -0.90880049 2.8869001 -0.92630138 1 P 0 ;0
L 2.8869001 -0.92630138 2.87489902 -0.94130276 1 P 0 ;0
L 2.87489902 -0.94130276 2.86089833 -0.95130059 1 P 0 ;0
L 2.86089833 -0.95130059 2.84489813 -0.9538 1 P 0 ;0
L 3.0488997 -0.81630197 3.03689862 -0.80879902 1 P 0 ;0
L 3.03689862 -0.80879902 3.02290157 -0.8038 1 P 0 ;0
L 3.02290157 -0.8038 3.00690138 -0.8038 1 P 0 ;0
L 3.00690138 -0.8038 2.98889783 -0.81130305 1 P 0 ;0
L 2.98889783 -0.81130305 2.97490089 -0.82380039 1 P 0 ;0
L 2.97490089 -0.82380039 2.96489931 -0.83880177 1 P 0 ;0
L 2.96489931 -0.83880177 2.95689734 -0.86380098 1 P 0 ;0
L 2.95689734 -0.86380098 2.95489783 -0.88630069 1 P 0 ;0
L 2.95489783 -0.88630069 2.95890059 -0.90880049 1 P 0 ;0
L 2.95890059 -0.90880049 2.96489931 -0.92380187 1 P 0 ;0
L 2.96489931 -0.92380187 2.97690039 -0.93880325 1 P 0 ;0
L 2.97690039 -0.93880325 2.99090108 -0.94880108 1 P 0 ;0
L 2.99090108 -0.94880108 3.00489813 -0.9538 1 P 0 ;0
L 3.00489813 -0.9538 3.01889882 -0.9538 1 P 0 ;0
L 3.01889882 -0.9538 3.03289951 -0.94880108 1 P 0 ;0
L 3.03289951 -0.94880108 3.04490059 -0.94130276 1 P 0 ;0
L 3.04490059 -0.94130276 3.05490207 -0.93130482 1 P 0 ;0
L 3.16489813 -0.8038 3.16489813 -0.9538 1 P 0 ;0
L 3.11890059 -0.8038 3.21089931 -0.8038 1 P 0 ;0
L 3.28889852 -0.95879892 3.36090138 -0.8038 1 P 0 ;0
L 3.44689892 -0.82879931 3.4589 -0.81380246 1 P 0 ;0
L 3.4589 -0.81380246 3.47290069 -0.80629951 1 P 0 ;0
L 3.47290069 -0.80629951 3.48890089 -0.8038 1 P 0 ;0
L 3.48890089 -0.8038 3.5089003 -0.80879902 1 P 0 ;0
L 3.5089003 -0.80879902 3.52290098 -0.82130089 1 P 0 ;0
L 3.52290098 -0.82130089 3.5269001 -0.83629764 1 P 0 ;0
L 3.5269001 -0.83629764 3.52490059 -0.85130364 1 P 0 ;0
L 3.52490059 -0.85130364 3.51689862 -0.86380098 1 P 0 ;0
L 3.51689862 -0.86380098 3.4768998 -0.8888002 1 P 0 ;0
L 3.4768998 -0.8888002 3.4589 -0.90630108 1 P 0 ;0
L 3.4589 -0.90630108 3.44689892 -0.93130482 1 P 0 ;0
L 3.44689892 -0.93130482 3.4428998 -0.9538 1 P 0 ;0
L 3.4428998 -0.9538 3.5269001 -0.9538 1 P 0 ;0
L 3.64089902 -0.9538 3.64489813 -0.92130246 1 P 0 ;0
L 3.64489813 -0.92130246 3.65090049 -0.89380374 1 P 0 ;0
L 3.65090049 -0.89380374 3.65889882 -0.8687999 1 P 0 ;0
L 3.65889882 -0.8687999 3.6689003 -0.84130118 1 P 0 ;0
L 3.6689003 -0.84130118 3.68490059 -0.8038 1 P 0 ;0
L 3.68490059 -0.8038 3.60489931 -0.8038 1 P 0 ;0
L 3.76889852 -0.95879892 3.84090138 -0.8038 1 P 0 ;0
L 3.92689892 -0.82879931 3.9389 -0.81380246 1 P 0 ;0
L 3.9389 -0.81380246 3.95290069 -0.80629951 1 P 0 ;0
L 3.95290069 -0.80629951 3.96890089 -0.8038 1 P 0 ;0
L 3.96890089 -0.8038 3.9889003 -0.80879902 1 P 0 ;0
L 3.9889003 -0.80879902 4.00290098 -0.82130089 1 P 0 ;0
L 4.00290098 -0.82130089 4.0069001 -0.83629764 1 P 0 ;0
L 4.0069001 -0.83629764 4.00490059 -0.85130364 1 P 0 ;0
L 4.00490059 -0.85130364 3.99689862 -0.86380098 1 P 0 ;0
L 3.99689862 -0.86380098 3.9568998 -0.8888002 1 P 0 ;0
L 3.9568998 -0.8888002 3.9389 -0.90630108 1 P 0 ;0
L 3.9389 -0.90630108 3.92689892 -0.93130482 1 P 0 ;0
L 3.92689892 -0.93130482 3.9228998 -0.9538 1 P 0 ;0
L 3.9228998 -0.9538 4.0069001 -0.9538 1 P 0 ;0
L 4.12489813 -0.8038 4.10889783 -0.80879902 1 P 0 ;0
L 4.10889783 -0.80879902 4.09690039 -0.82130089 1 P 0 ;0
L 4.09690039 -0.82130089 4.08889852 -0.83629764 1 P 0 ;0
L 4.08889852 -0.83629764 4.0828998 -0.85630256 1 P 0 ;0
L 4.0828998 -0.85630256 4.0809002 -0.87880236 1 P 0 ;0
L 4.0809002 -0.87880236 4.0828998 -0.90130207 1 P 0 ;0
L 4.0828998 -0.90130207 4.08889852 -0.92130246 1 P 0 ;0
L 4.08889852 -0.92130246 4.09690039 -0.93630374 1 P 0 ;0
L 4.09690039 -0.93630374 4.10889783 -0.94880108 1 P 0 ;0
L 4.10889783 -0.94880108 4.12489813 -0.9538 1 P 0 ;0
L 4.12489813 -0.9538 4.14089833 -0.94880108 1 P 0 ;0
L 4.14089833 -0.94880108 4.15289951 -0.93630374 1 P 0 ;0
L 4.15289951 -0.93630374 4.16090138 -0.92130246 1 P 0 ;0
L 4.16090138 -0.92130246 4.1669001 -0.90130207 1 P 0 ;0
L 4.1669001 -0.90130207 4.1688997 -0.87880236 1 P 0 ;0
L 4.1688997 -0.87880236 4.1669001 -0.85630256 1 P 0 ;0
L 4.1669001 -0.85630256 4.16090138 -0.83629764 1 P 0 ;0
L 4.16090138 -0.83629764 4.15289951 -0.82130089 1 P 0 ;0
L 4.15289951 -0.82130089 4.14089833 -0.80879902 1 P 0 ;0
L 4.14089833 -0.80879902 4.12489813 -0.8038 1 P 0 ;0
L 4.28489813 -0.9538 4.28489813 -0.8038 1 P 0 ;0
L 4.28489813 -0.8038 4.26089961 -0.83379823 1 P 0 ;0
L 4.26089961 -0.9538 4.30889665 -0.9538 1 P 0 ;0
L 4.44089902 -0.9538 4.44489813 -0.92130246 1 P 0 ;0
L 4.44489813 -0.92130246 4.45090049 -0.89380374 1 P 0 ;0
L 4.45090049 -0.89380374 4.45889882 -0.8687999 1 P 0 ;0
L 4.45889882 -0.8687999 4.4689003 -0.84130118 1 P 0 ;0
L 4.4689003 -0.84130118 4.48490059 -0.8038 1 P 0 ;0
L 4.48490059 -0.8038 4.40489931 -0.8038 1 P 0 ;0

### steps/drc/layers/l7/features
#
#Feature symbol names
#
$0 r2
$1 r6
$2 r15
$3 r20
$4 r28
$5 r30
$6 r32
$7 r33
$8 r40
$9 r50
$10 r57.09
$11 r59.45
$12 r78.74
$13 r86.61
$14 r90.55
$15 r100
$16 r131.89
$17 r137.8
$18 r150
$19 r161.42
$20 r168.31
$21 r173.23
$22 r181.1
$23 r204.72
$24 r224.41
$25 r393.7
$26 r433.07
$27 r440.94
$28 null
$29 oval236.22x177.17
$30 thr61.02x49.21x45x4x15.75

#
#Feature attribute names
#
@0 .nomenclature
@1 .geometry

#
#Feature attribute text strings
#
&0 TPB30V20D10AT28BPM
&1 C1_11P0_7
&2 C1_11P0_7TP
&3 V17D8AT30SM11
&4 V20D10AT28SM14
&5 C2_5N
&6 S1_11P0_7TP
&7 S1_11P0_7
&8 V20D10AT28PG
&9 C1_17P0_76TPM
&10 C1_9P1_4
&11 S1_9P1_4
&12 SP-8C5_2P0_254
&13 SP-9C5_7P0_254
&14 C3_175N-A
&15 C10N
&16 C3_3N
&17 C4_5N-B
&18 C4N-B
&19 C3_5N
&20 O5X3_5N
&21 C3N
&22 C1_3N
&23 C2_35N
&24 C1N

#
#Layer features
#
P 7.785 4.45 4 P 0 0;1=0
P 7.835 4.45 4 P 0 0;1=0
P 1.8 4.485 4 P 0 0;1=0
P 1.86 4.485 4 P 0 0;1=0
P 0.27165 1.72835 10 P 0 0;1=1
P 0.17323002 2.12205 10 P 0 0;1=1
P 12.73621004 1.76771998 10 P 0 0;1=1
P 12.81495 2.59448996 10 P 0 0;1=1
P 12.63778996 2.16141998 10 P 0 0;1=1
P 0.725 -0.25 10 P 0 0;1=2
P 0.875 -0.25 10 P 0 0;1=2
P 1.065 6.26 10 P 0 0;1=2
P 1.065 6.36 10 P 0 0;1=2
P 1.29 6.26 10 P 0 0;1=2
P 1.29 6.36 10 P 0 0;1=2
P 1.515 6.26 10 P 0 0;1=2
P 1.515 6.36 10 P 0 0;1=2
P 0.84 6.26 10 P 0 0;1=2
P 0.84 6.36 10 P 0 0;1=2
P 1.74 6.26 10 P 0 0;1=2
P 1.74 6.36 10 P 0 0;1=2
P 2.09606004 3.56615 5 P 0 0;1=3
P 8.1 3.56615 5 P 0 0;1=3
P 12.55905 3.38188996 10 P 0 0;1=1
P 12.81495 4.64173996 10 P 0 0;1=1
P 12.81495 1.88583002 10 P 0 0;1=1
P 0.35038996 4.60236998 10 P 0 0;1=1
P 0.35038996 2.55511998 10 P 0 0;1=1
P 0.35038996 1.84646004 10 P 0 0;1=1
P 0.09448996 3.34251998 10 P 0 0;1=1
P 6.385 5.03 4 P 0 0;1=4
P 12.68701998 0.97243996 17 P 0 0;1=5
P 0.22245 0.93306998 17 P 0 0;1=5
P 12.68701004 4.91338002 17 P 0 0;1=5
P 3.94 4.545 4 P 0 0;1=0
P 4.91 5.375 4 P 0 0;1=4
P 1.08 5.85 4 P 0 0;1=0
P 3.6817 5.74 4 P 0 0;1=4
P 10.07 2.928 4 P 0 0;1=4
P 4.105 4.985 4 P 0 0;1=0
P 4.125 2.725 4 P 0 0;1=4
P 4.02 4.355 4 P 0 0;1=0
P 1.16 5.85 4 P 0 0;1=0
P 3.815 5.815 4 P 0 0;1=4
P 1.19 6.36 30 P 0 3;1=6
P 1.19 6.26 30 P 0 3;1=6
P 1.415 6.36 30 P 0 3;1=6
P 1.415 6.26 30 P 0 3;1=6
P 1.64 6.36 30 P 0 3;1=6
P 1.64 6.26 30 P 0 3;1=6
P 0.965 6.26 30 P 0 3;1=6
P 0.965 6.36 30 P 0 3;1=6
P 0.74 6.26 30 P 0 3;1=6
P 0.74 6.36 30 P 0 3;1=6
P 12.63778996 1.37401998 10 P 0 0;1=7
P 0.17323002 1.33465 10 P 0 0;1=7
P 6.501 5.017 4 P 0 0;1=0
P 7.425 3.43 4 P 0 0;1=0
P 7.445 1.705 4 P 0 0;1=4
P 11.03661004 3.81615 5 P 0 0;1=3
P 11.135 2.845 4 P 0 0;1=4
P 11.03661004 2.16615 5 P 0 0;1=3
P 3.8899 4.765 4 P 0 0;1=0
P 4.93268002 2.41615 5 P 0 0;1=3
P 4.93268002 2.46615 5 P 0 0;1=3
P 7.2926 5.04351004 4 P 0 0;1=0
P 7.2426 5.04351004 4 P 0 0;1=0
P 3.45646004 5.3 4 P 0 0;1=0
P 1.28906004 5.04351004 4 P 0 0;1=0
P 1.23906004 5.04351004 4 P 0 0;1=0
P 9.46 5.3 4 P 0 0;1=0
P 4.68268002 2.36615 5 P 0 0;1=3
P 0.27165 4.01181004 10 P 0 0;1=1
P 4.58268002 2.36615 5 P 0 0;1=3
P 0.27165 4.16928996 10 P 0 0;1=1
P 4.63268002 2.41615 5 P 0 0;1=3
P 0.27165 4.32676998 10 P 0 0;1=1
P 4.73268002 2.26615 5 P 0 0;1=3
P 0.27165 3.38188996 10 P 0 0;1=1
P 4.73268002 2.41615 5 P 0 0;1=3
P 0.27165 4.48425 10 P 0 0;1=1
P 4.68268002 2.21615 5 P 0 0;1=3
P 0.27165 3.53936998 10 P 0 0;1=1
P 4.63268002 2.26615 5 P 0 0;1=3
P 0.27165 3.85433002 10 P 0 0;1=1
P 4.58268002 2.06615 5 P 0 0;1=3
P 0.35038996 3.02756004 10 P 0 0;1=1
P 4.58268002 2.11615 5 P 0 0;1=3
P 0.27165 2.98818996 10 P 0 0;1=1
P 4.63268002 1.86615 5 P 0 0;1=3
P 0.35038996 2.3189 10 P 0 0;1=1
P 4.58268002 1.96615 5 P 0 0;1=3
P 0.27165 2.43701004 10 P 0 0;1=1
P 4.68268002 2.06615 5 P 0 0;1=3
P 0.35038996 3.18503996 10 P 0 0;1=1
P 4.58268002 1.91615 5 P 0 0;1=3
P 0.35038996 2.47638002 10 P 0 0;1=1
P 0.27165 2.27953002 10 P 0 0;1=1
P 4.63268002 1.91615 5 P 0 0;1=3
P 5.42048002 1.7396 5 P 0 0;1=3
P 0.09448996 2.55511998 10 P 0 0;1=1
P 4.68268002 2.11615 5 P 0 0;1=3
P 0.27165 3.14566998 10 P 0 0;1=1
P 5.42048002 1.7796 5 P 0 0;1=3
P 0.17323002 2.51575 10 P 0 0;1=1
P 4.68268002 1.91615 5 P 0 0;1=3
P 0.35038996 2.16141998 10 P 0 0;1=1
P 4.68268002 1.96615 5 P 0 0;1=3
P 0.27165 2.12205 10 P 0 0;1=1
P 5.57531004 2.0878 5 P 0 0;1=3
P 0.09448996 3.1063 10 P 0 0;1=1
P 5.57531004 2.1278 5 P 0 0;1=3
P 0.17323002 3.06693002 10 P 0 0;1=1
P 5.57531004 2.2232 5 P 0 0;1=3
P 0.17323002 3.46063002 10 P 0 0;1=1
P 5.57531004 2.2632 5 P 0 0;1=3
P 0.09448996 3.42126004 10 P 0 0;1=1
P 5.42048002 2.4662 5 P 0 0;1=3
P 0.09448996 4.05118002 10 P 0 0;1=1
P 5.57531004 2.3986 5 P 0 0;1=3
P 0.09448996 3.8937 10 P 0 0;1=1
P 5.57531004 2.673 5 P 0 0;1=3
P 0.09448996 4.36613996 10 P 0 0;1=1
P 5.57531004 1.9869 5 P 0 0;1=3
P 0.17323002 2.75196998 10 P 0 0;1=1
P 5.57531004 2.4978 5 P 0 0;1=3
P 0.17323002 4.24803002 10 P 0 0;1=1
P 5.57531004 1.6718 5 P 0 0;1=3
P 0.17323002 2.20078996 10 P 0 0;1=1
P 5.57531004 2.633 5 P 0 0;1=3
P 0.17323002 4.40551004 10 P 0 0;1=1
P 5.57531004 1.7118 5 P 0 0;1=3
P 0.09448996 2.24016004 10 P 0 0;1=1
P 5.57531004 2.5378 5 P 0 0;1=3
P 0.09448996 4.20866004 10 P 0 0;1=1
P 5.42048002 1.6433 5 P 0 0;1=3
P 0.09448996 2.39763996 10 P 0 0;1=1
P 5.42048002 2.6054 5 P 0 0;1=3
P 0.09448996 4.52361998 10 P 0 0;1=1
P 5.42048002 1.87835 5 P 0 0;1=3
P 0.09448996 2.94881998 10 P 0 0;1=1
P 5.57531004 2.3586 5 P 0 0;1=3
P 0.17323002 3.93306998 10 P 0 0;1=1
P 5.42048002 1.6033 5 P 0 0;1=3
P 0.17323002 2.35826998 10 P 0 0;1=1
P 5.42048002 2.4262 5 P 0 0;1=3
P 0.17323002 4.09055 10 P 0 0;1=1
P 5.42048002 1.91835 5 P 0 0;1=3
P 0.17323002 2.90945 10 P 0 0;1=1
P 5.42048002 2.0547 5 P 0 0;1=3
P 0.17323002 3.22441004 10 P 0 0;1=1
P 5.57531004 1.9469 5 P 0 0;1=3
P 0.09448996 2.79133996 10 P 0 0;1=1
P 5.42048002 2.0147 5 P 0 0;1=3
P 0.09448996 3.26378002 10 P 0 0;1=1
P 5.57531004 1.8508 5 P 0 0;1=3
P 0.09448996 2.00393996 10 P 0 0;1=1
P 5.57531004 1.8108 5 P 0 0;1=3
P 0.17323002 2.04331004 10 P 0 0;1=1
P 0.35038996 3.97243996 10 P 0 0;1=1
P 4.68268002 2.41615 5 P 0 0;1=3
P 4.73268002 2.46615 5 P 0 0;1=3
P 0.35038996 4.44488002 10 P 0 0;1=1
P 4.63268002 2.46615 5 P 0 0;1=3
P 0.35038996 4.2874 10 P 0 0;1=1
P 0.35038996 4.12991998 10 P 0 0;1=1
P 4.58268002 2.41615 5 P 0 0;1=3
P 4.68268002 2.26615 5 P 0 0;1=3
P 0.35038996 3.5 10 P 0 0;1=1
P 5.42048002 2.1554 5 P 0 0;1=3
P 0.17323002 3.77558996 10 P 0 0;1=1
P 4.73268002 2.31615 5 P 0 0;1=3
P 0.35038996 3.34251998 10 P 0 0;1=1
P 4.63268002 2.31615 5 P 0 0;1=3
P 0.35038996 3.81496004 10 P 0 0;1=1
P 4.58268002 2.26615 5 P 0 0;1=3
P 0.35038996 3.65748002 10 P 0 0;1=1
P 5.42048002 2.5654 5 P 0 0;1=3
P 0.17323002 4.563 10 P 0 0;1=1
P 5.42048002 2.1954 5 P 0 0;1=3
P 0.09448996 3.73621998 10 P 0 0;1=1
P 0.09448996 3.57873996 10 P 0 0;1=1
P 5.42048002 2.3308 5 P 0 0;1=3
P 0.17323002 3.61811004 10 P 0 0;1=1
P 5.42048002 2.2908 5 P 0 0;1=3
P 0.35038996 1.9252 10 P 0 0;1=1
P 4.73268002 1.91615 5 P 0 0;1=3
P 4.73268002 1.86615 5 P 0 0;1=3
P 0.27165 1.96456998 10 P 0 0;1=1
P 4.58268002 2.21615 5 P 0 0;1=3
P 0.27165 3.69685 10 P 0 0;1=1
P 4.73268002 2.06615 5 P 0 0;1=3
P 0.27165 2.67323002 10 P 0 0;1=1
P 4.73268002 2.01615 5 P 0 0;1=3
P 0.35038996 2.7126 10 P 0 0;1=1
P 4.63268002 2.01615 5 P 0 0;1=3
P 0.35038996 2.87008002 10 P 0 0;1=1
P 4.63268002 2.06615 5 P 0 0;1=3
P 0.27165 2.83071004 10 P 0 0;1=1
P 6.785 4.725 4 P 0 0;1=4
P 6.785 4.685 4 P 0 0;1=4
P 6.74018996 4.765 4 P 0 0;1=4
P 6.74 4.805 4 P 0 0;1=0
P 6.785 4.845 4 P 0 0;1=4
P 6.785 4.805 4 P 0 0;1=4
P 6.785 4.765 4 P 0 0;1=4
P 6.74 4.845 4 P 0 0;1=4
P 6.65 5.055 4 P 0 0;1=0
P 6.49205 5.09705 4 P 0 0;1=0
P 6.495 4.9328 4 P 0 0;1=0
P 6.55118996 5.04705 4 P 0 0;1=0
P 6.78 4.94705 4 P 0 0;1=0
P 6.755 4.89705 4 P 0 0;1=0
P 6.74 4.987 4 P 0 0;1=0
P 12.73621004 2.08268002 10 P 0 0;1=1
P 12.73621004 2.63386004 10 P 0 0;1=1
P 12.81495 3.30315 10 P 0 0;1=1
P 12.73621004 4.60236998 10 P 0 0;1=1
P 12.55905 1.96456998 10 P 0 0;1=1
P 12.63778996 1.9252 10 P 0 0;1=1
P 0.09448996 1.9252 10 P 0 0;1=1
P 0.17323002 1.88583002 10 P 0 0;1=1
P 0.27165 2.04331004 10 P 0 0;1=1
P 0.27165 4.563 10 P 0 0;1=1
P 0.35038996 3.26378002 10 P 0 0;1=1
P 0.27165 2.59448996 10 P 0 0;1=1
P 0.17323002 1.72835 10 P 0 0;1=1
P 5.03268002 1.91615 5 P 0 0;1=3
P 1.025 -0.25 10 P 0 0;1=2
P 1.175 -0.25 10 P 0 0;1=2
P 1.325 -0.25 10 P 0 0;1=2
P 5.03268002 2.06615 5 P 0 0;1=3
P 12.63778996 4.12991998 10 P 0 0;1=1
P 11.53316004 2.372 5 P 0 0;1=3
P 5.08268002 2.26615 5 P 0 0;1=3
P 11.53316004 1.892 5 P 0 0;1=3
P 12.55905 3.30315 10 P 0 0;1=1
P 12.81495 2.51575 10 P 0 0;1=1
P 10.58661004 1.91615 5 P 0 0;1=3
P 10.26 1.66445 5 P 0 0;1=3
P 11.03998976 4.8431 28 P 0 0;1=4
P 11.08498976 4.8431 28 P 0 0;1=4
P 11.13498976 4.8431 28 P 0 0;1=4
P 11.17998976 4.8431 28 P 0 0;1=4
P 11.17998976 4.8031 28 P 0 0;1=4
P 11.17998976 4.7581 28 P 0 0;1=4
P 11.17998976 4.7131 28 P 0 0;1=4
P 11.17998976 4.6731 28 P 0 0;1=4
P 11.03998976 4.6731 28 P 0 0;1=4
P 11.08498976 4.6731 28 P 0 0;1=4
P 11.13498976 4.6731 28 P 0 0;1=4
P 11.03998976 4.7131 28 P 0 0;1=4
P 11.03998976 4.8031 28 P 0 0;1=4
P 11.03998976 4.7581 28 P 0 0;1=4
P 10.81998976 4.6631 28 P 0 0;1=4
P 10.85998976 4.6631 28 P 0 0;1=4
P 10.65998976 4.6631 28 P 0 0;1=4
P 10.69998976 4.6631 28 P 0 0;1=4
P 10.81998976 4.7031 28 P 0 0;1=4
P 10.81998976 4.8381 28 P 0 0;1=4
P 10.81998976 4.7931 28 P 0 0;1=4
P 10.81998976 4.7481 28 P 0 0;1=4
P 10.85998976 4.7031 28 P 0 0;1=4
P 10.85998976 4.8381 28 P 0 0;1=4
P 10.85998976 4.7931 28 P 0 0;1=4
P 10.85998976 4.7481 28 P 0 0;1=4
P 10.65998976 4.7031 28 P 0 0;1=4
P 10.65998976 4.8381 28 P 0 0;1=4
P 10.65998976 4.7931 28 P 0 0;1=4
P 10.65998976 4.7481 28 P 0 0;1=4
P 10.69998976 4.7031 28 P 0 0;1=4
P 10.69998976 4.8381 28 P 0 0;1=4
P 10.69998976 4.7931 28 P 0 0;1=4
P 10.69998976 4.7481 28 P 0 0;1=4
P 10.77998976 4.6431 28 P 0 0;1=4
P 10.73498976 4.6431 28 P 0 0;1=4
P 10.73998976 4.8381 28 P 0 0;1=4
P 10.77998976 4.8381 28 P 0 0;1=4
P 10.30998976 4.6631 28 P 0 0;1=4
P 10.26998976 4.6631 28 P 0 0;1=4
P 10.34498976 4.6431 28 P 0 0;1=4
P 10.38998976 4.6431 28 P 0 0;1=4
P 10.42998976 4.6631 28 P 0 0;1=4
P 10.46998976 4.6631 28 P 0 0;1=4
P 10.30998976 4.7481 28 P 0 0;1=4
P 10.30998976 4.7931 28 P 0 0;1=4
P 10.30998976 4.7031 28 P 0 0;1=4
P 10.26998976 4.7481 28 P 0 0;1=4
P 10.26998976 4.7931 28 P 0 0;1=4
P 10.26998976 4.7031 28 P 0 0;1=4
P 10.26998976 4.8381 28 P 0 0;1=4
P 10.30998976 4.8381 28 P 0 0;1=4
P 10.38998976 4.8381 28 P 0 0;1=4
P 10.34998976 4.8381 28 P 0 0;1=4
P 10.46998976 4.8381 28 P 0 0;1=4
P 10.42998976 4.8381 28 P 0 0;1=4
P 10.42998976 4.7031 28 P 0 0;1=4
P 10.42998976 4.7931 28 P 0 0;1=4
P 10.42998976 4.7481 28 P 0 0;1=4
P 10.46998976 4.7031 28 P 0 0;1=4
P 10.46998976 4.7931 28 P 0 0;1=4
P 10.46998976 4.7481 28 P 0 0;1=4
P 10.58660974 3.16615 28 P 0 0;1=3
P 10.63660974 3.01615 28 P 0 0;1=3
P 10.58660974 3.11615 28 P 0 0;1=3
P 10.58660974 3.01615 28 P 0 0;1=3
P 10.63660974 3.11615 28 P 0 0;1=3
P 10.63660974 2.96615 28 P 0 0;1=3
P 10.58660974 2.96615 28 P 0 0;1=3
P 10.58660974 3.41615 28 P 0 0;1=3
P 10.63660974 3.16615 28 P 0 0;1=3
P 10.63660974 3.26615 28 P 0 0;1=3
P 10.58660974 3.31615 28 P 0 0;1=3
P 10.58660974 3.26615 28 P 0 0;1=3
P 10.63660974 3.31615 28 P 0 0;1=3
P 10.63660974 3.56615 28 P 0 0;1=3
P 10.63660974 3.61615 28 P 0 0;1=3
P 10.58660974 3.56615 28 P 0 0;1=3
P 10.58660974 3.61615 28 P 0 0;1=3
P 10.63660974 3.46615 28 P 0 0;1=3
P 10.63660974 3.41615 28 P 0 0;1=3
P 10.58660974 3.46615 28 P 0 0;1=3
P 10.63660974 3.86615 28 P 0 0;1=3
P 10.63660974 3.76615 28 P 0 0;1=3
P 10.58660974 3.86615 28 P 0 0;1=3
P 10.58660974 3.76615 28 P 0 0;1=3
P 10.63660974 3.71615 28 P 0 0;1=3
P 10.58660974 3.71615 28 P 0 0;1=3
P 10.88660974 2.96615 28 P 0 0;1=3
P 10.83660974 2.96615 28 P 0 0;1=3
P 10.88660974 3.01615 28 P 0 0;1=3
P 10.83660974 3.01615 28 P 0 0;1=3
P 10.88660974 3.11615 28 P 0 0;1=3
P 10.83660974 3.11615 28 P 0 0;1=3
P 10.83660974 3.16615 28 P 0 0;1=3
P 10.78660974 3.16615 28 P 0 0;1=3
P 10.68660974 3.16615 28 P 0 0;1=3
P 10.73660974 3.16615 28 P 0 0;1=3
P 10.78660974 3.01615 28 P 0 0;1=3
P 10.78660974 3.11615 28 P 0 0;1=3
P 10.73660974 3.01615 28 P 0 0;1=3
P 10.73660974 3.11615 28 P 0 0;1=3
P 10.68660974 3.01615 28 P 0 0;1=3
P 10.68660974 3.11615 28 P 0 0;1=3
P 10.78660974 2.96615 28 P 0 0;1=3
P 10.73660974 2.96615 28 P 0 0;1=3
P 10.68660974 2.96615 28 P 0 0;1=3
P 10.88660974 3.16615 28 P 0 0;1=3
P 10.88660974 3.26615 28 P 0 0;1=3
P 10.83660974 3.26615 28 P 0 0;1=3
P 10.83660974 3.31615 28 P 0 0;1=3
P 10.88660974 3.31615 28 P 0 0;1=3
P 10.83660974 3.41615 28 P 0 0;1=3
P 10.78660974 3.41615 28 P 0 0;1=3
P 10.68660974 3.41615 28 P 0 0;1=3
P 10.73660974 3.41615 28 P 0 0;1=3
P 10.78660974 3.31615 28 P 0 0;1=3
P 10.78660974 3.26615 28 P 0 0;1=3
P 10.68660974 3.31615 28 P 0 0;1=3
P 10.68660974 3.26615 28 P 0 0;1=3
P 10.73660974 3.26615 28 P 0 0;1=3
P 10.73660974 3.31615 28 P 0 0;1=3
P 10.88660974 3.41615 28 P 0 0;1=3
P 10.83660974 3.46615 28 P 0 0;1=3
P 10.88660974 3.46615 28 P 0 0;1=3
P 10.83660974 3.56615 28 P 0 0;1=3
P 10.88660974 3.56615 28 P 0 0;1=3
P 10.83660974 3.61615 28 P 0 0;1=3
P 10.88660974 3.61615 28 P 0 0;1=3
P 10.78660974 3.56615 28 P 0 0;1=3
P 10.78660974 3.61615 28 P 0 0;1=3
P 10.68660974 3.61615 28 P 0 0;1=3
P 10.68660974 3.56615 28 P 0 0;1=3
P 10.73660974 3.61615 28 P 0 0;1=3
P 10.73660974 3.56615 28 P 0 0;1=3
P 10.78660974 3.46615 28 P 0 0;1=3
P 10.73660974 3.46615 28 P 0 0;1=3
P 10.68660974 3.46615 28 P 0 0;1=3
P 10.83660974 3.71615 28 P 0 0;1=3
P 10.88660974 3.71615 28 P 0 0;1=3
P 10.83660974 3.76615 28 P 0 0;1=3
P 10.88660974 3.76615 28 P 0 0;1=3
P 10.83660974 3.86615 28 P 0 0;1=3
P 10.88660974 3.86615 28 P 0 0;1=3
P 10.78660974 3.86615 28 P 0 0;1=3
P 10.78660974 3.76615 28 P 0 0;1=3
P 10.68660974 3.86615 28 P 0 0;1=3
P 10.68660974 3.76615 28 P 0 0;1=3
P 10.73660974 3.86615 28 P 0 0;1=3
P 10.73660974 3.76615 28 P 0 0;1=3
P 10.78660974 3.71615 28 P 0 0;1=3
P 10.68660974 3.71615 28 P 0 0;1=3
P 10.73660974 3.71615 28 P 0 0;1=3
P 11.03660974 2.96615 28 P 0 0;1=3
P 10.93660974 2.96615 28 P 0 0;1=3
P 10.98660974 2.96615 28 P 0 0;1=3
P 11.03660974 3.01615 28 P 0 0;1=3
P 10.93660974 3.01615 28 P 0 0;1=3
P 10.98660974 3.01615 28 P 0 0;1=3
P 11.03660974 3.11615 28 P 0 0;1=3
P 10.93660974 3.11615 28 P 0 0;1=3
P 10.98660974 3.11615 28 P 0 0;1=3
P 11.03660974 3.16615 28 P 0 0;1=3
P 10.93660974 3.16615 28 P 0 0;1=3
P 10.98660974 3.16615 28 P 0 0;1=3
P 11.03660974 3.26615 28 P 0 0;1=3
P 10.93660974 3.26615 28 P 0 0;1=3
P 10.98660974 3.26615 28 P 0 0;1=3
P 10.98660974 3.31615 28 P 0 0;1=3
P 10.93660974 3.31615 28 P 0 0;1=3
P 11.03660974 3.31615 28 P 0 0;1=3
P 10.98660974 3.41615 28 P 0 0;1=3
P 10.93660974 3.41615 28 P 0 0;1=3
P 11.03660974 3.41615 28 P 0 0;1=3
P 10.98660974 3.46615 28 P 0 0;1=3
P 10.93660974 3.46615 28 P 0 0;1=3
P 11.03660974 3.46615 28 P 0 0;1=3
P 10.98660974 3.56615 28 P 0 0;1=3
P 10.93660974 3.56615 28 P 0 0;1=3
P 11.03660974 3.56615 28 P 0 0;1=3
P 10.98660974 3.61615 28 P 0 0;1=3
P 10.93660974 3.61615 28 P 0 0;1=3
P 11.03660974 3.61615 28 P 0 0;1=3
P 10.98660974 3.71615 28 P 0 0;1=3
P 10.93660974 3.71615 28 P 0 0;1=3
P 11.03660974 3.71615 28 P 0 0;1=3
P 10.98660974 3.76615 28 P 0 0;1=3
P 10.93660974 3.76615 28 P 0 0;1=3
P 11.03660974 3.76615 28 P 0 0;1=3
P 10.98660974 3.86615 28 P 0 0;1=3
P 10.93660974 3.86615 28 P 0 0;1=3
P 11.03660974 3.86615 28 P 0 0;1=3
P 5.08268002 2.06615 5 P 0 0;1=3
P 10.58661004 2.36615 5 P 0 0;1=3
P 9.975 2.4709 5 P 0 0;1=3
P 12.73621004 4.20866004 10 P 0 0;1=1
P 11.08661004 2.36615 5 P 0 0;1=3
P 5.08268002 2.11615 5 P 0 0;1=3
P 11.08661004 2.41615 5 P 0 0;1=3
P 12.73621004 2.47638002 10 P 0 0;1=1
P 10.58661004 1.96615 5 P 0 0;1=3
P 10.26 1.70445 5 P 0 0;1=3
P 10.98661004 2.41615 5 P 0 0;1=3
P 8.5 3.76615 5 P 0 0;1=3
P 9.35271004 5.1035 5 P 0 0;1=3
P 4.98268002 2.06615 5 P 0 0;1=3
P 8.5 3.81615 5 P 0 0;1=3
P 9.31271004 5.1035 5 P 0 0;1=3
P 12.55905 2.59448996 10 P 0 0;1=1
P 11.53316004 1.572 5 P 0 0;1=3
P 4.98268002 2.11615 5 P 0 0;1=3
P 10.98661004 2.36615 5 P 0 0;1=3
P 8.5 3.61615 5 P 0 0;1=3
P 9.56531004 5.14 5 P 0 0;1=3
P 4.93268002 2.01615 5 P 0 0;1=3
P 11.53316004 1.412 5 P 0 0;1=3
P 12.63778996 2.39763996 10 P 0 0;1=1
P 8.5 3.66615 5 P 0 0;1=3
P 9.52531004 5.14 5 P 0 0;1=3
P 12.73621004 2.87008002 10 P 0 0;1=1
P 10.63661004 2.06615 5 P 0 0;1=3
P 10.225 1.96645 5 P 0 0;1=3
P 11.53316004 1.452 5 P 0 0;1=3
P 12.55905 2.43701004 10 P 0 0;1=1
P 8.35 3.66615 5 P 0 0;1=3
P 9.56531004 4.71973002 5 P 0 0;1=3
P 4.93268002 2.06615 5 P 0 0;1=3
P 8.35 3.71615 5 P 0 0;1=3
P 9.52531004 4.71973002 5 P 0 0;1=3
P 11.83316004 2.212 5 P 0 0;1=3
P 12.63778996 3.65748002 10 P 0 0;1=1
P 12.73621004 3.02756004 10 P 0 0;1=1
P 10.58661004 2.11615 5 P 0 0;1=3
P 10.09 2.05655 5 P 0 0;1=3
P 11.53316004 1.932 5 P 0 0;1=3
P 12.63778996 3.26378002 10 P 0 0;1=1
P 8.74578996 5.14 5 P 0 0;1=3
P 8.05 3.61615 5 P 0 0;1=3
P 12.81495 4.01181004 10 P 0 0;1=1
P 10.09 2.57845 5 P 0 0;1=3
P 10.68661004 2.41615 5 P 0 0;1=3
P 11.73316004 1.492 5 P 0 0;1=3
P 12.63778996 2.24016004 10 P 0 0;1=1
P 8.78578996 5.14 5 P 0 0;1=3
P 8.05 3.66615 5 P 0 0;1=3
P 12.73621004 2.7126 10 P 0 0;1=1
P 10.73661004 2.06615 5 P 0 0;1=3
P 10.26025 1.86845 5 P 0 0;1=3
P 11.03661004 2.46615 5 P 0 0;1=3
P 8.15 3.61615 5 P 0 0;1=3
P 8.88441004 5.17001998 5 P 0 0;1=3
P 12.55905 4.09055 10 P 0 0;1=1
P 11.53316004 2.412 5 P 0 0;1=3
P 11.03661004 2.51615 5 P 0 0;1=3
P 8.15 3.66615 5 P 0 0;1=3
P 8.92441004 5.17001998 5 P 0 0;1=3
P 1.057 5.027 4 P 0 0;1=0
P 12.73621004 3.18503996 10 P 0 0;1=1
P 10.68661004 2.11615 5 P 0 0;1=3
P 10.09 2.17095 5 P 0 0;1=3
P 11.78316004 1.692 5 P 0 0;1=3
P 12.55905 2.04331004 10 P 0 0;1=1
P 12.81495 2.90945 10 P 0 0;1=1
P 10.63661004 2.01615 5 P 0 0;1=3
P 10.225 1.92645 5 P 0 0;1=3
P 11.78316004 1.652 5 P 0 0;1=3
P 12.63778996 2.08268002 10 P 0 0;1=1
P 1.122 5.417 4 P 0 0;1=4
P 5.855 0.925 4 P 0 0;1=4
P 3.88 4.545 4 P 0 0;1=0
P 0.96555 5.78055 4 P 0 0;1=0
P 4.07 4.625 4 P 0 0;1=4
P 10.58661004 2.71615 5 P 0 0;1=3
P 9.91 4.433 4 P 0 0;1=0
P 9.995 2.936 4 P 0 0;1=4
P 11.83316004 2.252 5 P 0 0;1=3
P 12.55905 3.61811004 10 P 0 0;1=1
P 12.81495 3.06693002 10 P 0 0;1=1
P 10.58661004 2.06615 5 P 0 0;1=3
P 10.09 2.01655 5 P 0 0;1=3
P 8.1 3.81615 5 P 0 0;1=3
P 9.10011004 5.0535 5 P 0 0;1=3
P 8.1 3.86615 5 P 0 0;1=3
P 9.14011004 5.0535 5 P 0 0;1=3
P 3.9599 5.395 4 P 0 0;1=0
P 0.88681004 5.78181004 4 P 0 0;1=4
P 12.73621004 2.3189 10 P 0 0;1=1
P 10.63661004 1.91615 5 P 0 0;1=3
P 10.38371998 1.49328002 5 P 0 0;1=3
P 8.35 3.81615 5 P 0 0;1=3
P 9.28185 5.22001998 5 P 0 0;1=3
P 0.72933002 5.463 4 P 0 0;1=0
P 11.53316004 2.572 5 P 0 0;1=3
P 12.55905 4.56298996 10 P 0 0;1=1
P 8.35 3.86615 5 P 0 0;1=3
P 9.24185 5.22001998 5 P 0 0;1=3
P 4.125 2.682 4 P 0 0;1=4
P 3.94 4.42 4 P 0 0;1=0
P 5.03 5.4 4 P 0 0;1=4
P 4.58268002 2.71615 5 P 0 0;1=3
P 8.45 3.81615 5 P 0 0;1=3
P 9.21098002 4.78291998 5 P 0 0;1=3
P 8.45 3.86615 5 P 0 0;1=3
P 9.17098002 4.78291998 5 P 0 0;1=3
P 3.75998996 0.24001004 28 P 0 0;1=0
P 9.55795 0.26134026 28 P 0 0;1=0
P 3.71202972 0.77535 28 P 0 0;1=4
P 3.70998976 0.7 28 P 0 0;1=4
P 9.50795 0.72133002 28 P 0 0;1=4
P 9.46795 0.82632028 28 P 0 0;1=4
P 4.02893002 2.59336998 28 P 0 0;1=4
P 11.395 2.725 28 P 0 0;1=0
P 11.395 2.8 28 P 0 0;1=4
P 11.58612972 2.905 28 P 0 0;1=4
P 11.58612972 2.785 28 P 0 0;1=4
P 1.33905994 4.60351004 28 P 0 0;1=0
P 3.67 4.45 28 P 0 0;1=4
P 3.72 4.545 28 P 0 0;1=4
P 5.37968996 2.8 4 P 0 0;1=4
P 5.387 2.725 4 P 0 0;1=0
P 5.5822 2.785 4 P 0 0;1=4
P 5.5822 2.905 4 P 0 0;1=4
P 7.2426 4.69351024 28 P 0 0;1=4
P 7.2926 4.60351024 28 P 0 0;1=4
P 9.98 4.51 28 P 0 0;1=4
P 10.07286004 2.82336998 4 P 0 0;1=4
P 10.03 4.61 28 P 0 0;1=4
P 1.23905994 4.69351004 28 P 0 0;1=4
P 3.89 4.655 28 P 0 0;1=4
P 3.9899 4.765 28 P 0 0;1=4
P 4.1049 4.86 28 P 0 0;1=4
P 4.0599 5.395 28 P 0 0;1=4
P 3.91 5.51 28 P 0 0;1=4
P 5.125 5.4 28 P 0 0;1=4
P 1.37925 5.78 28 P 0 0;1=4
P 1.45798976 5.78 28 P 0 0;1=4
P 1.42 5.78 28 P 0 0;1=4
P 1.335 5.78 28 P 0 0;1=4
P 12.63778996 2.55511998 10 P 0 0;1=1
P 11.53316004 1.612 5 P 0 0;1=3
P 8.4 3.76615 5 P 0 0;1=3
P 9.28185 4.642 5 P 0 0;1=3
P 12.73621004 4.36613996 10 P 0 0;1=1
P 10.63661004 2.41615 5 P 0 0;1=3
P 9.975 2.66445 5 P 0 0;1=3
P 8.4 3.81615 5 P 0 0;1=3
P 9.24185 4.642 5 P 0 0;1=3
P 11.53316004 2.532 5 P 0 0;1=3
P 12.63778996 4.60236998 10 P 0 0;1=1
P 8.45 3.66615 5 P 0 0;1=3
P 9.42358002 4.78291998 5 P 0 0;1=3
P 0.95951004 5.4595 4 P 0 0;1=0
P 8.45 3.71615 5 P 0 0;1=3
P 9.38358002 4.78291998 5 P 0 0;1=3
P 8.4 3.61615 5 P 0 0;1=3
P 9.49445 4.587 5 P 0 0;1=3
P 8.4 3.66615 5 P 0 0;1=3
P 9.45445 4.587 5 P 0 0;1=3
P 9.07353996 4.42 4 P 0 0;1=4
P 7.1926 5.15351004 4 P 0 0;1=0
P 8.1 3.66615 5 P 0 0;1=3
P 8.74578996 4.667 5 P 0 0;1=3
P 8.1 3.71615 5 P 0 0;1=3
P 8.78578996 4.667 5 P 0 0;1=3
P 8.2 3.66615 5 P 0 0;1=3
P 8.81665 4.78291998 5 P 0 0;1=3
P 8.2 3.71615 5 P 0 0;1=3
P 8.85665 4.78291998 5 P 0 0;1=3
P 8.05 3.76615 5 P 0 0;1=3
P 8.89061998 4.667 5 P 0 0;1=3
P 8.05 3.81615 5 P 0 0;1=3
P 8.93061998 4.667 5 P 0 0;1=3
P 9.02925 4.667 5 P 0 0;1=3
P 8.2 3.81615 5 P 0 0;1=3
P 9.06925 4.667 5 P 0 0;1=3
P 8.2 3.86615 5 P 0 0;1=3
P 4.68268002 2.71615 5 P 0 0;1=3
P 4.98268002 2.71615 5 P 0 0;1=3
P 2.14606004 2.51615 5 P 0 0;1=3
P 8.45 3.41615 5 P 0 0;1=3
P 8.18811004 5.0535 5 P 0 0;1=3
P 5.03268002 3.81615 5 P 0 0;1=3
P 4.07408002 4.01978996 4 P 0 0;1=0
P 8.45 3.46615 5 P 0 0;1=3
P 8.14811004 5.0535 5 P 0 0;1=3
P 5.03268002 2.16615 5 P 0 0;1=3
P 3.9099 5.395 4 P 0 0;1=0
P 8.45 3.26615 5 P 0 0;1=3
P 8.40071004 5.115 5 P 0 0;1=3
P 8.45 3.31615 5 P 0 0;1=3
P 8.36071004 5.115 5 P 0 0;1=3
P 8.35 3.26615 5 P 0 0;1=3
P 8.40071004 4.742 5 P 0 0;1=3
P 8.35 3.31615 5 P 0 0;1=3
P 8.36071004 4.742 5 P 0 0;1=3
P 8.3 3.56615 5 P 0 0;1=3
P 8.05 3.31615 5 P 0 0;1=3
P 7.58118996 5.169 5 P 0 0;1=3
P 8.25 3.56615 5 P 0 0;1=3
P 8.05 3.36615 5 P 0 0;1=3
P 7.62118996 5.169 5 P 0 0;1=3
P 2.24606004 2.86615 5 P 0 0;1=3
P 8.05 2.61615 5 P 0 0;1=3
P 8.05 2.66615 5 P 0 0;1=3
P 8.1 2.46615 5 P 0 0;1=3
P 8.1 2.41615 5 P 0 0;1=3
P 8.2 2.46615 5 P 0 0;1=3
P 8.2 2.41615 5 P 0 0;1=3
P 8.15 2.41615 5 P 0 0;1=3
P 8.15 2.36615 5 P 0 0;1=3
P 8.05 2.41615 5 P 0 0;1=3
P 8.05 2.36615 5 P 0 0;1=3
P 8.2 2.31615 5 P 0 0;1=3
P 8.2 2.26615 5 P 0 0;1=3
P 8.15 2.26615 5 P 0 0;1=3
P 8.15 2.21615 5 P 0 0;1=3
P 8.1 2.31615 5 P 0 0;1=3
P 8.1 2.26615 5 P 0 0;1=3
P 8.05 2.26615 5 P 0 0;1=3
P 8.05 2.21615 5 P 0 0;1=3
P 8.1 2.11615 5 P 0 0;1=3
P 8.1 2.06615 5 P 0 0;1=3
P 8.2 2.11615 5 P 0 0;1=3
P 8.2 2.06615 5 P 0 0;1=3
P 8.15 2.06615 5 P 0 0;1=3
P 8.15 2.01615 5 P 0 0;1=3
P 8.05 2.06615 5 P 0 0;1=3
P 8.05 2.01615 5 P 0 0;1=3
P 8.2 1.96615 5 P 0 0;1=3
P 8.2 1.91615 5 P 0 0;1=3
P 8.15 1.91615 5 P 0 0;1=3
P 8.15 1.86615 5 P 0 0;1=3
P 8.1 1.96615 5 P 0 0;1=3
P 8.1 1.91615 5 P 0 0;1=3
P 8.05 1.91615 5 P 0 0;1=3
P 8.05 1.86615 5 P 0 0;1=3
P 8.1 3.16615 5 P 0 0;1=3
P 8.1 3.11615 5 P 0 0;1=3
P 8.2 3.16615 5 P 0 0;1=3
P 8.2 3.11615 5 P 0 0;1=3
P 8.15 3.11615 5 P 0 0;1=3
P 8.15 3.06615 5 P 0 0;1=3
P 8.05 3.11615 5 P 0 0;1=3
P 8.05 3.06615 5 P 0 0;1=3
P 8.2 3.01615 5 P 0 0;1=3
P 8.2 2.96615 5 P 0 0;1=3
P 8.15 2.96615 5 P 0 0;1=3
P 8.15 2.91615 5 P 0 0;1=3
P 8.1 3.01615 5 P 0 0;1=3
P 8.1 2.96615 5 P 0 0;1=3
P 8.05 2.96615 5 P 0 0;1=3
P 8.05 2.91615 5 P 0 0;1=3
P 8 2.81615 5 P 0 0;1=3
P 8 2.76615 5 P 0 0;1=3
P 8.15 2.81615 5 P 0 0;1=3
P 8.15 2.76615 5 P 0 0;1=3
P 8.2 2.76615 5 P 0 0;1=3
P 8.2 2.71615 5 P 0 0;1=3
P 8.1 2.76615 5 P 0 0;1=3
P 8.1 2.71615 5 P 0 0;1=3
P 8.15 2.66615 5 P 0 0;1=3
P 8.15 2.61615 5 P 0 0;1=3
P 8.2 2.61615 5 P 0 0;1=3
P 8.2 2.56615 5 P 0 0;1=3
P 8.1 2.61615 5 P 0 0;1=3
P 8.1 2.56615 5 P 0 0;1=3
P 8.35 2.56615 5 P 0 0;1=3
P 8.35 2.61615 5 P 0 0;1=3
P 8.35 2.46615 5 P 0 0;1=3
P 8.35 2.41615 5 P 0 0;1=3
P 8.45 2.46615 5 P 0 0;1=3
P 8.45 2.41615 5 P 0 0;1=3
P 8.5 2.41615 5 P 0 0;1=3
P 8.5 2.36615 5 P 0 0;1=3
P 8.4 2.41615 5 P 0 0;1=3
P 8.4 2.36615 5 P 0 0;1=3
P 8.45 2.31615 5 P 0 0;1=3
P 8.45 2.26615 5 P 0 0;1=3
P 8.5 2.26615 5 P 0 0;1=3
P 8.5 2.21615 5 P 0 0;1=3
P 8.4 2.26615 5 P 0 0;1=3
P 8.4 2.21615 5 P 0 0;1=3
P 8.35 2.31615 5 P 0 0;1=3
P 8.35 2.26615 5 P 0 0;1=3
P 8.35 2.11615 5 P 0 0;1=3
P 8.35 2.06615 5 P 0 0;1=3
P 8.45 2.11615 5 P 0 0;1=3
P 8.45 2.06615 5 P 0 0;1=3
P 8.5 2.06615 5 P 0 0;1=3
P 8.5 2.01615 5 P 0 0;1=3
P 8.4 2.06615 5 P 0 0;1=3
P 8.4 2.01615 5 P 0 0;1=3
P 8.45 1.96615 5 P 0 0;1=3
P 8.45 1.91615 5 P 0 0;1=3
P 8.5 1.91615 5 P 0 0;1=3
P 8.5 1.86615 5 P 0 0;1=3
P 8.4 1.91615 5 P 0 0;1=3
P 8.4 1.86615 5 P 0 0;1=3
P 8.35 1.96615 5 P 0 0;1=3
P 8.35 1.91615 5 P 0 0;1=3
P 8.35 3.16615 5 P 0 0;1=3
P 8.35 3.11615 5 P 0 0;1=3
P 8.45 3.16615 5 P 0 0;1=3
P 8.45 3.11615 5 P 0 0;1=3
P 8.5 3.11615 5 P 0 0;1=3
P 8.5 3.06615 5 P 0 0;1=3
P 8.4 3.11615 5 P 0 0;1=3
P 8.4 3.06615 5 P 0 0;1=3
P 8.45 3.01615 5 P 0 0;1=3
P 8.45 2.96615 5 P 0 0;1=3
P 8.5 2.96615 5 P 0 0;1=3
P 8.5 2.91615 5 P 0 0;1=3
P 8.4 2.96615 5 P 0 0;1=3
P 8.4 2.91615 5 P 0 0;1=3
P 8.35 3.01615 5 P 0 0;1=3
P 8.35 2.96615 5 P 0 0;1=3
P 8.4 2.81615 5 P 0 0;1=3
P 8.4 2.76615 5 P 0 0;1=3
P 8.5 2.81615 5 P 0 0;1=3
P 8.5 2.76615 5 P 0 0;1=3
P 8.45 2.76615 5 P 0 0;1=3
P 8.45 2.71615 5 P 0 0;1=3
P 8.35 2.76615 5 P 0 0;1=3
P 8.35 2.71615 5 P 0 0;1=3
P 8.5 2.66615 5 P 0 0;1=3
P 8.5 2.61615 5 P 0 0;1=3
P 8.45 2.61615 5 P 0 0;1=3
P 8.45 2.56615 5 P 0 0;1=3
P 8.4 2.66615 5 P 0 0;1=3
P 8.4 2.61615 5 P 0 0;1=3
P 2.04606004 2.61615 5 P 0 0;1=3
P 2.04606004 2.66615 5 P 0 0;1=3
P 2.09606004 2.46615 5 P 0 0;1=3
P 2.09606004 2.41615 5 P 0 0;1=3
P 2.19606004 2.46615 5 P 0 0;1=3
P 2.19606004 2.41615 5 P 0 0;1=3
P 2.14606004 2.41615 5 P 0 0;1=3
P 2.14606004 2.36615 5 P 0 0;1=3
P 2.04606004 2.41615 5 P 0 0;1=3
P 2.04606004 2.36615 5 P 0 0;1=3
P 2.19606004 2.31615 5 P 0 0;1=3
P 2.19606004 2.26615 5 P 0 0;1=3
P 2.14606004 2.26615 5 P 0 0;1=3
P 2.14606004 2.21615 5 P 0 0;1=3
P 2.09606004 2.31615 5 P 0 0;1=3
P 2.09606004 2.26615 5 P 0 0;1=3
P 2.04606004 2.26615 5 P 0 0;1=3
P 2.04606004 2.21615 5 P 0 0;1=3
P 2.09606004 2.11615 5 P 0 0;1=3
P 2.09606004 2.06615 5 P 0 0;1=3
P 2.19606004 2.11615 5 P 0 0;1=3
P 2.19606004 2.06615 5 P 0 0;1=3
P 2.14606004 2.06615 5 P 0 0;1=3
P 2.14606004 2.01615 5 P 0 0;1=3
P 2.04606004 2.06615 5 P 0 0;1=3
P 2.04606004 2.01615 5 P 0 0;1=3
P 2.19606004 1.96615 5 P 0 0;1=3
P 2.19606004 1.91615 5 P 0 0;1=3
P 2.14606004 1.91615 5 P 0 0;1=3
P 2.14606004 1.86615 5 P 0 0;1=3
P 2.09606004 1.96615 5 P 0 0;1=3
P 2.09606004 1.91615 5 P 0 0;1=3
P 2.04606004 1.91615 5 P 0 0;1=3
P 2.04606004 1.86615 5 P 0 0;1=3
P 2.09606004 3.16615 5 P 0 0;1=3
P 2.09606004 3.11615 5 P 0 0;1=3
P 2.19606004 3.16615 5 P 0 0;1=3
P 2.19606004 3.11615 5 P 0 0;1=3
P 2.14606004 3.11615 5 P 0 0;1=3
P 2.14606004 3.06615 5 P 0 0;1=3
P 2.04606004 3.11615 5 P 0 0;1=3
P 2.04606004 3.06615 5 P 0 0;1=3
P 2.19606004 3.01615 5 P 0 0;1=3
P 2.19606004 2.96615 5 P 0 0;1=3
P 2.14606004 2.96615 5 P 0 0;1=3
P 2.14606004 2.91615 5 P 0 0;1=3
P 2.09606004 3.01615 5 P 0 0;1=3
P 2.09606004 2.96615 5 P 0 0;1=3
P 2.04606004 2.96615 5 P 0 0;1=3
P 2.04606004 2.91615 5 P 0 0;1=3
P 1.99606004 2.81615 5 P 0 0;1=3
P 1.99606004 2.76615 5 P 0 0;1=3
P 2.14606004 2.81615 5 P 0 0;1=3
P 2.14606004 2.76615 5 P 0 0;1=3
P 2.19606004 2.76615 5 P 0 0;1=3
P 2.19606004 2.71615 5 P 0 0;1=3
P 2.09606004 2.76615 5 P 0 0;1=3
P 2.09606004 2.71615 5 P 0 0;1=3
P 2.14606004 2.66615 5 P 0 0;1=3
P 2.14606004 2.61615 5 P 0 0;1=3
P 2.19606004 2.61615 5 P 0 0;1=3
P 2.19606004 2.56615 5 P 0 0;1=3
P 2.09606004 2.61615 5 P 0 0;1=3
P 2.09606004 2.56615 5 P 0 0;1=3
P 2.34606004 2.56615 5 P 0 0;1=3
P 2.34606004 2.61615 5 P 0 0;1=3
P 2.34606004 2.46615 5 P 0 0;1=3
P 2.34606004 2.41615 5 P 0 0;1=3
P 2.44606004 2.46615 5 P 0 0;1=3
P 2.44606004 2.41615 5 P 0 0;1=3
P 2.49606004 2.41615 5 P 0 0;1=3
P 2.49606004 2.36615 5 P 0 0;1=3
P 2.39606004 2.41615 5 P 0 0;1=3
P 2.39606004 2.36615 5 P 0 0;1=3
P 2.44606004 2.31615 5 P 0 0;1=3
P 2.44606004 2.26615 5 P 0 0;1=3
P 2.49606004 2.26615 5 P 0 0;1=3
P 2.49606004 2.21615 5 P 0 0;1=3
P 2.39606004 2.26615 5 P 0 0;1=3
P 2.39606004 2.21615 5 P 0 0;1=3
P 2.34606004 2.31615 5 P 0 0;1=3
P 2.34606004 2.26615 5 P 0 0;1=3
P 2.34606004 2.11615 5 P 0 0;1=3
P 2.34606004 2.06615 5 P 0 0;1=3
P 2.44606004 2.11615 5 P 0 0;1=3
P 2.44606004 2.06615 5 P 0 0;1=3
P 2.49606004 2.06615 5 P 0 0;1=3
P 2.49606004 2.01615 5 P 0 0;1=3
P 2.39606004 2.06615 5 P 0 0;1=3
P 2.39606004 2.01615 5 P 0 0;1=3
P 2.44606004 1.96615 5 P 0 0;1=3
P 2.44606004 1.91615 5 P 0 0;1=3
P 2.49606004 1.91615 5 P 0 0;1=3
P 2.49606004 1.86615 5 P 0 0;1=3
P 2.39606004 1.91615 5 P 0 0;1=3
P 2.39606004 1.86615 5 P 0 0;1=3
P 2.34606004 1.96615 5 P 0 0;1=3
P 2.34606004 1.91615 5 P 0 0;1=3
P 2.34606004 3.16615 5 P 0 0;1=3
P 2.34606004 3.11615 5 P 0 0;1=3
P 2.44606004 3.16615 5 P 0 0;1=3
P 2.44606004 3.11615 5 P 0 0;1=3
P 2.49606004 3.11615 5 P 0 0;1=3
P 2.49606004 3.06615 5 P 0 0;1=3
P 2.39606004 3.11615 5 P 0 0;1=3
P 2.39606004 3.06615 5 P 0 0;1=3
P 2.44606004 3.01615 5 P 0 0;1=3
P 2.44606004 2.96615 5 P 0 0;1=3
P 2.49606004 2.96615 5 P 0 0;1=3
P 2.49606004 2.91615 5 P 0 0;1=3
P 2.39606004 2.96615 5 P 0 0;1=3
P 2.39606004 2.91615 5 P 0 0;1=3
P 2.34606004 3.01615 5 P 0 0;1=3
P 2.34606004 2.96615 5 P 0 0;1=3
P 2.39606004 2.81615 5 P 0 0;1=3
P 2.39606004 2.76615 5 P 0 0;1=3
P 2.49606004 2.81615 5 P 0 0;1=3
P 2.49606004 2.76615 5 P 0 0;1=3
P 2.44606004 2.76615 5 P 0 0;1=3
P 2.44606004 2.71615 5 P 0 0;1=3
P 2.34606004 2.76615 5 P 0 0;1=3
P 2.34606004 2.71615 5 P 0 0;1=3
P 2.49606004 2.66615 5 P 0 0;1=3
P 2.49606004 2.61615 5 P 0 0;1=3
P 2.44606004 2.61615 5 P 0 0;1=3
P 2.44606004 2.56615 5 P 0 0;1=3
P 2.39606004 2.66615 5 P 0 0;1=3
P 2.39606004 2.61615 5 P 0 0;1=3
P 8.94061998 4.70573996 4 P 0 0;1=4
P 9.01925 4.70573996 4 P 0 0;1=4
P 9.07925 4.70573996 4 P 0 0;1=4
P 8.73578996 4.70573996 4 P 0 0;1=4
P 8.79578996 4.70573996 4 P 0 0;1=4
P 8.86665 4.74418002 4 P 0 0;1=4
P 8.80665 4.74418002 4 P 0 0;1=4
P 9.43358002 4.74418002 4 P 0 0;1=4
P 9.51531004 4.68098996 4 P 0 0;1=4
P 9.57531004 4.68098996 4 P 0 0;1=4
P 9.44445 4.62573996 4 P 0 0;1=4
P 9.50445 4.62573996 4 P 0 0;1=4
P 9.23185 4.68073996 4 P 0 0;1=4
P 9.29185 4.68073996 4 P 0 0;1=4
P 9.16098002 4.74418002 4 P 0 0;1=4
P 9.37358002 4.74418002 4 P 0 0;1=4
P 9.22098002 4.74418002 4 P 0 0;1=4
P 9.51531004 5.17873996 4 P 0 0;1=4
P 9.57531004 5.17873996 4 P 0 0;1=4
P 9.43358002 5.18128002 4 P 0 0;1=4
P 9.23185 5.18128002 4 P 0 0;1=4
P 9.29185 5.18128002 4 P 0 0;1=4
P 9.37358002 5.18128002 4 P 0 0;1=4
P 9.36271004 5.14223996 4 P 0 0;1=4
P 9.30271004 5.14223996 4 P 0 0;1=4
P 9.15011004 5.09223996 4 P 0 0;1=4
P 9.09011004 5.09223996 4 P 0 0;1=4
P 9.07925 5.20373996 4 P 0 0;1=4
P 9.01925 5.20373996 4 P 0 0;1=4
P 8.93441004 5.20876004 4 P 0 0;1=4
P 8.73578996 5.17873996 4 P 0 0;1=4
P 8.79578996 5.17873996 4 P 0 0;1=4
P 8.87441004 5.20876004 4 P 0 0;1=4
P 7.64205 4.74418002 4 P 0 0;1=4
P 7.70205 4.74418002 4 P 0 0;1=4
P 7.63118996 4.66826004 4 P 0 0;1=4
P 7.57118996 4.66826004 4 P 0 0;1=4
P 7.91465 4.61826004 4 P 0 0;1=4
P 7.78378996 4.74418002 4 P 0 0;1=4
P 7.84378996 4.74418002 4 P 0 0;1=4
P 7.85465 4.61826004 4 P 0 0;1=4
P 8.06725 4.74418002 4 P 0 0;1=4
P 8.12725 4.74418002 4 P 0 0;1=4
P 8.02206998 4.62815 4 P 0 0;1=4
P 8.08206998 4.62815 4 P 0 0;1=4
P 8.41071004 4.70326004 4 P 0 0;1=4
P 8.35071004 4.70326004 4 P 0 0;1=4
P 8.20898002 4.74418002 4 P 0 0;1=4
P 8.26898002 4.74418002 4 P 0 0;1=4
P 8.21208996 4.62826004 4 P 0 0;1=4
P 8.27208996 4.62826004 4 P 0 0;1=4
P 8.19811004 5.09223996 4 P 0 0;1=4
P 8.12725 5.13026004 4 P 0 0;1=4
P 8.06725 5.13026004 4 P 0 0;1=4
P 7.91465 5.13026004 4 P 0 0;1=4
P 7.92551004 5.09223996 4 P 0 0;1=4
P 7.98551004 5.09223996 4 P 0 0;1=4
P 7.85465 5.13026004 4 P 0 0;1=4
P 7.64203996 5.09223996 4 P 0 0;1=4
P 7.70203996 5.09223996 4 P 0 0;1=4
P 7.57118996 5.13026004 4 P 0 0;1=4
P 7.63118996 5.13026004 4 P 0 0;1=4
P 2.73225 4.70573996 4 P 0 0;1=4
P 2.79225 4.70573996 4 P 0 0;1=4
P 3.22831004 5.18128002 4 P 0 0;1=4
P 3.28831004 5.18128002 4 P 0 0;1=4
P 3.01571004 5.20373996 4 P 0 0;1=4
P 3.07571004 5.20373996 4 P 0 0;1=4
P 2.73225 5.17873996 4 P 0 0;1=4
P 2.79225 5.17873996 4 P 0 0;1=4
P 1.56765 4.66826004 4 P 0 0;1=4
P 1.62765 4.66826004 4 P 0 0;1=4
P 1.56765 5.13026004 4 P 0 0;1=4
P 1.62765 5.13026004 4 P 0 0;1=4
P 1.91111004 5.13026004 4 P 0 0;1=4
P 1.85111004 5.13026004 4 P 0 0;1=4
P 5.08268002 2.76615 5 P 0 0;1=3
P 5.03268002 2.76615 5 P 0 0;1=3
P 5.03268002 2.71615 5 P 0 0;1=3
P 4.93268002 2.76615 5 P 0 0;1=3
P 4.98268002 2.76615 5 P 0 0;1=3
P 4.93268002 2.71615 5 P 0 0;1=3
P 5.08268002 2.66615 5 P 0 0;1=3
P 4.98268002 2.66615 5 P 0 0;1=3
P 5.03268002 2.56615 5 P 0 0;1=3
P 4.93268002 2.56615 5 P 0 0;1=3
P 4.98268002 2.46615 5 P 0 0;1=3
P 4.98268002 2.51615 5 P 0 0;1=3
P 4.93268002 2.51615 5 P 0 0;1=3
P 5.08268002 2.51615 5 P 0 0;1=3
P 5.08268002 2.46615 5 P 0 0;1=3
P 5.03268002 2.21615 5 P 0 0;1=3
P 4.93268002 2.21615 5 P 0 0;1=3
P 4.98268002 2.31615 5 P 0 0;1=3
P 4.93268002 2.36615 5 P 0 0;1=3
P 5.08268002 2.31615 5 P 0 0;1=3
P 5.08268002 2.16615 5 P 0 0;1=3
P 4.93268002 2.16615 5 P 0 0;1=3
P 4.98268002 2.16615 5 P 0 0;1=3
P 4.93268002 1.96615 5 P 0 0;1=3
P 5.03268002 1.96615 5 P 0 0;1=3
P 5.03268002 2.11615 5 P 0 0;1=3
P 4.93268002 2.11615 5 P 0 0;1=3
P 4.98268002 2.01615 5 P 0 0;1=3
P 5.08268002 2.01615 5 P 0 0;1=3
P 4.98268002 1.86615 5 P 0 0;1=3
P 5.08268002 1.86615 5 P 0 0;1=3
P 4.78268002 3.81615 5 P 0 0;1=3
P 4.78268002 3.66615 5 P 0 0;1=3
P 4.73268002 3.81615 5 P 0 0;1=3
P 4.73268002 3.66615 5 P 0 0;1=3
P 4.68268002 3.81615 5 P 0 0;1=3
P 4.68268002 3.66615 5 P 0 0;1=3
P 4.78268002 3.51615 5 P 0 0;1=3
P 4.73268002 3.51615 5 P 0 0;1=3
P 4.68268002 3.51615 5 P 0 0;1=3
P 4.78268002 3.36615 5 P 0 0;1=3
P 4.73268002 3.36615 5 P 0 0;1=3
P 4.78268002 3.21615 5 P 0 0;1=3
P 4.73268002 3.21615 5 P 0 0;1=3
P 4.68268002 3.36615 5 P 0 0;1=3
P 4.68268002 3.21615 5 P 0 0;1=3
P 4.78268002 3.06615 5 P 0 0;1=3
P 4.73268002 3.06615 5 P 0 0;1=3
P 4.68268002 3.06615 5 P 0 0;1=3
P 4.78268002 2.91615 5 P 0 0;1=3
P 4.73268002 2.91615 5 P 0 0;1=3
P 4.68268002 2.91615 5 P 0 0;1=3
P 4.88268002 2.76615 5 P 0 0;1=3
P 4.88268002 2.66615 5 P 0 0;1=3
P 4.78268002 2.46615 5 P 0 0;1=3
P 4.88268002 2.56615 5 P 0 0;1=3
P 4.88268002 2.61615 5 P 0 0;1=3
P 4.68268002 2.46615 5 P 0 0;1=3
P 4.88268002 2.46615 5 P 0 0;1=3
P 4.88268002 2.51615 5 P 0 0;1=3
P 4.78268002 2.41615 5 P 0 0;1=3
P 4.88268002 2.41615 5 P 0 0;1=3
P 4.78268002 2.36615 5 P 0 0;1=3
P 4.78268002 2.31615 5 P 0 0;1=3
P 4.78268002 2.26615 5 P 0 0;1=3
P 4.78268002 2.21615 5 P 0 0;1=3
P 4.73268002 2.36615 5 P 0 0;1=3
P 4.68268002 2.31615 5 P 0 0;1=3
P 4.73268002 2.21615 5 P 0 0;1=3
P 4.88268002 2.21615 5 P 0 0;1=3
P 4.88268002 2.26615 5 P 0 0;1=3
P 4.88268002 2.31615 5 P 0 0;1=3
P 4.88268002 2.36615 5 P 0 0;1=3
P 4.73268002 2.16615 5 P 0 0;1=3
P 4.68268002 2.16615 5 P 0 0;1=3
P 4.78268002 1.96615 5 P 0 0;1=3
P 4.78268002 2.06615 5 P 0 0;1=3
P 4.78268002 2.01615 5 P 0 0;1=3
P 4.88268002 1.96615 5 P 0 0;1=3
P 4.88268002 2.06615 5 P 0 0;1=3
P 4.88268002 2.01615 5 P 0 0;1=3
P 4.78268002 2.11615 5 P 0 0;1=3
P 4.88268002 2.11615 5 P 0 0;1=3
P 4.73268002 2.11615 5 P 0 0;1=3
P 4.68268002 2.01615 5 P 0 0;1=3
P 4.73268002 1.96615 5 P 0 0;1=3
P 4.78268002 1.86615 5 P 0 0;1=3
P 4.88268002 1.86615 5 P 0 0;1=3
P 4.68268002 1.86615 5 P 0 0;1=3
P 4.63268002 3.81615 5 P 0 0;1=3
P 4.63268002 3.66615 5 P 0 0;1=3
P 4.58268002 3.81615 5 P 0 0;1=3
P 4.58268002 3.66615 5 P 0 0;1=3
P 4.63268002 3.51615 5 P 0 0;1=3
P 4.58268002 3.51615 5 P 0 0;1=3
P 4.63268002 3.36615 5 P 0 0;1=3
P 4.58268002 3.36615 5 P 0 0;1=3
P 4.63268002 3.21615 5 P 0 0;1=3
P 4.58268002 3.21615 5 P 0 0;1=3
P 4.63268002 3.06615 5 P 0 0;1=3
P 4.58268002 3.06615 5 P 0 0;1=3
P 4.63268002 2.91615 5 P 0 0;1=3
P 4.58268002 2.91615 5 P 0 0;1=3
P 4.58268002 2.46615 5 P 0 0;1=3
P 4.63268002 2.21615 5 P 0 0;1=3
P 4.58268002 2.31615 5 P 0 0;1=3
P 4.63268002 2.36615 5 P 0 0;1=3
P 4.58268002 2.01615 5 P 0 0;1=3
P 4.63268002 2.11615 5 P 0 0;1=3
P 4.63268002 1.96615 5 P 0 0;1=3
P 4.58268002 1.86615 5 P 0 0;1=3
P 2.04606004 3.41615 5 P 0 0;1=3
P 2.09606004 3.51615 5 P 0 0;1=3
P 3.37003996 5.18128002 4 P 0 0;1=4
P 3.43003996 5.18128002 4 P 0 0;1=4
P 3.29916998 5.14223996 4 P 0 0;1=4
P 3.35916998 5.14223996 4 P 0 0;1=4
P 2.93708002 4.70573996 4 P 0 0;1=4
P 3.07571004 4.70573996 4 P 0 0;1=4
P 3.01571004 4.70573996 4 P 0 0;1=4
P 2.87708002 4.70573996 4 P 0 0;1=4
P 2.93086998 5.20876004 4 P 0 0;1=4
P 2.87086998 5.20876004 4 P 0 0;1=4
P 2.80311004 4.74418002 4 P 0 0;1=4
P 2.86311004 4.74418002 4 P 0 0;1=4
P 3.08656998 5.09223996 4 P 0 0;1=4
P 3.14656998 5.09223996 4 P 0 0;1=4
P 2.26855 4.62826004 4 P 0 0;1=4
P 2.20855 4.62826004 4 P 0 0;1=4
P 2.26543996 4.74418002 4 P 0 0;1=4
P 2.20543996 4.74418002 4 P 0 0;1=4
P 2.34716998 4.70326004 4 P 0 0;1=4
P 2.07853002 4.62815 4 P 0 0;1=4
P 2.01853002 4.62815 4 P 0 0;1=4
P 2.12371004 4.74418002 4 P 0 0;1=4
P 2.06371004 4.74418002 4 P 0 0;1=4
P 2.19456998 5.09223996 4 P 0 0;1=4
P 2.13456998 5.09223996 4 P 0 0;1=4
P 2.12371004 5.13026004 4 P 0 0;1=4
P 2.06371004 5.13026004 4 P 0 0;1=4
P 1.6985 5.09223996 4 P 0 0;1=4
P 1.6385 5.09223996 4 P 0 0;1=4
P 1.85111004 4.61826004 4 P 0 0;1=4
P 1.63851004 4.74418002 4 P 0 0;1=4
P 1.69851004 4.74418002 4 P 0 0;1=4
P 1.98196998 5.09223996 4 P 0 0;1=4
P 1.92196998 5.09223996 4 P 0 0;1=4
P 1.84025 4.74418002 4 P 0 0;1=4
P 1.78025 4.74418002 4 P 0 0;1=4
P 11.03661004 2.71615 5 P 0 0;1=3
P 10.93661004 2.71615 5 P 0 0;1=3
P 11.03661004 2.76615 5 P 0 0;1=3
P 10.98661004 2.76615 5 P 0 0;1=3
P 10.93661004 2.76615 5 P 0 0;1=3
P 11.08661004 2.76615 5 P 0 0;1=3
P 11.03661004 2.56615 5 P 0 0;1=3
P 10.93661004 2.56615 5 P 0 0;1=3
P 10.98661004 2.66615 5 P 0 0;1=3
P 10.98661004 2.51615 5 P 0 0;1=3
P 10.93661004 2.51615 5 P 0 0;1=3
P 11.08661004 2.66615 5 P 0 0;1=3
P 11.08661004 2.51615 5 P 0 0;1=3
P 11.08661004 2.46615 5 P 0 0;1=3
P 10.98661004 2.46615 5 P 0 0;1=3
P 11.08661004 2.31615 5 P 0 0;1=3
P 10.93661004 2.36615 5 P 0 0;1=3
P 10.98661004 2.31615 5 P 0 0;1=3
P 10.93661004 2.21615 5 P 0 0;1=3
P 11.03661004 2.21615 5 P 0 0;1=3
P 11.03661004 2.11615 5 P 0 0;1=3
P 10.93661004 2.11615 5 P 0 0;1=3
P 10.98661004 2.01615 5 P 0 0;1=3
P 10.93661004 1.96615 5 P 0 0;1=3
P 11.03661004 1.96615 5 P 0 0;1=3
P 11.08661004 2.01615 5 P 0 0;1=3
P 10.98661004 2.16615 5 P 0 0;1=3
P 10.93661004 2.16615 5 P 0 0;1=3
P 11.08661004 2.16615 5 P 0 0;1=3
P 10.98661004 1.86615 5 P 0 0;1=3
P 11.08661004 1.86615 5 P 0 0;1=3
P 10.73661004 2.71615 5 P 0 0;1=3
P 10.73661004 2.76615 5 P 0 0;1=3
P 10.88661004 2.76615 5 P 0 0;1=3
P 10.78661004 2.76615 5 P 0 0;1=3
P 10.73661004 2.56615 5 P 0 0;1=3
P 10.68661004 2.66615 5 P 0 0;1=3
P 10.73661004 2.51615 5 P 0 0;1=3
P 10.68661004 2.51615 5 P 0 0;1=3
P 10.88661004 2.61615 5 P 0 0;1=3
P 10.88661004 2.56615 5 P 0 0;1=3
P 10.88661004 2.51615 5 P 0 0;1=3
P 10.78661004 2.56615 5 P 0 0;1=3
P 10.78661004 2.61615 5 P 0 0;1=3
P 10.78661004 2.66615 5 P 0 0;1=3
P 10.78661004 2.51615 5 P 0 0;1=3
P 10.78661004 2.46615 5 P 0 0;1=3
P 10.68661004 2.46615 5 P 0 0;1=3
P 10.88661004 2.46615 5 P 0 0;1=3
P 10.78661004 2.21615 5 P 0 0;1=3
P 10.78661004 2.26615 5 P 0 0;1=3
P 10.78661004 2.31615 5 P 0 0;1=3
P 10.78661004 2.36615 5 P 0 0;1=3
P 10.68661004 2.31615 5 P 0 0;1=3
P 10.73661004 2.36615 5 P 0 0;1=3
P 10.73661004 2.21615 5 P 0 0;1=3
P 10.78661004 2.41615 5 P 0 0;1=3
P 10.88661004 2.36615 5 P 0 0;1=3
P 10.88661004 2.31615 5 P 0 0;1=3
P 10.88661004 2.26615 5 P 0 0;1=3
P 10.88661004 2.21615 5 P 0 0;1=3
P 10.73661004 1.96615 5 P 0 0;1=3
P 10.68661004 2.01615 5 P 0 0;1=3
P 10.73661004 2.11615 5 P 0 0;1=3
P 10.78661004 2.11615 5 P 0 0;1=3
P 10.78661004 2.01615 5 P 0 0;1=3
P 10.78661004 1.96615 5 P 0 0;1=3
P 10.78661004 2.06615 5 P 0 0;1=3
P 10.68661004 2.16615 5 P 0 0;1=3
P 10.73661004 2.16615 5 P 0 0;1=3
P 10.88661004 2.01615 5 P 0 0;1=3
P 10.88661004 2.06615 5 P 0 0;1=3
P 10.88661004 2.11615 5 P 0 0;1=3
P 10.88661004 1.96615 5 P 0 0;1=3
P 10.78661004 1.91615 5 P 0 0;1=3
P 10.68661004 1.86615 5 P 0 0;1=3
P 10.78661004 1.86615 5 P 0 0;1=3
P 10.88661004 1.86615 5 P 0 0;1=3
P 10.63661004 2.71615 5 P 0 0;1=3
P 10.63661004 2.76615 5 P 0 0;1=3
P 10.63661004 2.56615 5 P 0 0;1=3
P 10.58661004 2.66615 5 P 0 0;1=3
P 10.63661004 2.51615 5 P 0 0;1=3
P 10.58661004 2.51615 5 P 0 0;1=3
P 10.58661004 2.46615 5 P 0 0;1=3
P 10.63661004 2.36615 5 P 0 0;1=3
P 10.58661004 2.31615 5 P 0 0;1=3
P 10.58661004 2.01615 5 P 0 0;1=3
P 10.63661004 1.96615 5 P 0 0;1=3
P 10.63661004 2.11615 5 P 0 0;1=3
P 10.58661004 1.86615 5 P 0 0;1=3
P 1.92346004 5.377 4 P 0 0;1=4
P 2.14346004 5.377 4 P 0 0;1=4
P 7.927 5.377 4 P 0 0;1=4
P 8.147 5.377 4 P 0 0;1=4
P 3.43003996 4.74418002 4 P 0 0;1=4
P 3.51176998 4.68098996 4 P 0 0;1=4
P 3.57176998 4.68098996 4 P 0 0;1=4
P 3.21743996 4.74418002 4 P 0 0;1=4
P 3.37003996 4.74418002 4 P 0 0;1=4
P 3.41 5.332 4 P 0 0;1=4
P 5.38048002 1.5957 4 P 0 0;1=4
P 5.38048002 1.7891 4 P 0 0;1=4
P 5.38048002 1.732 4 P 0 0;1=4
P 5.38048002 1.6528 4 P 0 0;1=4
P 5.53531004 1.8603 4 P 0 0;1=4
P 5.53531004 1.8032 4 P 0 0;1=4
P 5.53531004 2.2727 4 P 0 0;1=4
P 5.53531004 2.1373 4 P 0 0;1=4
P 5.53531004 1.9964 4 P 0 0;1=4
P 5.38048002 2.3403 4 P 0 0;1=4
P 5.38048002 2.2832 4 P 0 0;1=4
P 5.38048002 2.2049 4 P 0 0;1=4
P 5.38048002 2.1478 4 P 0 0;1=4
P 5.38048002 2.0642 4 P 0 0;1=4
P 5.38048002 2.0071 4 P 0 0;1=4
P 5.38048002 1.9288 4 P 0 0;1=4
P 5.38048002 1.8717 4 P 0 0;1=4
P 5.53531004 2.351 4 P 0 0;1=4
P 5.38048002 2.4757 4 P 0 0;1=4
P 5.38048002 2.4186 4 P 0 0;1=4
P 5.53531004 2.4902 4 P 0 0;1=4
P 5.53531004 2.6825 4 P 0 0;1=4
P 5.53531004 2.6254 4 P 0 0;1=4
P 5.38048002 2.5578 4 P 0 0;1=4
P 5.38048002 2.6149 4 P 0 0;1=4
P 10.43 1.3341 4 P 0 0;1=4
P 10.43 1.277 4 P 0 0;1=4
P 10.4159 1.43 4 P 0 0;1=4
P 10.473 1.43 4 P 0 0;1=4
P 10.37313996 1.55336004 4 P 0 0;1=4
P 10.41451004 1.51198002 4 P 0 0;1=4
P 10.295 1.713 4 P 0 0;1=4
P 10.295 1.6559 4 P 0 0;1=4
P 10.26 1.9179 4 P 0 0;1=4
P 10.29525 1.877 4 P 0 0;1=4
P 10.29525 1.8199 4 P 0 0;1=4
P 10.26 1.975 4 P 0 0;1=4
P 10.125 2.0651 4 P 0 0;1=4
P 10.125 2.1224 4 P 0 0;1=4
P 10.125 2.1795 4 P 0 0;1=4
P 10.01 2.2481 4 P 0 0;1=4
P 10.01 2.191 4 P 0 0;1=4
P 10.01 2.38435 4 P 0 0;1=4
P 10.01 2.32725 4 P 0 0;1=4
P 10.125 2.3168 4 P 0 0;1=4
P 10.125 2.2597 4 P 0 0;1=4
P 10.125 2.4519 4 P 0 0;1=4
P 10.125 2.3948 4 P 0 0;1=4
P 10.01 2.51945 4 P 0 0;1=4
P 10.01 2.46235 4 P 0 0;1=4
P 10.125 2.587 4 P 0 0;1=4
P 10.125 2.5299 4 P 0 0;1=4
P 10.01 2.673 4 P 0 0;1=4
P 10.01 2.6159 4 P 0 0;1=4
P 11.74316004 1.7035 4 P 0 0;1=4
P 11.74316004 1.6405 4 P 0 0;1=4
P 11.69316004 1.4805 4 P 0 0;1=4
P 11.69316004 1.5435 4 P 0 0;1=4
P 11.49316004 1.5605 4 P 0 0;1=4
P 11.49316004 1.6235 4 P 0 0;1=4
P 11.49316004 1.4635 4 P 0 0;1=4
P 11.49366004 1.401 4 P 0 0;1=4
P 11.69316004 2.6005 4 P 0 0;1=4
P 11.69316004 2.5035 4 P 0 0;1=4
P 11.69316004 2.4405 4 P 0 0;1=4
P 11.69316004 2.3435 4 P 0 0;1=4
P 11.69316004 2.2805 4 P 0 0;1=4
P 11.69316004 2.1835 4 P 0 0;1=4
P 11.69316004 1.9605 4 P 0 0;1=4
P 11.69316004 2.0235 4 P 0 0;1=4
P 11.69316004 2.1205 4 P 0 0;1=4
P 11.69316004 1.8005 4 P 0 0;1=4
P 11.69316004 1.8635 4 P 0 0;1=4
P 11.49316004 2.5205 4 P 0 0;1=4
P 11.49316004 2.5835 4 P 0 0;1=4
P 11.49316004 2.4235 4 P 0 0;1=4
P 11.49316004 2.3605 4 P 0 0;1=4
P 11.79316004 2.2635 4 P 0 0;1=4
P 11.79316004 2.2005 4 P 0 0;1=4
P 11.49316004 1.9435 4 P 0 0;1=4
P 11.49316004 2.1035 4 P 0 0;1=4
P 11.49316004 2.0405 4 P 0 0;1=4
P 11.49316004 1.8805 4 P 0 0;1=4
P 11.49366004 1.721 4 P 0 0;1=4
P 11.49316004 1.7835 4 P 0 0;1=4
P 10.125 2.7451 4 P 0 0;1=4
P 10.125 2.688 4 P 0 0;1=4
P 12.34 2.19 4 P 0 0;1=4
P 9.415 5.332 4 P 0 0;1=4
P 9.265 5.332 4 P 0 0;1=4
P 9.07 5.332 4 P 0 0;1=4
P 4.7 5.54928996 4 P 0 0;1=4
P 4.81 5.375 4 P 0 0;1=4
P 4.96 5.375 4 P 0 0;1=4
P 5.16 5.645 4 P 0 0;1=4
P 5.04441004 5.605 4 P 0 0;1=4
P 4.92 5.7 4 P 0 0;1=4
P 9.91 4.7 4 P 0 0;1=4
P 3.57 4.45 4 P 0 0;1=4
P 10.465 5.195 4 P 0 0;1=4
P 10.515 5.32 4 P 0 0;1=4
P 10.465 5.275 4 P 0 0;1=4
P 12.025 4.915 4 P 0 0;1=4
P 12.12 4.965 4 P 0 0;1=4
P 12.185 4.915 4 P 0 0;1=4
P 3.72 4.45 4 P 0 0;1=4
P 3.66 4.63 4 P 0 0;1=4
P 3.77 4.86 4 P 0 0;1=4
P 9.96 4.69 4 P 0 0;1=4
P 10.03 4.51 4 P 0 0;1=4
P 3.835 4.6 4 P 0 0;1=4
P 3.9865 4.635 4 P 0 0;1=4
P 4.14 4.655 4 P 0 0;1=4
P 4.1049 4.7649 4 P 0 0;1=4
P 1.28051004 5.78 4 P 0 0;1=4
P 3.87 5.125 4 P 0 0;1=4
P 0.4826 5.8976 4 P 0 0;1=4
P 0.84953002 5.17 4 P 0 0;1=4
P 0.955 5.325 4 P 0 0;1=4
P 1.31 5.355 4 P 0 0;1=4
P 1.20176998 5.78 4 P 0 0;1=4
P 6.31295 4.99705 4 P 0 0;1=4
P 6.87 5 4 P 0 0;1=4
P 9.64796004 0.79643002 4 P 0 0;1=4
P 9.40795 0.26133002 4 P 0 0;1=4
P 3.60998996 0.24 4 P 0 0;1=4
P 3.65998996 0.345 4 P 0 0;1=4
P 3.86 0.7751 4 P 0 0;1=0
P 6.905 4.94705 4 P 0 0;1=4
P 6.905 4.88705 4 P 0 0;1=4
P 6.955 4.8 4 P 0 0;1=4
P 6.955 4.84 4 P 0 0;1=4
P 6.955 4.72 4 P 0 0;1=4
P 6.955 4.76 4 P 0 0;1=4
P 6.59708996 5.0502 4 P 0 0;1=4
P 6.65218996 4.77 4 P 0 0;1=4
P 6.62118996 4.95641998 4 P 0 0;1=8
P 6.6015 4.93673996 4 P 0 0;1=8
P 6.64088002 4.93673996 4 P 0 0;1=8
P 6.62118996 4.91705 4 P 0 0;1=8
P 6.62118996 4.87768002 4 P 0 0;1=8
P 6.6015 4.89736004 4 P 0 0;1=8
P 6.64088002 4.89736004 4 P 0 0;1=8
P 6.62 4.69 4 P 0 0;1=4
P 6.62 4.725 4 P 0 0;1=4
P 6.385 5.07 4 P 0 0;1=4
P 5.53593996 4.55505 4 P 0 0;1=4
P 6.05708996 4.5102 4 P 0 0;1=4
P 6.01708996 4.5102 4 P 0 0;1=4
P 5.97708996 4.5102 4 P 0 0;1=4
P 5.93708996 4.5102 4 P 0 0;1=4
P 5.89708996 4.5102 4 P 0 0;1=4
P 6.09708996 4.5102 4 P 0 0;1=4
P 5.61708996 4.5102 4 P 0 0;1=4
P 5.65708996 4.5102 4 P 0 0;1=4
P 5.85708996 4.5102 4 P 0 0;1=4
P 5.81708996 4.5102 4 P 0 0;1=4
P 5.77708996 4.5102 4 P 0 0;1=4
P 5.73708996 4.5102 4 P 0 0;1=4
P 5.69708996 4.5102 4 P 0 0;1=4
P 5.57708996 4.5102 4 P 0 0;1=4
P 0.036 0.10868002 4 P 0 0;1=4
P 0.036 0.15868002 4 P 0 0;1=4
P 0.036 0.20868002 4 P 0 0;1=4
P 0.22873996 0.036 4 P 0 0;1=4
P 0.17873996 0.036 4 P 0 0;1=4
P 0.12873996 0.036 4 P 0 0;1=4
P 0.07873996 0.036 4 P 0 0;1=4
P 0.47873996 0.036 4 P 0 0;1=4
P 0.42873996 0.036 4 P 0 0;1=4
P 0.37873996 0.036 4 P 0 0;1=4
P 0.32873996 0.036 4 P 0 0;1=4
P 0.27873996 0.036 4 P 0 0;1=4
P 0.77873996 0.036 4 P 0 0;1=4
P 0.72873996 0.036 4 P 0 0;1=4
P 0.67873996 0.036 4 P 0 0;1=4
P 0.62873996 0.036 4 P 0 0;1=4
P 0.57873996 0.036 4 P 0 0;1=4
P 0.52873996 0.036 4 P 0 0;1=4
P 1.02873996 0.036 4 P 0 0;1=4
P 0.97873996 0.036 4 P 0 0;1=4
P 0.92873996 0.036 4 P 0 0;1=4
P 0.87873996 0.036 4 P 0 0;1=4
P 0.82873996 0.036 4 P 0 0;1=4
P 1.27873996 0.036 4 P 0 0;1=4
P 1.22873996 0.036 4 P 0 0;1=4
P 1.17873996 0.036 4 P 0 0;1=4
P 1.12873996 0.036 4 P 0 0;1=4
P 1.07873996 0.036 4 P 0 0;1=4
P 1.52873996 0.036 4 P 0 0;1=4
P 1.47873996 0.036 4 P 0 0;1=4
P 1.42873996 0.036 4 P 0 0;1=4
P 1.37873996 0.036 4 P 0 0;1=4
P 1.32873996 0.036 4 P 0 0;1=4
P 1.82873996 0.036 4 P 0 0;1=4
P 1.77873996 0.036 4 P 0 0;1=4
P 1.72873996 0.036 4 P 0 0;1=4
P 1.67873996 0.036 4 P 0 0;1=4
P 1.62873996 0.036 4 P 0 0;1=4
P 1.57873996 0.036 4 P 0 0;1=4
P 2.07873996 0.036 4 P 0 0;1=4
P 2.02873996 0.036 4 P 0 0;1=4
P 1.97873996 0.036 4 P 0 0;1=4
P 1.92873996 0.036 4 P 0 0;1=4
P 1.87873996 0.036 4 P 0 0;1=4
P 2.32873996 0.036 4 P 0 0;1=4
P 2.27873996 0.036 4 P 0 0;1=4
P 2.22873996 0.036 4 P 0 0;1=4
P 2.17873996 0.036 4 P 0 0;1=4
P 2.12873996 0.036 4 P 0 0;1=4
P 2.62873996 0.036 4 P 0 0;1=4
P 2.57873996 0.036 4 P 0 0;1=4
P 2.52873996 0.036 4 P 0 0;1=4
P 2.47873996 0.036 4 P 0 0;1=4
P 2.42873996 0.036 4 P 0 0;1=4
P 2.37873996 0.036 4 P 0 0;1=4
P 2.87873996 0.036 4 P 0 0;1=4
P 2.82873996 0.036 4 P 0 0;1=4
P 2.77873996 0.036 4 P 0 0;1=4
P 2.72873996 0.036 4 P 0 0;1=4
P 2.67873996 0.036 4 P 0 0;1=4
P 3.12873996 0.036 4 P 0 0;1=4
P 3.07873996 0.036 4 P 0 0;1=4
P 3.02873996 0.036 4 P 0 0;1=4
P 2.97873996 0.036 4 P 0 0;1=4
P 2.92873996 0.036 4 P 0 0;1=4
P 3.37873996 0.036 4 P 0 0;1=4
P 3.32873996 0.036 4 P 0 0;1=4
P 3.27873996 0.036 4 P 0 0;1=4
P 3.22873996 0.036 4 P 0 0;1=4
P 3.17873996 0.036 4 P 0 0;1=4
P 3.67873996 0.036 4 P 0 0;1=4
P 3.62873996 0.036 4 P 0 0;1=4
P 3.57873996 0.036 4 P 0 0;1=4
P 3.52873996 0.036 4 P 0 0;1=4
P 3.47873996 0.036 4 P 0 0;1=4
P 3.42873996 0.036 4 P 0 0;1=4
P 3.92873996 0.036 4 P 0 0;1=4
P 3.87873996 0.036 4 P 0 0;1=4
P 3.82873996 0.036 4 P 0 0;1=4
P 3.77873996 0.036 4 P 0 0;1=4
P 3.72873996 0.036 4 P 0 0;1=4
P 4.17873996 0.036 4 P 0 0;1=4
P 4.12873996 0.036 4 P 0 0;1=4
P 4.07873996 0.036 4 P 0 0;1=4
P 4.02873996 0.036 4 P 0 0;1=4
P 3.97873996 0.036 4 P 0 0;1=4
P 4.42873996 0.036 4 P 0 0;1=4
P 4.37873996 0.036 4 P 0 0;1=4
P 4.32873996 0.036 4 P 0 0;1=4
P 4.27873996 0.036 4 P 0 0;1=4
P 4.22873996 0.036 4 P 0 0;1=4
P 4.72873996 0.036 4 P 0 0;1=4
P 4.67873996 0.036 4 P 0 0;1=4
P 4.62873996 0.036 4 P 0 0;1=4
P 4.57873996 0.036 4 P 0 0;1=4
P 4.52873996 0.036 4 P 0 0;1=4
P 4.47873996 0.036 4 P 0 0;1=4
P 4.81833996 0.21825 4 P 0 0;1=4
P 4.81833996 0.16825 4 P 0 0;1=4
P 4.81833996 0.11825 4 P 0 0;1=4
P 4.81703996 0.06826004 4 P 0 0;1=4
P 4.77873996 0.03611998 4 P 0 0;1=4
P 6.80731004 0.036 4 P 0 0;1=4
P 6.75731004 0.036 4 P 0 0;1=4
P 6.70731004 0.036 4 P 0 0;1=4
P 6.65731004 0.03676004 4 P 0 0;1=4
P 6.62298996 0.07311998 4 P 0 0;1=4
P 6.62261998 0.12311998 4 P 0 0;1=4
P 6.62261998 0.17311998 4 P 0 0;1=4
P 6.62261998 0.22311998 4 P 0 0;1=4
P 7.00731004 0.036 4 P 0 0;1=4
P 6.95731004 0.036 4 P 0 0;1=4
P 6.90731004 0.036 4 P 0 0;1=4
P 6.85731004 0.036 4 P 0 0;1=4
P 0.036 0.25868002 4 P 0 0;1=4
P 0.036 0.30868002 4 P 0 0;1=4
P 0.036 0.35868002 4 P 0 0;1=4
P 0.036 0.40868002 4 P 0 0;1=4
P 0.036 0.45868002 4 P 0 0;1=4
P 4.96803996 0.46906998 4 P 0 0;1=4
P 4.91805 0.46808002 4 P 0 0;1=4
P 4.87108996 0.45088996 4 P 0 0;1=4
P 4.83591004 0.41536004 4 P 0 0;1=4
P 4.81918996 0.36823996 4 P 0 0;1=4
P 4.81833996 0.31825 4 P 0 0;1=4
P 4.81833996 0.26825 4 P 0 0;1=4
P 5.21803996 0.46906998 4 P 0 0;1=4
P 5.16803996 0.46906998 4 P 0 0;1=4
P 5.11803996 0.46906998 4 P 0 0;1=4
P 5.06803996 0.46906998 4 P 0 0;1=4
P 5.01803996 0.46906998 4 P 0 0;1=4
P 5.51803996 0.46906998 4 P 0 0;1=4
P 5.46803996 0.46906998 4 P 0 0;1=4
P 5.41803996 0.46906998 4 P 0 0;1=4
P 5.36803996 0.46906998 4 P 0 0;1=4
P 5.31803996 0.46906998 4 P 0 0;1=4
P 5.26803996 0.46906998 4 P 0 0;1=4
P 5.76803996 0.46906998 4 P 0 0;1=4
P 5.71803996 0.46906998 4 P 0 0;1=4
P 5.66803996 0.46906998 4 P 0 0;1=4
P 5.61803996 0.46906998 4 P 0 0;1=4
P 5.56803996 0.46906998 4 P 0 0;1=4
P 6.01803996 0.46906998 4 P 0 0;1=4
P 5.96803996 0.46906998 4 P 0 0;1=4
P 5.91803996 0.46906998 4 P 0 0;1=4
P 5.86803996 0.46906998 4 P 0 0;1=4
P 5.81803996 0.46906998 4 P 0 0;1=4
P 6.31803996 0.46906998 4 P 0 0;1=4
P 6.26803996 0.46906998 4 P 0 0;1=4
P 6.21803996 0.46906998 4 P 0 0;1=4
P 6.16803996 0.46906998 4 P 0 0;1=4
P 6.11803996 0.46906998 4 P 0 0;1=4
P 6.06803996 0.46906998 4 P 0 0;1=4
P 6.56568002 0.45345 4 P 0 0;1=4
P 6.51803002 0.46861998 4 P 0 0;1=4
P 6.46803996 0.46906998 4 P 0 0;1=4
P 6.41803996 0.46906998 4 P 0 0;1=4
P 6.36803996 0.46906998 4 P 0 0;1=4
P 6.62261998 0.27311998 4 P 0 0;1=4
P 6.62261998 0.32311998 4 P 0 0;1=4
P 6.62106998 0.3731 4 P 0 0;1=4
P 6.60233996 0.41946004 4 P 0 0;1=4
P 0.036 0.50868002 4 P 0 0;1=4
P 0.036 0.55868002 4 P 0 0;1=4
P 11.845 2.85 4 P 0 0;1=4
P 8.98115 2.7861 4 P 0 0;1=4
P 8.98115 2.8989 4 P 0 0;1=4
P 11.58613002 2.855 4 P 0 0;1=4
P 11.50361998 2.8 4 P 0 0;1=4
P 11.50361998 2.73 4 P 0 0;1=4
P 5.5722 3 4 P 0 0;1=4
P 5.75778996 3.02558996 4 P 0 0;1=4
P 5.9192 2.943 4 P 0 0;1=4
P 4.07386004 2.55 4 P 0 0;1=4
P 3.86826998 2.64558996 4 P 0 0;1=4
P 9.995 2.87558996 4 P 0 0;1=4
P 10.11778996 2.78 4 P 0 0;1=4
P 7.2426 4.60351004 4 P 0 0;1=4
P 7.3401 4.85601004 4 P 0 0;1=4
P 7.1926 5.04351004 4 P 0 0;1=4
P 0.66 2.045 4 P 0 0;1=0
P 1.792 2.4781 4 P 0 0;1=4
P 2.97721004 2.8989 4 P 0 0;1=4
P 2.97721004 2.7861 4 P 0 0;1=4
P 2.9422 2.925 4 P 0 0;1=4
P 8.94278996 2.925 4 P 0 0;1=4
P 5.5822 2.855 4 P 0 0;1=4
P 5.84968996 2.85 4 P 0 0;1=4
P 0.65348996 1.85608996 4 P 0 0;1=4
P 0.65348996 1.91628996 4 P 0 0;1=4
P 0.09448996 4.60236998 10 P 0 0;1=1
P 0.35038996 4.20866004 10 P 0 0;1=1
P 0.09448996 4.2874 10 P 0 0;1=1
P 0.09448996 4.12991998 10 P 0 0;1=1
P 0.17323002 4.16928996 10 P 0 0;1=1
P 0.27165 4.09055 10 P 0 0;1=1
P 0.27165 3.93306998 10 P 0 0;1=1
P 0.35038996 4.05118002 10 P 0 0;1=1
P 0.35038996 3.8937 10 P 0 0;1=1
P 0.09448996 3.97243996 10 P 0 0;1=1
P 0.09448996 3.81496004 10 P 0 0;1=1
P 0.17323002 4.01181004 10 P 0 0;1=1
P 0.17323002 3.85433002 10 P 0 0;1=1
P 0.27165 3.77558996 10 P 0 0;1=1
P 0.27165 3.61811004 10 P 0 0;1=1
P 0.35038996 3.73621998 10 P 0 0;1=1
P 0.35038996 3.57873996 10 P 0 0;1=1
P 0.09448996 3.65748002 10 P 0 0;1=1
P 0.09448996 3.5 10 P 0 0;1=1
P 0.17323002 3.69685 10 P 0 0;1=1
P 0.17323002 3.53936998 10 P 0 0;1=1
P 0.27165 3.46063002 10 P 0 0;1=1
P 0.35038996 3.42126004 10 P 0 0;1=1
P 0.27165 3.30315 10 P 0 0;1=1
P 0.27165 3.22441004 10 P 0 0;1=1
P 0.17323002 3.38188996 10 P 0 0;1=1
P 0.17323002 3.30315 10 P 0 0;1=1
P 0.35038996 3.1063 10 P 0 0;1=1
P 0.35038996 2.94881998 10 P 0 0;1=1
P 0.27165 3.06693002 10 P 0 0;1=1
P 0.27165 2.90945 10 P 0 0;1=1
P 0.17323002 3.14566998 10 P 0 0;1=1
P 0.17323002 2.98818996 10 P 0 0;1=1
P 0.09448996 3.18503996 10 P 0 0;1=1
P 0.09448996 3.02756004 10 P 0 0;1=1
P 0.35038996 2.79133996 10 P 0 0;1=1
P 0.27165 2.75196998 10 P 0 0;1=1
P 0.35038996 2.63386004 10 P 0 0;1=1
P 0.17323002 2.83071004 10 P 0 0;1=1
P 0.09448996 2.87008002 10 P 0 0;1=1
P 0.09448996 2.7126 10 P 0 0;1=1
P 0.35038996 2.39763996 10 P 0 0;1=1
P 0.27165 2.51575 10 P 0 0;1=1
P 0.27165 2.35826998 10 P 0 0;1=1
P 0.17323002 2.59448996 10 P 0 0;1=1
P 0.17323002 2.43701004 10 P 0 0;1=1
P 0.09448996 2.47638002 10 P 0 0;1=1
P 0.09448996 2.3189 10 P 0 0;1=1
P 0.35038996 2.24016004 10 P 0 0;1=1
P 0.35038996 2.08268002 10 P 0 0;1=1
P 0.35038996 2.00393996 10 P 0 0;1=1
P 0.27165 2.20078996 10 P 0 0;1=1
P 0.17323002 2.27953002 10 P 0 0;1=1
P 0.09448996 2.16141998 10 P 0 0;1=1
P 0.09448996 2.08268002 10 P 0 0;1=1
P 0.17323002 1.96456998 10 P 0 0;1=1
P 0.09448996 1.84646004 10 P 0 0;1=1
P 0.09448996 4.44488002 10 P 0 0;1=1
P 12.63778996 2.00393996 10 P 0 0;1=1
P 12.55905 2.12205 10 P 0 0;1=1
P 12.55905 1.88583002 10 P 0 0;1=1
P 12.81495 2.12205 10 P 0 0;1=1
P 12.81495 2.04331004 10 P 0 0;1=1
P 12.73621004 2.39763996 10 P 0 0;1=1
P 12.73621004 2.24016004 10 P 0 0;1=1
P 12.63778996 2.3189 10 P 0 0;1=1
P 12.55905 2.35826998 10 P 0 0;1=1
P 12.55905 2.20078996 10 P 0 0;1=1
P 12.81495 2.43701004 10 P 0 0;1=1
P 12.81495 2.27953002 10 P 0 0;1=1
P 12.73621004 2.55511998 10 P 0 0;1=1
P 12.63778996 2.63386004 10 P 0 0;1=1
P 12.63778996 2.47638002 10 P 0 0;1=1
P 12.55905 2.51575 10 P 0 0;1=1
P 12.81495 2.67323002 10 P 0 0;1=1
P 12.73621004 2.94881998 10 P 0 0;1=1
P 12.73621004 2.79133996 10 P 0 0;1=1
P 12.63778996 3.02756004 10 P 0 0;1=1
P 12.63778996 2.87008002 10 P 0 0;1=1
P 12.55905 2.90945 10 P 0 0;1=1
P 12.55905 2.75196998 10 P 0 0;1=1
P 12.81495 2.98818996 10 P 0 0;1=1
P 12.81495 2.83071004 10 P 0 0;1=1
P 12.73621004 3.26378002 10 P 0 0;1=1
P 12.73621004 3.1063 10 P 0 0;1=1
P 12.63778996 3.18503996 10 P 0 0;1=1
P 12.55905 3.22441004 10 P 0 0;1=1
P 12.55905 3.06693002 10 P 0 0;1=1
P 12.81495 3.14566998 10 P 0 0;1=1
P 12.55905 3.53936998 10 P 0 0;1=1
P 12.63778996 3.57873996 10 P 0 0;1=1
P 12.63778996 3.42126004 10 P 0 0;1=1
P 12.73621004 3.5 10 P 0 0;1=1
P 12.73621004 3.34251998 10 P 0 0;1=1
P 12.63778996 3.34251998 10 P 0 0;1=1
P 12.81495 3.61811004 10 P 0 0;1=1
P 12.81495 3.46063002 10 P 0 0;1=1
P 12.55905 3.85433002 10 P 0 0;1=1
P 12.55905 3.69685 10 P 0 0;1=1
P 12.63778996 3.8937 10 P 0 0;1=1
P 12.63778996 3.73621998 10 P 0 0;1=1
P 12.73621004 3.81496004 10 P 0 0;1=1
P 12.73621004 3.65748002 10 P 0 0;1=1
P 12.81495 3.93306998 10 P 0 0;1=1
P 12.81495 3.77558996 10 P 0 0;1=1
P 12.55905 4.16928996 10 P 0 0;1=1
P 12.55905 4.01181004 10 P 0 0;1=1
P 12.63778996 4.20866004 10 P 0 0;1=1
P 12.63778996 4.05118002 10 P 0 0;1=1
P 12.73621004 4.12991998 10 P 0 0;1=1
P 12.73621004 3.97243996 10 P 0 0;1=1
P 12.81495 4.09055 10 P 0 0;1=1
P 12.55905 4.48425 10 P 0 0;1=1
P 12.55905 4.32676998 10 P 0 0;1=1
P 12.63778996 4.52361998 10 P 0 0;1=1
P 12.63778996 4.36613996 10 P 0 0;1=1
P 12.73621004 4.44488002 10 P 0 0;1=1
P 12.73621004 4.2874 10 P 0 0;1=1
P 12.81495 4.40551004 10 P 0 0;1=1
P 12.81495 4.24803002 10 P 0 0;1=1
P 12.55905 4.64173996 10 P 0 0;1=1
P 12.81495 4.56298996 10 P 0 0;1=1
P 0.27165 4.40551004 10 P 0 0;1=1
P 0.35038996 4.52361998 10 P 0 0;1=1
P 0.17323002 4.48425 10 P 0 0;1=1
P 0.27165 4.24803002 10 P 0 0;1=1
P 0.35038996 4.36613996 10 P 0 0;1=1
P 0.17323002 4.32676998 10 P 0 0;1=1
P 5.49221004 2.73 4 P 0 0;1=4
P 5.44886004 2.9414 4 P 0 0;1=4
P 5.44886004 3.0214 4 P 0 0;1=4
P 5.44886004 3.0564 4 P 0 0;1=4
P 5.44886004 3.1014 4 P 0 0;1=4
P 5.44886004 3.1364 4 P 0 0;1=4
P 5.44886004 3.2164 4 P 0 0;1=4
P 5.44886004 3.1814 4 P 0 0;1=4
P 5.44886004 2.9764 4 P 0 0;1=4
P 5.44886004 3.2614 4 P 0 0;1=4
P 5.44886004 3.2964 4 P 0 0;1=4
P 10.33998996 4.9231 4 P 0 0;1=4
P 10.38498996 4.9231 4 P 0 0;1=0
P 10.77498996 4.9231 4 P 0 0;1=4
P 10.72998996 4.9231 4 P 0 0;1=4
P 10.30498996 4.9431 4 P 0 0;1=4
P 10.26498996 4.9431 4 P 0 0;1=4
P 10.30498996 5.0281 4 P 0 0;1=4
P 10.30498996 5.0731 4 P 0 0;1=4
P 10.30498996 4.9831 4 P 0 0;1=4
P 10.26498996 5.0281 4 P 0 0;1=4
P 10.26498996 5.0731 4 P 0 0;1=4
P 10.26498996 4.9831 4 P 0 0;1=4
P 10.26498996 5.1181 4 P 0 0;1=4
P 10.30498996 5.1181 4 P 0 0;1=4
P 10.34498996 5.1181 4 P 0 0;1=4
P 10.42498996 4.9431 4 P 0 0;1=4
P 10.46498996 4.9431 4 P 0 0;1=4
P 10.38498996 5.1181 4 P 0 0;1=4
P 10.46498996 5.1181 4 P 0 0;1=4
P 10.42498996 5.1181 4 P 0 0;1=4
P 10.42498996 4.9831 4 P 0 0;1=4
P 10.42498996 5.0731 4 P 0 0;1=4
P 10.42498996 5.0281 4 P 0 0;1=4
P 10.46498996 4.9831 4 P 0 0;1=4
P 10.46498996 5.0731 4 P 0 0;1=4
P 10.46498996 5.0281 4 P 0 0;1=4
P 10.85498996 4.9431 4 P 0 0;1=4
P 10.81498996 4.9431 4 P 0 0;1=4
P 10.65498996 4.9431 4 P 0 0;1=4
P 10.69498996 4.9431 4 P 0 0;1=4
P 10.85498996 5.0281 4 P 0 0;1=4
P 10.85498996 5.0731 4 P 0 0;1=4
P 10.85498996 4.9831 4 P 0 0;1=4
P 10.81498996 5.0281 4 P 0 0;1=4
P 10.81498996 5.0731 4 P 0 0;1=4
P 10.81498996 4.9831 4 P 0 0;1=4
P 10.81498996 5.1181 4 P 0 0;1=4
P 10.85498996 5.1181 4 P 0 0;1=4
P 10.73498996 5.1181 4 P 0 0;1=4
P 10.69498996 5.1181 4 P 0 0;1=4
P 10.65498996 5.1181 4 P 0 0;1=4
P 10.77498996 5.1181 4 P 0 0;1=4
P 10.65498996 4.9831 4 P 0 0;1=4
P 10.65498996 5.0731 4 P 0 0;1=4
P 10.65498996 5.0281 4 P 0 0;1=4
P 10.69498996 4.9831 4 P 0 0;1=4
P 10.69498996 5.0731 4 P 0 0;1=4
P 10.69498996 5.0281 4 P 0 0;1=4
P 1.23906004 4.60351004 4 P 0 0;1=4
P 1.18906004 5.04351004 4 P 0 0;1=4
P 1.33656004 4.85601004 4 P 0 0;1=4
P 10.16606998 2.81 4 P 0 0;1=4
P 4.15221004 2.9281 4 P 0 0;1=4
P 11.45278996 2.9414 4 P 0 0;1=4
P 11.45278996 3.0214 4 P 0 0;1=4
P 11.45278996 3.0564 4 P 0 0;1=4
P 11.45278996 3.1014 4 P 0 0;1=4
P 11.45278996 3.1364 4 P 0 0;1=4
P 11.45278996 3.2164 4 P 0 0;1=4
P 11.45278996 3.1814 4 P 0 0;1=4
P 11.45278996 2.9764 4 P 0 0;1=4
P 11.45278996 3.2614 4 P 0 0;1=4
P 11.45278996 3.2964 4 P 0 0;1=4
P 0.09448996 1.45276004 10 P 0 0;1=1
P 0.27165 1.57086998 10 P 0 0;1=1
P 0.35038996 1.45276004 10 P 0 0;1=1
P 12.81495 1.49213002 10 P 0 0;1=1
P 12.73621004 1.61023996 10 P 0 0;1=1
P 12.55905 1.49213002 10 P 0 0;1=1
P 0.27165 1.88583002 10 P 0 0;1=1
P 12.73621004 1.9252 10 P 0 0;1=1
P 7.35731004 0.036 4 P 0 0;1=4
P 7.60731004 0.036 4 P 0 0;1=4
P 7.55731004 0.036 4 P 0 0;1=4
P 7.50731004 0.036 4 P 0 0;1=4
P 7.45731004 0.036 4 P 0 0;1=4
P 7.40731004 0.036 4 P 0 0;1=4
P 7.85731004 0.036 4 P 0 0;1=4
P 7.80731004 0.036 4 P 0 0;1=4
P 7.75731004 0.036 4 P 0 0;1=4
P 7.70731004 0.036 4 P 0 0;1=4
P 7.65731004 0.036 4 P 0 0;1=4
P 8.15731004 0.036 4 P 0 0;1=4
P 8.10731004 0.036 4 P 0 0;1=4
P 8.05731004 0.036 4 P 0 0;1=4
P 8.00731004 0.036 4 P 0 0;1=4
P 7.95731004 0.036 4 P 0 0;1=4
P 7.90731004 0.036 4 P 0 0;1=4
P 8.40731004 0.036 4 P 0 0;1=4
P 8.35731004 0.036 4 P 0 0;1=4
P 8.30731004 0.036 4 P 0 0;1=4
P 8.25731004 0.036 4 P 0 0;1=4
P 8.20731004 0.036 4 P 0 0;1=4
P 8.65731004 0.036 4 P 0 0;1=4
P 8.60731004 0.036 4 P 0 0;1=4
P 8.55731004 0.036 4 P 0 0;1=4
P 8.50731004 0.036 4 P 0 0;1=4
P 8.45731004 0.036 4 P 0 0;1=4
P 8.90731004 0.036 4 P 0 0;1=4
P 8.85731004 0.036 4 P 0 0;1=4
P 8.80731004 0.036 4 P 0 0;1=4
P 8.75731004 0.036 4 P 0 0;1=4
P 8.70731004 0.036 4 P 0 0;1=4
P 9.20731004 0.036 4 P 0 0;1=4
P 9.15731004 0.036 4 P 0 0;1=4
P 9.10731004 0.036 4 P 0 0;1=4
P 9.05731004 0.036 4 P 0 0;1=4
P 9.00731004 0.036 4 P 0 0;1=4
P 8.95731004 0.036 4 P 0 0;1=4
P 9.45731004 0.036 4 P 0 0;1=4
P 9.40731004 0.036 4 P 0 0;1=4
P 9.35731004 0.036 4 P 0 0;1=4
P 9.30731004 0.036 4 P 0 0;1=4
P 9.25731004 0.036 4 P 0 0;1=4
P 9.70731004 0.036 4 P 0 0;1=4
P 9.65731004 0.036 4 P 0 0;1=4
P 9.60731004 0.036 4 P 0 0;1=4
P 9.55731004 0.036 4 P 0 0;1=4
P 9.50731004 0.036 4 P 0 0;1=4
P 10.00731004 0.036 4 P 0 0;1=4
P 9.95731004 0.036 4 P 0 0;1=4
P 9.90731004 0.036 4 P 0 0;1=4
P 9.85731004 0.036 4 P 0 0;1=4
P 9.80731004 0.036 4 P 0 0;1=4
P 9.75731004 0.036 4 P 0 0;1=4
P 10.25731004 0.036 4 P 0 0;1=4
P 10.20731004 0.036 4 P 0 0;1=4
P 10.15731004 0.036 4 P 0 0;1=4
P 10.10731004 0.036 4 P 0 0;1=4
P 10.05731004 0.036 4 P 0 0;1=4
P 10.50731004 0.036 4 P 0 0;1=4
P 10.45731004 0.036 4 P 0 0;1=4
P 10.40731004 0.036 4 P 0 0;1=4
P 10.35731004 0.036 4 P 0 0;1=4
P 10.30731004 0.036 4 P 0 0;1=4
P 10.75731004 0.036 4 P 0 0;1=4
P 10.70731004 0.036 4 P 0 0;1=4
P 10.65731004 0.036 4 P 0 0;1=4
P 10.60731004 0.036 4 P 0 0;1=4
P 10.55731004 0.036 4 P 0 0;1=4
P 11.05731004 0.036 4 P 0 0;1=4
P 11.00731004 0.036 4 P 0 0;1=4
P 10.95731004 0.036 4 P 0 0;1=4
P 10.90731004 0.036 4 P 0 0;1=4
P 10.85731004 0.036 4 P 0 0;1=4
P 10.80731004 0.036 4 P 0 0;1=4
P 11.30731004 0.036 4 P 0 0;1=4
P 11.25731004 0.036 4 P 0 0;1=4
P 11.20731004 0.036 4 P 0 0;1=4
P 11.15731004 0.036 4 P 0 0;1=4
P 11.10731004 0.036 4 P 0 0;1=4
P 11.55731004 0.036 4 P 0 0;1=4
P 11.50731004 0.036 4 P 0 0;1=4
P 11.45731004 0.036 4 P 0 0;1=4
P 11.40731004 0.036 4 P 0 0;1=4
P 11.35731004 0.036 4 P 0 0;1=4
P 11.80731004 0.036 4 P 0 0;1=4
P 11.75731004 0.036 4 P 0 0;1=4
P 11.70731004 0.036 4 P 0 0;1=4
P 11.65731004 0.036 4 P 0 0;1=4
P 11.60731004 0.036 4 P 0 0;1=4
P 12.10731004 0.036 4 P 0 0;1=4
P 12.05731004 0.036 4 P 0 0;1=4
P 12.00731004 0.036 4 P 0 0;1=4
P 11.95731004 0.036 4 P 0 0;1=4
P 11.90731004 0.036 4 P 0 0;1=4
P 11.85731004 0.036 4 P 0 0;1=4
P 12.35731004 0.036 4 P 0 0;1=4
P 12.30731004 0.036 4 P 0 0;1=4
P 12.25731004 0.036 4 P 0 0;1=4
P 12.20731004 0.036 4 P 0 0;1=4
P 12.15731004 0.036 4 P 0 0;1=4
P 12.60731004 0.036 4 P 0 0;1=4
P 12.55731004 0.036 4 P 0 0;1=4
P 12.50731004 0.036 4 P 0 0;1=4
P 12.45731004 0.036 4 P 0 0;1=4
P 12.40731004 0.036 4 P 0 0;1=4
P 12.8892 0.22596004 4 P 0 0;1=4
P 12.8892 0.17596004 4 P 0 0;1=4
P 12.8892 0.12596004 4 P 0 0;1=4
P 12.88911004 0.07596004 4 P 0 0;1=4
P 12.85728996 0.03738996 4 P 0 0;1=4
P 12.80731004 0.036 4 P 0 0;1=4
P 12.75731004 0.036 4 P 0 0;1=4
P 12.70731004 0.036 4 P 0 0;1=4
P 12.65731004 0.036 4 P 0 0;1=4
P 12.8892 0.47596004 4 P 0 0;1=4
P 12.8892 0.42596004 4 P 0 0;1=4
P 12.8892 0.37596004 4 P 0 0;1=4
P 12.8892 0.32596004 4 P 0 0;1=4
P 12.8892 0.27596004 4 P 0 0;1=4
P 12.8892 0.62596004 4 P 0 0;1=4
P 12.8892 0.57596004 4 P 0 0;1=4
P 12.8892 0.52596004 4 P 0 0;1=4
P 0.036 1.00868002 4 P 0 0;1=4
P 0.036 1.05868002 4 P 0 0;1=4
P 0.036 1.10868002 4 P 0 0;1=4
P 0.036 1.15868002 4 P 0 0;1=4
P 0.036 1.20868002 4 P 0 0;1=4
P 0.036 1.25868002 4 P 0 0;1=4
P 0.036 1.30868002 4 P 0 0;1=4
P 0.036 1.35868002 4 P 0 0;1=4
P 0.036 1.40868002 4 P 0 0;1=4
P 0.036 1.45868002 4 P 0 0;1=4
P 0.036 1.50868002 4 P 0 0;1=4
P 0.036 1.55868002 4 P 0 0;1=4
P 0.036 1.60868002 4 P 0 0;1=4
P 0.036 1.65868002 4 P 0 0;1=4
P 0.036 1.70868002 4 P 0 0;1=4
P 0.036 1.75868002 4 P 0 0;1=4
P 0.036 1.80868002 4 P 0 0;1=4
P 0.036 1.85868002 4 P 0 0;1=4
P 0.036 1.90868002 4 P 0 0;1=4
P 0.036 1.95868002 4 P 0 0;1=4
P 0.036 2.00868002 4 P 0 0;1=4
P 0.036 2.05868002 4 P 0 0;1=4
P 0.036 2.10868002 4 P 0 0;1=4
P 0.036 2.15868002 4 P 0 0;1=4
P 0.036 2.20868002 4 P 0 0;1=4
P 0.036 2.25868002 4 P 0 0;1=4
P 0.036 2.30868002 4 P 0 0;1=4
P 0.036 2.35868002 4 P 0 0;1=4
P 0.036 2.40868002 4 P 0 0;1=4
P 0.036 2.45868002 4 P 0 0;1=4
P 0.036 2.50868002 4 P 0 0;1=4
P 0.036 2.55868002 4 P 0 0;1=4
P 0.036 2.60868002 4 P 0 0;1=4
P 0.036 2.65868002 4 P 0 0;1=4
P 0.036 2.70868002 4 P 0 0;1=4
P 0.036 2.75868002 4 P 0 0;1=4
P 0.036 2.80868002 4 P 0 0;1=4
P 0.036 2.85868002 4 P 0 0;1=4
P 0.036 2.90868002 4 P 0 0;1=4
P 0.036 2.95868002 4 P 0 0;1=4
P 0.036 3.00868002 4 P 0 0;1=4
P 0.036 3.05868002 4 P 0 0;1=4
P 0.036 3.10868002 4 P 0 0;1=4
P 0.036 3.15868002 4 P 0 0;1=4
P 0.036 3.20868002 4 P 0 0;1=4
P 0.036 3.25868002 4 P 0 0;1=4
P 0.036 3.30868002 4 P 0 0;1=4
P 0.036 3.35868002 4 P 0 0;1=4
P 0.036 3.40868002 4 P 0 0;1=4
P 0.036 3.45868002 4 P 0 0;1=4
P 0.036 3.50868002 4 P 0 0;1=4
P 0.036 3.55868002 4 P 0 0;1=4
P 0.036 3.60868002 4 P 0 0;1=4
P 0.036 3.65868002 4 P 0 0;1=4
P 0.036 3.70868002 4 P 0 0;1=4
P 0.036 3.75868002 4 P 0 0;1=4
P 0.036 3.80868002 4 P 0 0;1=4
P 0.036 3.85868002 4 P 0 0;1=4
P 0.036 3.90868002 4 P 0 0;1=4
P 0.036 3.95868002 4 P 0 0;1=4
P 0.036 4.00868002 4 P 0 0;1=4
P 0.036 4.05868002 4 P 0 0;1=4
P 0.036 4.10868002 4 P 0 0;1=4
P 0.036 4.15868002 4 P 0 0;1=4
P 0.036 4.20868002 4 P 0 0;1=4
P 0.036 4.25868002 4 P 0 0;1=4
P 0.036 4.30868002 4 P 0 0;1=4
P 0.036 4.35868002 4 P 0 0;1=4
P 0.036 4.40868002 4 P 0 0;1=4
P 0.036 4.45868002 4 P 0 0;1=4
P 0.036 4.50868002 4 P 0 0;1=4
P 0.036 4.55868002 4 P 0 0;1=4
P 0.036 4.60868002 4 P 0 0;1=4
P 0.036 4.65868002 4 P 0 0;1=4
P 0.036 4.70868002 4 P 0 0;1=4
P 0.036 4.75868002 4 P 0 0;1=4
P 12.8892 1.02596004 4 P 0 0;1=4
P 12.8892 1.27596004 4 P 0 0;1=4
P 12.8892 1.22596004 4 P 0 0;1=4
P 12.8892 1.17596004 4 P 0 0;1=4
P 12.8892 1.12596004 4 P 0 0;1=4
P 12.8892 1.07596004 4 P 0 0;1=4
P 12.8892 1.52596004 4 P 0 0;1=4
P 12.8892 1.47596004 4 P 0 0;1=4
P 12.8892 1.42596004 4 P 0 0;1=4
P 12.8892 1.37596004 4 P 0 0;1=4
P 12.8892 1.32596004 4 P 0 0;1=4
P 12.8892 1.77596004 4 P 0 0;1=4
P 12.8892 1.72596004 4 P 0 0;1=4
P 12.8892 1.67596004 4 P 0 0;1=4
P 12.8892 1.62596004 4 P 0 0;1=4
P 12.8892 1.57596004 4 P 0 0;1=4
P 12.8892 2.07596004 4 P 0 0;1=4
P 12.8892 2.02596004 4 P 0 0;1=4
P 12.8892 1.97596004 4 P 0 0;1=4
P 12.8892 1.92596004 4 P 0 0;1=4
P 12.8892 1.87596004 4 P 0 0;1=4
P 12.8892 1.82596004 4 P 0 0;1=4
P 12.8892 2.32596004 4 P 0 0;1=4
P 12.8892 2.27596004 4 P 0 0;1=4
P 12.8892 2.22596004 4 P 0 0;1=4
P 12.8892 2.17596004 4 P 0 0;1=4
P 12.8892 2.57596004 4 P 0 0;1=4
P 12.8892 2.52596004 4 P 0 0;1=4
P 12.8892 2.47596004 4 P 0 0;1=4
P 12.8892 2.42596004 4 P 0 0;1=4
P 12.8892 2.37596004 4 P 0 0;1=4
P 12.8892 2.82596004 4 P 0 0;1=4
P 12.8892 2.77596004 4 P 0 0;1=4
P 12.8892 2.72596004 4 P 0 0;1=4
P 12.8892 2.67596004 4 P 0 0;1=4
P 12.8892 2.62596004 4 P 0 0;1=4
P 12.8892 3.12596004 4 P 0 0;1=4
P 12.8892 3.07596004 4 P 0 0;1=4
P 12.8892 3.02596004 4 P 0 0;1=4
P 12.8892 2.97596004 4 P 0 0;1=4
P 12.8892 2.92596004 4 P 0 0;1=4
P 12.8892 2.87596004 4 P 0 0;1=4
P 12.8892 3.37596004 4 P 0 0;1=4
P 12.8892 3.32596004 4 P 0 0;1=4
P 12.8892 3.27596004 4 P 0 0;1=4
P 12.8892 3.22596004 4 P 0 0;1=4
P 12.8892 3.17596004 4 P 0 0;1=4
P 12.8892 3.62596004 4 P 0 0;1=4
P 12.8892 3.57596004 4 P 0 0;1=4
P 12.8892 3.52596004 4 P 0 0;1=4
P 12.8892 3.47596004 4 P 0 0;1=4
P 12.8892 3.42596004 4 P 0 0;1=4
P 12.8892 3.92596004 4 P 0 0;1=4
P 12.8892 3.87596004 4 P 0 0;1=4
P 12.8892 3.82596004 4 P 0 0;1=4
P 12.8892 3.77596004 4 P 0 0;1=4
P 12.8892 3.72596004 4 P 0 0;1=4
P 12.8892 3.67596004 4 P 0 0;1=4
P 12.8892 4.17596004 4 P 0 0;1=4
P 12.8892 4.12596004 4 P 0 0;1=4
P 12.8892 4.07596004 4 P 0 0;1=4
P 12.8892 4.02596004 4 P 0 0;1=4
P 12.8892 3.97596004 4 P 0 0;1=4
P 12.8892 4.42596004 4 P 0 0;1=4
P 12.8892 4.37596004 4 P 0 0;1=4
P 12.8892 4.32596004 4 P 0 0;1=4
P 12.8892 4.27596004 4 P 0 0;1=4
P 12.8892 4.22596004 4 P 0 0;1=4
P 12.8892 4.67596004 4 P 0 0;1=4
P 12.8892 4.62596004 4 P 0 0;1=4
P 12.8892 4.57596004 4 P 0 0;1=4
P 12.8892 4.52596004 4 P 0 0;1=4
P 12.8892 4.47596004 4 P 0 0;1=4
P 12.8892 4.82596004 4 P 0 0;1=4
P 12.8892 4.77596004 4 P 0 0;1=4
P 12.8892 4.72596004 4 P 0 0;1=4
P 0.036 5.25868002 4 P 0 0;1=4
P 0.036 5.30868002 4 P 0 0;1=4
P 0.036 5.35868002 4 P 0 0;1=4
P 0.036 5.40868002 4 P 0 0;1=4
P 0.036 5.45868002 4 P 0 0;1=4
P 0.036 5.50868002 4 P 0 0;1=4
P 0.036 5.55868002 4 P 0 0;1=4
P 0.036 5.60868002 4 P 0 0;1=4
P 0.036 5.65868002 4 P 0 0;1=4
P 0.036 5.70868002 4 P 0 0;1=4
P 0.036 5.75868002 4 P 0 0;1=4
P 0.036 5.80868002 4 P 0 0;1=4
P 0.036 5.85868002 4 P 0 0;1=4
P 0.036 5.90868002 4 P 0 0;1=4
P 0.03826998 5.95863002 4 P 0 0;1=4
P 0.07901004 5.98761998 4 P 0 0;1=4
P 0.12901004 5.98761998 4 P 0 0;1=4
P 0.17901004 5.98761998 4 P 0 0;1=4
P 0.22901004 5.98761998 4 P 0 0;1=4
P 0.27901004 5.98761998 4 P 0 0;1=4
P 0.32901004 5.98761998 4 P 0 0;1=4
P 0.37901004 5.98761998 4 P 0 0;1=4
P 0.42901004 5.98761998 4 P 0 0;1=4
P 0.47901004 5.98761998 4 P 0 0;1=4
P 0.52901004 5.98761998 4 P 0 0;1=4
P 0.57901004 5.98761998 4 P 0 0;1=4
P 0.62901004 5.98761998 4 P 0 0;1=4
P 0.67901004 5.98761998 4 P 0 0;1=4
P 0.72901004 5.98761998 4 P 0 0;1=4
P 0.77901004 5.98761998 4 P 0 0;1=4
P 0.82901004 5.98761998 4 P 0 0;1=4
P 0.87901004 5.98761998 4 P 0 0;1=4
P 0.92901004 5.98761998 4 P 0 0;1=4
P 0.97901004 5.98761998 4 P 0 0;1=4
P 1.02901004 5.98761998 4 P 0 0;1=4
P 1.07901004 5.98761998 4 P 0 0;1=4
P 1.12901004 5.98761998 4 P 0 0;1=4
P 1.17901004 5.98761998 4 P 0 0;1=4
P 1.22901004 5.98761998 4 P 0 0;1=4
P 1.27901004 5.98761998 4 P 0 0;1=4
P 1.32901004 5.98761998 4 P 0 0;1=4
P 1.37901004 5.98761998 4 P 0 0;1=4
P 1.42901004 5.98761998 4 P 0 0;1=4
P 1.47901004 5.98761998 4 P 0 0;1=4
P 1.52901004 5.98761998 4 P 0 0;1=4
P 1.57901004 5.98761998 4 P 0 0;1=4
P 1.62901004 5.98761998 4 P 0 0;1=4
P 1.67901004 5.98761998 4 P 0 0;1=4
P 1.72901004 5.98761998 4 P 0 0;1=4
P 1.77901004 5.98761998 4 P 0 0;1=4
P 1.82901004 5.98761998 4 P 0 0;1=4
P 1.87901004 5.98761998 4 P 0 0;1=4
P 1.92901004 5.98761998 4 P 0 0;1=4
P 1.97901004 5.98761998 4 P 0 0;1=4
P 2.02901004 5.98761998 4 P 0 0;1=4
P 2.07901004 5.98761998 4 P 0 0;1=4
P 2.12901004 5.98761998 4 P 0 0;1=4
P 2.17901004 5.98761998 4 P 0 0;1=4
P 2.22901004 5.98761998 4 P 0 0;1=4
P 2.27901004 5.98761998 4 P 0 0;1=4
P 2.32901004 5.98761998 4 P 0 0;1=4
P 2.37901004 5.98761998 4 P 0 0;1=4
P 2.42901004 5.98761998 4 P 0 0;1=4
P 2.47901004 5.98761998 4 P 0 0;1=4
P 2.52901004 5.98761998 4 P 0 0;1=4
P 2.57901004 5.98761998 4 P 0 0;1=4
P 2.62901004 5.98761998 4 P 0 0;1=4
P 2.67901004 5.98761998 4 P 0 0;1=4
P 2.72901004 5.98761998 4 P 0 0;1=4
P 2.77901004 5.98761998 4 P 0 0;1=4
P 2.82901004 5.98761998 4 P 0 0;1=4
P 2.87901004 5.98761998 4 P 0 0;1=4
P 2.92901004 5.98761998 4 P 0 0;1=4
P 2.97901004 5.98761998 4 P 0 0;1=4
P 3.02901004 5.98761998 4 P 0 0;1=4
P 3.07901004 5.98761998 4 P 0 0;1=4
P 3.12901004 5.98761998 4 P 0 0;1=4
P 3.17901004 5.98761998 4 P 0 0;1=4
P 3.22901004 5.98761998 4 P 0 0;1=4
P 3.27901004 5.98761998 4 P 0 0;1=4
P 3.32901004 5.98761998 4 P 0 0;1=4
P 3.37901004 5.98761998 4 P 0 0;1=4
P 3.42901004 5.98761998 4 P 0 0;1=4
P 3.47901004 5.98761998 4 P 0 0;1=4
P 3.52901004 5.98761998 4 P 0 0;1=4
P 3.57901004 5.98761998 4 P 0 0;1=4
P 3.62901004 5.98761998 4 P 0 0;1=4
P 3.67901004 5.98761998 4 P 0 0;1=4
P 3.72901004 5.98761998 4 P 0 0;1=4
P 3.77901004 5.98761998 4 P 0 0;1=4
P 3.82901004 5.98761998 4 P 0 0;1=4
P 3.87901004 5.98761998 4 P 0 0;1=4
P 3.92901004 5.98761998 4 P 0 0;1=4
P 3.97901004 5.98761998 4 P 0 0;1=4
P 4.02901004 5.98761998 4 P 0 0;1=4
P 4.07901004 5.98761998 4 P 0 0;1=4
P 4.12901004 5.98761998 4 P 0 0;1=4
P 4.17901004 5.98761998 4 P 0 0;1=4
P 4.22901004 5.98761998 4 P 0 0;1=4
P 4.27901004 5.98761998 4 P 0 0;1=4
P 4.32901004 5.98761998 4 P 0 0;1=4
P 4.37901004 5.98761998 4 P 0 0;1=4
P 4.42901004 5.98761998 4 P 0 0;1=4
P 4.47901004 5.98761998 4 P 0 0;1=4
P 4.52901004 5.98761998 4 P 0 0;1=4
P 4.57901004 5.98761998 4 P 0 0;1=4
P 4.62901004 5.98761998 4 P 0 0;1=4
P 4.67901004 5.98761998 4 P 0 0;1=4
P 4.72901004 5.98761998 4 P 0 0;1=4
P 4.77901004 5.98761998 4 P 0 0;1=4
P 4.82901004 5.98761998 4 P 0 0;1=4
P 4.87901004 5.98761998 4 P 0 0;1=4
P 4.92901004 5.98761998 4 P 0 0;1=4
P 4.97901004 5.98761998 4 P 0 0;1=4
P 5.02901004 5.98761998 4 P 0 0;1=4
P 5.07901004 5.98761998 4 P 0 0;1=4
P 5.12901004 5.98761998 4 P 0 0;1=4
P 5.17901004 5.98761998 4 P 0 0;1=4
P 5.22901004 5.98761998 4 P 0 0;1=4
P 5.27901004 5.98761998 4 P 0 0;1=4
P 5.32901004 5.98761998 4 P 0 0;1=4
P 5.37901004 5.98761998 4 P 0 0;1=4
P 5.42901004 5.98761998 4 P 0 0;1=4
P 5.47901004 5.98761998 4 P 0 0;1=4
P 5.52901004 5.98761998 4 P 0 0;1=4
P 5.57901004 5.98761998 4 P 0 0;1=4
P 5.62901004 5.98761998 4 P 0 0;1=4
P 5.67901004 5.98761998 4 P 0 0;1=4
P 5.72901004 5.98761998 4 P 0 0;1=4
P 5.77901004 5.98761998 4 P 0 0;1=4
P 5.82901004 5.98761998 4 P 0 0;1=4
P 5.87901004 5.98761998 4 P 0 0;1=4
P 5.92901004 5.98761998 4 P 0 0;1=4
P 5.97901004 5.98761998 4 P 0 0;1=4
P 6.02901004 5.98761998 4 P 0 0;1=4
P 6.07901004 5.98761998 4 P 0 0;1=4
P 6.12901004 5.98761998 4 P 0 0;1=4
P 6.17901004 5.98761998 4 P 0 0;1=4
P 6.22901004 5.98761998 4 P 0 0;1=4
P 6.27901004 5.98761998 4 P 0 0;1=4
P 6.32901004 5.98761998 4 P 0 0;1=4
P 6.37901004 5.98761998 4 P 0 0;1=4
P 6.42901004 5.98761998 4 P 0 0;1=4
P 6.47901004 5.98761998 4 P 0 0;1=4
P 6.52901004 5.98761998 4 P 0 0;1=4
P 6.57901004 5.98761998 4 P 0 0;1=4
P 6.62901004 5.98761998 4 P 0 0;1=4
P 6.67901004 5.98761998 4 P 0 0;1=4
P 6.72901004 5.98761998 4 P 0 0;1=4
P 6.77901004 5.98761998 4 P 0 0;1=4
P 6.82901004 5.98761998 4 P 0 0;1=4
P 6.87901004 5.98761998 4 P 0 0;1=4
P 6.92901004 5.98761998 4 P 0 0;1=4
P 6.97901004 5.98761998 4 P 0 0;1=4
P 12.8892 5.47596004 4 P 0 0;1=4
P 12.8892 5.42596004 4 P 0 0;1=4
P 12.8892 5.37596004 4 P 0 0;1=4
P 12.8892 5.32596004 4 P 0 0;1=4
P 12.8892 5.27596004 4 P 0 0;1=4
P 12.8892 5.72596004 4 P 0 0;1=4
P 12.8892 5.67596004 4 P 0 0;1=4
P 12.8892 5.62596004 4 P 0 0;1=4
P 12.8892 5.57596004 4 P 0 0;1=4
P 12.8892 5.52596004 4 P 0 0;1=4
P 7.37901004 5.98761998 4 P 0 0;1=4
P 7.42901004 5.98761998 4 P 0 0;1=4
P 7.47901004 5.98761998 4 P 0 0;1=4
P 7.52901004 5.98761998 4 P 0 0;1=4
P 7.57901004 5.98761998 4 P 0 0;1=4
P 7.62901004 5.98761998 4 P 0 0;1=4
P 7.67901004 5.98761998 4 P 0 0;1=4
P 7.72901004 5.98761998 4 P 0 0;1=4
P 7.77901004 5.98761998 4 P 0 0;1=4
P 7.82901004 5.98761998 4 P 0 0;1=4
P 7.87901004 5.98761998 4 P 0 0;1=4
P 7.92901004 5.98761998 4 P 0 0;1=4
P 7.97901004 5.98761998 4 P 0 0;1=4
P 8.02901004 5.98761998 4 P 0 0;1=4
P 8.07901004 5.98761998 4 P 0 0;1=4
P 8.12901004 5.98761998 4 P 0 0;1=4
P 8.17901004 5.98761998 4 P 0 0;1=4
P 8.22901004 5.98761998 4 P 0 0;1=4
P 8.27901004 5.98761998 4 P 0 0;1=4
P 8.32901004 5.98761998 4 P 0 0;1=4
P 8.37901004 5.98761998 4 P 0 0;1=4
P 8.42901004 5.98761998 4 P 0 0;1=4
P 8.47901004 5.98761998 4 P 0 0;1=4
P 8.52901004 5.98761998 4 P 0 0;1=4
P 8.57901004 5.98761998 4 P 0 0;1=4
P 8.62901004 5.98761998 4 P 0 0;1=4
P 8.67901004 5.98761998 4 P 0 0;1=4
P 8.72901004 5.98761998 4 P 0 0;1=4
P 8.77901004 5.98761998 4 P 0 0;1=4
P 8.82901004 5.98761998 4 P 0 0;1=4
P 8.87901004 5.98761998 4 P 0 0;1=4
P 8.92901004 5.98761998 4 P 0 0;1=4
P 8.97901004 5.98761998 4 P 0 0;1=4
P 9.02901004 5.98761998 4 P 0 0;1=4
P 9.07901004 5.98761998 4 P 0 0;1=4
P 9.12901004 5.98761998 4 P 0 0;1=4
P 9.17901004 5.98761998 4 P 0 0;1=4
P 9.22901004 5.98761998 4 P 0 0;1=4
P 9.27901004 5.98761998 4 P 0 0;1=4
P 9.32901004 5.98761998 4 P 0 0;1=4
P 9.37901004 5.98761998 4 P 0 0;1=4
P 9.42901004 5.98761998 4 P 0 0;1=4
P 9.47901004 5.98761998 4 P 0 0;1=4
P 9.52901004 5.98761998 4 P 0 0;1=4
P 9.57901004 5.98761998 4 P 0 0;1=4
P 9.62901004 5.98761998 4 P 0 0;1=4
P 9.67901004 5.98761998 4 P 0 0;1=4
P 9.72901004 5.98761998 4 P 0 0;1=4
P 9.77901004 5.98761998 4 P 0 0;1=4
P 9.82901004 5.98761998 4 P 0 0;1=4
P 9.87901004 5.98761998 4 P 0 0;1=4
P 9.92901004 5.98761998 4 P 0 0;1=4
P 9.97901004 5.98761998 4 P 0 0;1=4
P 10.02901004 5.98761998 4 P 0 0;1=4
P 10.07901004 5.98761998 4 P 0 0;1=4
P 10.12901004 5.98761998 4 P 0 0;1=4
P 10.17901004 5.98761998 4 P 0 0;1=4
P 10.22901004 5.98761998 4 P 0 0;1=4
P 10.27901004 5.98761998 4 P 0 0;1=4
P 10.32901004 5.98761998 4 P 0 0;1=4
P 10.37901004 5.98761998 4 P 0 0;1=4
P 10.42901004 5.98761998 4 P 0 0;1=4
P 10.47901004 5.98761998 4 P 0 0;1=4
P 10.52901004 5.98761998 4 P 0 0;1=4
P 10.57901004 5.98761998 4 P 0 0;1=4
P 10.62901004 5.98761998 4 P 0 0;1=4
P 10.67901004 5.98761998 4 P 0 0;1=4
P 10.72901004 5.98761998 4 P 0 0;1=4
P 10.77901004 5.98761998 4 P 0 0;1=4
P 10.82901004 5.98761998 4 P 0 0;1=4
P 10.87901004 5.98761998 4 P 0 0;1=4
P 10.92901004 5.98761998 4 P 0 0;1=4
P 10.97901004 5.98761998 4 P 0 0;1=4
P 11.02901004 5.98761998 4 P 0 0;1=4
P 11.07901004 5.98761998 4 P 0 0;1=4
P 11.12901004 5.98761998 4 P 0 0;1=4
P 11.17901004 5.98761998 4 P 0 0;1=4
P 11.22901004 5.98761998 4 P 0 0;1=4
P 11.27901004 5.98761998 4 P 0 0;1=4
P 11.32901004 5.98761998 4 P 0 0;1=4
P 11.37901004 5.98761998 4 P 0 0;1=4
P 11.42901004 5.98761998 4 P 0 0;1=4
P 11.47901004 5.98761998 4 P 0 0;1=4
P 11.52901004 5.98761998 4 P 0 0;1=4
P 11.57901004 5.98761998 4 P 0 0;1=4
P 11.62901004 5.98761998 4 P 0 0;1=4
P 11.67901004 5.98761998 4 P 0 0;1=4
P 11.72901004 5.98761998 4 P 0 0;1=4
P 11.77901004 5.98761998 4 P 0 0;1=4
P 11.82901004 5.98761998 4 P 0 0;1=4
P 11.87901004 5.98761998 4 P 0 0;1=4
P 11.92901004 5.98761998 4 P 0 0;1=4
P 11.97901004 5.98761998 4 P 0 0;1=4
P 12.02901004 5.98761998 4 P 0 0;1=4
P 12.07901004 5.98761998 4 P 0 0;1=4
P 12.12901004 5.98761998 4 P 0 0;1=4
P 12.17901004 5.98761998 4 P 0 0;1=4
P 12.22901004 5.98761998 4 P 0 0;1=4
P 12.27901004 5.98761998 4 P 0 0;1=4
P 12.32901004 5.98761998 4 P 0 0;1=4
P 12.37901004 5.98761998 4 P 0 0;1=4
P 12.42901004 5.98761998 4 P 0 0;1=4
P 12.47901004 5.98761998 4 P 0 0;1=4
P 12.52901004 5.98761998 4 P 0 0;1=4
P 12.57901004 5.98761998 4 P 0 0;1=4
P 12.62901004 5.98761998 4 P 0 0;1=4
P 12.67901004 5.98761998 4 P 0 0;1=4
P 12.72901004 5.98761998 4 P 0 0;1=4
P 12.77901004 5.98761998 4 P 0 0;1=4
P 12.82901004 5.98761998 4 P 0 0;1=4
P 12.87726004 5.97451004 4 P 0 0;1=4
P 12.8892 5.92596004 4 P 0 0;1=4
P 12.8892 5.87596004 4 P 0 0;1=4
P 12.8892 5.82596004 4 P 0 0;1=4
P 12.8892 5.77596004 4 P 0 0;1=4
P 4.33605 4.9231 4 P 0 0;1=4
P 4.38105 4.9231 4 P 0 0;1=4
P 4.30105 4.9431 4 P 0 0;1=4
P 4.42105 4.9431 4 P 0 0;1=4
P 4.46105 4.9431 4 P 0 0;1=4
P 4.26105 4.9431 4 P 0 0;1=4
P 4.72605 4.9231 4 P 0 0;1=4
P 4.65105 4.9431 4 P 0 0;1=4
P 4.69105 4.9431 4 P 0 0;1=4
P 4.85105 4.9431 4 P 0 0;1=4
P 4.81105 4.9431 4 P 0 0;1=4
P 4.77105 4.9231 4 P 0 0;1=4
P 4.30105 5.0281 4 P 0 0;1=4
P 4.30105 5.0731 4 P 0 0;1=4
P 4.30105 4.9831 4 P 0 0;1=4
P 4.34105 5.1181 4 P 0 0;1=4
P 4.38105 5.1181 4 P 0 0;1=4
P 4.46105 5.1181 4 P 0 0;1=4
P 4.42105 5.1181 4 P 0 0;1=4
P 4.42105 4.9831 4 P 0 0;1=4
P 4.42105 5.0731 4 P 0 0;1=4
P 4.42105 5.0281 4 P 0 0;1=4
P 4.46105 4.9831 4 P 0 0;1=4
P 4.46105 5.0731 4 P 0 0;1=4
P 4.46105 5.0281 4 P 0 0;1=4
P 4.26105 5.0281 4 P 0 0;1=4
P 4.26105 5.0731 4 P 0 0;1=4
P 4.26105 4.9831 4 P 0 0;1=4
P 4.73105 5.1181 4 P 0 0;1=4
P 4.69105 5.1181 4 P 0 0;1=4
P 4.65105 5.1181 4 P 0 0;1=4
P 4.65105 4.9831 4 P 0 0;1=4
P 4.65105 5.0731 4 P 0 0;1=4
P 4.65105 5.0281 4 P 0 0;1=4
P 4.69105 4.9831 4 P 0 0;1=4
P 4.69105 5.0731 4 P 0 0;1=4
P 4.69105 5.0281 4 P 0 0;1=4
P 4.85105 5.0281 4 P 0 0;1=4
P 4.85105 5.0731 4 P 0 0;1=4
P 4.85105 4.9831 4 P 0 0;1=4
P 4.81105 5.0281 4 P 0 0;1=4
P 4.81105 5.0731 4 P 0 0;1=4
P 4.81105 4.9831 4 P 0 0;1=4
P 4.81105 5.1181 4 P 0 0;1=4
P 4.85105 5.1181 4 P 0 0;1=4
P 4.77105 5.1181 4 P 0 0;1=4
P 4.30105 5.1181 4 P 0 0;1=4
P 4.26105 5.1181 4 P 0 0;1=4
P 9.45795 0.36633002 4 P 0 0;1=4
P 6.62 4.645 4 P 0 0;1=4
P 6.62 4.61 4 P 0 0;1=4
P 6.605 4.77 4 P 0 0;1=4
P 6.315 4.9 4 P 0 0;1=4
P 6.315 4.865 4 P 0 0;1=4
P 6.315 4.82 4 P 0 0;1=4
P 6.315 4.785 4 P 0 0;1=4
P 6.315 4.705 4 P 0 0;1=4
P 6.315 4.74 4 P 0 0;1=4
P 6.315 4.66 4 P 0 0;1=4
P 6.315 4.625 4 P 0 0;1=4
P 1.51673002 5.78 4 P 0 0;1=4
P 1.12303002 5.46016004 4 P 0 0;1=4
P 1.20176998 5.46016004 4 P 0 0;1=4
P 1.51673002 5.46016004 4 P 0 0;1=4
P 1.36 5.355 4 P 0 0;1=4
P 1.41 5.355 4 P 0 0;1=4
P 1.46 5.355 4 P 0 0;1=4
P 1.305 5.885 4 P 0 0;1=4
P 1.355 5.885 4 P 0 0;1=4
P 1.405 5.885 4 P 0 0;1=4
P 1.455 5.885 4 P 0 0;1=4
P 0.705 5.355 4 P 0 0;1=4
P 0.7 5.267 4 P 0 0;1=0
P 0.73 5.175 4 P 0 0;1=4
P 1.03 5.065 4 P 0 0;1=4
P 1.28051004 5.46016004 4 P 0 0;1=4
P 12.215 4.915 4 P 0 0;1=4
P 12.055 4.915 4 P 0 0;1=4
P 10.465 5.245 4 P 0 0;1=4
P 10.465 5.165 4 P 0 0;1=4
P 11.7719 4.80998996 4 P 0 0;1=4
P 11.7719 4.85498996 4 P 0 0;1=4
P 11.7719 4.90498996 4 P 0 0;1=4
P 11.7719 4.94998996 4 P 0 0;1=4
P 11.9719 4.94998996 4 P 0 0;1=4
P 11.9719 4.80998996 4 P 0 0;1=4
P 11.9719 4.85498996 4 P 0 0;1=4
P 11.9719 4.90498996 4 P 0 0;1=4
P 11.9219 4.94998996 4 P 0 0;1=4
P 11.9219 4.80998996 4 P 0 0;1=4
P 11.8719 4.94998996 4 P 0 0;1=4
P 11.8719 4.80998996 4 P 0 0;1=4
P 11.8219 4.80998996 4 P 0 0;1=4
P 11.8219 4.94998996 4 P 0 0;1=4
P 11.69316004 2.6635 4 P 0 0;1=4
P 10.125 2.008 4 P 0 0;1=4
P 5.53531004 1.6642 4 P 0 0;1=4
P 5.53531004 1.7213 4 P 0 0;1=4
P 5.53531004 2.0802 4 P 0 0;1=4
P 5.53531004 1.9393 4 P 0 0;1=4
P 5.53531004 2.2156 4 P 0 0;1=4
P 5.53531004 2.4081 4 P 0 0;1=4
P 5.53531004 2.5473 4 P 0 0;1=4
P 2.86855 4.92 4 P 0 0;1=4
P 2.79768002 4.92 4 P 0 0;1=4
P 3.08113996 4.92 4 P 0 0;1=4
P 3.36461004 4.926 4 P 0 0;1=4
P 3.22288002 4.92 4 P 0 0;1=4
P 3.50633996 4.92 4 P 0 0;1=4
P 3.43546998 4.928 4 P 0 0;1=4
P 3.15398002 4.81401998 4 P 0 0;1=4
P 3.22288002 4.81401998 4 P 0 0;1=4
P 3.36461004 4.81401998 4 P 0 0;1=4
P 3.43546998 4.81401998 4 P 0 0;1=4
P 3.50633996 4.81401998 4 P 0 0;1=4
P 3.22288002 5.023 4 P 0 0;1=4
P 3.50633996 5.023 4 P 0 0;1=4
P 3.43546998 5.023 4 P 0 0;1=4
P 3.14 4.92 4 P 0 0;1=4
P 3.275 4.92 4 P 0 0;1=4
P 3.26 5.332 4 P 0 0;1=4
P 3.06791998 5.332 4 P 0 0;1=4
P 3.51176998 5.17873996 4 P 0 0;1=4
P 3.57176998 5.17873996 4 P 0 0;1=4
P 3.15743996 4.74418002 4 P 0 0;1=4
P 1.63308002 4.92 4 P 0 0;1=4
P 1.84568002 4.92 4 P 0 0;1=4
P 1.77481004 4.92 4 P 0 0;1=4
P 1.70395 4.92 4 P 0 0;1=4
P 2.12913996 4.92 4 P 0 0;1=4
P 2.05828002 4.92 4 P 0 0;1=4
P 1.98741004 4.92 4 P 0 0;1=4
P 1.91653996 4.92 4 P 0 0;1=4
P 2.34173996 4.92 4 P 0 0;1=4
P 2.27086998 4.92 4 P 0 0;1=4
P 2.20001004 4.926 4 P 0 0;1=4
P 2.34173996 4.81 4 P 0 0;1=4
P 2.27086998 4.81 4 P 0 0;1=4
P 2.20001004 4.81 4 P 0 0;1=4
P 1.63173002 4.81526998 4 P 0 0;1=4
P 1.7 4.812 4 P 0 0;1=4
P 1.84568002 4.81 4 P 0 0;1=4
P 1.776 4.812 4 P 0 0;1=4
P 2.12913996 4.81 4 P 0 0;1=4
P 1.99 4.81 4 P 0 0;1=4
P 1.92 4.81 4 P 0 0;1=4
P 2.40716998 5.15373996 4 P 0 0;1=4
P 2.34716998 5.15373996 4 P 0 0;1=4
P 10.58661004 2.16615 5 P 0 0;1=3
P 10.63661004 2.16615 5 P 0 0;1=3
P 10.63661004 2.21615 5 P 0 0;1=3
P 10.88661004 1.91615 5 P 0 0;1=3
P 10.88661004 2.41615 5 P 0 0;1=3
P 10.88661004 2.66615 5 P 0 0;1=3
P 11.03661004 2.41615 5 P 0 0;1=3
P 11.03661004 2.36615 5 P 0 0;1=3
P 1.91111004 4.61826004 4 P 0 0;1=4
P 2.40716998 4.70326004 4 P 0 0;1=4
P 2.945 4.92 4 P 0 0;1=4
P 3.01028002 4.92 4 P 0 0;1=4
P 7.78 2.4781 4 P 0 0;1=0
P 2.24606004 3.86615 5 P 0 0;1=3
P 2.49606004 3.86615 5 P 0 0;1=3
P 2.24606004 3.81615 5 P 0 0;1=3
P 2.19606004 3.76615 5 P 0 0;1=3
P 2.24606004 3.76615 5 P 0 0;1=3
P 2.29606004 3.76615 5 P 0 0;1=3
P 2.49606004 3.71615 5 P 0 0;1=3
P 2.49606004 3.56615 5 P 0 0;1=3
P 2.44606004 3.56615 5 P 0 0;1=3
P 2.39606004 3.56615 5 P 0 0;1=3
P 2.29606004 3.61615 5 P 0 0;1=3
P 2.24606004 3.71615 5 P 0 0;1=3
P 2.24606004 3.66615 5 P 0 0;1=3
P 2.24606004 3.61615 5 P 0 0;1=3
P 2.19606004 3.61615 5 P 0 0;1=3
P 2.19606004 3.56615 5 P 0 0;1=3
P 2.14606004 3.56615 5 P 0 0;1=3
P 2.04606004 3.56615 5 P 0 0;1=3
P 1.99606004 3.56615 5 P 0 0;1=3
P 2.04606004 3.51615 5 P 0 0;1=3
P 2.04606004 3.46615 5 P 0 0;1=3
P 2.19606004 3.51615 5 P 0 0;1=3
P 2.24606004 3.51615 5 P 0 0;1=3
P 2.29606004 3.51615 5 P 0 0;1=3
P 2.49606004 3.41615 5 P 0 0;1=3
P 2.44606004 3.36615 5 P 0 0;1=3
P 2.24606004 3.46615 5 P 0 0;1=3
P 2.24606004 3.41615 5 P 0 0;1=3
P 2.29606004 3.36615 5 P 0 0;1=3
P 2.24606004 3.36615 5 P 0 0;1=3
P 2.19606004 3.36615 5 P 0 0;1=3
P 1.99606004 3.41615 5 P 0 0;1=3
P 2.09606004 3.36615 5 P 0 0;1=3
P 2.24606004 3.31615 5 P 0 0;1=3
P 2.24606004 3.26615 5 P 0 0;1=3
P 2.29606004 3.21615 5 P 0 0;1=3
P 2.24606004 3.21615 5 P 0 0;1=3
P 2.19606004 3.21615 5 P 0 0;1=3
P 2.09606004 3.21615 5 P 0 0;1=3
P 2.14606004 3.16615 5 P 0 0;1=3
P 2.04606004 3.16615 5 P 0 0;1=3
P 2.24606004 3.16615 5 P 0 0;1=3
P 2.29606004 3.16615 5 P 0 0;1=3
P 2.34606004 3.21615 5 P 0 0;1=3
P 2.44606004 3.21615 5 P 0 0;1=3
P 2.49606004 3.21615 5 P 0 0;1=3
P 2.49606004 3.26615 5 P 0 0;1=3
P 2.49606004 3.16615 5 P 0 0;1=3
P 2.39606004 3.16615 5 P 0 0;1=3
P 2.29606004 3.06615 5 P 0 0;1=3
P 2.29606004 3.11615 5 P 0 0;1=3
P 2.29606004 2.96615 5 P 0 0;1=3
P 2.29606004 3.01615 5 P 0 0;1=3
P 2.24606004 3.06615 5 P 0 0;1=3
P 2.24606004 3.11615 5 P 0 0;1=3
P 2.24606004 2.96615 5 P 0 0;1=3
P 2.24606004 3.01615 5 P 0 0;1=3
P 2.34606004 2.86615 5 P 0 0;1=3
P 2.34606004 2.91615 5 P 0 0;1=3
P 2.29606004 2.76615 5 P 0 0;1=3
P 2.29606004 2.81615 5 P 0 0;1=3
P 2.24606004 2.76615 5 P 0 0;1=3
P 2.24606004 2.81615 5 P 0 0;1=3
P 2.19606004 2.81615 5 P 0 0;1=3
P 2.09606004 2.81615 5 P 0 0;1=3
P 2.09606004 2.86615 5 P 0 0;1=3
P 2.19606004 3.06615 5 P 0 0;1=3
P 2.14606004 3.01615 5 P 0 0;1=3
P 2.09606004 3.06615 5 P 0 0;1=3
P 2.04606004 3.01615 5 P 0 0;1=3
P 2.09606004 2.91615 5 P 0 0;1=3
P 2.14606004 2.86615 5 P 0 0;1=3
P 2.04606004 2.86615 5 P 0 0;1=3
P 2.19606004 2.91615 5 P 0 0;1=3
P 2.24606004 2.91615 5 P 0 0;1=3
P 2.29606004 2.91615 5 P 0 0;1=3
P 2.39606004 3.01615 5 P 0 0;1=3
P 2.34606004 3.06615 5 P 0 0;1=3
P 2.44606004 3.06615 5 P 0 0;1=3
P 2.49606004 3.01615 5 P 0 0;1=3
P 2.44606004 2.91615 5 P 0 0;1=3
P 2.44606004 2.86615 5 P 0 0;1=3
P 2.39606004 2.86615 5 P 0 0;1=3
P 2.34606004 2.81615 5 P 0 0;1=3
P 2.44606004 2.81615 5 P 0 0;1=3
P 2.49606004 2.86615 5 P 0 0;1=3
P 2.49606004 2.71615 5 P 0 0;1=3
P 2.44606004 2.66615 5 P 0 0;1=3
P 2.39606004 2.71615 5 P 0 0;1=3
P 2.34606004 2.66615 5 P 0 0;1=3
P 2.29606004 2.71615 5 P 0 0;1=3
P 2.29606004 2.66615 5 P 0 0;1=3
P 2.24606004 2.71615 5 P 0 0;1=3
P 2.24606004 2.66615 5 P 0 0;1=3
P 2.19606004 2.66615 5 P 0 0;1=3
P 2.14606004 2.71615 5 P 0 0;1=3
P 2.09606004 2.66615 5 P 0 0;1=3
P 2.04606004 2.71615 5 P 0 0;1=3
P 2.04606004 2.56615 5 P 0 0;1=3
P 2.04606004 2.51615 5 P 0 0;1=3
P 2.04606004 2.46615 5 P 0 0;1=3
P 2.09606004 2.51615 5 P 0 0;1=3
P 2.14606004 2.56615 5 P 0 0;1=3
P 2.24606004 2.61615 5 P 0 0;1=3
P 2.24606004 2.56615 5 P 0 0;1=3
P 2.29606004 2.61615 5 P 0 0;1=3
P 2.29606004 2.56615 5 P 0 0;1=3
P 2.34606004 2.51615 5 P 0 0;1=3
P 2.29606004 2.51615 5 P 0 0;1=3
P 2.24606004 2.51615 5 P 0 0;1=3
P 2.19606004 2.51615 5 P 0 0;1=3
P 2.14606004 2.46615 5 P 0 0;1=3
P 2.24606004 2.46615 5 P 0 0;1=3
P 2.29606004 2.46615 5 P 0 0;1=3
P 2.29606004 2.41615 5 P 0 0;1=3
P 2.24606004 2.41615 5 P 0 0;1=3
P 2.24606004 2.36615 5 P 0 0;1=3
P 2.19606004 2.36615 5 P 0 0;1=3
P 2.29606004 2.36615 5 P 0 0;1=3
P 2.39606004 2.46615 5 P 0 0;1=3
P 2.39606004 2.51615 5 P 0 0;1=3
P 2.39606004 2.56615 5 P 0 0;1=3
P 2.44606004 2.51615 5 P 0 0;1=3
P 2.49606004 2.56615 5 P 0 0;1=3
P 2.49606004 2.51615 5 P 0 0;1=3
P 2.49606004 2.46615 5 P 0 0;1=3
P 2.44606004 2.36615 5 P 0 0;1=3
P 2.49606004 2.31615 5 P 0 0;1=3
P 2.39606004 2.31615 5 P 0 0;1=3
P 2.34606004 2.36615 5 P 0 0;1=3
P 2.29606004 2.31615 5 P 0 0;1=3
P 2.24606004 2.31615 5 P 0 0;1=3
P 2.04606004 2.31615 5 P 0 0;1=3
P 2.04606004 2.16615 5 P 0 0;1=3
P 2.04606004 2.11615 5 P 0 0;1=3
P 2.04606004 1.96615 5 P 0 0;1=3
P 2.09606004 2.01615 5 P 0 0;1=3
P 2.14606004 1.96615 5 P 0 0;1=3
P 2.09606004 1.86615 5 P 0 0;1=3
P 2.19606004 1.86615 5 P 0 0;1=3
P 2.24606004 1.86615 5 P 0 0;1=3
P 2.29606004 1.86615 5 P 0 0;1=3
P 2.34606004 1.86615 5 P 0 0;1=3
P 2.24606004 1.91615 5 P 0 0;1=3
P 2.29606004 1.91615 5 P 0 0;1=3
P 2.24606004 1.96615 5 P 0 0;1=3
P 2.29606004 1.96615 5 P 0 0;1=3
P 2.19606004 2.01615 5 P 0 0;1=3
P 2.24606004 2.01615 5 P 0 0;1=3
P 2.29606004 2.01615 5 P 0 0;1=3
P 2.34606004 2.01615 5 P 0 0;1=3
P 2.39606004 1.96615 5 P 0 0;1=3
P 2.44606004 2.01615 5 P 0 0;1=3
P 2.49606004 1.96615 5 P 0 0;1=3
P 2.44606004 1.86615 5 P 0 0;1=3
P 2.49606004 2.11615 5 P 0 0;1=3
P 2.44606004 2.16615 5 P 0 0;1=3
P 2.49606004 2.16615 5 P 0 0;1=3
P 2.44606004 2.21615 5 P 0 0;1=3
P 2.39606004 2.16615 5 P 0 0;1=3
P 2.39606004 2.11615 5 P 0 0;1=3
P 2.34606004 2.16615 5 P 0 0;1=3
P 2.34606004 2.21615 5 P 0 0;1=3
P 2.29606004 2.21615 5 P 0 0;1=3
P 2.29606004 2.16615 5 P 0 0;1=3
P 2.29606004 2.06615 5 P 0 0;1=3
P 2.29606004 2.11615 5 P 0 0;1=3
P 2.24606004 2.11615 5 P 0 0;1=3
P 2.24606004 2.16615 5 P 0 0;1=3
P 2.24606004 2.06615 5 P 0 0;1=3
P 2.24606004 2.21615 5 P 0 0;1=3
P 2.29606004 2.26615 5 P 0 0;1=3
P 2.24606004 2.26615 5 P 0 0;1=3
P 2.19606004 2.21615 5 P 0 0;1=3
P 2.19606004 2.16615 5 P 0 0;1=3
P 2.14606004 2.11615 5 P 0 0;1=3
P 2.14606004 2.16615 5 P 0 0;1=3
P 2.09606004 2.21615 5 P 0 0;1=3
P 2.09606004 2.16615 5 P 0 0;1=3
P 2.09606004 2.36615 5 P 0 0;1=3
P 2.14606004 2.31615 5 P 0 0;1=3
P 1.99606004 2.71615 5 P 0 0;1=3
P 1.99606004 2.86615 5 P 0 0;1=3
P 2.04606004 2.81615 5 P 0 0;1=3
P 2.04606004 2.76615 5 P 0 0;1=3
P 3.29373996 5.023 4 P 0 0;1=4
P 2.14606004 3.26615 5 P 0 0;1=3
P 2.04606004 3.26615 5 P 0 0;1=3
P 2.04606004 3.21615 5 P 0 0;1=3
P 2.14606004 3.21615 5 P 0 0;1=3
P 2.39606004 3.21615 5 P 0 0;1=3
P 2.39606004 3.26615 5 P 0 0;1=3
P 2.29606004 3.26615 5 P 0 0;1=3
P 2.29606004 3.31615 5 P 0 0;1=3
P 2.34606004 3.36615 5 P 0 0;1=3
P 2.14606004 3.41615 5 P 0 0;1=3
P 2.09606004 3.61615 5 P 0 0;1=3
P 2.29606004 3.46615 5 P 0 0;1=3
P 2.29606004 3.41615 5 P 0 0;1=3
P 2.39606004 3.41615 5 P 0 0;1=3
P 2.34606004 3.51615 5 P 0 0;1=3
P 2.34606004 3.61615 5 P 0 0;1=3
P 2.34606004 3.56615 5 P 0 0;1=3
P 2.44606004 3.51615 5 P 0 0;1=3
P 2.44606004 3.61615 5 P 0 0;1=3
P 2.14606004 3.71615 5 P 0 0;1=3
P 2.04606004 3.71615 5 P 0 0;1=3
P 2.09606004 3.76615 5 P 0 0;1=3
P 2.14606004 3.86615 5 P 0 0;1=3
P 2.04606004 3.86615 5 P 0 0;1=3
P 2.29606004 3.71615 5 P 0 0;1=3
P 2.29606004 3.66615 5 P 0 0;1=3
P 2.39606004 3.71615 5 P 0 0;1=3
P 2.34606004 3.76615 5 P 0 0;1=3
P 2.29606004 3.81615 5 P 0 0;1=3
P 2.39606004 3.86615 5 P 0 0;1=3
P 2.29606004 3.86615 5 P 0 0;1=3
P 2.44606004 3.76615 5 P 0 0;1=3
P 2.19606004 2.86615 5 P 0 0;1=3
P 3.36461004 5.023 4 P 0 0;1=4
P 3.29373996 4.81401998 4 P 0 0;1=4
P 3.01028002 4.81401998 4 P 0 0;1=4
P 2.94141004 4.81401998 4 P 0 0;1=4
P 2.86555 4.81401998 4 P 0 0;1=4
P 2.79768002 4.81401998 4 P 0 0;1=4
P 3.15201004 5.023 4 P 0 0;1=4
P 3.08113996 5.023 4 P 0 0;1=4
P 3.01028002 5.023 4 P 0 0;1=4
P 2.93941004 5.023 4 P 0 0;1=4
P 2.86855 5.023 4 P 0 0;1=4
P 2.79768002 5.023 4 P 0 0;1=4
P 1.70395 5.023 4 P 0 0;1=4
P 1.63308002 5.023 4 P 0 0;1=4
P 1.77481004 5.023 4 P 0 0;1=4
P 1.91653996 5.023 4 P 0 0;1=4
P 1.84568002 5.023 4 P 0 0;1=4
P 1.98741004 5.023 4 P 0 0;1=4
P 2.05828002 5.023 4 P 0 0;1=4
P 2.12913996 5.023 4 P 0 0;1=4
P 2.20001004 5.023 4 P 0 0;1=4
P 2.27086998 5.023 4 P 0 0;1=4
P 2.34173996 5.023 4 P 0 0;1=4
P 1.56221004 5.023 4 P 0 0;1=4
P 1.56221004 4.81401998 4 P 0 0;1=4
P 2.06086998 4.81 4 P 0 0;1=4
P 2.41261004 5.023 4 P 0 0;1=4
P 2.41261004 4.81401998 4 P 0 0;1=4
P 2.72681004 5.023 4 P 0 0;1=4
P 2.72681004 4.81401998 4 P 0 0;1=4
P 3.57721004 4.81401998 4 P 0 0;1=4
P 3.57721004 5.023 4 P 0 0;1=4
P 4.88268002 1.91615 5 P 0 0;1=3
P 4.78268002 1.91615 5 P 0 0;1=3
P 5.03268002 2.36615 5 P 0 0;1=3
P 5.03268002 2.41615 5 P 0 0;1=3
P 4.88268002 3.66615 5 P 0 0;1=3
P 4.83268002 3.66615 5 P 0 0;1=3
P 5.03268002 3.66615 5 P 0 0;1=3
P 4.93268002 3.66615 5 P 0 0;1=3
P 4.98268002 3.66615 5 P 0 0;1=3
P 4.88268002 3.51615 5 P 0 0;1=3
P 4.83268002 3.51615 5 P 0 0;1=3
P 5.03268002 3.51615 5 P 0 0;1=3
P 4.93268002 3.51615 5 P 0 0;1=3
P 4.98268002 3.51615 5 P 0 0;1=3
P 4.88268002 3.81615 5 P 0 0;1=3
P 4.83268002 3.81615 5 P 0 0;1=3
P 4.93268002 3.81615 5 P 0 0;1=3
P 4.98268002 3.81615 5 P 0 0;1=3
P 4.88268002 3.36615 5 P 0 0;1=3
P 4.83268002 3.36615 5 P 0 0;1=3
P 5.03268002 3.36615 5 P 0 0;1=3
P 4.93268002 3.36615 5 P 0 0;1=3
P 4.98268002 3.36615 5 P 0 0;1=3
P 4.83268002 3.21615 5 P 0 0;1=3
P 4.88268002 3.21615 5 P 0 0;1=3
P 4.98268002 3.21615 5 P 0 0;1=3
P 4.93268002 3.21615 5 P 0 0;1=3
P 5.03268002 3.21615 5 P 0 0;1=3
P 4.83268002 3.06615 5 P 0 0;1=3
P 4.88268002 3.06615 5 P 0 0;1=3
P 4.98268002 3.06615 5 P 0 0;1=3
P 4.93268002 3.06615 5 P 0 0;1=3
P 5.03268002 3.06615 5 P 0 0;1=3
P 4.83268002 2.91615 5 P 0 0;1=3
P 4.88268002 2.91615 5 P 0 0;1=3
P 4.98268002 2.91615 5 P 0 0;1=3
P 4.93268002 2.91615 5 P 0 0;1=3
P 5.03268002 2.91615 5 P 0 0;1=3
P 4.78268002 2.51615 5 P 0 0;1=3
P 4.73268002 2.51615 5 P 0 0;1=3
P 4.68268002 2.51615 5 P 0 0;1=3
P 4.63268002 2.51615 5 P 0 0;1=3
P 4.58268002 2.51615 5 P 0 0;1=3
P 4.63268002 2.56615 5 P 0 0;1=3
P 4.73268002 2.56615 5 P 0 0;1=3
P 4.78268002 2.56615 5 P 0 0;1=3
P 4.78268002 2.61615 5 P 0 0;1=3
P 4.78268002 2.66615 5 P 0 0;1=3
P 4.68268002 2.66615 5 P 0 0;1=3
P 4.58268002 2.66615 5 P 0 0;1=3
P 4.73268002 2.71615 5 P 0 0;1=3
P 4.63268002 2.71615 5 P 0 0;1=3
P 4.63268002 2.76615 5 P 0 0;1=3
P 4.73268002 2.76615 5 P 0 0;1=3
P 4.78268002 2.76615 5 P 0 0;1=3
P 4.63268002 2.16615 5 P 0 0;1=3
P 4.78268002 2.16615 5 P 0 0;1=3
P 10.63661004 2.91615 5 P 0 0;1=3
P 10.58661004 2.91615 5 P 0 0;1=3
P 10.63661004 3.06615 5 P 0 0;1=3
P 10.58661004 3.06615 5 P 0 0;1=3
P 10.63661004 3.36615 5 P 0 0;1=3
P 10.58661004 3.36615 5 P 0 0;1=3
P 10.63661004 3.21615 5 P 0 0;1=3
P 10.58661004 3.21615 5 P 0 0;1=3
P 10.58661004 3.66615 5 P 0 0;1=3
P 10.63661004 3.51615 5 P 0 0;1=3
P 10.58661004 3.51615 5 P 0 0;1=3
P 10.63661004 3.81615 5 P 0 0;1=3
P 10.63661004 3.66615 5 P 0 0;1=3
P 10.58661004 3.81615 5 P 0 0;1=3
P 10.83661004 2.91615 5 P 0 0;1=3
P 10.78661004 2.91615 5 P 0 0;1=3
P 10.73661004 2.91615 5 P 0 0;1=3
P 10.68661004 2.91615 5 P 0 0;1=3
P 10.88661004 2.91615 5 P 0 0;1=3
P 10.88661004 3.06615 5 P 0 0;1=3
P 10.83661004 3.06615 5 P 0 0;1=3
P 10.78661004 3.06615 5 P 0 0;1=3
P 10.73661004 3.06615 5 P 0 0;1=3
P 10.68661004 3.06615 5 P 0 0;1=3
P 10.88661004 3.21615 5 P 0 0;1=3
P 10.83661004 3.21615 5 P 0 0;1=3
P 10.83661004 3.36615 5 P 0 0;1=3
P 10.88661004 3.36615 5 P 0 0;1=3
P 10.78661004 3.36615 5 P 0 0;1=3
P 10.73661004 3.36615 5 P 0 0;1=3
P 10.78661004 3.21615 5 P 0 0;1=3
P 10.73661004 3.21615 5 P 0 0;1=3
P 10.68661004 3.36615 5 P 0 0;1=3
P 10.68661004 3.21615 5 P 0 0;1=3
P 10.83661004 3.51615 5 P 0 0;1=3
P 10.88661004 3.51615 5 P 0 0;1=3
P 10.83661004 3.66615 5 P 0 0;1=3
P 10.78661004 3.66615 5 P 0 0;1=3
P 10.73661004 3.66615 5 P 0 0;1=3
P 10.68661004 3.66615 5 P 0 0;1=3
P 10.78661004 3.51615 5 P 0 0;1=3
P 10.73661004 3.51615 5 P 0 0;1=3
P 10.68661004 3.51615 5 P 0 0;1=3
P 10.83661004 3.81615 5 P 0 0;1=3
P 10.88661004 3.81615 5 P 0 0;1=3
P 10.88661004 3.66615 5 P 0 0;1=3
P 10.78661004 3.81615 5 P 0 0;1=3
P 10.73661004 3.81615 5 P 0 0;1=3
P 10.68661004 3.81615 5 P 0 0;1=3
P 11.03661004 2.91615 5 P 0 0;1=3
P 10.93661004 2.91615 5 P 0 0;1=3
P 10.98661004 2.91615 5 P 0 0;1=3
P 11.03661004 3.06615 5 P 0 0;1=3
P 10.93661004 3.06615 5 P 0 0;1=3
P 10.98661004 3.06615 5 P 0 0;1=3
P 11.03661004 3.21615 5 P 0 0;1=3
P 10.93661004 3.21615 5 P 0 0;1=3
P 10.98661004 3.21615 5 P 0 0;1=3
P 10.98661004 3.36615 5 P 0 0;1=3
P 10.93661004 3.36615 5 P 0 0;1=3
P 11.03661004 3.36615 5 P 0 0;1=3
P 10.98661004 3.51615 5 P 0 0;1=3
P 10.93661004 3.51615 5 P 0 0;1=3
P 11.03661004 3.51615 5 P 0 0;1=3
P 10.98661004 3.66615 5 P 0 0;1=3
P 10.93661004 3.66615 5 P 0 0;1=3
P 11.03661004 3.66615 5 P 0 0;1=3
P 10.98661004 3.81615 5 P 0 0;1=3
P 10.93661004 3.81615 5 P 0 0;1=3
P 3.07691004 4.81401998 4 P 0 0;1=4
P 8.1 1.86615 5 P 0 0;1=3
P 8.15 2.16615 5 P 0 0;1=3
P 8.15 2.11615 5 P 0 0;1=3
P 8.15 1.96615 5 P 0 0;1=3
P 8.1 2.01615 5 P 0 0;1=3
P 8.05 1.96615 5 P 0 0;1=3
P 8.05 2.11615 5 P 0 0;1=3
P 8.05 2.16615 5 P 0 0;1=3
P 8.15 2.31615 5 P 0 0;1=3
P 8.1 2.36615 5 P 0 0;1=3
P 8.1 2.16615 5 P 0 0;1=3
P 8.1 2.21615 5 P 0 0;1=3
P 8.05 2.31615 5 P 0 0;1=3
P 8.15 2.46615 5 P 0 0;1=3
P 8.15 2.56615 5 P 0 0;1=3
P 8.1 2.51615 5 P 0 0;1=3
P 8.05 2.46615 5 P 0 0;1=3
P 8.05 2.51615 5 P 0 0;1=3
P 8.05 2.56615 5 P 0 0;1=3
P 8.1 2.66615 5 P 0 0;1=3
P 8.05 2.76615 5 P 0 0;1=3
P 8.05 2.81615 5 P 0 0;1=3
P 8 2.86615 5 P 0 0;1=3
P 8 2.71615 5 P 0 0;1=3
P 8.05 2.71615 5 P 0 0;1=3
P 8.15 2.71615 5 P 0 0;1=3
P 8.05 2.86615 5 P 0 0;1=3
P 8.15 2.86615 5 P 0 0;1=3
P 8.1 2.91615 5 P 0 0;1=3
P 8.1 2.86615 5 P 0 0;1=3
P 8.1 2.81615 5 P 0 0;1=3
P 8.05 3.01615 5 P 0 0;1=3
P 8.1 3.06615 5 P 0 0;1=3
P 8.15 3.01615 5 P 0 0;1=3
P 8.15 3.16615 5 P 0 0;1=3
P 8.05 3.16615 5 P 0 0;1=3
P 8 3.41615 5 P 0 0;1=3
P 8.05 3.41615 5 P 0 0;1=3
P 8.1 3.36615 5 P 0 0;1=3
P 8.1 3.21615 5 P 0 0;1=3
P 8.15 3.56615 5 P 0 0;1=3
P 8.05 3.56615 5 P 0 0;1=3
P 8 3.56615 5 P 0 0;1=3
P 8.05 3.51615 5 P 0 0;1=3
P 8.05 3.46615 5 P 0 0;1=3
P 8.1 3.51615 5 P 0 0;1=3
P 8.35 1.86615 5 P 0 0;1=3
P 8.3 1.86615 5 P 0 0;1=3
P 8.25 1.86615 5 P 0 0;1=3
P 8.2 1.86615 5 P 0 0;1=3
P 8.25 2.06615 5 P 0 0;1=3
P 8.25 2.16615 5 P 0 0;1=3
P 8.25 2.11615 5 P 0 0;1=3
P 8.3 2.11615 5 P 0 0;1=3
P 8.3 2.06615 5 P 0 0;1=3
P 8.4 2.11615 5 P 0 0;1=3
P 8.4 2.16615 5 P 0 0;1=3
P 8.4 1.96615 5 P 0 0;1=3
P 8.35 2.01615 5 P 0 0;1=3
P 8.3 2.01615 5 P 0 0;1=3
P 8.25 2.01615 5 P 0 0;1=3
P 8.2 2.01615 5 P 0 0;1=3
P 8.3 1.96615 5 P 0 0;1=3
P 8.25 1.96615 5 P 0 0;1=3
P 8.3 1.91615 5 P 0 0;1=3
P 8.25 1.91615 5 P 0 0;1=3
P 8.2 2.16615 5 P 0 0;1=3
P 8.2 2.21615 5 P 0 0;1=3
P 8.25 2.26615 5 P 0 0;1=3
P 8.3 2.26615 5 P 0 0;1=3
P 8.25 2.21615 5 P 0 0;1=3
P 8.3 2.16615 5 P 0 0;1=3
P 8.3 2.21615 5 P 0 0;1=3
P 8.35 2.21615 5 P 0 0;1=3
P 8.35 2.16615 5 P 0 0;1=3
P 8.25 2.31615 5 P 0 0;1=3
P 8.3 2.31615 5 P 0 0;1=3
P 8.35 2.36615 5 P 0 0;1=3
P 8.4 2.31615 5 P 0 0;1=3
P 8.3 2.36615 5 P 0 0;1=3
P 8.2 2.36615 5 P 0 0;1=3
P 8.25 2.36615 5 P 0 0;1=3
P 8.25 2.41615 5 P 0 0;1=3
P 8.3 2.41615 5 P 0 0;1=3
P 8.4 2.56615 5 P 0 0;1=3
P 8.4 2.51615 5 P 0 0;1=3
P 8.4 2.46615 5 P 0 0;1=3
P 8.3 2.46615 5 P 0 0;1=3
P 8.25 2.46615 5 P 0 0;1=3
P 8.2 2.51615 5 P 0 0;1=3
P 8.25 2.51615 5 P 0 0;1=3
P 8.3 2.51615 5 P 0 0;1=3
P 8.35 2.51615 5 P 0 0;1=3
P 8.3 2.56615 5 P 0 0;1=3
P 8.3 2.61615 5 P 0 0;1=3
P 8.25 2.56615 5 P 0 0;1=3
P 8.25 2.61615 5 P 0 0;1=3
P 8.2 2.66615 5 P 0 0;1=3
P 8.25 2.66615 5 P 0 0;1=3
P 8.3 2.66615 5 P 0 0;1=3
P 8.35 2.66615 5 P 0 0;1=3
P 8.25 2.71615 5 P 0 0;1=3
P 8.3 2.71615 5 P 0 0;1=3
P 8.4 2.71615 5 P 0 0;1=3
P 8.35 2.81615 5 P 0 0;1=3
P 8.4 2.86615 5 P 0 0;1=3
P 8.3 2.91615 5 P 0 0;1=3
P 8.25 2.91615 5 P 0 0;1=3
P 8.2 2.91615 5 P 0 0;1=3
P 8.2 2.81615 5 P 0 0;1=3
P 8.25 2.81615 5 P 0 0;1=3
P 8.25 2.76615 5 P 0 0;1=3
P 8.3 2.81615 5 P 0 0;1=3
P 8.3 2.76615 5 P 0 0;1=3
P 8.35 2.91615 5 P 0 0;1=3
P 8.35 2.86615 5 P 0 0;1=3
P 8.35 3.06615 5 P 0 0;1=3
P 8.4 3.01615 5 P 0 0;1=3
P 8.2 3.06615 5 P 0 0;1=3
P 8.25 3.01615 5 P 0 0;1=3
P 8.25 2.96615 5 P 0 0;1=3
P 8.25 3.11615 5 P 0 0;1=3
P 8.25 3.06615 5 P 0 0;1=3
P 8.3 3.01615 5 P 0 0;1=3
P 8.3 2.96615 5 P 0 0;1=3
P 8.3 3.11615 5 P 0 0;1=3
P 8.3 3.06615 5 P 0 0;1=3
P 8.25 3.16615 5 P 0 0;1=3
P 8.3 3.16615 5 P 0 0;1=3
P 8.4 3.16615 5 P 0 0;1=3
P 8.25 3.41615 5 P 0 0;1=3
P 8.3 3.36615 5 P 0 0;1=3
P 8.25 3.36615 5 P 0 0;1=3
P 8.2 3.36615 5 P 0 0;1=3
P 8.25 3.31615 5 P 0 0;1=3
P 8.25 3.26615 5 P 0 0;1=3
P 8.3 3.21615 5 P 0 0;1=3
P 8.25 3.21615 5 P 0 0;1=3
P 8.2 3.21615 5 P 0 0;1=3
P 8.35 3.21615 5 P 0 0;1=3
P 8.4 3.56615 5 P 0 0;1=3
P 8.3 3.61615 5 P 0 0;1=3
P 8.25 3.66615 5 P 0 0;1=3
P 8.25 3.61615 5 P 0 0;1=3
P 8.2 3.61615 5 P 0 0;1=3
P 8.2 3.56615 5 P 0 0;1=3
P 8.2 3.51615 5 P 0 0;1=3
P 8.25 3.51615 5 P 0 0;1=3
P 8.3 3.51615 5 P 0 0;1=3
P 8.25 3.46615 5 P 0 0;1=3
P 8.25 3.86615 5 P 0 0;1=3
P 8.25 3.81615 5 P 0 0;1=3
P 8.2 3.76615 5 P 0 0;1=3
P 8.25 3.76615 5 P 0 0;1=3
P 8.3 3.76615 5 P 0 0;1=3
P 8.25 3.71615 5 P 0 0;1=3
P 8.45 1.86615 5 P 0 0;1=3
P 8.5 2.16615 5 P 0 0;1=3
P 8.5 2.11615 5 P 0 0;1=3
P 8.5 1.96615 5 P 0 0;1=3
P 8.45 2.01615 5 P 0 0;1=3
P 8.45 2.21615 5 P 0 0;1=3
P 8.45 2.16615 5 P 0 0;1=3
P 8.5 2.31615 5 P 0 0;1=3
P 8.45 2.36615 5 P 0 0;1=3
P 8.5 2.46615 5 P 0 0;1=3
P 8.5 2.51615 5 P 0 0;1=3
P 8.5 2.56615 5 P 0 0;1=3
P 8.45 2.51615 5 P 0 0;1=3
P 8.45 2.66615 5 P 0 0;1=3
P 8.5 2.71615 5 P 0 0;1=3
P 8.5 2.86615 5 P 0 0;1=3
P 8.45 2.81615 5 P 0 0;1=3
P 8.45 2.86615 5 P 0 0;1=3
P 8.45 2.91615 5 P 0 0;1=3
P 8.5 3.01615 5 P 0 0;1=3
P 8.45 3.06615 5 P 0 0;1=3
P 8.5 3.16615 5 P 0 0;1=3
P 8.5 3.41615 5 P 0 0;1=3
P 8.45 3.36615 5 P 0 0;1=3
P 8.45 3.21615 5 P 0 0;1=3
P 8.5 3.21615 5 P 0 0;1=3
P 8.5 3.26615 5 P 0 0;1=3
P 8.5 3.56615 5 P 0 0;1=3
P 8.45 3.56615 5 P 0 0;1=3
P 8.5 3.86615 5 P 0 0;1=3
P 8.5 3.71615 5 P 0 0;1=3
P 8.2 2.86615 5 P 0 0;1=3
P 8.05 3.26615 5 P 0 0;1=3
P 8.05 3.21615 5 P 0 0;1=3
P 8.3 3.26615 5 P 0 0;1=3
P 8.3 3.31615 5 P 0 0;1=3
P 8.35 3.36615 5 P 0 0;1=3
P 8.15 3.26615 5 P 0 0;1=3
P 8.15 3.21615 5 P 0 0;1=3
P 8.4 3.21615 5 P 0 0;1=3
P 8.4 3.26615 5 P 0 0;1=3
P 8.1 3.61615 5 P 0 0;1=3
P 8.3 3.46615 5 P 0 0;1=3
P 8.3 3.41615 5 P 0 0;1=3
P 8.35 3.51615 5 P 0 0;1=3
P 8.35 3.61615 5 P 0 0;1=3
P 8.35 3.56615 5 P 0 0;1=3
P 8.15 3.41615 5 P 0 0;1=3
P 8.45 3.51615 5 P 0 0;1=3
P 8.45 3.61615 5 P 0 0;1=3
P 8.4 3.41615 5 P 0 0;1=3
P 8.05 3.71615 5 P 0 0;1=3
P 8.1 3.76615 5 P 0 0;1=3
P 8.05 3.86615 5 P 0 0;1=3
P 8.3 3.71615 5 P 0 0;1=3
P 8.3 3.66615 5 P 0 0;1=3
P 8.35 3.76615 5 P 0 0;1=3
P 8.3 3.81615 5 P 0 0;1=3
P 8.3 3.86615 5 P 0 0;1=3
P 8.15 3.71615 5 P 0 0;1=3
P 8.15 3.86615 5 P 0 0;1=3
P 8.45 3.76615 5 P 0 0;1=3
P 8.4 3.71615 5 P 0 0;1=3
P 8.4 3.86615 5 P 0 0;1=3
P 3.28831004 4.68073996 4 P 0 0;1=4
P 3.22831004 4.68073996 4 P 0 0;1=4
P 3.50091004 4.62573996 4 P 0 0;1=4
P 3.44091004 4.62573996 4 P 0 0;1=4
P 7.56575 5.023 4 P 0 0;1=4
P 7.63661998 5.023 4 P 0 0;1=4
P 7.84921998 5.023 4 P 0 0;1=4
P 7.77835 5.023 4 P 0 0;1=4
P 7.70748996 5.023 4 P 0 0;1=4
P 7.92008002 5.023 4 P 0 0;1=4
P 8.06181998 5.023 4 P 0 0;1=4
P 8.13268002 5.023 4 P 0 0;1=4
P 7.99095 5.023 4 P 0 0;1=4
P 8.34528002 5.023 4 P 0 0;1=4
P 8.27441004 5.023 4 P 0 0;1=4
P 8.20355 5.023 4 P 0 0;1=4
P 8.41615 5.023 4 P 0 0;1=4
P 7.63661998 4.92 4 P 0 0;1=4
P 7.84921998 4.9207 4 P 0 0;1=4
P 7.70748996 4.9207 4 P 0 0;1=4
P 7.77835 4.9207 4 P 0 0;1=4
P 7.99095 4.9207 4 P 0 0;1=4
P 7.92008002 4.9207 4 P 0 0;1=4
P 8.06181998 4.9207 4 P 0 0;1=4
P 8.13268002 4.9207 4 P 0 0;1=4
P 8.27441004 4.9207 4 P 0 0;1=4
P 8.20355 4.9267 4 P 0 0;1=4
P 8.34528002 4.9207 4 P 0 0;1=4
P 7.63526998 4.81526998 4 P 0 0;1=4
P 7.84921998 4.81 4 P 0 0;1=4
P 7.77953996 4.812 4 P 0 0;1=4
P 7.70353996 4.812 4 P 0 0;1=4
P 8.13268002 4.81 4 P 0 0;1=4
P 8.06441004 4.81 4 P 0 0;1=4
P 7.99353996 4.81 4 P 0 0;1=4
P 7.92353996 4.81 4 P 0 0;1=4
P 8.27441004 4.81 4 P 0 0;1=4
P 8.34528002 4.81 4 P 0 0;1=4
P 8.20355 4.81 4 P 0 0;1=4
P 8.41615 4.81401998 4 P 0 0;1=4
P 8.86908996 4.81401998 4 P 0 0;1=4
P 8.73035 4.81401998 4 P 0 0;1=4
P 8.80121998 4.81401998 4 P 0 0;1=4
P 8.94495 4.81401998 4 P 0 0;1=4
P 9.08045 4.81401998 4 P 0 0;1=4
P 9.01381998 4.81401998 4 P 0 0;1=4
P 9.36815 4.81401998 4 P 0 0;1=4
P 9.29728002 4.81401998 4 P 0 0;1=4
P 9.22641998 4.81401998 4 P 0 0;1=4
P 9.15751998 4.81401998 4 P 0 0;1=4
P 9.43901004 4.81401998 4 P 0 0;1=4
P 9.50988002 4.81401998 4 P 0 0;1=4
P 9.58075 4.81401998 4 P 0 0;1=4
P 8.80121998 5.023 4 P 0 0;1=4
P 8.73035 5.023 4 P 0 0;1=4
P 8.87208996 5.023 4 P 0 0;1=4
P 9.08468002 5.023 4 P 0 0;1=4
P 9.01381998 5.023 4 P 0 0;1=4
P 8.94295 5.023 4 P 0 0;1=4
P 8.87208996 4.92 4 P 0 0;1=4
P 8.80121998 4.92 4 P 0 0;1=4
P 9.01381998 4.92 4 P 0 0;1=4
P 9.08468002 4.92 4 P 0 0;1=4
P 9.22641998 4.92 4 P 0 0;1=4
P 9.36815 4.926 4 P 0 0;1=4
P 9.50988002 4.92 4 P 0 0;1=4
P 9.43901004 4.928 4 P 0 0;1=4
P 9.36815 5.023 4 P 0 0;1=4
P 9.29728002 5.023 4 P 0 0;1=4
P 9.22641998 5.023 4 P 0 0;1=4
P 9.15555 5.023 4 P 0 0;1=4
P 9.50988002 5.023 4 P 0 0;1=4
P 9.43901004 5.023 4 P 0 0;1=4
P 9.58075 5.023 4 P 0 0;1=4
P 8.94853996 4.92 4 P 0 0;1=4
P 9.27853996 4.92 4 P 0 0;1=4
P 9.14353996 4.92 4 P 0 0;1=4
P 8.13811004 5.09223996 4 P 0 0;1=4
P 8.35071004 5.15373996 4 P 0 0;1=4
P 8.41071004 5.15373996 4 P 0 0;1=4
P 7.56575 4.81401998 4 P 0 0;1=4
P 8.88061998 4.70573996 4 P 0 0;1=4
P 2.45985 4.77875 11 P 0 0;1=9
P 1.51496998 4.77875 11 P 0 0;1=9
P 2.44016998 5.05826998 11 P 0 0;1=9
P 1.53465 5.05826998 11 P 0 0;1=9
P 3.60476998 4.77875 11 P 0 0;1=9
P 2.67956998 4.77875 11 P 0 0;1=9
P 3.60476998 5.05826998 11 P 0 0;1=9
P 2.69925 5.05826998 11 P 0 0;1=9
P 8.46338996 4.77875 11 P 0 0;1=9
P 7.51851004 4.77875 11 P 0 0;1=9
P 8.44371004 5.05826998 11 P 0 0;1=9
P 7.53818996 5.05826998 11 P 0 0;1=9
P 9.60831004 4.77875 11 P 0 0;1=9
P 8.68311004 4.77875 11 P 0 0;1=9
P 9.60831004 5.05826998 11 P 0 0;1=9
P 8.70278996 5.05826998 11 P 0 0;1=9
P 10.82676998 5.49685 13 P 0 0;1=10
P 10.99213002 5.49685 13 P 0 0;1=10
P 11.15748002 5.49685 13 P 0 0;1=10
P 11.32283996 5.49685 13 P 0 0;1=10
P 11.48818996 5.49685 13 P 0 0;1=10
P 11.65353996 5.49685 13 P 0 0;1=10
P 11.8189 5.49685 13 P 0 0;1=10
P 11.98425 5.49685 13 P 0 0;1=10
P 12.14961004 5.49685 13 P 0 0;1=11
P 10.83661998 1.50786998 25 P 0 0;1=12
P 10.83661998 1.50788002 25 P 0 0;1=12
P 8.25 1.50788002 25 P 0 0;1=12
P 8.25 1.50786998 25 P 0 0;1=12
P 6.96456998 1.52756004 25 P 0 0;1=12
P 6.96456998 1.52756004 25 P 0 0;1=12
P 6.96456998 4.20471998 25 P 0 0;1=12
P 6.96456998 4.20473002 25 P 0 0;1=12
P 8.25 4.22441004 25 P 0 0;1=12
P 8.25 4.22441004 25 P 0 0;1=12
P 10.83661998 4.22441004 25 P 0 0;1=12
P 10.83661998 4.22441004 25 P 0 0;1=12
P 12.12205 4.20471998 25 P 0 0;1=12
P 12.12205 4.20473002 25 P 0 0;1=12
P 12.12205 1.52756004 25 P 0 0;1=12
P 12.12205 1.52756004 25 P 0 0;1=12
P 11.99213002 4.20473002 4 P 0 0;1=4
P 12.03018002 4.11286004 4 P 0 0;1=4
P 12.03018002 4.2966 4 P 0 0;1=4
P 12.21391998 4.11286004 4 P 0 0;1=4
P 12.25196998 4.20473002 4 P 0 0;1=4
P 12.21391998 4.2966 4 P 0 0;1=4
P 10.7067 4.22441004 4 P 0 0;1=4
P 10.74475 4.13253996 4 P 0 0;1=4
P 10.74475 4.31628002 4 P 0 0;1=4
P 10.92848996 4.13253996 4 P 0 0;1=4
P 10.96653996 4.22441004 4 P 0 0;1=4
P 10.92848996 4.31628002 4 P 0 0;1=4
P 8.12008002 4.22441004 4 P 0 0;1=4
P 8.15813002 4.13253996 4 P 0 0;1=4
P 8.15813002 4.31628002 4 P 0 0;1=4
P 8.34186998 4.13253996 4 P 0 0;1=4
P 8.37991998 4.22441004 4 P 0 0;1=4
P 8.34186998 4.31628002 4 P 0 0;1=4
P 6.83465 4.20473002 4 P 0 0;1=4
P 6.8727 4.11286004 4 P 0 0;1=4
P 6.8727 4.2966 4 P 0 0;1=4
P 7.05643996 4.11286004 4 P 0 0;1=4
P 7.09448996 4.20473002 4 P 0 0;1=4
P 7.05643996 4.2966 4 P 0 0;1=4
P 6.83465 1.52756004 4 P 0 0;1=4
P 6.8727 1.43568996 4 P 0 0;1=4
P 6.8727 1.61943002 4 P 0 0;1=4
P 7.05643996 1.43568996 4 P 0 0;1=4
P 7.09448996 1.52756004 4 P 0 0;1=4
P 7.05643996 1.61943002 4 P 0 0;1=4
P 8.15813002 1.416 4 P 0 0;1=4
P 8.12008002 1.50786998 4 P 0 0;1=4
P 8.15813002 1.59975 4 P 0 0;1=4
P 8.34186998 1.416 4 P 0 0;1=4
P 8.34186998 1.59975 4 P 0 0;1=4
P 8.37991998 1.50786998 4 P 0 0;1=4
P 10.74475 1.59975 4 P 0 0;1=4
P 10.92848996 1.59975 4 P 0 0;1=4
P 10.96653996 1.50786998 4 P 0 0;1=4
P 10.92848996 1.416 4 P 0 0;1=4
P 10.74475 1.416 4 P 0 0;1=4
P 10.7067 1.50786998 4 P 0 0;1=4
P 12.2126 1.43701004 4 P 0 0;1=4
P 12.25196998 1.52756004 4 P 0 0;1=4
P 12.2126 1.61811004 4 P 0 0;1=4
P 12.0315 1.61811004 4 P 0 0;1=4
P 11.99213002 1.52756004 4 P 0 0;1=4
P 12.0315 1.43701004 4 P 0 0;1=4
P 4.83268002 1.50786998 25 P 0 0;1=12
P 4.83268002 1.50788002 25 P 0 0;1=12
P 2.24606004 1.50788002 25 P 0 0;1=12
P 2.24606004 1.50786998 25 P 0 0;1=12
P 0.96063002 1.52756004 25 P 0 0;1=12
P 0.96063002 1.52756004 25 P 0 0;1=12
P 0.96063002 4.20471998 25 P 0 0;1=12
P 0.96063002 4.20473002 25 P 0 0;1=12
P 2.24606004 4.22441004 25 P 0 0;1=12
P 2.24606004 4.22441004 25 P 0 0;1=12
P 4.83268002 4.22441004 25 P 0 0;1=12
P 4.83268002 4.22441004 25 P 0 0;1=12
P 6.11811004 4.20471998 25 P 0 0;1=12
P 6.11811004 4.20473002 25 P 0 0;1=12
P 6.11811004 1.52756004 25 P 0 0;1=12
P 6.11811004 1.52756004 25 P 0 0;1=12
P 5.98818996 4.20473002 4 P 0 0;1=4
P 6.02623996 4.11286004 4 P 0 0;1=4
P 6.02623996 4.2966 4 P 0 0;1=4
P 6.20998002 4.11286004 4 P 0 0;1=4
P 6.24803002 4.20473002 4 P 0 0;1=4
P 6.20998002 4.2966 4 P 0 0;1=4
P 4.70276004 4.22441004 4 P 0 0;1=4
P 4.74081004 4.13253996 4 P 0 0;1=4
P 4.74081004 4.31628002 4 P 0 0;1=4
P 4.92455 4.13253996 4 P 0 0;1=4
P 4.9626 4.22441004 4 P 0 0;1=4
P 4.92455 4.31628002 4 P 0 0;1=4
P 2.11613996 4.22441004 4 P 0 0;1=4
P 2.15418996 4.13253996 4 P 0 0;1=4
P 2.15418996 4.31628002 4 P 0 0;1=4
P 2.33793002 4.13253996 4 P 0 0;1=4
P 2.37598002 4.22441004 4 P 0 0;1=4
P 2.33793002 4.31628002 4 P 0 0;1=4
P 0.83071004 4.20473002 4 P 0 0;1=4
P 0.86876004 4.11286004 4 P 0 0;1=4
P 0.86876004 4.2966 4 P 0 0;1=4
P 1.0525 4.11286004 4 P 0 0;1=4
P 1.09055 4.20473002 4 P 0 0;1=4
P 1.0525 4.2966 4 P 0 0;1=4
P 0.83071004 1.52756004 4 P 0 0;1=4
P 0.86876004 1.43568996 4 P 0 0;1=4
P 0.86876004 1.61943002 4 P 0 0;1=4
P 1.0525 1.43568996 4 P 0 0;1=4
P 1.09055 1.52756004 4 P 0 0;1=4
P 1.0525 1.61943002 4 P 0 0;1=4
P 2.15418996 1.416 4 P 0 0;1=4
P 2.11613996 1.50786998 4 P 0 0;1=4
P 2.15418996 1.59975 4 P 0 0;1=4
P 2.33793002 1.416 4 P 0 0;1=4
P 2.33793002 1.59975 4 P 0 0;1=4
P 2.37598002 1.50786998 4 P 0 0;1=4
P 4.74081004 1.59975 4 P 0 0;1=4
P 4.92455 1.59975 4 P 0 0;1=4
P 4.9626 1.50786998 4 P 0 0;1=4
P 4.92455 1.416 4 P 0 0;1=4
P 4.74081004 1.416 4 P 0 0;1=4
P 4.70276004 1.50786998 4 P 0 0;1=4
P 6.20866004 1.43701004 4 P 0 0;1=4
P 6.24803002 1.52756004 4 P 0 0;1=4
P 6.20866004 1.61811004 4 P 0 0;1=4
P 6.02756004 1.61811004 4 P 0 0;1=4
P 5.98818996 1.52756004 4 P 0 0;1=4
P 6.02756004 1.43701004 4 P 0 0;1=4
P 12.59646998 0.8189 4 P 0 0;1=4
P 12.5571 0.72835 4 P 0 0;1=4
P 12.59646998 0.6378 4 P 0 0;1=4
P 12.68701998 0.72835 25 P 0 0;1=12
P 12.77756998 0.6378 4 P 0 0;1=4
P 12.81693996 0.72835 4 P 0 0;1=4
P 12.77756998 0.8189 4 P 0 0;1=4
P 12.68701998 0.72835 25 P 0 0;1=12
P 12.59646998 5.24803002 4 P 0 0;1=4
P 12.5571 5.15748002 4 P 0 0;1=4
P 12.59646998 5.06693002 4 P 0 0;1=4
P 12.68701998 5.15748002 25 P 0 0;1=12
P 12.77756998 5.06693002 4 P 0 0;1=4
P 12.81693996 5.15748002 4 P 0 0;1=4
P 12.77756998 5.24803002 4 P 0 0;1=4
P 12.68701998 5.15748002 25 P 0 0;1=12
P 0.1319 5.20866004 4 P 0 0;1=4
P 0.09253002 5.11811004 4 P 0 0;1=4
P 0.1319 5.02756004 4 P 0 0;1=4
P 0.22245 5.11811004 25 P 0 0;1=12
P 0.313 5.02756004 4 P 0 0;1=4
P 0.35236998 5.11811004 4 P 0 0;1=4
P 0.313 5.20866004 4 P 0 0;1=4
P 0.22245 5.11811004 25 P 0 0;1=12
P 0.1319 0.77953002 4 P 0 0;1=4
P 0.09253002 0.68898002 4 P 0 0;1=4
P 0.1319 0.59843002 4 P 0 0;1=4
P 0.22245 0.68898002 25 P 0 0;1=12
P 0.313 0.59843002 4 P 0 0;1=4
P 0.35236998 0.68898002 4 P 0 0;1=4
P 0.313 0.77953002 4 P 0 0;1=4
P 0.22245 0.68898002 25 P 0 0;1=12
P 10.80498996 5.56656004 4 P 0 0;1=4
P 10.84498996 5.56656004 4 P 0 0;1=4
P 10.80498996 5.42656004 4 P 0 0;1=4
P 10.84498996 5.42656004 4 P 0 0;1=4
P 11.01035 5.42656004 4 P 0 0;1=4
P 10.97035 5.42656004 4 P 0 0;1=4
P 11.01035 5.56656004 4 P 0 0;1=4
P 10.97035 5.56656004 4 P 0 0;1=4
P 11.17571004 5.42656004 4 P 0 0;1=4
P 11.13571004 5.42656004 4 P 0 0;1=4
P 11.17571004 5.56656004 4 P 0 0;1=4
P 11.13571004 5.56656004 4 P 0 0;1=4
P 11.34106998 5.42656004 4 P 0 0;1=4
P 11.30106998 5.42656004 4 P 0 0;1=4
P 11.34106998 5.56656004 4 P 0 0;1=4
P 11.30106998 5.56656004 4 P 0 0;1=4
P 11.50643002 5.42656004 4 P 0 0;1=4
P 11.46643002 5.42656004 4 P 0 0;1=4
P 11.50643002 5.56656004 4 P 0 0;1=4
P 11.46643002 5.56656004 4 P 0 0;1=4
P 11.67178996 5.42656004 4 P 0 0;1=4
P 11.63178996 5.42656004 4 P 0 0;1=4
P 11.67178996 5.56656004 4 P 0 0;1=4
P 11.63178996 5.56656004 4 P 0 0;1=4
P 11.83715 5.42656004 4 P 0 0;1=4
P 11.79715 5.42656004 4 P 0 0;1=4
P 11.83715 5.56656004 4 P 0 0;1=4
P 11.79715 5.56656004 4 P 0 0;1=4
P 12.00251004 5.42656004 4 P 0 0;1=4
P 11.96251004 5.42656004 4 P 0 0;1=4
P 12.00251004 5.56656004 4 P 0 0;1=4
P 11.96251004 5.56656004 4 P 0 0;1=4
P 12.16786998 5.42656004 4 P 0 0;1=4
P 12.12786998 5.42656004 4 P 0 0;1=4
P 12.16786998 5.56656004 4 P 0 0;1=4
P 12.12786998 5.56656004 4 P 0 0;1=4
P 7.32283996 0.23621998 4 P 0 0;1=4
P 7.28016998 0.33921998 4 P 0 0;1=4
P 7.17716998 0.23621998 26 P 0 0;1=13
P 7.28016998 0.13321998 4 P 0 0;1=4
P 7.17716998 0.23621998 26 P 0 0;1=13
P 7.07416998 0.13321998 4 P 0 0;1=4
P 7.0315 0.23621998 4 P 0 0;1=4
P 7.07416998 0.33921998 4 P 0 0;1=4
P 7.32283996 5.7874 4 P 0 0;1=4
P 7.28016998 5.8904 4 P 0 0;1=4
P 7.17716998 5.7874 26 P 0 0;1=13
P 7.28016998 5.6844 4 P 0 0;1=4
P 7.17716998 5.7874 26 P 0 0;1=13
P 7.07416998 5.6844 4 P 0 0;1=4
P 7.0315 5.7874 4 P 0 0;1=4
P 7.07416998 5.8904 4 P 0 0;1=4
P 2.24606004 3.56615 5 P 0 0;1=3
P 8.2 3.26615 5 P 0 0;1=3
P 7.65203996 5.0535 5 P 0 0;1=3
P 2.29606004 2.86615 5 P 0 0;1=3
P 2.29606004 3.56615 5 P 0 0;1=3
P 7.69203996 5.0535 5 P 0 0;1=3
P 8.2 3.31615 5 P 0 0;1=3
P 1.33906004 4.69351004 4 P 0 0;1=0
P 0.80806998 5.46193996 4 P 0 0;1=0
P 3.733 5.075 4 P 0 0;1=4
P 1.28906004 4.69351004 4 P 0 0;1=0
P 8.2 3.41615 5 P 0 0;1=3
P 7.86465 5.169 5 P 0 0;1=3
P 3.94 4.765 4 P 0 0;1=0
P 2.34606004 3.26615 5 P 0 0;1=3
P 2.39716998 4.742 5 P 0 0;1=3
P 8.2 3.46615 5 P 0 0;1=3
P 7.90465 5.169 5 P 0 0;1=3
P 2.06646004 5.29 4 P 0 0;1=0
P 2.34606004 3.31615 5 P 0 0;1=3
P 2.35716998 4.742 5 P 0 0;1=3
P 1.33906004 5.15351004 4 P 0 0;1=0
P 3.105 4.47 4 P 0 0;1=4
P 8 3.46615 5 P 0 0;1=3
P 7.93551004 5.0535 5 P 0 0;1=3
P 2.00146004 5.29 4 P 0 0;1=0
P 2.25855 4.667 5 P 0 0;1=3
P 2.39606004 3.31615 5 P 0 0;1=3
P 1.18906004 5.15351004 4 P 0 0;1=0
P 3.07 4.42 4 P 0 0;1=4
P 8 3.51615 5 P 0 0;1=3
P 7.97551004 5.0535 5 P 0 0;1=3
P 2.21855 4.667 5 P 0 0;1=3
P 2.39606004 3.36615 5 P 0 0;1=3
P 8.11725 5.169 5 P 0 0;1=3
P 8.4 3.46615 5 P 0 0;1=3
P 3.635 0.715 4 P 0 0;1=0
P 4.63268002 2.81615 5 P 0 0;1=3
P 2.44606004 3.26615 5 P 0 0;1=3
P 2.39716998 5.115 5 P 0 0;1=3
P 8.07725 5.169 5 P 0 0;1=3
P 8.4 3.51615 5 P 0 0;1=3
P 2.44606004 3.31615 5 P 0 0;1=3
P 2.35716998 5.115 5 P 0 0;1=3
P 8.5 3.46615 5 P 0 0;1=3
P 8.07206998 4.66688996 5 P 0 0;1=3
P 2.25543996 4.78291998 5 P 0 0;1=3
P 2.49606004 3.31615 5 P 0 0;1=3
P 8.5 3.51615 5 P 0 0;1=3
P 8.03206998 4.66688996 5 P 0 0;1=3
P 4.02 4.42 4 P 0 0;1=0
P 4.58268002 2.76615 5 P 0 0;1=3
P 2.21543996 4.78291998 5 P 0 0;1=3
P 2.49606004 3.36615 5 P 0 0;1=3
P 8.35 3.41615 5 P 0 0;1=3
P 8.11725 4.78291998 5 P 0 0;1=3
P 4.78268002 2.71615 5 P 0 0;1=3
P 2.11371004 4.78291998 5 P 0 0;1=3
P 2.34606004 3.41615 5 P 0 0;1=3
P 8.35 3.46615 5 P 0 0;1=3
P 8.07725 4.78291998 5 P 0 0;1=3
P 5.08268002 2.71615 5 P 0 0;1=3
P 4.06 4.86 4 P 0 0;1=0
P 2.07371004 4.78291998 5 P 0 0;1=3
P 2.34606004 3.46615 5 P 0 0;1=3
P 2.18456998 5.0535 5 P 0 0;1=3
P 2.44606004 3.41615 5 P 0 0;1=3
P 10.93661004 2.41615 5 P 0 0;1=3
P 2.14456998 5.0535 5 P 0 0;1=3
P 2.44606004 3.46615 5 P 0 0;1=3
P 10.93661004 2.46615 5 P 0 0;1=3
P 8.5 3.31615 5 P 0 0;1=3
P 8.25898002 4.78291998 5 P 0 0;1=3
P 4.88268002 2.71615 5 P 0 0;1=3
P 2.06853002 4.66688996 5 P 0 0;1=3
P 2.49606004 3.46615 5 P 0 0;1=3
P 8.5 3.36615 5 P 0 0;1=3
P 8.21898002 4.78291998 5 P 0 0;1=3
P 2.02853002 4.66688996 5 P 0 0;1=3
P 2.49606004 3.51615 5 P 0 0;1=3
P 8.4 3.31615 5 P 0 0;1=3
P 8.26208996 4.667 5 P 0 0;1=3
P 2.11371004 5.169 5 P 0 0;1=3
P 2.39606004 3.46615 5 P 0 0;1=3
P 8.4 3.36615 5 P 0 0;1=3
P 8.22208996 4.667 5 P 0 0;1=3
P 3.84 0.69 4 P 0 0;1=0
P 4.68268002 2.76615 5 P 0 0;1=3
P 2.07371004 5.169 5 P 0 0;1=3
P 2.39606004 3.51615 5 P 0 0;1=3
P 3.56 0.49 4 P 0 0;1=0
P 4.73268002 2.81615 5 P 0 0;1=3
P 1.57765 5.169 5 P 0 0;1=3
P 2.04606004 3.31615 5 P 0 0;1=3
P 9.10853996 4.47 4 P 0 0;1=4
P 7.3426 5.15351004 4 P 0 0;1=0
P 3.785 0.69 4 P 0 0;1=0
P 4.78268002 2.81615 5 P 0 0;1=3
P 1.61765 5.169 5 P 0 0;1=3
P 2.04606004 3.36615 5 P 0 0;1=3
P 8.1 3.26615 5 P 0 0;1=3
P 7.58118996 4.707 5 P 0 0;1=3
P 2.09606004 3.26615 5 P 0 0;1=3
P 1.57765 4.707 5 P 0 0;1=3
P 5.08268002 1.96615 5 P 0 0;1=3
P 8.1 3.31615 5 P 0 0;1=3
P 7.62118996 4.707 5 P 0 0;1=3
P 3.75998996 0.345 4 P 0 0;1=0
P 4.68268002 2.81615 5 P 0 0;1=3
P 2.09606004 3.31615 5 P 0 0;1=3
P 1.61765 4.707 5 P 0 0;1=3
P 0.58 5.591 4 P 0 0;1=0
P 11.67761998 2.85 4 P 0 0;1=4
P 11.865 4.455 4 P 0 0;1=0
P 5.67368996 2.85 4 P 0 0;1=4
P 5.855 3.07 4 P 0 0;1=4
P 5.8522 2.97 4 P 0 0;1=4
P 7.2926 5.15351004 4 P 0 0;1=4
P 7.2426 5.15351004 4 P 0 0;1=4
P 7.1926 4.95351004 4 P 0 0;1=4
P 7.42603996 5.15895 4 P 0 0;1=0
P 3.94 4.655 4 P 0 0;1=4
P 3.77 4.765 4 P 0 0;1=4
P 4.14 4.745 4 P 0 0;1=4
P 4.76 5.375 4 P 0 0;1=4
P 4.96 5.5 4 P 0 0;1=4
P 5.16 5.555 4 P 0 0;1=4
P 4.892 5.767 4 P 0 0;1=4
P 5.088 5.767 4 P 0 0;1=4
P 0.91 5.075 4 P 0 0;1=4
P 1.03 4.96 4 P 0 0;1=4
P 1.03 5.155 4 P 0 0;1=4
P 1.38906004 5.15351004 4 P 0 0;1=0
P 1.23906004 5.15351004 4 P 0 0;1=4
P 1.28906004 5.15351004 4 P 0 0;1=4
P 1.18906004 4.95351004 4 P 0 0;1=4
P 0.83 5.355 4 P 0 0;1=4
P 0.9 5.355 4 P 0 0;1=4
P 0.755 5.355 4 P 0 0;1=4
P 0.73 5.205 4 P 0 0;1=4
P 0.81016004 5.17 4 P 0 0;1=4
P 1.094 5.356 4 P 0 0;1=0
P 1.044 5.448 4 P 0 0;1=4
P 1.4 5.46 4 P 0 0;1=4
P 1.32 5.46 4 P 0 0;1=4
P 1.43798996 5.46016004 4 P 0 0;1=4
P 1.35925 5.46016004 4 P 0 0;1=4
P 0.89 5.885 4 P 0 0;1=4
P 0.81 5.885 4 P 0 0;1=4
P 0.73 5.885 4 P 0 0;1=4
P 0.97 5.885 4 P 0 0;1=4
P 1.04 5.885 4 P 0 0;1=4
P 1.12 5.885 4 P 0 0;1=4
P 8.15 3.31615 5 P 0 0;1=3
P 7.65205 4.78291998 5 P 0 0;1=3
P 11.235 3.3 4 P 0 0;1=4
P 5.815 0.925 4 P 0 0;1=0
P 3.635 0.49 4 P 0 0;1=0
P 4.58268002 2.81615 5 P 0 0;1=3
P 2.19606004 3.26615 5 P 0 0;1=3
P 1.6485 5.0535 5 P 0 0;1=3
P 8.15 3.36615 5 P 0 0;1=3
P 7.69205 4.78291998 5 P 0 0;1=3
P 2.19606004 3.31615 5 P 0 0;1=3
P 1.6885 5.0535 5 P 0 0;1=3
P 8.1 3.41615 5 P 0 0;1=3
P 7.79378996 4.78291998 5 P 0 0;1=3
P 2.14606004 3.31615 5 P 0 0;1=3
P 1.64851004 4.78291998 5 P 0 0;1=3
P 8.1 3.46615 5 P 0 0;1=3
P 7.83378996 4.78291998 5 P 0 0;1=3
P 2.14606004 3.36615 5 P 0 0;1=3
P 1.68851004 4.78291998 5 P 0 0;1=3
P 0.73 4.96 4 P 0 0;1=0
P 3.795 4.6 4 P 0 0;1=4
P 4.86 5.375 4 P 0 0;1=4
P 8.15 3.46615 5 P 0 0;1=3
P 7.86465 4.657 5 P 0 0;1=3
P 2.09606004 3.41615 5 P 0 0;1=3
P 1.79025 4.78291998 5 P 0 0;1=3
P 8.15 3.51615 5 P 0 0;1=3
P 7.90465 4.657 5 P 0 0;1=3
P 2.09606004 3.46615 5 P 0 0;1=3
P 1.83025 4.78291998 5 P 0 0;1=3
P 2.19606004 3.41615 5 P 0 0;1=3
P 1.86111004 5.169 5 P 0 0;1=3
P 2.19606004 3.46615 5 P 0 0;1=3
P 1.90111004 5.169 5 P 0 0;1=3
P 6.72708996 4.5652 4 P 0 0;1=4
P 6.76208996 4.5652 4 P 0 0;1=4
P 6.79708996 4.5652 4 P 0 0;1=4
P 6.83708996 4.5652 4 P 0 0;1=0
P 6.90208996 4.5652 4 P 0 0;1=4
P 6.87208996 4.5652 4 P 0 0;1=4
P 10.99998996 4.9531 4 P 0 0;1=4
P 11.03998996 4.9531 4 P 0 0;1=4
P 10.99998996 4.9131 4 P 0 0;1=4
P 11.03998996 4.9131 4 P 0 0;1=4
P 11.21998996 4.9531 4 P 0 0;1=4
P 11.17998996 4.9531 4 P 0 0;1=4
P 11.13498996 4.9531 4 P 0 0;1=4
P 11.08498996 4.9531 4 P 0 0;1=4
P 11.21998996 4.9131 4 P 0 0;1=4
P 11.17998996 4.9131 4 P 0 0;1=4
P 11.08498996 4.9131 4 P 0 0;1=4
P 11.13498996 4.9131 4 P 0 0;1=4
P 10.99998996 5.1631 4 P 0 0;1=4
P 11.03998996 5.1631 4 P 0 0;1=4
P 10.99998996 5.1231 4 P 0 0;1=4
P 10.99998996 5.0381 4 P 0 0;1=4
P 10.99998996 5.0831 4 P 0 0;1=4
P 10.99998996 4.9931 4 P 0 0;1=4
P 11.03998996 4.9931 4 P 0 0;1=4
P 11.03998996 5.0831 4 P 0 0;1=4
P 11.03998996 5.0381 4 P 0 0;1=4
P 11.03998996 5.1231 4 P 0 0;1=4
P 11.21998996 5.1631 4 P 0 0;1=4
P 11.17998996 5.1631 4 P 0 0;1=4
P 11.08498996 5.1631 4 P 0 0;1=4
P 11.13498996 5.1631 4 P 0 0;1=4
P 11.21998996 5.1231 4 P 0 0;1=4
P 11.21998996 5.0381 4 P 0 0;1=4
P 11.21998996 5.0831 4 P 0 0;1=4
P 11.21998996 4.9931 4 P 0 0;1=4
P 11.17998996 4.9931 4 P 0 0;1=4
P 11.17998996 5.1231 4 P 0 0;1=4
P 11.17998996 5.0831 4 P 0 0;1=4
P 11.17998996 5.0381 4 P 0 0;1=4
P 11.13498996 5.1231 4 P 0 0;1=4
P 11.08498996 5.1231 4 P 0 0;1=4
P 11.6269 4.90498996 4 P 0 0;1=4
P 11.6269 4.85498996 4 P 0 0;1=4
P 11.4269 4.80998996 4 P 0 0;1=4
P 11.4269 4.85498996 4 P 0 0;1=4
P 11.4269 4.90498996 4 P 0 0;1=4
P 11.4269 4.94998996 4 P 0 0;1=4
P 11.4769 4.94998996 4 P 0 0;1=4
P 11.4769 4.80998996 4 P 0 0;1=4
P 11.5269 4.94998996 4 P 0 0;1=4
P 11.5269 4.80998996 4 P 0 0;1=4
P 11.5769 4.94998996 4 P 0 0;1=4
P 11.6269 4.94998996 4 P 0 0;1=4
P 11.6269 4.80998996 4 P 0 0;1=4
P 11.5769 4.80998996 4 P 0 0;1=4
P 10.82676998 5.71338996 13 P 0 0;1=10
P 10.99213002 5.71338996 13 P 0 0;1=10
P 11.15748002 5.71338996 13 P 0 0;1=10
P 11.32283996 5.71338996 13 P 0 0;1=10
P 11.48818996 5.71338996 13 P 0 0;1=10
P 11.65353996 5.71338996 13 P 0 0;1=10
P 11.8189 5.71338996 13 P 0 0;1=10
P 11.98425 5.71338996 13 P 0 0;1=10
P 12.14961004 5.71338996 13 P 0 0;1=10
P 10.80498996 5.7831 4 P 0 0;1=4
P 10.84498996 5.7831 4 P 0 0;1=4
P 10.80498996 5.6431 4 P 0 0;1=4
P 10.84498996 5.6431 4 P 0 0;1=4
P 11.01035 5.6431 4 P 0 0;1=4
P 10.97035 5.6431 4 P 0 0;1=4
P 11.01035 5.7831 4 P 0 0;1=4
P 10.97035 5.7831 4 P 0 0;1=4
P 11.17571004 5.6431 4 P 0 0;1=4
P 11.13571004 5.6431 4 P 0 0;1=4
P 11.17571004 5.7831 4 P 0 0;1=4
P 11.13571004 5.7831 4 P 0 0;1=4
P 11.34106998 5.6431 4 P 0 0;1=4
P 11.30106998 5.6431 4 P 0 0;1=4
P 11.34106998 5.7831 4 P 0 0;1=4
P 11.30106998 5.7831 4 P 0 0;1=4
P 11.50643002 5.6431 4 P 0 0;1=4
P 11.46643002 5.6431 4 P 0 0;1=4
P 11.50643002 5.7831 4 P 0 0;1=4
P 11.46643002 5.7831 4 P 0 0;1=4
P 11.67178996 5.6431 4 P 0 0;1=4
P 11.63178996 5.6431 4 P 0 0;1=4
P 11.67178996 5.7831 4 P 0 0;1=4
P 11.63178996 5.7831 4 P 0 0;1=4
P 11.83715 5.6431 4 P 0 0;1=4
P 11.79715 5.6431 4 P 0 0;1=4
P 11.83715 5.7831 4 P 0 0;1=4
P 11.79715 5.7831 4 P 0 0;1=4
P 12.00251004 5.6431 4 P 0 0;1=4
P 11.96251004 5.6431 4 P 0 0;1=4
P 12.00251004 5.7831 4 P 0 0;1=4
P 11.96251004 5.7831 4 P 0 0;1=4
P 12.16786998 5.6431 4 P 0 0;1=4
P 12.12786998 5.6431 4 P 0 0;1=4
P 12.16786998 5.7831 4 P 0 0;1=4
P 12.12786998 5.7831 4 P 0 0;1=4
P 5.03605 5.1631 4 P 0 0;1=4
P 5.03605 4.9931 4 P 0 0;1=4
P 5.03605 5.0831 4 P 0 0;1=4
P 5.03605 5.0381 4 P 0 0;1=4
P 5.03605 5.1231 4 P 0 0;1=4
P 5.21605 5.1631 4 P 0 0;1=4
P 5.17605 5.1631 4 P 0 0;1=4
P 5.08105 5.1631 4 P 0 0;1=4
P 5.13105 5.1631 4 P 0 0;1=4
P 5.21605 5.1231 4 P 0 0;1=4
P 5.21605 5.0381 4 P 0 0;1=4
P 5.21605 5.0831 4 P 0 0;1=4
P 5.21605 4.9931 4 P 0 0;1=4
P 5.17605 4.9931 4 P 0 0;1=4
P 5.17605 5.1231 4 P 0 0;1=4
P 5.17605 5.0831 4 P 0 0;1=4
P 5.17605 5.0381 4 P 0 0;1=4
P 5.13105 5.1231 4 P 0 0;1=4
P 5.08105 5.1231 4 P 0 0;1=4
P 4.99605 5.1631 4 P 0 0;1=4
P 4.99605 5.1231 4 P 0 0;1=4
P 4.99605 5.0381 4 P 0 0;1=4
P 4.99605 5.0831 4 P 0 0;1=4
P 4.99605 4.9931 4 P 0 0;1=4
P 5.03605 4.9531 4 P 0 0;1=4
P 5.03605 4.9131 4 P 0 0;1=4
P 5.21605 4.9531 4 P 0 0;1=4
P 5.17605 4.9531 4 P 0 0;1=4
P 5.13105 4.9531 4 P 0 0;1=4
P 5.08105 4.9531 4 P 0 0;1=4
P 5.21605 4.9131 4 P 0 0;1=4
P 5.17605 4.9131 4 P 0 0;1=4
P 5.08105 4.9131 4 P 0 0;1=4
P 5.13105 4.9131 4 P 0 0;1=4
P 4.99605 4.9531 4 P 0 0;1=4
P 4.99605 4.9131 4 P 0 0;1=4
P 6.34948996 5.03 4 P 0 0;1=4
P 2.74225 5.14 5 P 0 0;1=3
P 2.04606004 3.61615 5 P 0 0;1=3
P 2.14606004 3.46615 5 P 0 0;1=3
P 1.86111004 4.657 5 P 0 0;1=3
P 2.78225 5.14 5 P 0 0;1=3
P 2.04606004 3.66615 5 P 0 0;1=3
P 2.14606004 3.51615 5 P 0 0;1=3
P 1.90111004 4.657 5 P 0 0;1=3
P 1.93196998 5.0535 5 P 0 0;1=3
P 1.99606004 3.46615 5 P 0 0;1=3
P 4.58268002 2.56615 5 P 0 0;1=3
P 1.97196998 5.0535 5 P 0 0;1=3
P 1.99606004 3.51615 5 P 0 0;1=3
P 2.88086998 5.17001998 5 P 0 0;1=3
P 2.14606004 3.61615 5 P 0 0;1=3
P 2.34606004 3.66615 5 P 0 0;1=3
P 3.56176998 4.71973002 5 P 0 0;1=3
P 2.92086998 5.17001998 5 P 0 0;1=3
P 2.14606004 3.66615 5 P 0 0;1=3
P 2.34606004 3.71615 5 P 0 0;1=3
P 3.52176998 4.71973002 5 P 0 0;1=3
P 2.39606004 3.61615 5 P 0 0;1=3
P 3.49091004 4.587 5 P 0 0;1=3
P 2.39606004 3.66615 5 P 0 0;1=3
P 3.45091004 4.587 5 P 0 0;1=3
P 2.49606004 3.61615 5 P 0 0;1=3
P 3.56176998 5.14 5 P 0 0;1=3
P 2.49606004 3.66615 5 P 0 0;1=3
P 3.52176998 5.14 5 P 0 0;1=3
P 2.44606004 3.66615 5 P 0 0;1=3
P 3.42003996 4.78291998 5 P 0 0;1=3
P 4.30605 4.6631 28 P 0 0;1=4
P 4.34105 4.6431 28 P 0 0;1=4
P 4.38605 4.6431 28 P 0 0;1=4
P 4.42605 4.6631 28 P 0 0;1=4
P 4.46605 4.6631 28 P 0 0;1=4
P 4.30605 4.7031 28 P 0 0;1=4
P 4.42605 4.7031 28 P 0 0;1=4
P 4.46605 4.7031 28 P 0 0;1=4
P 4.26605 4.6631 28 P 0 0;1=4
P 4.26605 4.7031 28 P 0 0;1=4
P 4.65605 4.6631 28 P 0 0;1=4
P 4.69605 4.6631 28 P 0 0;1=4
P 4.65605 4.7031 28 P 0 0;1=4
P 4.69605 4.7031 28 P 0 0;1=4
P 4.73105 4.6431 28 P 0 0;1=4
P 4.81605 4.6631 28 P 0 0;1=4
P 4.85605 4.6631 28 P 0 0;1=4
P 4.81605 4.7031 28 P 0 0;1=4
P 4.85605 4.7031 28 P 0 0;1=4
P 4.77605 4.6431 28 P 0 0;1=4
P 5.17605 4.7131 28 P 0 0;1=4
P 5.17605 4.6731 28 P 0 0;1=4
P 5.08105 4.6731 28 P 0 0;1=4
P 5.13105 4.6731 28 P 0 0;1=4
P 5.03605 4.6731 28 P 0 0;1=4
P 5.03605 4.7131 28 P 0 0;1=4
P 4.30605 4.7481 28 P 0 0;1=4
P 4.30605 4.7931 28 P 0 0;1=4
P 4.30605 4.8381 28 P 0 0;1=4
P 4.38605 4.8381 28 P 0 0;1=4
P 4.34605 4.8381 28 P 0 0;1=4
P 4.46605 4.8381 28 P 0 0;1=4
P 4.42605 4.8381 28 P 0 0;1=4
P 4.42605 4.7931 28 P 0 0;1=4
P 4.42605 4.7481 28 P 0 0;1=4
P 4.46605 4.7931 28 P 0 0;1=4
P 4.46605 4.7481 28 P 0 0;1=4
P 4.26605 4.7481 28 P 0 0;1=4
P 4.26605 4.7931 28 P 0 0;1=4
P 4.26605 4.8381 28 P 0 0;1=4
P 4.65605 4.8381 28 P 0 0;1=4
P 4.65605 4.7931 28 P 0 0;1=4
P 4.65605 4.7481 28 P 0 0;1=4
P 4.69605 4.8381 28 P 0 0;1=4
P 4.69605 4.7931 28 P 0 0;1=4
P 4.69605 4.7481 28 P 0 0;1=4
P 4.73605 4.8381 28 P 0 0;1=4
P 4.81605 4.8381 28 P 0 0;1=4
P 4.81605 4.7931 28 P 0 0;1=4
P 4.81605 4.7481 28 P 0 0;1=4
P 4.85605 4.8381 28 P 0 0;1=4
P 4.85605 4.7931 28 P 0 0;1=4
P 4.85605 4.7481 28 P 0 0;1=4
P 4.77605 4.8381 28 P 0 0;1=4
P 5.08105 4.8431 28 P 0 0;1=4
P 5.13105 4.8431 28 P 0 0;1=4
P 5.17605 4.8431 28 P 0 0;1=4
P 5.17605 4.8031 28 P 0 0;1=4
P 5.17605 4.7581 28 P 0 0;1=4
P 5.03605 4.8431 28 P 0 0;1=4
P 5.03605 4.8031 28 P 0 0;1=4
P 5.03605 4.7581 28 P 0 0;1=4
P 4.58267972 2.96615 28 P 0 0;1=3
P 4.63267972 2.96615 28 P 0 0;1=3
P 4.63267972 3.11615 28 P 0 0;1=3
P 4.58267972 3.01615 28 P 0 0;1=3
P 4.58267972 3.11615 28 P 0 0;1=3
P 4.63267972 3.01615 28 P 0 0;1=3
P 4.63267972 3.31615 28 P 0 0;1=3
P 4.58267972 3.26615 28 P 0 0;1=3
P 4.58267972 3.31615 28 P 0 0;1=3
P 4.63267972 3.26615 28 P 0 0;1=3
P 4.63267972 3.16615 28 P 0 0;1=3
P 4.58267972 3.16615 28 P 0 0;1=3
P 4.58267972 3.46615 28 P 0 0;1=3
P 4.63267972 3.41615 28 P 0 0;1=3
P 4.63267972 3.46615 28 P 0 0;1=3
P 4.58267972 3.41615 28 P 0 0;1=3
P 4.58267972 3.61615 28 P 0 0;1=3
P 4.58267972 3.56615 28 P 0 0;1=3
P 4.63267972 3.61615 28 P 0 0;1=3
P 4.63267972 3.56615 28 P 0 0;1=3
P 4.58267972 3.71615 28 P 0 0;1=3
P 4.63267972 3.71615 28 P 0 0;1=3
P 4.58267972 3.76615 28 P 0 0;1=3
P 4.58267972 3.86615 28 P 0 0;1=3
P 4.63267972 3.76615 28 P 0 0;1=3
P 4.63267972 3.86615 28 P 0 0;1=3
P 4.68267972 2.96615 28 P 0 0;1=3
P 4.73267972 2.96615 28 P 0 0;1=3
P 4.78267972 2.96615 28 P 0 0;1=3
P 4.68267972 3.11615 28 P 0 0;1=3
P 4.68267972 3.01615 28 P 0 0;1=3
P 4.73267972 3.11615 28 P 0 0;1=3
P 4.73267972 3.01615 28 P 0 0;1=3
P 4.78267972 3.11615 28 P 0 0;1=3
P 4.78267972 3.01615 28 P 0 0;1=3
P 4.73267972 3.31615 28 P 0 0;1=3
P 4.73267972 3.26615 28 P 0 0;1=3
P 4.68267972 3.26615 28 P 0 0;1=3
P 4.68267972 3.31615 28 P 0 0;1=3
P 4.78267972 3.26615 28 P 0 0;1=3
P 4.78267972 3.31615 28 P 0 0;1=3
P 4.73267972 3.16615 28 P 0 0;1=3
P 4.68267972 3.16615 28 P 0 0;1=3
P 4.78267972 3.16615 28 P 0 0;1=3
P 4.73267972 3.41615 28 P 0 0;1=3
P 4.68267972 3.41615 28 P 0 0;1=3
P 4.68267972 3.46615 28 P 0 0;1=3
P 4.73267972 3.46615 28 P 0 0;1=3
P 4.78267972 3.46615 28 P 0 0;1=3
P 4.78267972 3.41615 28 P 0 0;1=3
P 4.73267972 3.56615 28 P 0 0;1=3
P 4.73267972 3.61615 28 P 0 0;1=3
P 4.68267972 3.56615 28 P 0 0;1=3
P 4.68267972 3.61615 28 P 0 0;1=3
P 4.78267972 3.61615 28 P 0 0;1=3
P 4.78267972 3.56615 28 P 0 0;1=3
P 4.73267972 3.71615 28 P 0 0;1=3
P 4.68267972 3.71615 28 P 0 0;1=3
P 4.78267972 3.71615 28 P 0 0;1=3
P 4.73267972 3.76615 28 P 0 0;1=3
P 4.73267972 3.86615 28 P 0 0;1=3
P 4.68267972 3.76615 28 P 0 0;1=3
P 4.68267972 3.86615 28 P 0 0;1=3
P 4.78267972 3.76615 28 P 0 0;1=3
P 4.78267972 3.86615 28 P 0 0;1=3
P 4.88267972 3.86615 28 P 0 0;1=3
P 4.83267972 3.86615 28 P 0 0;1=3
P 5.03267972 3.86615 28 P 0 0;1=3
P 4.93267972 3.86615 28 P 0 0;1=3
P 4.98267972 3.86615 28 P 0 0;1=3
P 4.88267972 3.76615 28 P 0 0;1=3
P 4.83267972 3.76615 28 P 0 0;1=3
P 5.03267972 3.76615 28 P 0 0;1=3
P 4.93267972 3.76615 28 P 0 0;1=3
P 4.98267972 3.76615 28 P 0 0;1=3
P 4.88267972 3.71615 28 P 0 0;1=3
P 4.83267972 3.71615 28 P 0 0;1=3
P 5.03267972 3.71615 28 P 0 0;1=3
P 4.93267972 3.71615 28 P 0 0;1=3
P 4.98267972 3.71615 28 P 0 0;1=3
P 4.88267972 3.61615 28 P 0 0;1=3
P 4.83267972 3.61615 28 P 0 0;1=3
P 5.03267972 3.61615 28 P 0 0;1=3
P 4.93267972 3.61615 28 P 0 0;1=3
P 4.98267972 3.61615 28 P 0 0;1=3
P 4.88267972 3.56615 28 P 0 0;1=3
P 4.83267972 3.56615 28 P 0 0;1=3
P 5.03267972 3.56615 28 P 0 0;1=3
P 4.93267972 3.56615 28 P 0 0;1=3
P 4.98267972 3.56615 28 P 0 0;1=3
P 4.88267972 3.46615 28 P 0 0;1=3
P 4.83267972 3.46615 28 P 0 0;1=3
P 5.03267972 3.46615 28 P 0 0;1=3
P 4.93267972 3.46615 28 P 0 0;1=3
P 4.98267972 3.46615 28 P 0 0;1=3
P 4.88267972 3.41615 28 P 0 0;1=3
P 4.83267972 3.41615 28 P 0 0;1=3
P 5.03267972 3.41615 28 P 0 0;1=3
P 4.93267972 3.41615 28 P 0 0;1=3
P 4.98267972 3.41615 28 P 0 0;1=3
P 4.88267972 3.31615 28 P 0 0;1=3
P 4.83267972 3.31615 28 P 0 0;1=3
P 5.03267972 3.31615 28 P 0 0;1=3
P 4.93267972 3.31615 28 P 0 0;1=3
P 4.98267972 3.31615 28 P 0 0;1=3
P 4.83267972 3.26615 28 P 0 0;1=3
P 4.88267972 3.26615 28 P 0 0;1=3
P 4.98267972 3.26615 28 P 0 0;1=3
P 4.93267972 3.26615 28 P 0 0;1=3
P 5.03267972 3.26615 28 P 0 0;1=3
P 4.83267972 3.16615 28 P 0 0;1=3
P 4.88267972 3.16615 28 P 0 0;1=3
P 4.98267972 3.16615 28 P 0 0;1=3
P 4.93267972 3.16615 28 P 0 0;1=3
P 5.03267972 3.16615 28 P 0 0;1=3
P 4.83267972 3.11615 28 P 0 0;1=3
P 4.88267972 3.11615 28 P 0 0;1=3
P 4.98267972 3.11615 28 P 0 0;1=3
P 4.93267972 3.11615 28 P 0 0;1=3
P 5.03267972 3.11615 28 P 0 0;1=3
P 4.83267972 3.01615 28 P 0 0;1=3
P 4.88267972 3.01615 28 P 0 0;1=3
P 4.98267972 3.01615 28 P 0 0;1=3
P 4.93267972 3.01615 28 P 0 0;1=3
P 5.03267972 3.01615 28 P 0 0;1=3
P 4.83267972 2.96615 28 P 0 0;1=3
P 4.88267972 2.96615 28 P 0 0;1=3
P 4.98267972 2.96615 28 P 0 0;1=3
P 4.93267972 2.96615 28 P 0 0;1=3
P 5.03267972 2.96615 28 P 0 0;1=3
P 2.44606004 3.71615 5 P 0 0;1=3
P 3.38003996 4.78291998 5 P 0 0;1=3
P 2.19606004 3.81615 5 P 0 0;1=3
P 3.02571004 4.667 5 P 0 0;1=3
P 2.19606004 3.86615 5 P 0 0;1=3
P 3.06571004 4.667 5 P 0 0;1=3
P 3.27831004 4.642 5 P 0 0;1=3
P 2.39606004 3.76615 5 P 0 0;1=3
P 4.73268002 2.66615 5 P 0 0;1=3
P 10.73661004 2.66615 5 P 0 0;1=3
P 3.23831004 4.642 5 P 0 0;1=3
P 2.39606004 3.81615 5 P 0 0;1=3
P 5.03268002 2.61615 5 P 0 0;1=3
P 3.34916998 5.1035 5 P 0 0;1=3
P 2.49606004 3.76615 5 P 0 0;1=3
P 3.30916998 5.1035 5 P 0 0;1=3
P 2.49606004 3.81615 5 P 0 0;1=3
P 11.03661004 2.61615 5 P 0 0;1=3
P 2.74225 4.667 5 P 0 0;1=3
P 2.09606004 3.66615 5 P 0 0;1=3
P 2.44606004 3.81615 5 P 0 0;1=3
P 3.20743996 4.78291998 5 P 0 0;1=3
P 2.78225 4.667 5 P 0 0;1=3
P 2.09606004 3.71615 5 P 0 0;1=3
P 2.44606004 3.86615 5 P 0 0;1=3
P 3.16743996 4.78291998 5 P 0 0;1=3
P 2.34606004 3.81615 5 P 0 0;1=3
P 3.27831004 5.22001998 5 P 0 0;1=3
P 2.34606004 3.86615 5 P 0 0;1=3
P 3.23831004 5.22001998 5 P 0 0;1=3
P 4.63268002 2.61615 5 P 0 0;1=3
P 10.98661004 2.61615 5 P 0 0;1=3
P 2.19606004 3.66615 5 P 0 0;1=3
P 2.81311004 4.78291998 5 P 0 0;1=3
P 10.98661004 2.56615 5 P 0 0;1=3
P 2.19606004 3.71615 5 P 0 0;1=3
P 2.85311004 4.78291998 5 P 0 0;1=3
P 0.64808996 1.655 4 P 0 0;1=4
P 5.76 2.66 4 P 0 0;1=0
P 10.63661004 2.61615 5 P 0 0;1=3
P 2.09606004 3.81615 5 P 0 0;1=3
P 3.09656998 5.0535 5 P 0 0;1=3
P 2.09606004 3.86615 5 P 0 0;1=3
P 3.13656998 5.0535 5 P 0 0;1=3
P 2.88708002 4.667 5 P 0 0;1=3
P 2.04606004 3.76615 5 P 0 0;1=3
P 10.73661004 2.61615 5 P 0 0;1=3
P 2.92708002 4.667 5 P 0 0;1=3
P 2.04606004 3.81615 5 P 0 0;1=3
P 10.68661004 2.61615 5 P 0 0;1=3
P 5.03268002 2.46615 5 P 0 0;1=3
P 5.03268002 2.51615 5 P 0 0;1=3
P 11.08661004 2.56615 5 P 0 0;1=3
P 10.68661004 2.56615 5 P 0 0;1=3
P 9.175 5.255 4 P 0 0;1=0
P 4.73268002 2.61615 5 P 0 0;1=3
P 9.11853996 5.255 4 P 0 0;1=0
P 5.08268002 2.41615 5 P 0 0;1=3
P 10.93661004 2.66615 5 P 0 0;1=3
P 10.58661004 2.61615 5 P 0 0;1=3
P 8.15 3.76615 5 P 0 0;1=3
P 9.02925 5.165 5 P 0 0;1=3
P 4.98268002 2.21615 5 P 0 0;1=3
P 10.58661004 2.56615 5 P 0 0;1=3
P 8.15 3.81615 5 P 0 0;1=3
P 9.06925 5.165 5 P 0 0;1=3
P 11.03661004 2.66615 5 P 0 0;1=3
P 4.98268002 2.26615 5 P 0 0;1=3
P 10.93661004 2.61615 5 P 0 0;1=3
P 5.03268002 2.26615 5 P 0 0;1=3
P 11.08661004 2.61615 5 P 0 0;1=3
P 5.03268002 2.31615 5 P 0 0;1=3
P 10.63661004 2.66615 5 P 0 0;1=3
P 3.775 5.295 4 P 0 0;1=0
P 0.73 5.78 4 P 0 0;1=4
P 8.07 5.29 4 P 0 0;1=0
P 3.8399 4.765 4 P 0 0;1=0
P 0.81 5.78 4 P 0 0;1=4
P 8.005 5.29 4 P 0 0;1=0
P 11.08661004 1.91615 5 P 0 0;1=3
P 4.98268002 1.91615 5 P 0 0;1=3
P 4.98268002 1.96615 5 P 0 0;1=3
P 4.93268002 1.86615 5 P 0 0;1=3
P 4.93268002 1.91615 5 P 0 0;1=3
P 5.03268002 1.86615 5 P 0 0;1=3
P 5.08268002 1.91615 5 P 0 0;1=3
P 5.08268002 2.56615 5 P 0 0;1=3
P 8.15 2.51615 5 P 0 0;1=3
P 4.98268002 2.61615 5 P 0 0;1=3
P 10.68661004 2.71615 5 P 0 0;1=3
P 10.98661004 2.71615 5 P 0 0;1=3
P 10.78661004 2.71615 5 P 0 0;1=3
P 4.93268002 2.66615 5 P 0 0;1=3
P 10.88661004 2.71615 5 P 0 0;1=3
P 10.68661004 2.76615 5 P 0 0;1=3
P 9.64 0.71 4 P 0 0;1=0
P 10.58661004 2.81615 5 P 0 0;1=3
P 9.43296004 0.49133002 4 P 0 0;1=0
P 9.43296004 0.73633002 4 P 0 0;1=0
P 10.63661004 2.81615 5 P 0 0;1=3
P 4.68268002 2.56615 5 P 0 0;1=3
P 10.68661004 2.81615 5 P 0 0;1=3
P 9.55795 0.36633002 4 P 0 0;1=0
P 10.73661004 2.81615 5 P 0 0;1=3
P 9.35796004 0.49133002 4 P 0 0;1=0
P 5.03268002 2.66615 5 P 0 0;1=3
P 10.78661004 2.81615 5 P 0 0;1=3
P 9.58296004 0.71133002 4 P 0 0;1=0
P 5.08268002 2.61615 5 P 0 0;1=3
P 11.08661004 1.96615 5 P 0 0;1=3
P 11.03661004 1.86615 5 P 0 0;1=3
P 11.03661004 1.91615 5 P 0 0;1=3
P 10.93661004 1.86615 5 P 0 0;1=3
P 10.93661004 1.91615 5 P 0 0;1=3
P 10.98661004 1.91615 5 P 0 0;1=3
P 10.98661004 1.96615 5 P 0 0;1=3
P 4.93268002 2.61615 5 P 0 0;1=3
P 11.03661004 2.01615 5 P 0 0;1=3
P 11.03661004 2.06615 5 P 0 0;1=3
P 10.93661004 2.01615 5 P 0 0;1=3
P 10.93661004 2.06615 5 P 0 0;1=3
P 10.98661004 2.06615 5 P 0 0;1=3
P 10.98661004 2.11615 5 P 0 0;1=3
P 11.08661004 2.06615 5 P 0 0;1=3
P 11.08661004 2.11615 5 P 0 0;1=3
P 3.115 5.255 4 P 0 0;1=0
P 4.63268002 2.66615 5 P 0 0;1=3
P 11.08661004 2.21615 5 P 0 0;1=3
P 4.98268002 2.56615 5 P 0 0;1=3
P 11.08661004 2.26615 5 P 0 0;1=3
P 11.03661004 2.26615 5 P 0 0;1=3
P 2.14606004 3.76615 5 P 0 0;1=3
P 3.02571004 5.165 5 P 0 0;1=3
P 11.03661004 2.31615 5 P 0 0;1=3
P 10.98661004 2.21615 5 P 0 0;1=3
P 10.98661004 2.26615 5 P 0 0;1=3
P 3.17146004 5.255 4 P 0 0;1=0
P 4.68268002 2.61615 5 P 0 0;1=3
P 10.93661004 2.26615 5 P 0 0;1=3
P 10.58661004 2.76615 5 P 0 0;1=3
P 4 5.29 4 P 0 0;1=0
P 10.93661004 2.31615 5 P 0 0;1=3
P 10.88661004 2.16615 5 P 0 0;1=3
P 10.73661004 1.91615 5 P 0 0;1=3
P 10.395 1.28555 5 P 0 0;1=3
P 12.81495 1.96456998 10 P 0 0;1=1
P 9.42358002 5.22001998 5 P 0 0;1=3
P 8.98115 2.825 5 P 0 0;1=3
P 4.58268002 2.61615 5 P 0 0;1=3
P 9.38358002 5.22001998 5 P 0 0;1=3
P 8.98115 2.865 5 P 0 0;1=3
P 2.14606004 3.81615 5 P 0 0;1=3
P 3.06571004 5.165 5 P 0 0;1=3
P 11.08661004 2.71615 5 P 0 0;1=3
P 3.985 4.88998996 4 P 0 0;1=0
P 11.73316004 2.652 5 P 0 0;1=3
P 12.55905 4.40551004 10 P 0 0;1=1
P 11.73316004 2.612 5 P 0 0;1=3
P 12.63778996 4.44488002 10 P 0 0;1=1
P 8.3 2.86615 5 P 0 0;1=3
P 4.83268002 2.16615 5 P 0 0;1=3
P 0.69348996 1.90611998 5 P 0 0;1=3
P 11.73316004 2.492 5 P 0 0;1=3
P 12.55905 4.24803002 10 P 0 0;1=1
P 4.88268002 2.16615 5 P 0 0;1=3
P 0.69348996 1.86611998 5 P 0 0;1=3
P 11.73316004 2.452 5 P 0 0;1=3
P 12.63778996 4.2874 10 P 0 0;1=1
P 8.25 2.86615 5 P 0 0;1=3
P 12.55905 3.93306998 10 P 0 0;1=1
P 11.73316004 2.332 5 P 0 0;1=3
P 12.63778996 3.97243996 10 P 0 0;1=1
P 11.73316004 2.292 5 P 0 0;1=3
P 10.83661004 2.16615 5 P 0 0;1=3
P 11.53316004 2.092 5 P 0 0;1=3
P 12.55905 3.77558996 10 P 0 0;1=1
P 11.53316004 2.052 5 P 0 0;1=3
P 12.63778996 3.81496004 10 P 0 0;1=1
P 12.81495 3.53936998 10 P 0 0;1=1
P 10.68661004 2.26615 5 P 0 0;1=3
P 9.975 2.3758 5 P 0 0;1=3
P 12.81495 3.38188996 10 P 0 0;1=1
P 10.73661004 2.31615 5 P 0 0;1=3
P 9.975 2.23955 5 P 0 0;1=3
P 12.81495 2.20078996 10 P 0 0;1=1
P 10.68661004 1.91615 5 P 0 0;1=3
P 10.42445 1.395 5 P 0 0;1=3
P 12.81495 2.75196998 10 P 0 0;1=1
P 10.73661004 2.01615 5 P 0 0;1=3
P 10.26025 1.82845 5 P 0 0;1=3
P 12.73621004 3.73621998 10 P 0 0;1=1
P 10.58661004 2.21615 5 P 0 0;1=3
P 10.09 2.26825 5 P 0 0;1=3
P 10.73661004 2.41615 5 P 0 0;1=3
P 10.09 2.69655 5 P 0 0;1=3
P 12.73621004 4.52361998 10 P 0 0;1=1
P 7.3426 4.69351004 4 P 0 0;1=0
P 11.73316004 1.532 5 P 0 0;1=3
P 12.55905 2.27953002 10 P 0 0;1=1
P 7.2926 4.69351004 4 P 0 0;1=0
P 12.73621004 3.57873996 10 P 0 0;1=1
P 10.68661004 2.21615 5 P 0 0;1=3
P 9.975 2.3358 5 P 0 0;1=3
P 12.73621004 3.42126004 10 P 0 0;1=1
P 10.73661004 2.26615 5 P 0 0;1=3
P 9.975 2.19955 5 P 0 0;1=3
P 11.73316004 2.172 5 P 0 0;1=3
P 12.55905 3.46063002 10 P 0 0;1=1
P 4.98268002 2.36615 5 P 0 0;1=3
P 10.73661004 1.86615 5 P 0 0;1=3
P 10.395 1.32555 5 P 0 0;1=3
P 12.73621004 2.00393996 10 P 0 0;1=1
P 11.73316004 2.132 5 P 0 0;1=3
P 12.63778996 3.5 10 P 0 0;1=1
P 3.38003996 5.22001998 5 P 0 0;1=3
P 2.97721004 2.865 5 P 0 0;1=3
P 4.98268002 2.41615 5 P 0 0;1=3
P 12.63778996 1.76771998 10 P 0 0;1=1
P 3.42003996 5.22001998 5 P 0 0;1=3
P 2.97721004 2.825 5 P 0 0;1=3
P 4.88267972 2.81615 28 P 0 0;1=3
P 4.93267972 2.81615 28 P 0 0;1=3
P 4.98267972 2.81615 28 P 0 0;1=3
P 5.03267972 2.81615 28 P 0 0;1=3
P 5.08267972 2.81615 28 P 0 0;1=3
P 11.03660974 2.81615 28 P 0 0;1=3
P 11.08660974 2.81615 28 P 0 0;1=3
P 10.98660974 2.81615 28 P 0 0;1=3
P 10.93660974 2.81615 28 P 0 0;1=3
P 10.88660974 2.81615 28 P 0 0;1=3
P 5.27885974 3.0214 28 P 0 0;1=4
P 5.27885974 3.0564 28 P 0 0;1=4
P 5.27885974 3.1014 28 P 0 0;1=4
P 5.27885974 3.1364 28 P 0 0;1=4
P 5.27885974 2.9764 28 P 0 0;1=4
P 5.27885974 2.9414 28 P 0 0;1=4
P 5.27885974 3.2614 28 P 0 0;1=4
P 5.27885974 3.2964 28 P 0 0;1=4
P 5.27885974 3.2164 28 P 0 0;1=4
P 5.27885974 3.1814 28 P 0 0;1=4
P 11.28278976 3.1814 28 P 0 0;1=4
P 11.28278976 3.2164 28 P 0 0;1=4
P 11.28278976 3.2964 28 P 0 0;1=4
P 11.28278976 3.2614 28 P 0 0;1=4
P 11.28278976 2.9414 28 P 0 0;1=4
P 11.28278976 2.9764 28 P 0 0;1=4
P 11.28278976 3.1364 28 P 0 0;1=4
P 11.28278976 3.1014 28 P 0 0;1=4
P 11.28278976 3.0564 28 P 0 0;1=4
P 11.28278976 3.0214 28 P 0 0;1=4
P 5.59708976 4.7302 28 P 0 0;1=4
P 5.57708976 4.6802 28 P 0 0;1=4
P 5.75708976 4.7302 28 P 0 0;1=4
P 5.83708976 4.7302 28 P 0 0;1=4
P 5.69708976 4.6802 28 P 0 0;1=4
P 5.73708976 4.6802 28 P 0 0;1=4
P 5.77708976 4.6802 28 P 0 0;1=4
P 5.81708976 4.6802 28 P 0 0;1=4
P 5.85708976 4.6802 28 P 0 0;1=4
P 5.67708976 4.7302 28 P 0 0;1=4
P 5.65708976 4.6802 28 P 0 0;1=4
P 5.61708976 4.6802 28 P 0 0;1=4
P 6.13708976 4.7602 28 P 0 0;1=4
P 6.09708976 4.6802 28 P 0 0;1=4
P 6.13708976 4.6402 28 P 0 0;1=4
P 6.13708976 4.6802 28 P 0 0;1=4
P 6.13708976 4.7202 28 P 0 0;1=4
P 5.91708976 4.7302 28 P 0 0;1=4
P 5.99708976 4.7302 28 P 0 0;1=4
P 6.07708976 4.7302 28 P 0 0;1=4
P 5.89708976 4.6802 28 P 0 0;1=4
P 5.93708976 4.6802 28 P 0 0;1=4
P 5.97708976 4.6802 28 P 0 0;1=4
P 6.01708976 4.6802 28 P 0 0;1=4
P 6.05708976 4.6802 28 P 0 0;1=4
P 5.59708976 4.7702 28 P 0 0;1=4
P 5.59708976 4.8102 28 P 0 0;1=4
P 5.75708976 4.8102 28 P 0 0;1=4
P 5.83708976 4.8102 28 P 0 0;1=4
P 5.75708976 4.7702 28 P 0 0;1=4
P 5.83708976 4.7702 28 P 0 0;1=4
P 5.67708976 4.8102 28 P 0 0;1=4
P 5.67708976 4.7702 28 P 0 0;1=4
P 6.13708976 4.9252 28 P 0 0;1=4
P 6.13708976 4.8402 28 P 0 0;1=4
P 6.13708976 4.8002 28 P 0 0;1=4
P 6.13708976 4.8852 28 P 0 0;1=4
P 5.91708976 4.8102 28 P 0 0;1=4
P 5.99708976 4.8102 28 P 0 0;1=4
P 5.91708976 4.7702 28 P 0 0;1=4
P 5.99708976 4.7702 28 P 0 0;1=4
P 6.07708976 4.8102 28 P 0 0;1=4
P 6.07708976 4.7702 28 P 0 0;1=4
P 4.93268002 2.26615 5 P 0 0;1=3
P 4.93268002 2.31615 5 P 0 0;1=3
P 5.08268002 2.36615 5 P 0 0;1=3
P 12.81495 3.22441004 10 P 0 0;1=1
P 10.68661004 2.06615 5 P 0 0;1=3
P 10.09 2.13095 5 P 0 0;1=3
P 10.63661004 2.31615 5 P 0 0;1=3
P 10.09 2.40335 5 P 0 0;1=3
P 12.81495 3.85433002 10 P 0 0;1=1
P 11.73316004 2.012 5 P 0 0;1=3
P 12.63778996 3.1063 10 P 0 0;1=1
P 11.73316004 1.972 5 P 0 0;1=3
P 12.55905 3.14566998 10 P 0 0;1=1
P 11.53316004 1.732 5 P 0 0;1=3
P 12.55905 2.98818996 10 P 0 0;1=1
P 12.81495 3.69685 10 P 0 0;1=1
P 10.58661004 2.26615 5 P 0 0;1=3
P 10.09 2.30825 5 P 0 0;1=3
P 11.53316004 1.772 5 P 0 0;1=3
P 12.63778996 2.94881998 10 P 0 0;1=1
P 12.81495 4.32676998 10 P 0 0;1=1
P 10.63661004 2.46615 5 P 0 0;1=3
P 9.975 2.62445 5 P 0 0;1=3
P 12.63778996 2.79133996 10 P 0 0;1=1
P 11.73316004 1.852 5 P 0 0;1=3
P 12.55905 2.83071004 10 P 0 0;1=1
P 11.73316004 1.812 5 P 0 0;1=3
P 10.73661004 2.46615 5 P 0 0;1=3
P 10.09 2.73655 5 P 0 0;1=3
P 12.81495 4.48425 10 P 0 0;1=1
P 10.63661004 2.26615 5 P 0 0;1=3
P 10.09 2.44335 5 P 0 0;1=3
P 12.73621004 3.8937 10 P 0 0;1=1
P 10.58661004 2.41615 5 P 0 0;1=3
P 9.975 2.5109 5 P 0 0;1=3
P 12.81495 4.16928996 10 P 0 0;1=1
P 1.025 -0.35 30 P 0 3;1=6
P 1.325 -0.35 30 P 0 3;1=6
P 1.175 -0.35 30 P 0 3;1=6
P 0.725 -0.35 30 P 0 3;1=6
P 0.875 -0.35 30 P 0 3;1=6
P 12.73621004 4.05118002 10 P 0 0;1=1
P 10.68661004 2.36615 5 P 0 0;1=3
P 10.09 2.53845 5 P 0 0;1=3
P 12.81495 2.35826998 10 P 0 0;1=1
P 10.63661004 1.86615 5 P 0 0;1=3
P 10.35543002 1.52156998 5 P 0 0;1=3
P 5.03268002 2.01615 5 P 0 0;1=3
P 5.08268002 2.21615 5 P 0 0;1=3
P 12.73621004 2.16141998 10 P 0 0;1=1
P 10.68661004 1.96615 5 P 0 0;1=3
P 10.46445 1.395 5 P 0 0;1=3
P 0.2 -0.293 20 P 0 0;1=14
P 12.27 0.29 20 P 0 0;1=14
P 0.66 0.29 20 P 0 0;1=14
P 0.2 5.82361998 20 P 0 0;1=14
P 12.81495 1.57086998 10 P 0 0;1=1
P 12.73621004 1.5315 10 P 0 0;1=1
P 12.63778996 2.7126 10 P 0 0;1=1
P 12.55905 2.67323002 10 P 0 0;1=1
P 12.55905 1.64961004 10 P 0 0;1=1
P 12.63778996 1.61023996 10 P 0 0;1=1
P 12.55905 1.57086998 10 P 0 0;1=1
P 12.63778996 1.5315 10 P 0 0;1=1
P 12.73621004 1.68898002 10 P 0 0;1=1
P 12.81495 1.64961004 10 P 0 0;1=1
P 12.63778996 1.68898002 10 P 0 0;1=1
P 12.55905 1.72835 10 P 0 0;1=1
P 12.81495 1.72835 10 P 0 0;1=1
P 12.73621004 1.45276004 10 P 0 0;1=1
P 12.81495 1.41338996 10 P 0 0;1=1
P 12.73621004 1.37401998 10 P 0 0;1=7
P 12.63778996 1.45276004 10 P 0 0;1=1
P 12.55905 1.41338996 10 P 0 0;1=1
P 0.35038996 1.5315 10 P 0 0;1=1
P 0.27165 1.49213002 10 P 0 0;1=1
P 0.17323002 2.67323002 10 P 0 0;1=1
P 0.09448996 2.63386004 10 P 0 0;1=1
P 0.09448996 1.61023996 10 P 0 0;1=1
P 0.17323002 1.57086998 10 P 0 0;1=1
P 0.09448996 1.5315 10 P 0 0;1=1
P 0.17323002 1.49213002 10 P 0 0;1=1
P 0.27165 1.64961004 10 P 0 0;1=1
P 0.35038996 1.61023996 10 P 0 0;1=1
P 0.17323002 1.64961004 10 P 0 0;1=1
P 0.09448996 1.68898002 10 P 0 0;1=1
P 0.35038996 1.68898002 10 P 0 0;1=1
P 0.27165 1.41338996 10 P 0 0;1=1
P 0.35038996 1.37401998 10 P 0 0;1=1
P 0.27165 1.33465 10 P 0 0;1=7
P 0.17323002 1.41338996 10 P 0 0;1=1
P 0.09448996 1.37401998 10 P 0 0;1=1
P 10.20866004 5.4441 27 P 0 0;1=15
P 5.78346004 5.4441 27 P 0 0;1=15
P 12.7252 6.31661998 20 P 0 0;1=14
P 0.2 6.31661998 20 P 0 0;1=14
P 12.7252 -0.293 20 P 0 0;1=14
P 0.22245 4.87401004 17 P 0 0;1=5
P 12.68701004 0.46063002 21 P 0 0;1=16
P 12.68701998 5.4252 21 P 0 0;1=16
P 0.22245 0.42126004 21 P 0 0;1=16
P 0.22255 5.38583002 21 P 0 0;1=16
P 7.17716998 5.7874 24 P 0 0;1=17
P 7.17716998 0.23621998 24 P 0 0;1=17
P 0.22245 0.68898002 23 P 0 0;1=18
P 0.22245 5.11811004 23 P 0 0;1=18
P 12.68701998 5.15748002 23 P 0 0;1=18
P 12.68701998 0.72835 23 P 0 0;1=18
P 6.11811004 1.52756004 23 P 0 0;1=18
P 6.11811004 4.20473002 23 P 0 0;1=18
P 4.83268002 4.22441004 23 P 0 0;1=18
P 2.24606004 4.22441004 23 P 0 0;1=18
P 0.96063002 4.20473002 23 P 0 0;1=18
P 0.96063002 1.52756004 23 P 0 0;1=18
P 2.24606004 1.50786998 23 P 0 0;1=18
P 4.83268002 1.50786998 23 P 0 0;1=18
P 6.04921004 2.58268002 22 P 0 0;1=19
P 1.05905 2.58268002 29 P 0 0;1=20
P 12.12205 1.52756004 23 P 0 0;1=18
P 12.12205 4.20473002 23 P 0 0;1=18
P 10.83661998 4.22441004 23 P 0 0;1=18
P 8.25 4.22441004 23 P 0 0;1=18
P 6.96456998 4.20473002 23 P 0 0;1=18
P 6.96456998 1.52756004 23 P 0 0;1=18
P 8.25 1.50786998 23 P 0 0;1=18
P 10.83661998 1.50786998 23 P 0 0;1=18
P 12.05315 2.58268002 22 P 0 0;1=19
P 7.06298996 2.58268002 29 P 0 0;1=20
P 12.33465 5.69528002 19 P 0 0;1=21
P 3.58311004 4.91851004 14 P 0 0;1=22
P 2.72091004 4.91851004 14 P 0 0;1=22
P 9.58665 4.91851004 14 P 0 0;1=22
P 8.72445 4.91851004 14 P 0 0;1=22
P 2.41851004 4.91851004 14 P 0 0;1=22
P 1.55631004 4.91851004 14 P 0 0;1=22
P 8.42205 4.91851004 14 P 0 0;1=22
P 7.55985 4.91851004 14 P 0 0;1=22
P 0.22243996 1.79331004 16 P 0 0;1=23
P 0.22243996 4.67323002 16 P 0 0;1=23
P 12.687 1.83268002 16 P 0 0;1=23
P 12.687 4.7126 16 P 0 0;1=23
P 0.7687 5.62008002 12 P 0 0;1=24
P 1.47736004 5.62008002 12 P 0 0;1=24
L 1.88908002 -1.91246004 1.89293002 -1.91246004 0 P 0 ;0
L 1.89126998 -1.91146004 1.89656998 -1.91146004 0 P 0 ;0
L 1.89393996 -1.91046004 1.9155 -1.91046004 0 P 0 ;0
L 1.91593996 -1.91246004 1.92048996 -1.91246004 0 P 0 ;0
L 1.9126 -1.91146004 1.9184 -1.91146004 0 P 0 ;0
L 1.89763002 -1.90946004 1.91016998 -1.90946004 0 P 0 ;0
L 1.89053002 -1.96001004 1.8974 -1.96001004 0 P 0 ;0
L 1.89053002 -1.95901004 1.8974 -1.95901004 0 P 0 ;0
L 1.89053002 -1.95801004 1.8974 -1.95801004 0 P 0 ;0
L 1.89053002 -1.95701004 1.8974 -1.95701004 0 P 0 ;0
L 1.89053002 -1.95601004 1.8974 -1.95601004 0 P 0 ;0
L 1.89053002 -1.95501004 1.8974 -1.95501004 0 P 0 ;0
L 1.89053002 -1.95401004 1.8974 -1.95401004 0 P 0 ;0
L 1.89053002 -1.95301004 1.89741004 -1.95301004 0 P 0 ;0
L 1.89053002 -1.95201004 1.89741998 -1.95201004 0 P 0 ;0
L 1.89053002 -1.95101004 1.89743996 -1.95101004 0 P 0 ;0
L 1.89053002 -1.95001004 1.89745 -1.95001004 0 P 0 ;0
L 1.89053002 -1.94901004 1.89746004 -1.94901004 0 P 0 ;0
L 1.89053002 -1.94801004 1.89753002 -1.94801004 0 P 0 ;0
L 1.89053002 -1.94701004 1.8977 -1.94701004 0 P 0 ;0
L 1.89053002 -1.94601004 1.89798002 -1.94601004 0 P 0 ;0
L 1.89053002 -1.94501004 1.89861004 -1.94501004 0 P 0 ;0
L 1.89053002 -1.94401004 1.90005 -1.94401004 0 P 0 ;0
L 1.89053002 -1.94301004 1.9113 -1.94301004 0 P 0 ;0
L 1.89053002 -1.94201004 1.91168002 -1.94201004 0 P 0 ;0
L 1.89053002 -1.94101004 1.91246998 -1.94101004 0 P 0 ;0
L 1.89053002 -1.94001004 1.90093996 -1.94001004 0 P 0 ;0
L 1.89053002 -1.93901004 1.89856004 -1.93901004 0 P 0 ;0
L 1.89053002 -1.93801004 1.89786998 -1.93801004 0 P 0 ;0
L 1.89053002 -1.93701004 1.89753996 -1.93701004 0 P 0 ;0
L 1.89053002 -1.93601004 1.89746998 -1.93601004 0 P 0 ;0
L 1.89053002 -1.93501004 1.89743996 -1.93501004 0 P 0 ;0
L 1.89053002 -1.93401004 1.89741998 -1.93401004 0 P 0 ;0
L 1.89053002 -1.93301004 1.8974 -1.93301004 0 P 0 ;0
L 1.89053002 -1.93201004 1.8974 -1.93201004 0 P 0 ;0
L 1.89053002 -1.93101004 1.8974 -1.93101004 0 P 0 ;0
L 1.89053002 -1.93001004 1.8974 -1.93001004 0 P 0 ;0
L 1.89053002 -1.92901004 1.8974 -1.92901004 0 P 0 ;0
L 1.89053002 -1.92801004 1.89753002 -1.92801004 0 P 0 ;0
L 1.89053002 -1.92701004 1.89793996 -1.92701004 0 P 0 ;0
L 1.89053002 -1.92601004 1.91713002 -1.92601004 0 P 0 ;0
L 1.89053002 -1.92501004 1.91628996 -1.92501004 0 P 0 ;0
L 1.89053002 -1.92401004 1.91513996 -1.92401004 0 P 0 ;0
L 1.89053002 -1.92301004 1.91321998 -1.92301004 0 P 0 ;0
L 1.89053002 -1.92201004 1.90551004 -1.92201004 0 P 0 ;0
L 1.89438996 -1.97246004 1.91331004 -1.97246004 0 P 0 ;0
L 1.89106998 -1.97146004 1.89973002 -1.97146004 0 P 0 ;0
L 1.88878002 -1.97046004 1.8949 -1.97046004 0 P 0 ;0
L 1.88698002 -1.96946004 1.89206998 -1.96946004 0 P 0 ;0
L 1.88546004 -1.96846004 1.88986998 -1.96846004 0 P 0 ;0
L 1.88416998 -1.96746004 1.88808996 -1.96746004 0 P 0 ;0
L 1.88288002 -1.96646004 1.88655 -1.96646004 0 P 0 ;0
L 1.88176998 -1.96546004 1.88518002 -1.96546004 0 P 0 ;0
L 1.88068996 -1.96446004 1.88393996 -1.96446004 0 P 0 ;0
L 1.87968996 -1.96346004 1.88286004 -1.96346004 0 P 0 ;0
L 1.87878002 -1.96246004 1.88186004 -1.96246004 0 P 0 ;0
L 1.8786 -1.92046004 1.88126998 -1.92046004 0 P 0 ;0
L 1.87946998 -1.91946004 1.88223002 -1.91946004 0 P 0 ;0
L 1.88048002 -1.91846004 1.88321004 -1.91846004 0 P 0 ;0
L 1.88153996 -1.91746004 1.88436998 -1.91746004 0 P 0 ;0
L 1.88273002 -1.91646004 1.88558996 -1.91646004 0 P 0 ;0
L 1.88406004 -1.91546004 1.88696998 -1.91546004 0 P 0 ;0
L 1.88548996 -1.91446004 1.88853002 -1.91446004 0 P 0 ;0
L 1.88718002 -1.91346004 1.89041998 -1.91346004 0 P 0 ;0
L 1.90896004 -1.92963996 1.90921998 -1.92991998 0 P 0 ;0
L 1.90921998 -1.92991998 1.90945 -1.93021998 0 P 0 ;0
L 1.90945 -1.93021998 1.90966004 -1.93053002 0 P 0 ;0
L 1.90966004 -1.93053002 1.90983002 -1.93086004 0 P 0 ;0
L 1.90983002 -1.93086004 1.90998002 -1.93121004 0 P 0 ;0
L 1.90998002 -1.93121004 1.9101 -1.93156998 0 P 0 ;0
L 1.9101 -1.93156998 1.91018996 -1.93193996 0 P 0 ;0
L 1.91018996 -1.93193996 1.91023996 -1.93231004 0 P 0 ;0
L 1.91023996 -1.93231004 1.91026998 -1.93265 0 P 0 ;0
L 1.91026998 -1.93265 1.91026004 -1.93298002 0 P 0 ;0
L 1.91026004 -1.93298002 1.91023002 -1.93331004 0 P 0 ;0
L 1.91023002 -1.93331004 1.91016998 -1.93363996 0 P 0 ;0
L 1.91016998 -1.93363996 1.91008996 -1.93396004 0 P 0 ;0
L 1.91008996 -1.93396004 1.90998002 -1.93428002 0 P 0 ;0
L 1.90998002 -1.93428002 1.90983996 -1.93458002 0 P 0 ;0
L 1.90983996 -1.93458002 1.90968996 -1.93486998 0 P 0 ;0
L 1.90968996 -1.93486998 1.90951004 -1.93516004 0 P 0 ;0
L 1.90951004 -1.93516004 1.90921004 -1.93556004 0 P 0 ;0
L 1.90921004 -1.93556004 1.90888002 -1.93593002 0 P 0 ;0
L 1.90888002 -1.93593002 1.90853002 -1.93626998 0 P 0 ;0
L 1.90853002 -1.93626998 1.90815 -1.93658996 0 P 0 ;0
L 1.90815 -1.93658996 1.90773996 -1.93686998 0 P 0 ;0
L 1.90773996 -1.93686998 1.90731998 -1.93711998 0 P 0 ;0
L 1.90731998 -1.93711998 1.90686998 -1.93733996 0 P 0 ;0
L 1.90686998 -1.93733996 1.90615 -1.93761004 0 P 0 ;0
L 1.90615 -1.93761004 1.90541998 -1.93783002 0 P 0 ;0
L 1.90541998 -1.93783002 1.90466004 -1.93798002 0 P 0 ;0
L 1.90466004 -1.93798002 1.9039 -1.93808002 0 P 0 ;0
L 1.9039 -1.93808002 1.90311998 -1.9381 0 P 0 ;0
L 1.90311998 -1.9381 1.90196004 -1.93808002 0 P 0 ;0
L 1.90196004 -1.93808002 1.90078996 -1.93798996 0 P 0 ;0
L 1.90078996 -1.93798996 1.90068002 -1.93798002 0 P 0 ;0
L 1.90068002 -1.93798002 1.90058002 -1.93795 0 P 0 ;0
L 1.90058002 -1.93795 1.90046998 -1.93791998 0 P 0 ;0
L 1.90046998 -1.93791998 1.90038002 -1.93788002 0 P 0 ;0
L 1.90038002 -1.93788002 1.90028002 -1.93783002 0 P 0 ;0
L 1.90028002 -1.93783002 1.90018996 -1.93778002 0 P 0 ;0
L 1.90018996 -1.93778002 1.9001 -1.93771004 0 P 0 ;0
L 1.9001 -1.93771004 1.90001998 -1.93763996 0 P 0 ;0
L 1.90001998 -1.93763996 1.89988002 -1.93748002 0 P 0 ;0
L 1.89988002 -1.93748002 1.89978002 -1.93733996 0 P 0 ;0
L 1.89978002 -1.93733996 1.89961998 -1.93703996 0 P 0 ;0
L 1.89961998 -1.93703996 1.89956998 -1.93688002 0 P 0 ;0
L 1.89956998 -1.93688002 1.89951998 -1.93671004 0 P 0 ;0
L 1.89951998 -1.93671004 1.89948996 -1.93655 0 P 0 ;0
L 1.89948996 -1.93655 1.89946998 -1.93636998 0 P 0 ;0
L 1.89946998 -1.93636998 1.8994 -1.93323002 0 P 0 ;0
L 1.8994 -1.93323002 1.8994 -1.92833002 0 P 0 ;0
L 1.8994 -1.92833002 1.90353996 -1.92833002 0 P 0 ;0
L 1.90353996 -1.92833002 1.90436998 -1.92835 0 P 0 ;0
L 1.90436998 -1.92835 1.9052 -1.92843002 0 P 0 ;0
L 1.9052 -1.92843002 1.90603002 -1.92853996 0 P 0 ;0
L 1.90603002 -1.92853996 1.90683996 -1.92871004 0 P 0 ;0
L 1.90683996 -1.92871004 1.90751004 -1.9289 0 P 0 ;0
L 1.90751004 -1.9289 1.90818002 -1.92913002 0 P 0 ;0
L 1.90818002 -1.92913002 1.90851998 -1.92928996 0 P 0 ;0
L 1.90851998 -1.92928996 1.90868002 -1.92938996 0 P 0 ;0
L 1.90868002 -1.92938996 1.90883002 -1.92951004 0 P 0 ;0
L 1.90883002 -1.92951004 1.90896004 -1.92963996 0 P 0 ;0
L 1.91188996 -1.96001004 1.91638996 -1.96001004 0 P 0 ;0
L 1.91156998 -1.95901004 1.91926998 -1.95901004 0 P 0 ;0
L 1.91125 -1.95801004 1.91891998 -1.95801004 0 P 0 ;0
L 1.91091998 -1.95701004 1.91853002 -1.95701004 0 P 0 ;0
L 1.9106 -1.95601004 1.91811004 -1.95601004 0 P 0 ;0
L 1.91025 -1.95501004 1.91765 -1.95501004 0 P 0 ;0
L 1.90988996 -1.95401004 1.91718996 -1.95401004 0 P 0 ;0
L 1.90953002 -1.95301004 1.91673002 -1.95301004 0 P 0 ;0
L 1.90918002 -1.95201004 1.91626998 -1.95201004 0 P 0 ;0
L 1.90881998 -1.95101004 1.91576004 -1.95101004 0 P 0 ;0
L 1.90841004 -1.95001004 1.91523996 -1.95001004 0 P 0 ;0
L 1.90793996 -1.94901004 1.91471004 -1.94901004 0 P 0 ;0
L 1.90738996 -1.94801004 1.91418002 -1.94801004 0 P 0 ;0
L 1.90676998 -1.94701004 1.9136 -1.94701004 0 P 0 ;0
L 1.90598996 -1.94601004 1.91261004 -1.94601004 0 P 0 ;0
L 1.90495 -1.94501004 1.91175 -1.94501004 0 P 0 ;0
L 1.90325 -1.94401004 1.91133002 -1.94401004 0 P 0 ;0
L 1.90456004 -1.94001004 1.91383002 -1.94001004 0 P 0 ;0
L 1.90801004 -1.93901004 1.91523002 -1.93901004 0 P 0 ;0
L 1.90956998 -1.93801004 1.91635 -1.93801004 0 P 0 ;0
L 1.9106 -1.93701004 1.91718002 -1.93701004 0 P 0 ;0
L 1.91133996 -1.93601004 1.91781004 -1.93601004 0 P 0 ;0
L 1.91183996 -1.93501004 1.91826004 -1.93501004 0 P 0 ;0
L 1.91213002 -1.93401004 1.9186 -1.93401004 0 P 0 ;0
L 1.91226004 -1.93301004 1.9188 -1.93301004 0 P 0 ;0
L 1.91221998 -1.93201004 1.9189 -1.93201004 0 P 0 ;0
L 1.91201998 -1.93101004 1.9189 -1.93101004 0 P 0 ;0
L 1.91163996 -1.93001004 1.91878996 -1.93001004 0 P 0 ;0
L 1.91105 -1.92901004 1.91856998 -1.92901004 0 P 0 ;0
L 1.91013996 -1.92801004 1.91823002 -1.92801004 0 P 0 ;0
L 1.90816998 -1.92701004 1.91776004 -1.92701004 0 P 0 ;0
L 1.90313996 -1.94011004 1.90316998 -1.9401 0 P 0 ;0
L 1.90316998 -1.9401 1.9032 -1.9401 0 P 0 ;0
L 1.9032 -1.9401 1.90398002 -1.94006998 0 P 0 ;0
L 1.90398002 -1.94006998 1.90406004 -1.94006998 0 P 0 ;0
L 1.90406004 -1.94006998 1.90413996 -1.94006004 0 P 0 ;0
L 1.90413996 -1.94006004 1.9049 -1.93996998 0 P 0 ;0
L 1.9049 -1.93996998 1.90493996 -1.93996004 0 P 0 ;0
L 1.90493996 -1.93996004 1.90498996 -1.93996004 0 P 0 ;0
L 1.90498996 -1.93996004 1.90506998 -1.93993996 0 P 0 ;0
L 1.90506998 -1.93993996 1.90581998 -1.93978002 0 P 0 ;0
L 1.90581998 -1.93978002 1.90586004 -1.93978002 0 P 0 ;0
L 1.90586004 -1.93978002 1.90593996 -1.93976004 0 P 0 ;0
L 1.90593996 -1.93976004 1.90596998 -1.93973996 0 P 0 ;0
L 1.90596998 -1.93973996 1.90671004 -1.93953002 0 P 0 ;0
L 1.90671004 -1.93953002 1.90678996 -1.93951004 0 P 0 ;0
L 1.90678996 -1.93951004 1.90758996 -1.93921004 0 P 0 ;0
L 1.90758996 -1.93921004 1.90766004 -1.93916998 0 P 0 ;0
L 1.90766004 -1.93916998 1.9077 -1.93915 0 P 0 ;0
L 1.9077 -1.93915 1.90773996 -1.93913996 0 P 0 ;0
L 1.90773996 -1.93913996 1.90818996 -1.93891998 0 P 0 ;0
L 1.90818996 -1.93891998 1.90821998 -1.9389 0 P 0 ;0
L 1.90821998 -1.9389 1.90826004 -1.93888996 0 P 0 ;0
L 1.90826004 -1.93888996 1.90828996 -1.93886998 0 P 0 ;0
L 1.90828996 -1.93886998 1.90833002 -1.93885 0 P 0 ;0
L 1.90833002 -1.93885 1.90875 -1.9386 0 P 0 ;0
L 1.90875 -1.9386 1.90883002 -1.93856004 0 P 0 ;0
L 1.90883002 -1.93856004 1.90888996 -1.93851004 0 P 0 ;0
L 1.90888996 -1.93851004 1.90928996 -1.93823002 0 P 0 ;0
L 1.90928996 -1.93823002 1.90933002 -1.9382 0 P 0 ;0
L 1.90933002 -1.9382 1.90936004 -1.93818002 0 P 0 ;0
L 1.90936004 -1.93818002 1.90938996 -1.93815 0 P 0 ;0
L 1.90938996 -1.93815 1.90941998 -1.93813002 0 P 0 ;0
L 1.90941998 -1.93813002 1.9098 -1.93781998 0 P 0 ;0
L 1.9098 -1.93781998 1.90986004 -1.93776004 0 P 0 ;0
L 1.90986004 -1.93776004 1.90988996 -1.93773996 0 P 0 ;0
L 1.90988996 -1.93773996 1.90991998 -1.93771004 0 P 0 ;0
L 1.90991998 -1.93771004 1.91028002 -1.93736004 0 P 0 ;0
L 1.91028002 -1.93736004 1.91038996 -1.93725 0 P 0 ;0
L 1.91038996 -1.93725 1.91071004 -1.93688002 0 P 0 ;0
L 1.91071004 -1.93688002 1.91073996 -1.93685 0 P 0 ;0
L 1.91073996 -1.93685 1.91116004 -1.9363 0 P 0 ;0
L 1.91116004 -1.9363 1.9112 -1.93623002 0 P 0 ;0
L 1.9112 -1.93623002 1.91138002 -1.93595 0 P 0 ;0
L 1.91138002 -1.93595 1.9114 -1.93591004 0 P 0 ;0
L 1.9114 -1.93591004 1.91143996 -1.93585 0 P 0 ;0
L 1.91143996 -1.93585 1.91146004 -1.93581004 0 P 0 ;0
L 1.91146004 -1.93581004 1.91161004 -1.93551998 0 P 0 ;0
L 1.91161004 -1.93551998 1.91163002 -1.93548996 0 P 0 ;0
L 1.91163002 -1.93548996 1.91165 -1.93545 0 P 0 ;0
L 1.91165 -1.93545 1.91166004 -1.93541004 0 P 0 ;0
L 1.91166004 -1.93541004 1.91168002 -1.93538002 0 P 0 ;0
L 1.91168002 -1.93538002 1.91181004 -1.93506998 0 P 0 ;0
L 1.91181004 -1.93506998 1.91183996 -1.935 0 P 0 ;0
L 1.91183996 -1.935 1.91186004 -1.93496004 0 P 0 ;0
L 1.91186004 -1.93496004 1.91186998 -1.93493002 0 P 0 ;0
L 1.91186998 -1.93493002 1.91198002 -1.93461004 0 P 0 ;0
L 1.91198002 -1.93461004 1.91198996 -1.93456998 0 P 0 ;0
L 1.91198996 -1.93456998 1.912 -1.93453996 0 P 0 ;0
L 1.912 -1.93453996 1.9121 -1.93413996 0 P 0 ;0
L 1.9121 -1.93413996 1.91211998 -1.9341 0 P 0 ;0
L 1.91211998 -1.9341 1.91211998 -1.93406004 0 P 0 ;0
L 1.91211998 -1.93406004 1.91213002 -1.93401998 0 P 0 ;0
L 1.91213002 -1.93401998 1.91213996 -1.93398996 0 P 0 ;0
L 1.91213996 -1.93398996 1.9122 -1.93366004 0 P 0 ;0
L 1.9122 -1.93366004 1.91221004 -1.93358002 0 P 0 ;0
L 1.91221004 -1.93358002 1.91221004 -1.93353996 0 P 0 ;0
L 1.91221004 -1.93353996 1.91221998 -1.9335 0 P 0 ;0
L 1.91221998 -1.9335 1.91225 -1.93316998 0 P 0 ;0
L 1.91225 -1.93316998 1.91226004 -1.93308996 0 P 0 ;0
L 1.91226004 -1.93308996 1.91226004 -1.93268002 0 P 0 ;0
L 1.91226004 -1.93268002 1.91226998 -1.93263996 0 P 0 ;0
L 1.91226998 -1.93263996 1.91226998 -1.9326 0 P 0 ;0
L 1.91226998 -1.9326 1.91226004 -1.93251998 0 P 0 ;0
L 1.91226004 -1.93251998 1.91223996 -1.93218996 0 P 0 ;0
L 1.91223996 -1.93218996 1.91223996 -1.93215 0 P 0 ;0
L 1.91223996 -1.93215 1.91223002 -1.9321 0 P 0 ;0
L 1.91223002 -1.9321 1.91223002 -1.93206004 0 P 0 ;0
L 1.91223002 -1.93206004 1.91221998 -1.93201998 0 P 0 ;0
L 1.91221998 -1.93201998 1.91216998 -1.93163996 0 P 0 ;0
L 1.91216998 -1.93163996 1.91216004 -1.9316 0 P 0 ;0
L 1.91216004 -1.9316 1.91213996 -1.93151004 0 P 0 ;0
L 1.91213996 -1.93151004 1.91213002 -1.93146998 0 P 0 ;0
L 1.91213002 -1.93146998 1.91205 -1.93111004 0 P 0 ;0
L 1.91205 -1.93111004 1.91203996 -1.93106004 0 P 0 ;0
L 1.91203996 -1.93106004 1.91203002 -1.93101998 0 P 0 ;0
L 1.91203002 -1.93101998 1.91201004 -1.93098002 0 P 0 ;0
L 1.91201004 -1.93098002 1.912 -1.93093996 0 P 0 ;0
L 1.912 -1.93093996 1.91188002 -1.93058002 0 P 0 ;0
L 1.91188002 -1.93058002 1.91186998 -1.93053996 0 P 0 ;0
L 1.91186998 -1.93053996 1.91185 -1.9305 0 P 0 ;0
L 1.91185 -1.9305 1.91183996 -1.93046004 0 P 0 ;0
L 1.91183996 -1.93046004 1.91181998 -1.93043002 0 P 0 ;0
L 1.91181998 -1.93043002 1.91166998 -1.93008002 0 P 0 ;0
L 1.91166998 -1.93008002 1.91166004 -1.93003996 0 P 0 ;0
L 1.91166004 -1.93003996 1.9116 -1.92991998 0 P 0 ;0
L 1.9116 -1.92991998 1.91141998 -1.92958996 0 P 0 ;0
L 1.91141998 -1.92958996 1.9114 -1.92955 0 P 0 ;0
L 1.9114 -1.92955 1.91138002 -1.92951998 0 P 0 ;0
L 1.91138002 -1.92951998 1.91133002 -1.92945 0 P 0 ;0
L 1.91133002 -1.92945 1.91113002 -1.92913002 0 P 0 ;0
L 1.91113002 -1.92913002 1.91111004 -1.92908996 0 P 0 ;0
L 1.91111004 -1.92908996 1.91108996 -1.92906004 0 P 0 ;0
L 1.91108996 -1.92906004 1.91106004 -1.92901998 0 P 0 ;0
L 1.91106004 -1.92901998 1.91103002 -1.92898996 0 P 0 ;0
L 1.91103002 -1.92898996 1.9108 -1.92868996 0 P 0 ;0
L 1.9108 -1.92868996 1.91076998 -1.92866004 0 P 0 ;0
L 1.91076998 -1.92866004 1.91075 -1.92861998 0 P 0 ;0
L 1.91075 -1.92861998 1.91068996 -1.92856004 0 P 0 ;0
L 1.91068996 -1.92856004 1.91043002 -1.92828002 0 P 0 ;0
L 1.91043002 -1.92828002 1.91035 -1.9282 0 P 0 ;0
L 1.91035 -1.9282 1.91033002 -1.92816998 0 P 0 ;0
L 1.91033002 -1.92816998 1.91018996 -1.92803996 0 P 0 ;0
L 1.91018996 -1.92803996 1.91018002 -1.92803996 0 P 0 ;0
L 1.91018002 -1.92803996 1.91016004 -1.92801998 0 P 0 ;0
L 1.91016004 -1.92801998 1.91011998 -1.92798996 0 P 0 ;0
L 1.91011998 -1.92798996 1.91006004 -1.92793002 0 P 0 ;0
L 1.91006004 -1.92793002 1.90991004 -1.92781998 0 P 0 ;0
L 1.90991004 -1.92781998 1.90988002 -1.9278 0 P 0 ;0
L 1.90988002 -1.9278 1.90983996 -1.92776998 0 P 0 ;0
L 1.90983996 -1.92776998 1.90976998 -1.92771998 0 P 0 ;0
L 1.90976998 -1.92771998 1.90961004 -1.92761998 0 P 0 ;0
L 1.90961004 -1.92761998 1.90953996 -1.92756998 0 P 0 ;0
L 1.90953996 -1.92756998 1.9095 -1.92755 0 P 0 ;0
L 1.9095 -1.92755 1.90946998 -1.92753002 0 P 0 ;0
L 1.90946998 -1.92753002 1.9093 -1.92743996 0 P 0 ;0
L 1.9093 -1.92743996 1.90926004 -1.92741998 0 P 0 ;0
L 1.90926004 -1.92741998 1.90923002 -1.9274 0 P 0 ;0
L 1.90923002 -1.9274 1.90915 -1.92736998 0 P 0 ;0
L 1.90915 -1.92736998 1.90896998 -1.92728996 0 P 0 ;0
L 1.90896998 -1.92728996 1.90893996 -1.92728002 0 P 0 ;0
L 1.90893996 -1.92728002 1.9089 -1.92726004 0 P 0 ;0
L 1.9089 -1.92726004 1.90886998 -1.92725 0 P 0 ;0
L 1.90886998 -1.92725 1.90883002 -1.92723996 0 P 0 ;0
L 1.90883002 -1.92723996 1.90816004 -1.92701004 0 P 0 ;0
L 1.90816004 -1.92701004 1.90813996 -1.927 0 P 0 ;0
L 1.90813996 -1.927 1.9081 -1.92698996 0 P 0 ;0
L 1.9081 -1.92698996 1.90803996 -1.92696998 0 P 0 ;0
L 1.90803996 -1.92696998 1.90736998 -1.92678002 0 P 0 ;0
L 1.90736998 -1.92678002 1.90723996 -1.92675 0 P 0 ;0
L 1.90723996 -1.92675 1.90643002 -1.92658996 0 P 0 ;0
L 1.90643002 -1.92658996 1.90636998 -1.92656998 0 P 0 ;0
L 1.90636998 -1.92656998 1.90633996 -1.92656998 0 P 0 ;0
L 1.90633996 -1.92656998 1.90631004 -1.92656004 0 P 0 ;0
L 1.90631004 -1.92656004 1.90548996 -1.92645 0 P 0 ;0
L 1.90548996 -1.92645 1.90543996 -1.92643996 0 P 0 ;0
L 1.90543996 -1.92643996 1.9054 -1.92643002 0 P 0 ;0
L 1.9054 -1.92643002 1.90538002 -1.92643002 0 P 0 ;0
L 1.90538002 -1.92643002 1.90455 -1.92636004 0 P 0 ;0
L 1.90455 -1.92636004 1.90443002 -1.92636004 0 P 0 ;0
L 1.90443002 -1.92636004 1.9036 -1.92633002 0 P 0 ;0
L 1.9036 -1.92633002 1.8994 -1.92633002 0 P 0 ;0
L 1.8994 -1.92633002 1.89798002 -1.92691004 0 P 0 ;0
L 1.89798002 -1.92691004 1.8974 -1.92833002 0 P 0 ;0
L 1.8974 -1.92833002 1.8974 -1.93328002 0 P 0 ;0
L 1.8974 -1.93328002 1.89748002 -1.93643002 0 P 0 ;0
L 1.89748002 -1.93643002 1.89748002 -1.93656004 0 P 0 ;0
L 1.89748002 -1.93656004 1.8975 -1.93673002 0 P 0 ;0
L 1.8975 -1.93673002 1.89751004 -1.93681004 0 P 0 ;0
L 1.89751004 -1.93681004 1.89751998 -1.9369 0 P 0 ;0
L 1.89751998 -1.9369 1.89755 -1.93706004 0 P 0 ;0
L 1.89755 -1.93706004 1.89758002 -1.93718996 0 P 0 ;0
L 1.89758002 -1.93718996 1.89758996 -1.93723002 0 P 0 ;0
L 1.89758996 -1.93723002 1.89763002 -1.9374 0 P 0 ;0
L 1.89763002 -1.9374 1.89763996 -1.93743996 0 P 0 ;0
L 1.89763996 -1.93743996 1.89766004 -1.93748002 0 P 0 ;0
L 1.89766004 -1.93748002 1.89768002 -1.93756004 0 P 0 ;0
L 1.89768002 -1.93756004 1.89773996 -1.93771998 0 P 0 ;0
L 1.89773996 -1.93771998 1.89776004 -1.93776004 0 P 0 ;0
L 1.89776004 -1.93776004 1.89776998 -1.9378 0 P 0 ;0
L 1.89776998 -1.9378 1.89781004 -1.93788002 0 P 0 ;0
L 1.89781004 -1.93788002 1.89788002 -1.93803996 0 P 0 ;0
L 1.89788002 -1.93803996 1.8979 -1.93808002 0 P 0 ;0
L 1.8979 -1.93808002 1.89791998 -1.93811004 0 P 0 ;0
L 1.89791998 -1.93811004 1.89796004 -1.93818996 0 P 0 ;0
L 1.89796004 -1.93818996 1.89803996 -1.93833996 0 P 0 ;0
L 1.89803996 -1.93833996 1.89813996 -1.93848002 0 P 0 ;0
L 1.89813996 -1.93848002 1.89823002 -1.93861998 0 P 0 ;0
L 1.89823002 -1.93861998 1.89828002 -1.93868996 0 P 0 ;0
L 1.89828002 -1.93868996 1.89831004 -1.93873002 0 P 0 ;0
L 1.89831004 -1.93873002 1.89833996 -1.93876004 0 P 0 ;0
L 1.89833996 -1.93876004 1.8984 -1.93883996 0 P 0 ;0
L 1.8984 -1.93883996 1.89848996 -1.93893002 0 P 0 ;0
L 1.89848996 -1.93893002 1.89851004 -1.93896004 0 P 0 ;0
L 1.89851004 -1.93896004 1.89868002 -1.93913002 0 P 0 ;0
L 1.89868002 -1.93913002 1.89871004 -1.93915 0 P 0 ;0
L 1.89871004 -1.93915 1.89878996 -1.93921998 0 P 0 ;0
L 1.89878996 -1.93921998 1.89885 -1.93928002 0 P 0 ;0
L 1.89885 -1.93928002 1.89888002 -1.9393 0 P 0 ;0
L 1.89888002 -1.9393 1.89891998 -1.93931998 0 P 0 ;0
L 1.89891998 -1.93931998 1.89901004 -1.93938996 0 P 0 ;0
L 1.89901004 -1.93938996 1.89903996 -1.93941004 0 P 0 ;0
L 1.89903996 -1.93941004 1.89906998 -1.93943996 0 P 0 ;0
L 1.89906998 -1.93943996 1.8991 -1.93946004 0 P 0 ;0
L 1.8991 -1.93946004 1.89913996 -1.93948002 0 P 0 ;0
L 1.89913996 -1.93948002 1.89923002 -1.93953996 0 P 0 ;0
L 1.89923002 -1.93953996 1.89926998 -1.93956004 0 P 0 ;0
L 1.89926998 -1.93956004 1.8993 -1.93958002 0 P 0 ;0
L 1.8993 -1.93958002 1.89933996 -1.9396 0 P 0 ;0
L 1.89933996 -1.9396 1.89936998 -1.93961004 0 P 0 ;0
L 1.89936998 -1.93961004 1.89938002 -1.93961004 0 P 0 ;0
L 1.89938002 -1.93961004 1.89946998 -1.93966004 0 P 0 ;0
L 1.89946998 -1.93966004 1.89953996 -1.9397 0 P 0 ;0
L 1.89953996 -1.9397 1.89971998 -1.93976998 0 P 0 ;0
L 1.89971998 -1.93976998 1.89975 -1.93978996 0 P 0 ;0
L 1.89975 -1.93978996 1.89978996 -1.9398 0 P 0 ;0
L 1.89978996 -1.9398 1.89986998 -1.93983002 0 P 0 ;0
L 1.89986998 -1.93983002 1.89996998 -1.93986004 0 P 0 ;0
L 1.89996998 -1.93986004 1.90001004 -1.93986998 0 P 0 ;0
L 1.90001004 -1.93986998 1.90005 -1.93988996 0 P 0 ;0
L 1.90005 -1.93988996 1.90013002 -1.9399 0 P 0 ;0
L 1.90013002 -1.9399 1.90023002 -1.93993002 0 P 0 ;0
L 1.90023002 -1.93993002 1.90023996 -1.93993002 0 P 0 ;0
L 1.90023996 -1.93993002 1.90028002 -1.93993996 0 P 0 ;0
L 1.90028002 -1.93993996 1.90031004 -1.93995 0 P 0 ;0
L 1.90031004 -1.93995 1.90036004 -1.93995 0 P 0 ;0
L 1.90036004 -1.93995 1.9004 -1.93996004 0 P 0 ;0
L 1.9004 -1.93996004 1.9005 -1.93996998 0 P 0 ;0
L 1.9005 -1.93996998 1.90061004 -1.93998996 0 P 0 ;0
L 1.90061004 -1.93998996 1.90063996 -1.93998996 0 P 0 ;0
L 1.90063996 -1.93998996 1.90181004 -1.94006998 0 P 0 ;0
L 1.90181004 -1.94006998 1.90183996 -1.94008002 0 P 0 ;0
L 1.90183996 -1.94008002 1.90191004 -1.94008002 0 P 0 ;0
L 1.90191004 -1.94008002 1.90308002 -1.9401 0 P 0 ;0
L 1.90308002 -1.9401 1.90311004 -1.9401 0 P 0 ;0
L 1.90311004 -1.9401 1.90313996 -1.94011004 0 P 0 ;0
L 1.90841004 -1.97146004 1.91683996 -1.97146004 0 P 0 ;0
L 1.9135 -1.97046004 1.91931004 -1.97046004 0 P 0 ;0
L 1.91655 -1.96946004 1.92131004 -1.96946004 0 P 0 ;0
L 1.91891998 -1.96846004 1.92301004 -1.96846004 0 P 0 ;0
L 1.92088996 -1.96746004 1.9245 -1.96746004 0 P 0 ;0
L 1.92251004 -1.96646004 1.9258 -1.96646004 0 P 0 ;0
L 1.92391004 -1.96546004 1.92696004 -1.96546004 0 P 0 ;0
L 1.92513002 -1.96446004 1.92803002 -1.96446004 0 P 0 ;0
L 1.9262 -1.96346004 1.92898996 -1.96346004 0 P 0 ;0
L 1.92713996 -1.96246004 1.92986004 -1.96246004 0 P 0 ;0
L 1.928 -1.96146004 1.93068996 -1.96146004 0 P 0 ;0
L 1.92878002 -1.96046004 1.93143002 -1.96046004 0 P 0 ;0
L 1.92951004 -1.95946004 1.93216004 -1.95946004 0 P 0 ;0
L 1.93016998 -1.95846004 1.93278996 -1.95846004 0 P 0 ;0
L 1.93078002 -1.95746004 1.93341004 -1.95746004 0 P 0 ;0
L 1.93133002 -1.95646004 1.93396004 -1.95646004 0 P 0 ;0
L 1.93185 -1.95546004 1.93448996 -1.95546004 0 P 0 ;0
L 1.93231004 -1.95446004 1.93495 -1.95446004 0 P 0 ;0
L 1.93275 -1.95346004 1.93541004 -1.95346004 0 P 0 ;0
L 1.93311998 -1.95246004 1.93586004 -1.95246004 0 P 0 ;0
L 1.93348002 -1.95146004 1.93628996 -1.95146004 0 P 0 ;0
L 1.93376998 -1.95046004 1.93666004 -1.95046004 0 P 0 ;0
L 1.93405 -1.94946004 1.93693002 -1.94946004 0 P 0 ;0
L 1.93428002 -1.94846004 1.93715 -1.94846004 0 P 0 ;0
L 1.93446998 -1.94746004 1.93733002 -1.94746004 0 P 0 ;0
L 1.93466004 -1.94646004 1.93743002 -1.94646004 0 P 0 ;0
L 1.93478996 -1.94546004 1.93748996 -1.94546004 0 P 0 ;0
L 1.9349 -1.94446998 1.93751998 -1.94446998 0 P 0 ;0
L 1.93496998 -1.94346004 1.93755 -1.94346004 0 P 0 ;0
L 1.93501998 -1.94246004 1.93758002 -1.94246004 0 P 0 ;0
L 1.93505 -1.94146998 1.93758996 -1.94146998 0 P 0 ;0
L 1.93503002 -1.94046004 1.93755 -1.94046004 0 P 0 ;0
L 1.935 -1.93946004 1.93751998 -1.93946004 0 P 0 ;0
L 1.93491998 -1.93846004 1.93748002 -1.93846004 0 P 0 ;0
L 1.93481004 -1.93746004 1.93738996 -1.93746004 0 P 0 ;0
L 1.93468996 -1.93646004 1.93726998 -1.93646004 0 P 0 ;0
L 1.93451004 -1.93546004 1.93716004 -1.93546004 0 P 0 ;0
L 1.93433002 -1.93446004 1.93703996 -1.93446004 0 P 0 ;0
L 1.93408996 -1.93346004 1.93685 -1.93346004 0 P 0 ;0
L 1.93383002 -1.93246004 1.93666004 -1.93246004 0 P 0 ;0
L 1.93353002 -1.93146004 1.93638996 -1.93146004 0 P 0 ;0
L 1.9332 -1.93046004 1.93611998 -1.93046004 0 P 0 ;0
L 1.93283996 -1.92946004 1.93576998 -1.92946004 0 P 0 ;0
L 1.93241004 -1.92846004 1.93541004 -1.92846004 0 P 0 ;0
L 1.93198996 -1.92746004 1.93498002 -1.92746004 0 P 0 ;0
L 1.93146998 -1.92646004 1.93451004 -1.92646004 0 P 0 ;0
L 1.93096004 -1.92546004 1.93398002 -1.92546004 0 P 0 ;0
L 1.93035 -1.92446998 1.93338002 -1.92446998 0 P 0 ;0
L 1.92973002 -1.92346004 1.93275 -1.92346004 0 P 0 ;0
L 1.92903002 -1.92246004 1.93201004 -1.92246004 0 P 0 ;0
L 1.92831004 -1.92146004 1.93125 -1.92146004 0 P 0 ;0
L 1.92746998 -1.92046004 1.93041004 -1.92046004 0 P 0 ;0
L 1.92661004 -1.91946004 1.92948996 -1.91946004 0 P 0 ;0
L 1.92558996 -1.91846004 1.92851004 -1.91846004 0 P 0 ;0
L 1.9245 -1.91746004 1.92741998 -1.91746004 0 P 0 ;0
L 1.92328996 -1.91646004 1.92621998 -1.91646004 0 P 0 ;0
L 1.92188002 -1.91546004 1.92491998 -1.91546004 0 P 0 ;0
L 1.92026004 -1.91446004 1.92358996 -1.91446004 0 P 0 ;0
L 1.91835 -1.91346004 1.92208002 -1.91346004 0 P 0 ;0
L 1.82446998 -2.08323996 1.87608002 -2.08323996 0 P 0 ;0
L 1.82403002 -2.08223996 1.87601004 -2.08223996 0 P 0 ;0
L 1.8234 -2.08123996 1.87591004 -2.08123996 0 P 0 ;0
L 1.82256004 -2.08023996 1.87578002 -2.08023996 0 P 0 ;0
L 1.82166004 -2.07923996 1.87558996 -2.07923996 0 P 0 ;0
L 1.82061998 -2.07823996 1.87533002 -2.07823996 0 P 0 ;0
L 1.81946004 -2.07723996 1.87498996 -2.07723996 0 P 0 ;0
L 1.81818002 -2.07623996 1.8746 -2.07623996 0 P 0 ;0
L 1.8168 -2.07523996 1.87416998 -2.07523996 0 P 0 ;0
L 1.81541998 -2.07423996 1.87371004 -2.07423996 0 P 0 ;0
L 1.81403002 -2.07323996 1.87316998 -2.07323996 0 P 0 ;0
L 1.81265 -2.07223996 1.87261004 -2.07223996 0 P 0 ;0
L 1.81126998 -2.07123996 1.87196004 -2.07123996 0 P 0 ;0
L 1.80986004 -2.07023996 1.87128002 -2.07023996 0 P 0 ;0
L 1.80843996 -2.06923996 1.87051998 -2.06923996 0 P 0 ;0
L 1.80703002 -2.06823996 1.8697 -2.06823996 0 P 0 ;0
L 1.80561004 -2.06723996 1.86883002 -2.06723996 0 P 0 ;0
L 1.8042 -2.06623996 1.86796004 -2.06623996 0 P 0 ;0
L 1.80278002 -2.06523996 1.86705 -2.06523996 0 P 0 ;0
L 1.80136004 -2.06423996 1.86608002 -2.06423996 0 P 0 ;0
L 1.79995 -2.06323996 1.8651 -2.06323996 0 P 0 ;0
L 1.79865 -2.06223996 1.86411004 -2.06223996 0 P 0 ;0
L 1.79735 -2.06123996 1.86301998 -2.06123996 0 P 0 ;0
L 1.79605 -2.06023996 1.86193002 -2.06023996 0 P 0 ;0
L 1.79475 -2.05923996 1.86083996 -2.05923996 0 P 0 ;0
L 1.79345 -2.05823996 1.85966998 -2.05823996 0 P 0 ;0
L 1.79215 -2.05723996 1.85846004 -2.05723996 0 P 0 ;0
L 1.79088002 -2.05623996 1.85726004 -2.05623996 0 P 0 ;0
L 1.78971998 -2.05523996 1.85598996 -2.05523996 0 P 0 ;0
L 1.78856004 -2.05423996 1.85461998 -2.05423996 0 P 0 ;0
L 1.7874 -2.05323996 1.85326004 -2.05323996 0 P 0 ;0
L 1.78623002 -2.05223996 1.8519 -2.05223996 0 P 0 ;0
L 1.78506998 -2.05123996 1.85053996 -2.05123996 0 P 0 ;0
L 1.78398002 -2.05023996 1.84918002 -2.05023996 0 P 0 ;0
L 1.783 -2.04923996 1.84781004 -2.04923996 0 P 0 ;0
L 1.87086004 -2.03023996 1.87535 -2.03023996 0 P 0 ;0
L 1.91633002 -1.91473002 1.9183 -1.91565 0 P 0 ;0
L 1.9183 -1.91565 1.92018996 -1.91673002 0 P 0 ;0
L 1.92018996 -1.91673002 1.92196998 -1.91796998 0 P 0 ;0
L 1.92196998 -1.91796998 1.92365 -1.91936004 0 P 0 ;0
L 1.92365 -1.91936004 1.9252 -1.92088002 0 P 0 ;0
L 1.9252 -1.92088002 1.92661004 -1.92253996 0 P 0 ;0
L 1.92661004 -1.92253996 1.92795 -1.92436998 0 P 0 ;0
L 1.92795 -1.92436998 1.92913996 -1.9263 0 P 0 ;0
L 1.92913996 -1.9263 1.93018002 -1.92831998 0 P 0 ;0
L 1.93018002 -1.92831998 1.93106998 -1.93041004 0 P 0 ;0
L 1.93106998 -1.93041004 1.93178996 -1.93256004 0 P 0 ;0
L 1.93178996 -1.93256004 1.93236004 -1.93476004 0 P 0 ;0
L 1.93236004 -1.93476004 1.93276004 -1.93703996 0 P 0 ;0
L 1.93276004 -1.93703996 1.93298996 -1.93933996 0 P 0 ;0
L 1.93298996 -1.93933996 1.93306004 -1.94165 0 P 0 ;0
L 1.93306004 -1.94165 1.93295 -1.94396998 0 P 0 ;0
L 1.93295 -1.94396998 1.93268002 -1.94626004 0 P 0 ;0
L 1.93268002 -1.94626004 1.93223002 -1.94853996 0 P 0 ;0
L 1.93223002 -1.94853996 1.93161998 -1.95071998 0 P 0 ;0
L 1.93161998 -1.95071998 1.93085 -1.95285 0 P 0 ;0
L 1.93085 -1.95285 1.92991004 -1.95491004 0 P 0 ;0
L 1.92991004 -1.95491004 1.92881004 -1.95688996 0 P 0 ;0
L 1.92881004 -1.95688996 1.92756004 -1.95878002 0 P 0 ;0
L 1.92756004 -1.95878002 1.92616004 -1.96056998 0 P 0 ;0
L 1.92616004 -1.96056998 1.92493996 -1.9619 0 P 0 ;0
L 1.92493996 -1.9619 1.92361998 -1.96313996 0 P 0 ;0
L 1.92361998 -1.96313996 1.9222 -1.96426004 0 P 0 ;0
L 1.9222 -1.96426004 1.9207 -1.96526998 0 P 0 ;0
L 1.9207 -1.96526998 1.91911004 -1.96616998 0 P 0 ;0
L 1.91911004 -1.96616998 1.91686998 -1.96721004 0 P 0 ;0
L 1.91686998 -1.96721004 1.91456004 -1.96806998 0 P 0 ;0
L 1.91456004 -1.96806998 1.91218996 -1.96876004 0 P 0 ;0
L 1.91218996 -1.96876004 1.90975 -1.96926998 0 P 0 ;0
L 1.90975 -1.96926998 1.90725 -1.9696 0 P 0 ;0
L 1.90725 -1.9696 1.90473002 -1.96973996 0 P 0 ;0
L 1.90473002 -1.96973996 1.9022 -1.96968996 0 P 0 ;0
L 1.9022 -1.96968996 1.89966998 -1.96945 0 P 0 ;0
L 1.89966998 -1.96945 1.89778002 -1.96913002 0 P 0 ;0
L 1.89778002 -1.96913002 1.89591998 -1.96868996 0 P 0 ;0
L 1.89591998 -1.96868996 1.8941 -1.96811004 0 P 0 ;0
L 1.8941 -1.96811004 1.89231004 -1.96741004 0 P 0 ;0
L 1.89231004 -1.96741004 1.89058002 -1.96658002 0 P 0 ;0
L 1.89058002 -1.96658002 1.88875 -1.96553996 0 P 0 ;0
L 1.88875 -1.96553996 1.88698996 -1.96435 0 P 0 ;0
L 1.88698996 -1.96435 1.88533996 -1.96303002 0 P 0 ;0
L 1.88533996 -1.96303002 1.88378996 -1.9616 0 P 0 ;0
L 1.88378996 -1.9616 1.88235 -1.96003996 0 P 0 ;0
L 1.88235 -1.96003996 1.88103002 -1.95838996 0 P 0 ;0
L 1.88103002 -1.95838996 1.87983996 -1.95663002 0 P 0 ;0
L 1.87983996 -1.95663002 1.87861998 -1.95446998 0 P 0 ;0
L 1.87861998 -1.95446998 1.87758002 -1.9522 0 P 0 ;0
L 1.87758002 -1.9522 1.87673996 -1.94986004 0 P 0 ;0
L 1.87673996 -1.94986004 1.8761 -1.94745 0 P 0 ;0
L 1.8761 -1.94745 1.87568002 -1.945 0 P 0 ;0
L 1.87568002 -1.945 1.87546004 -1.94248996 0 P 0 ;0
L 1.87546004 -1.94248996 1.87546004 -1.93998996 0 P 0 ;0
L 1.87546004 -1.93998996 1.87566998 -1.93748996 0 P 0 ;0
L 1.87566998 -1.93748996 1.87608996 -1.93501998 0 P 0 ;0
L 1.87608996 -1.93501998 1.87671998 -1.9326 0 P 0 ;0
L 1.87671998 -1.9326 1.87755 -1.93023002 0 P 0 ;0
L 1.87755 -1.93023002 1.8786 -1.92793002 0 P 0 ;0
L 1.8786 -1.92793002 1.87981998 -1.92575 0 P 0 ;0
L 1.87981998 -1.92575 1.88123002 -1.92368002 0 P 0 ;0
L 1.88123002 -1.92368002 1.88281004 -1.92175 0 P 0 ;0
L 1.88281004 -1.92175 1.88455 -1.91996004 0 P 0 ;0
L 1.88455 -1.91996004 1.88643002 -1.91831998 0 P 0 ;0
L 1.88643002 -1.91831998 1.88845 -1.91686004 0 P 0 ;0
L 1.88845 -1.91686004 1.88986998 -1.91598996 0 P 0 ;0
L 1.88986998 -1.91598996 1.89135 -1.91523002 0 P 0 ;0
L 1.89135 -1.91523002 1.89288002 -1.91458996 0 P 0 ;0
L 1.89288002 -1.91458996 1.89446998 -1.91406004 0 P 0 ;0
L 1.89446998 -1.91406004 1.89688996 -1.91343996 0 P 0 ;0
L 1.89688996 -1.91343996 1.89935 -1.91298996 0 P 0 ;0
L 1.89935 -1.91298996 1.90183996 -1.91271004 0 P 0 ;0
L 1.90183996 -1.91271004 1.9044 -1.91261004 0 P 0 ;0
L 1.9044 -1.91261004 1.90695 -1.91268002 0 P 0 ;0
L 1.90695 -1.91268002 1.90948996 -1.91291998 0 P 0 ;0
L 1.90948996 -1.91291998 1.91181998 -1.91331998 0 P 0 ;0
L 1.91181998 -1.91331998 1.91408996 -1.91393002 0 P 0 ;0
L 1.91408996 -1.91393002 1.91633002 -1.91473002 0 P 0 ;0
L 1.89498002 -1.90801998 1.8922 -1.90893002 0 P 0 ;0
L 1.8922 -1.90893002 1.88948002 -1.91003002 0 P 0 ;0
L 1.88948002 -1.91003002 1.88686004 -1.91133002 0 P 0 ;0
L 1.88686004 -1.91133002 1.88431004 -1.91283996 0 P 0 ;0
L 1.88431004 -1.91283996 1.88201004 -1.91446004 0 P 0 ;0
L 1.88201004 -1.91446004 1.87985 -1.91626998 0 P 0 ;0
L 1.87985 -1.91626998 1.87785 -1.91826004 0 P 0 ;0
L 1.87785 -1.91826004 1.87601998 -1.92041004 0 P 0 ;0
L 1.87601998 -1.92041004 1.87441004 -1.92266998 0 P 0 ;0
L 1.87441004 -1.92266998 1.87298996 -1.92505 0 P 0 ;0
L 1.87298996 -1.92505 1.87178002 -1.92756004 0 P 0 ;0
L 1.87178002 -1.92756004 1.87078996 -1.93015 0 P 0 ;0
L 1.87078996 -1.93015 1.87 -1.93286998 0 P 0 ;0
L 1.87 -1.93286998 1.86943996 -1.93563996 0 P 0 ;0
L 1.86943996 -1.93563996 1.86908996 -1.93845 0 P 0 ;0
L 1.86908996 -1.93845 1.86898002 -1.94128996 0 P 0 ;0
L 1.86898002 -1.94128996 1.86911998 -1.94485 0 P 0 ;0
L 1.86911998 -1.94485 1.86953996 -1.94841004 0 P 0 ;0
L 1.86953996 -1.94841004 1.86996004 -1.95048996 0 P 0 ;0
L 1.86996004 -1.95048996 1.87053002 -1.95251998 0 P 0 ;0
L 1.87053002 -1.95251998 1.87125 -1.95451998 0 P 0 ;0
L 1.87125 -1.95451998 1.87211004 -1.95643002 0 P 0 ;0
L 1.87211004 -1.95643002 1.8731 -1.95826004 0 P 0 ;0
L 1.8731 -1.95826004 1.87423996 -1.96001998 0 P 0 ;0
L 1.87423996 -1.96001998 1.87636998 -1.96278996 0 P 0 ;0
L 1.87636998 -1.96278996 1.87871998 -1.96536998 0 P 0 ;0
L 1.87871998 -1.96536998 1.88145 -1.96788002 0 P 0 ;0
L 1.88145 -1.96788002 1.88436998 -1.97015 0 P 0 ;0
L 1.88436998 -1.97015 1.88621004 -1.97135 0 P 0 ;0
L 1.88621004 -1.97135 1.88813002 -1.97238002 0 P 0 ;0
L 1.88813002 -1.97238002 1.89013002 -1.97326004 0 P 0 ;0
L 1.89013002 -1.97326004 1.89228002 -1.97398996 0 P 0 ;0
L 1.89228002 -1.97398996 1.89446998 -1.97455 0 P 0 ;0
L 1.89446998 -1.97455 1.89671004 -1.97493996 0 P 0 ;0
L 1.89671004 -1.97493996 1.90076998 -1.97533996 0 P 0 ;0
L 1.90076998 -1.97533996 1.90485 -1.97546998 0 P 0 ;0
L 1.90485 -1.97546998 1.90821004 -1.97531998 0 P 0 ;0
L 1.90821004 -1.97531998 1.91153996 -1.97488996 0 P 0 ;0
L 1.91153996 -1.97488996 1.91481998 -1.97418996 0 P 0 ;0
L 1.91481998 -1.97418996 1.9171 -1.9735 0 P 0 ;0
L 1.9171 -1.9735 1.91933002 -1.97266004 0 P 0 ;0
L 1.91933002 -1.97266004 1.92148002 -1.97166004 0 P 0 ;0
L 1.92148002 -1.97166004 1.92356998 -1.97048996 0 P 0 ;0
L 1.92356998 -1.97048996 1.92553996 -1.96918996 0 P 0 ;0
L 1.92553996 -1.96918996 1.92741004 -1.96773996 0 P 0 ;0
L 1.92741004 -1.96773996 1.92916004 -1.96616998 0 P 0 ;0
L 1.92916004 -1.96616998 1.93081004 -1.96446004 0 P 0 ;0
L 1.93081004 -1.96446004 1.93236998 -1.96256998 0 P 0 ;0
L 1.93236998 -1.96256998 1.93381004 -1.96058996 0 P 0 ;0
L 1.93381004 -1.96058996 1.93511998 -1.95851004 0 P 0 ;0
L 1.93511998 -1.95851004 1.93628996 -1.95633996 0 P 0 ;0
L 1.93628996 -1.95633996 1.93803996 -1.95251998 0 P 0 ;0
L 1.93803996 -1.95251998 1.93858002 -1.95101998 0 P 0 ;0
L 1.93858002 -1.95101998 1.93898996 -1.94948002 0 P 0 ;0
L 1.93898996 -1.94948002 1.93928996 -1.94786998 0 P 0 ;0
L 1.93928996 -1.94786998 1.93946004 -1.94625 0 P 0 ;0
L 1.93946004 -1.94625 1.9396 -1.94178002 0 P 0 ;0
L 1.9396 -1.94178002 1.93946004 -1.93803996 0 P 0 ;0
L 1.93946004 -1.93803996 1.93905 -1.9343 0 P 0 ;0
L 1.93905 -1.9343 1.93863996 -1.93213996 0 P 0 ;0
L 1.93863996 -1.93213996 1.93808002 -1.93001998 0 P 0 ;0
L 1.93808002 -1.93001998 1.93736004 -1.92795 0 P 0 ;0
L 1.93736004 -1.92795 1.93653002 -1.92601004 0 P 0 ;0
L 1.93653002 -1.92601004 1.93555 -1.92415 0 P 0 ;0
L 1.93555 -1.92415 1.93441998 -1.92236004 0 P 0 ;0
L 1.93441998 -1.92236004 1.9331 -1.92056004 0 P 0 ;0
L 1.9331 -1.92056004 1.93166998 -1.91885 0 P 0 ;0
L 1.93166998 -1.91885 1.93011998 -1.91723002 0 P 0 ;0
L 1.93011998 -1.91723002 1.92896004 -1.91615 0 P 0 ;0
L 1.92896004 -1.91615 1.92775 -1.91511004 0 P 0 ;0
L 1.92775 -1.91511004 1.92493002 -1.91295 0 P 0 ;0
L 1.92493002 -1.91295 1.9221 -1.91108002 0 P 0 ;0
L 1.9221 -1.91108002 1.92095 -1.91043002 0 P 0 ;0
L 1.92095 -1.91043002 1.91975 -1.90985 0 P 0 ;0
L 1.91975 -1.90985 1.91796004 -1.90913996 0 P 0 ;0
L 1.91796004 -1.90913996 1.91613002 -1.90856004 0 P 0 ;0
L 1.91613002 -1.90856004 1.91423996 -1.9081 0 P 0 ;0
L 1.91423996 -1.9081 1.91086004 -1.90751998 0 P 0 ;0
L 1.91086004 -1.90751998 1.90743002 -1.90716004 0 P 0 ;0
L 1.90743002 -1.90716004 1.90401004 -1.90701004 0 P 0 ;0
L 1.90401004 -1.90701004 1.90058002 -1.90708002 0 P 0 ;0
L 1.90058002 -1.90708002 1.8987 -1.90726004 0 P 0 ;0
L 1.8987 -1.90726004 1.89683002 -1.90756998 0 P 0 ;0
L 1.89683002 -1.90756998 1.89498002 -1.90801998 0 P 0 ;0
L 1.86643002 -2.02923996 1.87525 -2.02923996 0 P 0 ;0
L 1.86176998 -2.02823996 1.87515 -2.02823996 0 P 0 ;0
L 1.85588996 -2.02723996 1.87505 -2.02723996 0 P 0 ;0
L 1.78365 -2.00523996 1.87281004 -2.00523996 0 P 0 ;0
L 1.78451004 -2.00423996 1.87271004 -2.00423996 0 P 0 ;0
L 1.78546998 -2.00323996 1.87261004 -2.00323996 0 P 0 ;0
L 1.78655 -2.00223996 1.8725 -2.00223996 0 P 0 ;0
L 1.78776004 -2.00123996 1.8724 -2.00123996 0 P 0 ;0
L 1.78915 -2.00023996 1.8723 -2.00023996 0 P 0 ;0
L 1.79078996 -1.99923996 1.8722 -1.99923996 0 P 0 ;0
L 1.79263996 -1.99823996 1.87208996 -1.99823996 0 P 0 ;0
L 1.79458996 -1.99723996 1.87198996 -1.99723996 0 P 0 ;0
L 1.79686998 -1.99623996 1.87188002 -1.99623996 0 P 0 ;0
L 1.79946004 -1.99523996 1.87178002 -1.99523996 0 P 0 ;0
L 1.80231004 -1.99423996 1.86961998 -1.99423996 0 P 0 ;0
L 1.80596004 -1.99323996 1.86218002 -1.99323996 0 P 0 ;0
L 1.81051004 -1.99223996 1.85398002 -1.99223996 0 P 0 ;0
L 1.81676004 -1.99123996 1.84395 -1.99123996 0 P 0 ;0
L 1.87786998 -1.96146004 1.88093996 -1.96146004 0 P 0 ;0
L 1.8771 -1.96046004 1.88013002 -1.96046004 0 P 0 ;0
L 1.87633996 -1.95946004 1.87933996 -1.95946004 0 P 0 ;0
L 1.87561998 -1.95846004 1.87866998 -1.95846004 0 P 0 ;0
L 1.87496998 -1.95746004 1.87801998 -1.95746004 0 P 0 ;0
L 1.8744 -1.95646004 1.87745 -1.95646004 0 P 0 ;0
L 1.87386998 -1.95546004 1.87688002 -1.95546004 0 P 0 ;0
L 1.87341998 -1.95446004 1.87641998 -1.95446004 0 P 0 ;0
L 1.87298996 -1.95346004 1.87596004 -1.95346004 0 P 0 ;0
L 1.87263002 -1.95246004 1.87555 -1.95246004 0 P 0 ;0
L 1.87231004 -1.95146004 1.87518996 -1.95146004 0 P 0 ;0
L 1.87203002 -1.95046004 1.87483002 -1.95046004 0 P 0 ;0
L 1.87178996 -1.94946004 1.87456998 -1.94946004 0 P 0 ;0
L 1.87158996 -1.94846004 1.87431004 -1.94846004 0 P 0 ;0
L 1.87143996 -1.94746004 1.87408002 -1.94746004 0 P 0 ;0
L 1.87133002 -1.94646004 1.8739 -1.94646004 0 P 0 ;0
L 1.87121004 -1.94546004 1.87373002 -1.94546004 0 P 0 ;0
L 1.8711 -1.94446998 1.87361998 -1.94446998 0 P 0 ;0
L 1.87106998 -1.94346004 1.87353996 -1.94346004 0 P 0 ;0
L 1.87103002 -1.94246004 1.87346004 -1.94246004 0 P 0 ;0
L 1.87098996 -1.94146998 1.87346004 -1.94146998 0 P 0 ;0
L 1.87101004 -1.94046004 1.87346004 -1.94046004 0 P 0 ;0
L 1.87106004 -1.93946004 1.87348996 -1.93946004 0 P 0 ;0
L 1.87111004 -1.93846004 1.87358002 -1.93846004 0 P 0 ;0
L 1.87123002 -1.93746004 1.87366004 -1.93746004 0 P 0 ;0
L 1.87135 -1.93646004 1.87381998 -1.93646004 0 P 0 ;0
L 1.87151004 -1.93546004 1.87398996 -1.93546004 0 P 0 ;0
L 1.87171998 -1.93446004 1.87416998 -1.93446004 0 P 0 ;0
L 1.87191998 -1.93346004 1.87443002 -1.93346004 0 P 0 ;0
L 1.8722 -1.93246004 1.87468996 -1.93246004 0 P 0 ;0
L 1.87248996 -1.93146004 1.875 -1.93146004 0 P 0 ;0
L 1.87281004 -1.93046004 1.87535 -1.93046004 0 P 0 ;0
L 1.87318996 -1.92946004 1.87571004 -1.92946004 0 P 0 ;0
L 1.87356998 -1.92846004 1.87616004 -1.92846004 0 P 0 ;0
L 1.87405 -1.92746004 1.87661004 -1.92746004 0 P 0 ;0
L 1.87453002 -1.92646004 1.87711998 -1.92646004 0 P 0 ;0
L 1.87506998 -1.92546004 1.87768996 -1.92546004 0 P 0 ;0
L 1.87566004 -1.92446998 1.87826998 -1.92446998 0 P 0 ;0
L 1.87628996 -1.92346004 1.87896004 -1.92346004 0 P 0 ;0
L 1.87701004 -1.92246004 1.87963996 -1.92246004 0 P 0 ;0
L 1.87775 -1.92146004 1.88046004 -1.92146004 0 P 0 ;0
L 1.90483996 -1.97346004 1.9009 -1.97333996 0 P 0 ;0
L 1.9009 -1.97333996 1.89698002 -1.97295 0 P 0 ;0
L 1.89698002 -1.97295 1.89488996 -1.97258996 0 P 0 ;0
L 1.89488996 -1.97258996 1.89285 -1.97206998 0 P 0 ;0
L 1.89285 -1.97206998 1.89086004 -1.97138996 0 P 0 ;0
L 1.89086004 -1.97138996 1.889 -1.97058002 0 P 0 ;0
L 1.889 -1.97058002 1.88723002 -1.96961998 0 P 0 ;0
L 1.88723002 -1.96961998 1.88553002 -1.96851998 0 P 0 ;0
L 1.88553002 -1.96851998 1.88273996 -1.96636004 0 P 0 ;0
L 1.88273996 -1.96636004 1.88013996 -1.96396004 0 P 0 ;0
L 1.88013996 -1.96396004 1.8779 -1.9615 0 P 0 ;0
L 1.8779 -1.9615 1.87588002 -1.95886998 0 P 0 ;0
L 1.87588002 -1.95886998 1.87483002 -1.95723996 0 P 0 ;0
L 1.87483002 -1.95723996 1.8739 -1.95553996 0 P 0 ;0
L 1.8739 -1.95553996 1.87311004 -1.95376998 0 P 0 ;0
L 1.87311004 -1.95376998 1.87243002 -1.95191004 0 P 0 ;0
L 1.87243002 -1.95191004 1.8719 -1.95001998 0 P 0 ;0
L 1.8719 -1.95001998 1.87151998 -1.9481 0 P 0 ;0
L 1.87151998 -1.9481 1.87111004 -1.94468996 0 P 0 ;0
L 1.87111004 -1.94468996 1.87098002 -1.94128996 0 P 0 ;0
L 1.87098002 -1.94128996 1.87108996 -1.93861004 0 P 0 ;0
L 1.87108996 -1.93861004 1.87141004 -1.93596998 0 P 0 ;0
L 1.87141004 -1.93596998 1.87195 -1.93335 0 P 0 ;0
L 1.87195 -1.93335 1.87268996 -1.93078996 0 P 0 ;0
L 1.87268996 -1.93078996 1.87361998 -1.92835 0 P 0 ;0
L 1.87361998 -1.92835 1.87475 -1.926 0 P 0 ;0
L 1.87475 -1.926 1.87608996 -1.92376004 0 P 0 ;0
L 1.87608996 -1.92376004 1.8776 -1.92163996 0 P 0 ;0
L 1.8776 -1.92163996 1.87931998 -1.91961998 0 P 0 ;0
L 1.87931998 -1.91961998 1.8812 -1.91775 0 P 0 ;0
L 1.8812 -1.91775 1.88323002 -1.91605 0 P 0 ;0
L 1.88323002 -1.91605 1.8854 -1.91451998 0 P 0 ;0
L 1.8854 -1.91451998 1.88781004 -1.91308996 0 P 0 ;0
L 1.88781004 -1.91308996 1.89031004 -1.91186004 0 P 0 ;0
L 1.89031004 -1.91186004 1.89288002 -1.9108 0 P 0 ;0
L 1.89288002 -1.9108 1.89553002 -1.90995 0 P 0 ;0
L 1.89553002 -1.90995 1.89723002 -1.90953002 0 P 0 ;0
L 1.89723002 -1.90953002 1.89896004 -1.90923996 0 P 0 ;0
L 1.89896004 -1.90923996 1.90068996 -1.90908002 0 P 0 ;0
L 1.90068996 -1.90908002 1.90398996 -1.90901004 0 P 0 ;0
L 1.90398996 -1.90901004 1.90728002 -1.90915 0 P 0 ;0
L 1.90728002 -1.90915 1.91058996 -1.90951004 0 P 0 ;0
L 1.91058996 -1.90951004 1.91383996 -1.91006004 0 P 0 ;0
L 1.91383996 -1.91006004 1.91558996 -1.91048996 0 P 0 ;0
L 1.91558996 -1.91048996 1.91728996 -1.91101998 0 P 0 ;0
L 1.91728996 -1.91101998 1.91895 -1.91168002 0 P 0 ;0
L 1.91895 -1.91168002 1.92001998 -1.9122 0 P 0 ;0
L 1.92001998 -1.9122 1.92105 -1.91278996 0 P 0 ;0
L 1.92105 -1.91278996 1.92376998 -1.91458002 0 P 0 ;0
L 1.92376998 -1.91458002 1.92648996 -1.91666998 0 P 0 ;0
L 1.92648996 -1.91666998 1.92763002 -1.91763996 0 P 0 ;0
L 1.92763002 -1.91763996 1.92871004 -1.91865 0 P 0 ;0
L 1.92871004 -1.91865 1.93018002 -1.92018996 0 P 0 ;0
L 1.93018002 -1.92018996 1.93153002 -1.9218 0 P 0 ;0
L 1.93153002 -1.9218 1.93276998 -1.92348996 0 P 0 ;0
L 1.93276998 -1.92348996 1.93381004 -1.92515 0 P 0 ;0
L 1.93381004 -1.92515 1.93471998 -1.92686998 0 P 0 ;0
L 1.93471998 -1.92686998 1.9355 -1.92866998 0 P 0 ;0
L 1.9355 -1.92866998 1.93616998 -1.93061004 0 P 0 ;0
L 1.93616998 -1.93061004 1.93668996 -1.93258002 0 P 0 ;0
L 1.93668996 -1.93258002 1.93706998 -1.93458996 0 P 0 ;0
L 1.93706998 -1.93458996 1.93746998 -1.93818996 0 P 0 ;0
L 1.93746998 -1.93818996 1.9376 -1.94178996 0 P 0 ;0
L 1.9376 -1.94178996 1.93746004 -1.94611004 0 P 0 ;0
L 1.93746004 -1.94611004 1.93731004 -1.94758996 0 P 0 ;0
L 1.93731004 -1.94758996 1.93705 -1.94903996 0 P 0 ;0
L 1.93705 -1.94903996 1.93666998 -1.95041998 0 P 0 ;0
L 1.93666998 -1.95041998 1.93618002 -1.95176004 0 P 0 ;0
L 1.93618002 -1.95176004 1.9345 -1.95545 0 P 0 ;0
L 1.9345 -1.95545 1.93338996 -1.9575 0 P 0 ;0
L 1.93338996 -1.9575 1.93216004 -1.95946998 0 P 0 ;0
L 1.93216004 -1.95946998 1.93078996 -1.96133996 0 P 0 ;0
L 1.93078996 -1.96133996 1.92931004 -1.96311998 0 P 0 ;0
L 1.92931004 -1.96311998 1.92776998 -1.96473002 0 P 0 ;0
L 1.92776998 -1.96473002 1.92613002 -1.96621004 0 P 0 ;0
L 1.92613002 -1.96621004 1.92438002 -1.96756004 0 P 0 ;0
L 1.92438002 -1.96756004 1.92253002 -1.96878002 0 P 0 ;0
L 1.92253002 -1.96878002 1.92056998 -1.96986998 0 P 0 ;0
L 1.92056998 -1.96986998 1.91855 -1.97081998 0 P 0 ;0
L 1.91855 -1.97081998 1.91646004 -1.97161004 0 P 0 ;0
L 1.91646004 -1.97161004 1.91433002 -1.97223996 0 P 0 ;0
L 1.91433002 -1.97223996 1.9112 -1.97291004 0 P 0 ;0
L 1.9112 -1.97291004 1.90803996 -1.97331998 0 P 0 ;0
L 1.90803996 -1.97331998 1.90483996 -1.97346004 0 P 0 ;0
L 1.90476004 -1.97173996 1.9048 -1.97173996 0 P 0 ;0
L 1.9048 -1.97173996 1.90483996 -1.97173002 0 P 0 ;0
L 1.90483996 -1.97173002 1.90736004 -1.9716 0 P 0 ;0
L 1.90736004 -1.9716 1.9074 -1.97158996 0 P 0 ;0
L 1.9074 -1.97158996 1.90746998 -1.97158996 0 P 0 ;0
L 1.90746998 -1.97158996 1.90751004 -1.97158002 0 P 0 ;0
L 1.90751004 -1.97158002 1.91001004 -1.97126004 0 P 0 ;0
L 1.91001004 -1.97126004 1.91005 -1.97125 0 P 0 ;0
L 1.91005 -1.97125 1.91008002 -1.97123996 0 P 0 ;0
L 1.91008002 -1.97123996 1.91011998 -1.97123996 0 P 0 ;0
L 1.91011998 -1.97123996 1.91016004 -1.97123002 0 P 0 ;0
L 1.91016004 -1.97123002 1.9126 -1.97071998 0 P 0 ;0
L 1.9126 -1.97071998 1.9126 -1.97071004 0 P 0 ;0
L 1.9126 -1.97071004 1.91266998 -1.97071004 0 P 0 ;0
L 1.91266998 -1.97071004 1.91271004 -1.97068996 0 P 0 ;0
L 1.91271004 -1.97068996 1.91275 -1.97068002 0 P 0 ;0
L 1.91275 -1.97068002 1.91511998 -1.96998996 0 P 0 ;0
L 1.91511998 -1.96998996 1.91515 -1.96998996 0 P 0 ;0
L 1.91515 -1.96998996 1.91518996 -1.96996998 0 P 0 ;0
L 1.91518996 -1.96996998 1.91523002 -1.96996004 0 P 0 ;0
L 1.91523002 -1.96996004 1.91526004 -1.96995 0 P 0 ;0
L 1.91526004 -1.96995 1.91756998 -1.96908002 0 P 0 ;0
L 1.91756998 -1.96908002 1.91761004 -1.96906998 0 P 0 ;0
L 1.91761004 -1.96906998 1.91768002 -1.96903996 0 P 0 ;0
L 1.91768002 -1.96903996 1.91771004 -1.96901998 0 P 0 ;0
L 1.91771004 -1.96901998 1.91995 -1.96798002 0 P 0 ;0
L 1.91995 -1.96798002 1.92001998 -1.96795 0 P 0 ;0
L 1.92001998 -1.96795 1.92005 -1.96793002 0 P 0 ;0
L 1.92005 -1.96793002 1.92008996 -1.96791004 0 P 0 ;0
L 1.92008996 -1.96791004 1.92168002 -1.96701998 0 P 0 ;0
L 1.92168002 -1.96701998 1.92171998 -1.967 0 P 0 ;0
L 1.92171998 -1.967 1.92175 -1.96698002 0 P 0 ;0
L 1.92175 -1.96698002 1.92178996 -1.96695 0 P 0 ;0
L 1.92178996 -1.96695 1.92181998 -1.96693002 0 P 0 ;0
L 1.92181998 -1.96693002 1.92331998 -1.96591998 0 P 0 ;0
L 1.92331998 -1.96591998 1.92336004 -1.9659 0 P 0 ;0
L 1.92336004 -1.9659 1.92341998 -1.96586004 0 P 0 ;0
L 1.92341998 -1.96586004 1.92345 -1.96583002 0 P 0 ;0
L 1.92345 -1.96583002 1.92486004 -1.9647 0 P 0 ;0
L 1.92486004 -1.9647 1.92493002 -1.96465 0 P 0 ;0
L 1.92493002 -1.96465 1.92496004 -1.96463002 0 P 0 ;0
L 1.92496004 -1.96463002 1.92498996 -1.9646 0 P 0 ;0
L 1.92498996 -1.9646 1.92631004 -1.96336998 0 P 0 ;0
L 1.92631004 -1.96336998 1.9264 -1.96328002 0 P 0 ;0
L 1.9264 -1.96328002 1.92641998 -1.96325 0 P 0 ;0
L 1.92641998 -1.96325 1.92763996 -1.96191998 0 P 0 ;0
L 1.92763996 -1.96191998 1.92766998 -1.96188996 0 P 0 ;0
L 1.92766998 -1.96188996 1.92768996 -1.96186004 0 P 0 ;0
L 1.92768996 -1.96186004 1.92771998 -1.96183002 0 P 0 ;0
L 1.92771998 -1.96183002 1.92773996 -1.9618 0 P 0 ;0
L 1.92773996 -1.9618 1.92913996 -1.96001004 0 P 0 ;0
L 1.92913996 -1.96001004 1.92918996 -1.95995 0 P 0 ;0
L 1.92918996 -1.95995 1.92921004 -1.95991004 0 P 0 ;0
L 1.92921004 -1.95991004 1.92923002 -1.95988002 0 P 0 ;0
L 1.92923002 -1.95988002 1.93048002 -1.95798996 0 P 0 ;0
L 1.93048002 -1.95798996 1.93051998 -1.95793002 0 P 0 ;0
L 1.93051998 -1.95793002 1.93053996 -1.95788996 0 P 0 ;0
L 1.93053996 -1.95788996 1.93056004 -1.95786004 0 P 0 ;0
L 1.93056004 -1.95786004 1.93166004 -1.95588002 0 P 0 ;0
L 1.93166004 -1.95588002 1.93171004 -1.95576998 0 P 0 ;0
L 1.93171004 -1.95576998 1.93173002 -1.95573996 0 P 0 ;0
L 1.93173002 -1.95573996 1.93266998 -1.95366998 0 P 0 ;0
L 1.93266998 -1.95366998 1.93271004 -1.95356998 0 P 0 ;0
L 1.93271004 -1.95356998 1.93273002 -1.95353002 0 P 0 ;0
L 1.93273002 -1.95353002 1.9335 -1.9514 0 P 0 ;0
L 1.9335 -1.9514 1.93351004 -1.95136998 0 P 0 ;0
L 1.93351004 -1.95136998 1.93353002 -1.95133002 0 P 0 ;0
L 1.93353002 -1.95133002 1.93355 -1.95125 0 P 0 ;0
L 1.93355 -1.95125 1.93416004 -1.94906998 0 P 0 ;0
L 1.93416004 -1.94906998 1.93416998 -1.94903002 0 P 0 ;0
L 1.93416998 -1.94903002 1.93418002 -1.949 0 P 0 ;0
L 1.93418002 -1.949 1.93418002 -1.94896004 0 P 0 ;0
L 1.93418002 -1.94896004 1.93418996 -1.94891998 0 P 0 ;0
L 1.93418996 -1.94891998 1.93463996 -1.94665 0 P 0 ;0
L 1.93463996 -1.94665 1.93463996 -1.94661004 0 P 0 ;0
L 1.93463996 -1.94661004 1.93465 -1.94656998 0 P 0 ;0
L 1.93465 -1.94656998 1.93466004 -1.9465 0 P 0 ;0
L 1.93466004 -1.9465 1.93493996 -1.9442 0 P 0 ;0
L 1.93493996 -1.9442 1.93493996 -1.94413002 0 P 0 ;0
L 1.93493996 -1.94413002 1.93495 -1.94408996 0 P 0 ;0
L 1.93495 -1.94408996 1.93495 -1.94406004 0 P 0 ;0
L 1.93495 -1.94406004 1.93505 -1.94173996 0 P 0 ;0
L 1.93505 -1.94173996 1.93506004 -1.94171004 0 P 0 ;0
L 1.93506004 -1.94171004 1.93506004 -1.9416 0 P 0 ;0
L 1.93506004 -1.9416 1.93498996 -1.93928996 0 P 0 ;0
L 1.93498996 -1.93928996 1.93498996 -1.93921004 0 P 0 ;0
L 1.93498996 -1.93921004 1.93498002 -1.93913996 0 P 0 ;0
L 1.93498002 -1.93913996 1.93475 -1.93683996 0 P 0 ;0
L 1.93475 -1.93683996 1.93473996 -1.93676998 0 P 0 ;0
L 1.93473996 -1.93676998 1.93473002 -1.93673002 0 P 0 ;0
L 1.93473002 -1.93673002 1.93473002 -1.93668996 0 P 0 ;0
L 1.93473002 -1.93668996 1.93433002 -1.93441004 0 P 0 ;0
L 1.93433002 -1.93441004 1.93431998 -1.93436998 0 P 0 ;0
L 1.93431998 -1.93436998 1.93431004 -1.93433996 0 P 0 ;0
L 1.93431004 -1.93433996 1.93428996 -1.93426004 0 P 0 ;0
L 1.93428996 -1.93426004 1.93373002 -1.93206004 0 P 0 ;0
L 1.93373002 -1.93206004 1.93368996 -1.93191998 0 P 0 ;0
L 1.93368996 -1.93191998 1.93296004 -1.92976998 0 P 0 ;0
L 1.93296004 -1.92976998 1.93293996 -1.9297 0 P 0 ;0
L 1.93293996 -1.9297 1.93291004 -1.92963002 0 P 0 ;0
L 1.93291004 -1.92963002 1.93201998 -1.92753996 0 P 0 ;0
L 1.93201998 -1.92753996 1.93196998 -1.92743002 0 P 0 ;0
L 1.93196998 -1.92743002 1.93196004 -1.9274 0 P 0 ;0
L 1.93196004 -1.9274 1.93091998 -1.92538996 0 P 0 ;0
L 1.93091998 -1.92538996 1.9309 -1.92536004 0 P 0 ;0
L 1.9309 -1.92536004 1.93088002 -1.92531998 0 P 0 ;0
L 1.93088002 -1.92531998 1.93086004 -1.92528996 0 P 0 ;0
L 1.93086004 -1.92528996 1.93083996 -1.92525 0 P 0 ;0
L 1.93083996 -1.92525 1.92965 -1.92331998 0 P 0 ;0
L 1.92965 -1.92331998 1.92956998 -1.9232 0 P 0 ;0
L 1.92956998 -1.9232 1.92823002 -1.92136004 0 P 0 ;0
L 1.92823002 -1.92136004 1.92818002 -1.9213 0 P 0 ;0
L 1.92818002 -1.9213 1.92816004 -1.92126998 0 P 0 ;0
L 1.92816004 -1.92126998 1.92813002 -1.92123996 0 P 0 ;0
L 1.92813002 -1.92123996 1.92671998 -1.91958002 0 P 0 ;0
L 1.92671998 -1.91958002 1.9266 -1.91946004 0 P 0 ;0
L 1.9266 -1.91946004 1.92505 -1.91793002 0 P 0 ;0
L 1.92505 -1.91793002 1.92498996 -1.91786998 0 P 0 ;0
L 1.92498996 -1.91786998 1.92493002 -1.91781998 0 P 0 ;0
L 1.92493002 -1.91781998 1.92325 -1.91643002 0 P 0 ;0
L 1.92325 -1.91643002 1.92318996 -1.91636998 0 P 0 ;0
L 1.92318996 -1.91636998 1.92311998 -1.91631998 0 P 0 ;0
L 1.92311998 -1.91631998 1.92133002 -1.91508002 0 P 0 ;0
L 1.92133002 -1.91508002 1.92126004 -1.91503996 0 P 0 ;0
L 1.92126004 -1.91503996 1.92121998 -1.91501004 0 P 0 ;0
L 1.92121998 -1.91501004 1.92118002 -1.91498996 0 P 0 ;0
L 1.92118002 -1.91498996 1.91928996 -1.91391004 0 P 0 ;0
L 1.91928996 -1.91391004 1.91926004 -1.91388996 0 P 0 ;0
L 1.91926004 -1.91388996 1.91913996 -1.91383002 0 P 0 ;0
L 1.91913996 -1.91383002 1.91716998 -1.91291004 0 P 0 ;0
L 1.91716998 -1.91291004 1.91711998 -1.91288996 0 P 0 ;0
L 1.91711998 -1.91288996 1.91705 -1.91286004 0 P 0 ;0
L 1.91705 -1.91286004 1.917 -1.91285 0 P 0 ;0
L 1.917 -1.91285 1.91476998 -1.91203996 0 P 0 ;0
L 1.91476998 -1.91203996 1.91468996 -1.91201998 0 P 0 ;0
L 1.91468996 -1.91201998 1.91465 -1.912 0 P 0 ;0
L 1.91465 -1.912 1.9146 -1.91198996 0 P 0 ;0
L 1.9146 -1.91198996 1.91233002 -1.91138996 0 P 0 ;0
L 1.91233002 -1.91138996 1.91228002 -1.91138002 0 P 0 ;0
L 1.91228002 -1.91138002 1.91223996 -1.91136998 0 P 0 ;0
L 1.91223996 -1.91136998 1.91216004 -1.91136004 0 P 0 ;0
L 1.91216004 -1.91136004 1.90983002 -1.91095 0 P 0 ;0
L 1.90983002 -1.91095 1.9098 -1.91093996 0 P 0 ;0
L 1.9098 -1.91093996 1.90976004 -1.91093996 0 P 0 ;0
L 1.90976004 -1.91093996 1.90971998 -1.91093002 0 P 0 ;0
L 1.90971998 -1.91093002 1.90968002 -1.91093002 0 P 0 ;0
L 1.90968002 -1.91093002 1.90713996 -1.91068996 0 P 0 ;0
L 1.90713996 -1.91068996 1.9071 -1.91068002 0 P 0 ;0
L 1.9071 -1.91068002 1.907 -1.91068002 0 P 0 ;0
L 1.907 -1.91068002 1.90445 -1.91061004 0 P 0 ;0
L 1.90445 -1.91061004 1.90431004 -1.91061004 0 P 0 ;0
L 1.90431004 -1.91061004 1.90176004 -1.91071004 0 P 0 ;0
L 1.90176004 -1.91071004 1.90173002 -1.91071998 0 P 0 ;0
L 1.90173002 -1.91071998 1.90166004 -1.91071998 0 P 0 ;0
L 1.90166004 -1.91071998 1.90161998 -1.91073002 0 P 0 ;0
L 1.90161998 -1.91073002 1.89913002 -1.911 0 P 0 ;0
L 1.89913002 -1.911 1.89906004 -1.91101004 0 P 0 ;0
L 1.89906004 -1.91101004 1.89901998 -1.91101998 0 P 0 ;0
L 1.89901998 -1.91101998 1.89898996 -1.91101998 0 P 0 ;0
L 1.89898996 -1.91101998 1.89653002 -1.91146998 0 P 0 ;0
L 1.89653002 -1.91146998 1.8965 -1.91148002 0 P 0 ;0
L 1.8965 -1.91148002 1.89646004 -1.91148002 0 P 0 ;0
L 1.89646004 -1.91148002 1.8964 -1.9115 0 P 0 ;0
L 1.8964 -1.9115 1.89396998 -1.91211998 0 P 0 ;0
L 1.89396998 -1.91211998 1.89393996 -1.91213002 0 P 0 ;0
L 1.89393996 -1.91213002 1.89383002 -1.91216004 0 P 0 ;0
L 1.89383002 -1.91216004 1.89225 -1.91268996 0 P 0 ;0
L 1.89225 -1.91268996 1.89218002 -1.91271998 0 P 0 ;0
L 1.89218002 -1.91271998 1.89211004 -1.91273996 0 P 0 ;0
L 1.89211004 -1.91273996 1.8921 -1.91273996 0 P 0 ;0
L 1.8921 -1.91273996 1.89058002 -1.91338996 0 P 0 ;0
L 1.89058002 -1.91338996 1.89043996 -1.91345 0 P 0 ;0
L 1.89043996 -1.91345 1.88896004 -1.91421004 0 P 0 ;0
L 1.88896004 -1.91421004 1.88893002 -1.91423002 0 P 0 ;0
L 1.88893002 -1.91423002 1.8889 -1.91423996 0 P 0 ;0
L 1.8889 -1.91423996 1.88886004 -1.91426004 0 P 0 ;0
L 1.88886004 -1.91426004 1.88883002 -1.91428002 0 P 0 ;0
L 1.88883002 -1.91428002 1.88741004 -1.91515 0 P 0 ;0
L 1.88741004 -1.91515 1.88733996 -1.91518996 0 P 0 ;0
L 1.88733996 -1.91518996 1.88728002 -1.91523996 0 P 0 ;0
L 1.88728002 -1.91523996 1.88526004 -1.9167 0 P 0 ;0
L 1.88526004 -1.9167 1.88521998 -1.91673002 0 P 0 ;0
L 1.88521998 -1.91673002 1.88518996 -1.91675 0 P 0 ;0
L 1.88518996 -1.91675 1.88516004 -1.91678002 0 P 0 ;0
L 1.88516004 -1.91678002 1.88511998 -1.91681004 0 P 0 ;0
L 1.88511998 -1.91681004 1.88323002 -1.91845 0 P 0 ;0
L 1.88323002 -1.91845 1.8832 -1.91846998 0 P 0 ;0
L 1.8832 -1.91846998 1.88311004 -1.91856004 0 P 0 ;0
L 1.88311004 -1.91856004 1.88136998 -1.92036004 0 P 0 ;0
L 1.88136998 -1.92036004 1.88128002 -1.92045 0 P 0 ;0
L 1.88128002 -1.92045 1.88125 -1.92048996 0 P 0 ;0
L 1.88125 -1.92048996 1.87968002 -1.92241998 0 P 0 ;0
L 1.87968002 -1.92241998 1.87965 -1.92245 0 P 0 ;0
L 1.87965 -1.92245 1.87961998 -1.92248996 0 P 0 ;0
L 1.87961998 -1.92248996 1.87956998 -1.92256004 0 P 0 ;0
L 1.87956998 -1.92256004 1.87816998 -1.92461998 0 P 0 ;0
L 1.87816998 -1.92461998 1.8781 -1.92473002 0 P 0 ;0
L 1.8781 -1.92473002 1.87808002 -1.92476998 0 P 0 ;0
L 1.87808002 -1.92476998 1.87685 -1.92695 0 P 0 ;0
L 1.87685 -1.92695 1.87683002 -1.92698996 0 P 0 ;0
L 1.87683002 -1.92698996 1.87681004 -1.92701998 0 P 0 ;0
L 1.87681004 -1.92701998 1.87678996 -1.92706998 0 P 0 ;0
L 1.87678996 -1.92706998 1.87676998 -1.92711004 0 P 0 ;0
L 1.87676998 -1.92711004 1.87573002 -1.92941004 0 P 0 ;0
L 1.87573002 -1.92941004 1.87571004 -1.92945 0 P 0 ;0
L 1.87571004 -1.92945 1.8757 -1.92948996 0 P 0 ;0
L 1.8757 -1.92948996 1.87568002 -1.92951998 0 P 0 ;0
L 1.87568002 -1.92951998 1.87566998 -1.92956998 0 P 0 ;0
L 1.87566998 -1.92956998 1.87483996 -1.93193002 0 P 0 ;0
L 1.87483996 -1.93193002 1.87481004 -1.93201004 0 P 0 ;0
L 1.87481004 -1.93201004 1.87478996 -1.93208996 0 P 0 ;0
L 1.87478996 -1.93208996 1.87416004 -1.93451998 0 P 0 ;0
L 1.87416004 -1.93451998 1.87413996 -1.93456004 0 P 0 ;0
L 1.87413996 -1.93456004 1.87413002 -1.9346 0 P 0 ;0
L 1.87413002 -1.9346 1.87413002 -1.93463996 0 P 0 ;0
L 1.87413002 -1.93463996 1.87411998 -1.93468002 0 P 0 ;0
L 1.87411998 -1.93468002 1.8737 -1.93715 0 P 0 ;0
L 1.8737 -1.93715 1.87368996 -1.93718996 0 P 0 ;0
L 1.87368996 -1.93718996 1.87368002 -1.93723996 0 P 0 ;0
L 1.87368002 -1.93723996 1.87368002 -1.93731998 0 P 0 ;0
L 1.87368002 -1.93731998 1.87346998 -1.93981998 0 P 0 ;0
L 1.87346998 -1.93981998 1.87346004 -1.93986004 0 P 0 ;0
L 1.87346004 -1.93986004 1.87346004 -1.94258002 0 P 0 ;0
L 1.87346004 -1.94258002 1.87346998 -1.94266004 0 P 0 ;0
L 1.87346998 -1.94266004 1.87368002 -1.94516998 0 P 0 ;0
L 1.87368002 -1.94516998 1.87368996 -1.94521004 0 P 0 ;0
L 1.87368996 -1.94521004 1.87368996 -1.94525 0 P 0 ;0
L 1.87368996 -1.94525 1.87371004 -1.94533996 0 P 0 ;0
L 1.87371004 -1.94533996 1.87413996 -1.94778996 0 P 0 ;0
L 1.87413996 -1.94778996 1.87413996 -1.94783996 0 P 0 ;0
L 1.87413996 -1.94783996 1.87416998 -1.94796004 0 P 0 ;0
L 1.87416998 -1.94796004 1.87481004 -1.95036998 0 P 0 ;0
L 1.87481004 -1.95036998 1.87483996 -1.95048996 0 P 0 ;0
L 1.87483996 -1.95048996 1.87486004 -1.95053002 0 P 0 ;0
L 1.87486004 -1.95053002 1.8757 -1.95288002 0 P 0 ;0
L 1.8757 -1.95288002 1.87571004 -1.95291998 0 P 0 ;0
L 1.87571004 -1.95291998 1.87575 -1.953 0 P 0 ;0
L 1.87575 -1.953 1.87576004 -1.95303996 0 P 0 ;0
L 1.87576004 -1.95303996 1.8768 -1.9553 0 P 0 ;0
L 1.8768 -1.9553 1.87686004 -1.95541998 0 P 0 ;0
L 1.87686004 -1.95541998 1.87688002 -1.95545 0 P 0 ;0
L 1.87688002 -1.95545 1.8781 -1.95761004 0 P 0 ;0
L 1.8781 -1.95761004 1.87811998 -1.95761004 0 P 0 ;0
L 1.87811998 -1.95761004 1.8781 -1.95761998 0 P 0 ;0
L 1.8781 -1.95761998 1.87813996 -1.95768996 0 P 0 ;0
L 1.87813996 -1.95768996 1.87816998 -1.95771998 0 P 0 ;0
L 1.87816998 -1.95771998 1.87818996 -1.95775 0 P 0 ;0
L 1.87818996 -1.95775 1.87938002 -1.95951004 0 P 0 ;0
L 1.87938002 -1.95951004 1.87943996 -1.9596 0 P 0 ;0
L 1.87943996 -1.9596 1.87946998 -1.95963002 0 P 0 ;0
L 1.87946998 -1.95963002 1.88078002 -1.96128996 0 P 0 ;0
L 1.88078002 -1.96128996 1.88081004 -1.96131998 0 P 0 ;0
L 1.88081004 -1.96131998 1.88083002 -1.96135 0 P 0 ;0
L 1.88083002 -1.96135 1.88086004 -1.96136998 0 P 0 ;0
L 1.88086004 -1.96136998 1.88088002 -1.9614 0 P 0 ;0
L 1.88088002 -1.9614 1.88231998 -1.96295 0 P 0 ;0
L 1.88231998 -1.96295 1.88233996 -1.96298002 0 P 0 ;0
L 1.88233996 -1.96298002 1.8824 -1.96303996 0 P 0 ;0
L 1.8824 -1.96303996 1.88243002 -1.96306004 0 P 0 ;0
L 1.88243002 -1.96306004 1.88398002 -1.9645 0 P 0 ;0
L 1.88398002 -1.9645 1.88401004 -1.96451998 0 P 0 ;0
L 1.88401004 -1.96451998 1.88403002 -1.96455 0 P 0 ;0
L 1.88403002 -1.96455 1.88406998 -1.96458002 0 P 0 ;0
L 1.88406998 -1.96458002 1.88408996 -1.9646 0 P 0 ;0
L 1.88408996 -1.9646 1.88575 -1.96591004 0 P 0 ;0
L 1.88575 -1.96591004 1.88578002 -1.96593996 0 P 0 ;0
L 1.88578002 -1.96593996 1.88586998 -1.966 0 P 0 ;0
L 1.88586998 -1.966 1.88761998 -1.96718996 0 P 0 ;0
L 1.88761998 -1.96718996 1.88766004 -1.96721004 0 P 0 ;0
L 1.88766004 -1.96721004 1.88775 -1.96726998 0 P 0 ;0
L 1.88775 -1.96726998 1.88958996 -1.96831998 0 P 0 ;0
L 1.88958996 -1.96831998 1.88965 -1.96836004 0 P 0 ;0
L 1.88965 -1.96836004 1.88968002 -1.96836998 0 P 0 ;0
L 1.88968002 -1.96836998 1.88971998 -1.96838996 0 P 0 ;0
L 1.88971998 -1.96838996 1.89145 -1.96921998 0 P 0 ;0
L 1.89145 -1.96921998 1.89151004 -1.96925 0 P 0 ;0
L 1.89151004 -1.96925 1.89155 -1.96926004 0 P 0 ;0
L 1.89155 -1.96926004 1.89158002 -1.96926998 0 P 0 ;0
L 1.89158002 -1.96926998 1.89336004 -1.96996998 0 P 0 ;0
L 1.89336004 -1.96996998 1.89336004 -1.96998002 0 P 0 ;0
L 1.89336004 -1.96998002 1.89346004 -1.97001004 0 P 0 ;0
L 1.89346004 -1.97001004 1.89348996 -1.97001998 0 P 0 ;0
L 1.89348996 -1.97001998 1.89531998 -1.9706 0 P 0 ;0
L 1.89531998 -1.9706 1.89536004 -1.97061004 0 P 0 ;0
L 1.89536004 -1.97061004 1.89541998 -1.97063002 0 P 0 ;0
L 1.89541998 -1.97063002 1.89546004 -1.97063002 0 P 0 ;0
L 1.89546004 -1.97063002 1.89731998 -1.97108002 0 P 0 ;0
L 1.89731998 -1.97108002 1.89741998 -1.9711 0 P 0 ;0
L 1.89741998 -1.9711 1.89746004 -1.9711 0 P 0 ;0
L 1.89746004 -1.9711 1.89746004 -1.97111004 0 P 0 ;0
L 1.89746004 -1.97111004 1.89933996 -1.97141998 0 P 0 ;0
L 1.89933996 -1.97141998 1.89936998 -1.97143002 0 P 0 ;0
L 1.89936998 -1.97143002 1.89941004 -1.97143002 0 P 0 ;0
L 1.89941004 -1.97143002 1.89945 -1.97143996 0 P 0 ;0
L 1.89945 -1.97143996 1.89948002 -1.97143996 0 P 0 ;0
L 1.89948002 -1.97143996 1.90201004 -1.97168002 0 P 0 ;0
L 1.90201004 -1.97168002 1.90205 -1.97168002 0 P 0 ;0
L 1.90205 -1.97168002 1.90208996 -1.97168996 0 P 0 ;0
L 1.90208996 -1.97168996 1.90216004 -1.97168996 0 P 0 ;0
L 1.90216004 -1.97168996 1.90468996 -1.97173996 0 P 0 ;0
L 1.90468996 -1.97173996 1.90476004 -1.97173996 0 P 0 ;0
L 1.80616004 -2.12823996 1.83348996 -2.12823996 0 P 0 ;0
L 1.79591998 -2.12723996 1.8396 -2.12723996 0 P 0 ;0
L 1.78818002 -2.12623996 1.84465 -2.12623996 0 P 0 ;0
L 1.82003996 -2.09123996 1.87618996 -2.09123996 0 P 0 ;0
L 1.82198996 -2.09023996 1.8762 -2.09023996 0 P 0 ;0
L 1.82325 -2.08923996 1.8762 -2.08923996 0 P 0 ;0
L 1.82411998 -2.08823996 1.87618996 -2.08823996 0 P 0 ;0
L 1.82463002 -2.08723996 1.87616998 -2.08723996 0 P 0 ;0
L 1.82488002 -2.08623996 1.87615 -2.08623996 0 P 0 ;0
L 1.82493002 -2.08523996 1.87613002 -2.08523996 0 P 0 ;0
L 1.82476998 -2.08423996 1.87611004 -2.08423996 0 P 0 ;0
L 1.64846004 -2.08295 1.73316998 -2.08295 0 P 0 ;0
L 1.64811998 -2.08195 1.73356998 -2.08195 0 P 0 ;0
L 1.64776998 -2.08095 1.73398002 -2.08095 0 P 0 ;0
L 1.64743002 -2.07995 1.73438002 -2.07995 0 P 0 ;0
L 1.64708996 -2.07895 1.73478996 -2.07895 0 P 0 ;0
L 1.64673996 -2.07795 1.7352 -2.07795 0 P 0 ;0
L 1.6464 -2.07695 1.7356 -2.07695 0 P 0 ;0
L 1.64605 -2.07595 1.73601004 -2.07595 0 P 0 ;0
L 1.64571004 -2.07495 1.73641004 -2.07495 0 P 0 ;0
L 1.64536004 -2.07395 1.73681004 -2.07395 0 P 0 ;0
L 1.64501998 -2.07295 1.73721998 -2.07295 0 P 0 ;0
L 1.64466998 -2.07195 1.73761998 -2.07195 0 P 0 ;0
L 1.64433002 -2.07095 1.73803002 -2.07095 0 P 0 ;0
L 1.64398002 -2.06995 1.69251004 -2.06995 0 P 0 ;0
L 1.69583002 -2.06995 1.73843996 -2.06995 0 P 0 ;0
L 1.64363002 -2.06895 1.69168002 -2.06895 0 P 0 ;0
L 1.69671998 -2.06895 1.73883996 -2.06895 0 P 0 ;0
L 1.64328996 -2.06795 1.69136004 -2.06795 0 P 0 ;0
L 1.69708996 -2.06795 1.73925 -2.06795 0 P 0 ;0
L 1.64293996 -2.06695 1.69108002 -2.06695 0 P 0 ;0
L 1.69738002 -2.06695 1.73965 -2.06695 0 P 0 ;0
L 1.64258996 -2.06595 1.6908 -2.06595 0 P 0 ;0
L 1.69768002 -2.06595 1.74006004 -2.06595 0 P 0 ;0
L 1.64223996 -2.06495 1.69051998 -2.06495 0 P 0 ;0
L 1.69796998 -2.06495 1.74046004 -2.06495 0 P 0 ;0
L 1.6419 -2.06395 1.69023002 -2.06395 0 P 0 ;0
L 1.69826998 -2.06395 1.74086004 -2.06395 0 P 0 ;0
L 1.64155 -2.06295 1.68996004 -2.06295 0 P 0 ;0
L 1.69856004 -2.06295 1.74126998 -2.06295 0 P 0 ;0
L 1.6412 -2.06195 1.68966998 -2.06195 0 P 0 ;0
L 1.69886004 -2.06195 1.74168002 -2.06195 0 P 0 ;0
L 1.64085 -2.06095 1.68938996 -2.06095 0 P 0 ;0
L 1.69915 -2.06095 1.74208002 -2.06095 0 P 0 ;0
L 1.6405 -2.05995 1.68911004 -2.05995 0 P 0 ;0
L 1.69945 -2.05995 1.74248002 -2.05995 0 P 0 ;0
L 1.64016004 -2.05895 1.68883002 -2.05895 0 P 0 ;0
L 1.69973996 -2.05895 1.74288996 -2.05895 0 P 0 ;0
L 1.63981004 -2.05795 1.68855 -2.05795 0 P 0 ;0
L 1.70003996 -2.05795 1.74328996 -2.05795 0 P 0 ;0
L 1.63946004 -2.05695 1.68826998 -2.05695 0 P 0 ;0
L 1.70033002 -2.05695 1.7437 -2.05695 0 P 0 ;0
L 1.63911004 -2.05595 1.68798996 -2.05595 0 P 0 ;0
L 1.70063002 -2.05595 1.7441 -2.05595 0 P 0 ;0
L 1.63876998 -2.05495 1.68771004 -2.05495 0 P 0 ;0
L 1.70091998 -2.05495 1.74451004 -2.05495 0 P 0 ;0
L 1.63841998 -2.05395 1.68741998 -2.05395 0 P 0 ;0
L 1.70121998 -2.05395 1.74491004 -2.05395 0 P 0 ;0
L 1.63806998 -2.05295 1.68713996 -2.05295 0 P 0 ;0
L 1.70151004 -2.05295 1.74531004 -2.05295 0 P 0 ;0
L 1.63771998 -2.05195 1.68686004 -2.05195 0 P 0 ;0
L 1.70181004 -2.05195 1.74571998 -2.05195 0 P 0 ;0
L 1.63738002 -2.05095 1.68658002 -2.05095 0 P 0 ;0
L 1.7021 -2.05095 1.74611998 -2.05095 0 P 0 ;0
L 1.63703002 -2.04995 1.6863 -2.04995 0 P 0 ;0
L 1.7024 -2.04995 1.74653002 -2.04995 0 P 0 ;0
L 1.63668002 -2.04895 1.68601998 -2.04895 0 P 0 ;0
L 1.70268996 -2.04895 1.74693002 -2.04895 0 P 0 ;0
L 1.63633002 -2.04795 1.68573996 -2.04795 0 P 0 ;0
L 1.70298996 -2.04795 1.74733002 -2.04795 0 P 0 ;0
L 1.63598002 -2.04695 1.68546004 -2.04695 0 P 0 ;0
L 1.70328002 -2.04695 1.74773996 -2.04695 0 P 0 ;0
L 1.63563996 -2.04595 1.68518002 -2.04595 0 P 0 ;0
L 1.70358002 -2.04595 1.74813996 -2.04595 0 P 0 ;0
L 1.63528996 -2.04495 1.6849 -2.04495 0 P 0 ;0
L 1.70386998 -2.04495 1.74855 -2.04495 0 P 0 ;0
L 1.63493996 -2.04395 1.68461004 -2.04395 0 P 0 ;0
L 1.70416998 -2.04395 1.74895 -2.04395 0 P 0 ;0
L 1.63458996 -2.04295 1.68433002 -2.04295 0 P 0 ;0
L 1.70446004 -2.04295 1.74936004 -2.04295 0 P 0 ;0
L 1.63425 -2.04195 1.68405 -2.04195 0 P 0 ;0
L 1.70475 -2.04195 1.74976004 -2.04195 0 P 0 ;0
L 1.6339 -2.04095 1.68376998 -2.04095 0 P 0 ;0
L 1.70503002 -2.04095 1.75016004 -2.04095 0 P 0 ;0
L 1.63355 -2.03995 1.68348996 -2.03995 0 P 0 ;0
L 1.70531998 -2.03995 1.75056998 -2.03995 0 P 0 ;0
L 1.6332 -2.03895 1.68321004 -2.03895 0 P 0 ;0
L 1.7056 -2.03895 1.75096998 -2.03895 0 P 0 ;0
L 1.63286004 -2.03795 1.68293002 -2.03795 0 P 0 ;0
L 1.70588996 -2.03795 1.75138002 -2.03795 0 P 0 ;0
L 1.63251004 -2.03695 1.68266004 -2.03695 0 P 0 ;0
L 1.70618002 -2.03695 1.75178002 -2.03695 0 P 0 ;0
L 1.63216004 -2.03595 1.68238002 -2.03595 0 P 0 ;0
L 1.70646998 -2.03595 1.75218996 -2.03595 0 P 0 ;0
L 1.63181004 -2.03495 1.6821 -2.03495 0 P 0 ;0
L 1.70675 -2.03495 1.75258996 -2.03495 0 P 0 ;0
L 1.63146998 -2.03395 1.68183002 -2.03395 0 P 0 ;0
L 1.70703996 -2.03395 1.75298996 -2.03395 0 P 0 ;0
L 1.63111998 -2.03295 1.68155 -2.03295 0 P 0 ;0
L 1.70733002 -2.03295 1.7534 -2.03295 0 P 0 ;0
L 1.63076998 -2.03195 1.68126998 -2.03195 0 P 0 ;0
L 1.70761004 -2.03195 1.75381004 -2.03195 0 P 0 ;0
L 1.63041998 -2.03095 1.68098996 -2.03095 0 P 0 ;0
L 1.7079 -2.03095 1.75421004 -2.03095 0 P 0 ;0
L 1.63006998 -2.02995 1.68071004 -2.02995 0 P 0 ;0
L 1.70818996 -2.02995 1.75461004 -2.02995 0 P 0 ;0
L 1.62973002 -2.02895 1.68043996 -2.02895 0 P 0 ;0
L 1.70846998 -2.02895 1.75501998 -2.02895 0 P 0 ;0
L 1.62938002 -2.02795 1.68016004 -2.02795 0 P 0 ;0
L 1.70876004 -2.02795 1.75541998 -2.02795 0 P 0 ;0
L 1.62903002 -2.02695 1.67988002 -2.02695 0 P 0 ;0
L 1.70905 -2.02695 1.75583002 -2.02695 0 P 0 ;0
L 1.62868002 -2.02595 1.6796 -2.02595 0 P 0 ;0
L 1.70933996 -2.02595 1.75623002 -2.02595 0 P 0 ;0
L 1.62831004 -2.02495 1.67933002 -2.02495 0 P 0 ;0
L 1.70961998 -2.02495 1.75663996 -2.02495 0 P 0 ;0
L 1.62793996 -2.02395 1.67905 -2.02395 0 P 0 ;0
L 1.70991004 -2.02395 1.75703996 -2.02395 0 P 0 ;0
L 1.62756998 -2.02295 1.67876998 -2.02295 0 P 0 ;0
L 1.7102 -2.02295 1.75743996 -2.02295 0 P 0 ;0
L 1.6272 -2.02195 1.6785 -2.02195 0 P 0 ;0
L 1.71048002 -2.02195 1.75785 -2.02195 0 P 0 ;0
L 1.62683002 -2.02095 1.67821998 -2.02095 0 P 0 ;0
L 1.71076004 -2.02095 1.75825 -2.02095 0 P 0 ;0
L 1.62646998 -2.01995 1.67793996 -2.01995 0 P 0 ;0
L 1.71101004 -2.01995 1.75866004 -2.01995 0 P 0 ;0
L 1.6261 -2.01895 1.67766004 -2.01895 0 P 0 ;0
L 1.71126998 -2.01895 1.75906004 -2.01895 0 P 0 ;0
L 1.62573002 -2.01795 1.67738996 -2.01795 0 P 0 ;0
L 1.71151998 -2.01795 1.75946998 -2.01795 0 P 0 ;0
L 1.62536004 -2.01695 1.67711004 -2.01695 0 P 0 ;0
L 1.71176998 -2.01695 1.75986998 -2.01695 0 P 0 ;0
L 1.62498996 -2.01595 1.67683002 -2.01595 0 P 0 ;0
L 1.71203002 -2.01595 1.76026998 -2.01595 0 P 0 ;0
L 1.62461998 -2.01495 1.67656004 -2.01495 0 P 0 ;0
L 1.71228002 -2.01495 1.76068002 -2.01495 0 P 0 ;0
L 1.62425 -2.01395 1.67628002 -2.01395 0 P 0 ;0
L 1.71253996 -2.01395 1.76108002 -2.01395 0 P 0 ;0
L 1.62388002 -2.01295 1.67601998 -2.01295 0 P 0 ;0
L 1.71278996 -2.01295 1.76148996 -2.01295 0 P 0 ;0
L 1.62351004 -2.01195 1.67576998 -2.01195 0 P 0 ;0
L 1.71305 -2.01195 1.76188996 -2.01195 0 P 0 ;0
L 1.62313996 -2.01095 1.67551998 -2.01095 0 P 0 ;0
L 1.7133 -2.01095 1.76228996 -2.01095 0 P 0 ;0
L 1.62276998 -2.00995 1.67528002 -2.00995 0 P 0 ;0
L 1.71355 -2.00995 1.7627 -2.00995 0 P 0 ;0
L 1.6224 -2.00895 1.67503002 -2.00895 0 P 0 ;0
L 1.71381004 -2.00895 1.7631 -2.00895 0 P 0 ;0
L 1.62203002 -2.00795 1.67478996 -2.00795 0 P 0 ;0
L 1.71406004 -2.00795 1.76351004 -2.00795 0 P 0 ;0
L 1.62166004 -2.00695 1.67453996 -2.00695 0 P 0 ;0
L 1.71431004 -2.00695 1.76391004 -2.00695 0 P 0 ;0
L 1.62128996 -2.00595 1.67428996 -2.00595 0 P 0 ;0
L 1.71453996 -2.00595 1.76431998 -2.00595 0 P 0 ;0
L 1.62091004 -2.00495 1.67405 -2.00495 0 P 0 ;0
L 1.71476998 -2.00495 1.76471998 -2.00495 0 P 0 ;0
L 1.62051998 -2.00395 1.6738 -2.00395 0 P 0 ;0
L 1.715 -2.00395 1.76511998 -2.00395 0 P 0 ;0
L 1.62013002 -2.00295 1.67355 -2.00295 0 P 0 ;0
L 1.71523002 -2.00295 1.76553002 -2.00295 0 P 0 ;0
L 1.61973996 -2.00195 1.67331004 -2.00195 0 P 0 ;0
L 1.71546004 -2.00195 1.76593996 -2.00195 0 P 0 ;0
L 1.61935 -2.00095 1.67306004 -2.00095 0 P 0 ;0
L 1.71568996 -2.00095 1.76633996 -2.00095 0 P 0 ;0
L 1.61896004 -1.99995 1.67283996 -1.99995 0 P 0 ;0
L 1.71591998 -1.99995 1.76673996 -1.99995 0 P 0 ;0
L 1.61856998 -1.99895 1.67261998 -1.99895 0 P 0 ;0
L 1.71613996 -1.99895 1.76715 -1.99895 0 P 0 ;0
L 1.71638002 -1.99795 1.76755 -1.99795 0 P 0 ;0
L 1.7166 -1.99695 1.76796004 -1.99695 0 P 0 ;0
L 1.71683002 -1.99595 1.76836004 -1.99595 0 P 0 ;0
L 1.71866998 -1.99495 1.76876998 -1.99495 0 P 0 ;0
L 1.78213996 -2.04823996 1.84641998 -2.04823996 0 P 0 ;0
L 1.78138002 -2.04723996 1.84498996 -2.04723996 0 P 0 ;0
L 1.78071004 -2.04623996 1.84356004 -2.04623996 0 P 0 ;0
L 1.7801 -2.04523996 1.84213996 -2.04523996 0 P 0 ;0
L 1.77956004 -2.04423996 1.84071004 -2.04423996 0 P 0 ;0
L 1.77908996 -2.04323996 1.83928002 -2.04323996 0 P 0 ;0
L 1.77866004 -2.04223996 1.83786004 -2.04223996 0 P 0 ;0
L 1.77831004 -2.04123996 1.83658996 -2.04123996 0 P 0 ;0
L 1.77796004 -2.04023996 1.83536004 -2.04023996 0 P 0 ;0
L 1.77761004 -2.03923996 1.83428002 -2.03923996 0 P 0 ;0
L 1.77733996 -2.03823996 1.83321998 -2.03823996 0 P 0 ;0
L 1.77706998 -2.03723996 1.83236998 -2.03723996 0 P 0 ;0
L 1.7768 -2.03623996 1.83171004 -2.03623996 0 P 0 ;0
L 1.7766 -2.03523996 1.83121004 -2.03523996 0 P 0 ;0
L 1.77641004 -2.03423996 1.83085 -2.03423996 0 P 0 ;0
L 1.77621004 -2.03323996 1.83071004 -2.03323996 0 P 0 ;0
L 1.77608002 -2.03223996 1.83076998 -2.03223996 0 P 0 ;0
L 1.77596004 -2.03123996 1.83106004 -2.03123996 0 P 0 ;0
L 1.77583996 -2.03023996 1.83158996 -2.03023996 0 P 0 ;0
L 1.77576004 -2.02923996 1.83238002 -2.02923996 0 P 0 ;0
L 1.7757 -2.02823996 1.83356998 -2.02823996 0 P 0 ;0
L 1.7757 -2.02723996 1.83591998 -2.02723996 0 P 0 ;0
L 1.77571998 -2.02623996 1.87495 -2.02623996 0 P 0 ;0
L 1.7758 -2.02523996 1.87485 -2.02523996 0 P 0 ;0
L 1.77588996 -2.02423996 1.87475 -2.02423996 0 P 0 ;0
L 1.77605 -2.02323996 1.87465 -2.02323996 0 P 0 ;0
L 1.77621004 -2.02223996 1.87455 -2.02223996 0 P 0 ;0
L 1.7764 -2.02123996 1.87445 -2.02123996 0 P 0 ;0
L 1.77665 -2.02023996 1.87433996 -2.02023996 0 P 0 ;0
L 1.7769 -2.01923996 1.87425 -2.01923996 0 P 0 ;0
L 1.7772 -2.01823996 1.87413996 -2.01823996 0 P 0 ;0
L 1.77753002 -2.01723996 1.87405 -2.01723996 0 P 0 ;0
L 1.77786004 -2.01623996 1.87393996 -2.01623996 0 P 0 ;0
L 1.77823002 -2.01523996 1.87383996 -2.01523996 0 P 0 ;0
L 1.77863996 -2.01423996 1.87373996 -2.01423996 0 P 0 ;0
L 1.77903996 -2.01323996 1.87363996 -2.01323996 0 P 0 ;0
L 1.7795 -2.01223996 1.87353996 -2.01223996 0 P 0 ;0
L 1.77998996 -2.01123996 1.87343996 -2.01123996 0 P 0 ;0
L 1.78046998 -2.01023996 1.87333002 -2.01023996 0 P 0 ;0
L 1.78103996 -2.00923996 1.87323002 -2.00923996 0 P 0 ;0
L 1.78161004 -2.00823996 1.87311998 -2.00823996 0 P 0 ;0
L 1.78221004 -2.00723996 1.87301998 -2.00723996 0 P 0 ;0
L 1.78288002 -2.00623996 1.87291998 -2.00623996 0 P 0 ;0
L 1.64213996 -2.14795 1.70566004 -2.14795 0 P 0 ;0
L 1.64518996 -2.14695 1.7062 -2.14695 0 P 0 ;0
L 1.64728996 -2.14595 1.70673996 -2.14595 0 P 0 ;0
L 1.64906998 -2.14495 1.70728002 -2.14495 0 P 0 ;0
L 1.65058002 -2.14395 1.70783002 -2.14395 0 P 0 ;0
L 1.6519 -2.14295 1.70836998 -2.14295 0 P 0 ;0
L 1.65311998 -2.14195 1.70881998 -2.14195 0 P 0 ;0
L 1.65416998 -2.14095 1.70926998 -2.14095 0 P 0 ;0
L 1.65508996 -2.13995 1.70973002 -2.13995 0 P 0 ;0
L 1.65588002 -2.13895 1.71018002 -2.13895 0 P 0 ;0
L 1.65658002 -2.13795 1.71063002 -2.13795 0 P 0 ;0
L 1.65726998 -2.13695 1.71108996 -2.13695 0 P 0 ;0
L 1.65791998 -2.13595 1.71153996 -2.13595 0 P 0 ;0
L 1.65853002 -2.13495 1.71198996 -2.13495 0 P 0 ;0
L 1.65913002 -2.13395 1.71245 -2.13395 0 P 0 ;0
L 1.65968002 -2.13295 1.7129 -2.13295 0 P 0 ;0
L 1.66021998 -2.13195 1.71331004 -2.13195 0 P 0 ;0
L 1.66071998 -2.13095 1.71371998 -2.13095 0 P 0 ;0
L 1.66121004 -2.12995 1.71411998 -2.12995 0 P 0 ;0
L 1.66166998 -2.12895 1.71453002 -2.12895 0 P 0 ;0
L 1.66201004 -2.12795 1.71493996 -2.12795 0 P 0 ;0
L 1.66223996 -2.12695 1.71533996 -2.12695 0 P 0 ;0
L 1.66235 -2.12595 1.71575 -2.12595 0 P 0 ;0
L 1.66236004 -2.12495 1.71615 -2.12495 0 P 0 ;0
L 1.66228002 -2.12395 1.71656004 -2.12395 0 P 0 ;0
L 1.66211998 -2.12295 1.71696004 -2.12295 0 P 0 ;0
L 1.66188002 -2.12195 1.71736004 -2.12195 0 P 0 ;0
L 1.66156004 -2.12095 1.71776998 -2.12095 0 P 0 ;0
L 1.66121004 -2.11995 1.71818002 -2.11995 0 P 0 ;0
L 1.66086998 -2.11895 1.71858002 -2.11895 0 P 0 ;0
L 1.66053002 -2.11795 1.71898996 -2.11795 0 P 0 ;0
L 1.66018002 -2.11695 1.71938996 -2.11695 0 P 0 ;0
L 1.65983996 -2.11595 1.7198 -2.11595 0 P 0 ;0
L 1.65948996 -2.11495 1.7202 -2.11495 0 P 0 ;0
L 1.65913996 -2.11395 1.72061004 -2.11395 0 P 0 ;0
L 1.6588 -2.11295 1.72101004 -2.11295 0 P 0 ;0
L 1.65846004 -2.11195 1.72141998 -2.11195 0 P 0 ;0
L 1.65811004 -2.11095 1.72181998 -2.11095 0 P 0 ;0
L 1.65776998 -2.10995 1.72223002 -2.10995 0 P 0 ;0
L 1.65741998 -2.10895 1.72263002 -2.10895 0 P 0 ;0
L 1.65708002 -2.10795 1.72303996 -2.10795 0 P 0 ;0
L 1.65673002 -2.10695 1.72343996 -2.10695 0 P 0 ;0
L 1.65638996 -2.10595 1.72385 -2.10595 0 P 0 ;0
L 1.65605 -2.10495 1.72425 -2.10495 0 P 0 ;0
L 1.6557 -2.10395 1.72466004 -2.10395 0 P 0 ;0
L 1.65536004 -2.10295 1.72506998 -2.10295 0 P 0 ;0
L 1.65501004 -2.10195 1.72546998 -2.10195 0 P 0 ;0
L 1.65466998 -2.10095 1.72588002 -2.10095 0 P 0 ;0
L 1.65431998 -2.09995 1.72628002 -2.09995 0 P 0 ;0
L 1.65398002 -2.09895 1.72668996 -2.09895 0 P 0 ;0
L 1.65363002 -2.09795 1.72708996 -2.09795 0 P 0 ;0
L 1.65328996 -2.09695 1.72748996 -2.09695 0 P 0 ;0
L 1.65293996 -2.09595 1.7279 -2.09595 0 P 0 ;0
L 1.6526 -2.09495 1.72831004 -2.09495 0 P 0 ;0
L 1.65225 -2.09395 1.72871004 -2.09395 0 P 0 ;0
L 1.65191004 -2.09295 1.72911998 -2.09295 0 P 0 ;0
L 1.65156998 -2.09195 1.72951998 -2.09195 0 P 0 ;0
L 1.65121998 -2.09095 1.72993002 -2.09095 0 P 0 ;0
L 1.65088002 -2.08995 1.73033002 -2.08995 0 P 0 ;0
L 1.65053002 -2.08895 1.73073996 -2.08895 0 P 0 ;0
L 1.65018996 -2.08795 1.73113996 -2.08795 0 P 0 ;0
L 1.64983996 -2.08695 1.73155 -2.08695 0 P 0 ;0
L 1.6495 -2.08595 1.73195 -2.08595 0 P 0 ;0
L 1.64915 -2.08495 1.73236004 -2.08495 0 P 0 ;0
L 1.64881004 -2.08395 1.73276004 -2.08395 0 P 0 ;0
L 1.81726998 -1.98915 1.81196004 -1.9899 0 P 0 ;0
L 1.81196004 -1.9899 1.80668996 -1.99096998 0 P 0 ;0
L 1.80668996 -1.99096998 1.8019 -1.99226004 0 P 0 ;0
L 1.8019 -1.99226004 1.79718996 -1.99391004 0 P 0 ;0
L 1.79718996 -1.99391004 1.79316004 -1.99568002 0 P 0 ;0
L 1.79316004 -1.99568002 1.78926998 -1.99778002 0 P 0 ;0
L 1.78926998 -1.99778002 1.78771004 -1.99878002 0 P 0 ;0
L 1.78771004 -1.99878002 1.78623002 -1.99988002 0 P 0 ;0
L 1.78623002 -1.99988002 1.78481004 -2.00108002 0 P 0 ;0
L 1.78481004 -2.00108002 1.78346998 -2.00238996 0 P 0 ;0
L 1.78346998 -2.00238996 1.78228996 -2.00371998 0 P 0 ;0
L 1.78228996 -2.00371998 1.78121004 -2.00513002 0 P 0 ;0
L 1.78121004 -2.00513002 1.78023002 -2.00661004 0 P 0 ;0
L 1.78023002 -2.00661004 1.77868002 -2.00933996 0 P 0 ;0
L 1.77868002 -2.00933996 1.77731998 -2.01216998 0 P 0 ;0
L 1.77731998 -2.01216998 1.77611004 -2.01516004 0 P 0 ;0
L 1.77611004 -2.01516004 1.77508996 -2.01823002 0 P 0 ;0
L 1.77508996 -2.01823002 1.77436998 -2.02111004 0 P 0 ;0
L 1.77436998 -2.02111004 1.77388996 -2.02406004 0 P 0 ;0
L 1.77388996 -2.02406004 1.77371998 -2.02603996 0 P 0 ;0
L 1.77371998 -2.02603996 1.77368996 -2.02801998 0 P 0 ;0
L 1.77368996 -2.02801998 1.7738 -2.03001998 0 P 0 ;0
L 1.7738 -2.03001998 1.7742 -2.03338996 0 P 0 ;0
L 1.7742 -2.03338996 1.77485 -2.03671004 0 P 0 ;0
L 1.77485 -2.03671004 1.77573002 -2.03993996 0 P 0 ;0
L 1.77573002 -2.03993996 1.77683996 -2.04308002 0 P 0 ;0
L 1.77683996 -2.04308002 1.7776 -2.04481998 0 P 0 ;0
L 1.7776 -2.04481998 1.7785 -2.04648996 0 P 0 ;0
L 1.7785 -2.04648996 1.77953002 -2.04808996 0 P 0 ;0
L 1.77953002 -2.04808996 1.78061004 -2.04953996 0 P 0 ;0
L 1.78061004 -2.04953996 1.78181004 -2.05091004 0 P 0 ;0
L 1.78181004 -2.05091004 1.78311004 -2.05218996 0 P 0 ;0
L 1.78311004 -2.05218996 1.78988996 -2.05801998 0 P 0 ;0
L 1.78988996 -2.05801998 1.79883996 -2.06491004 0 P 0 ;0
L 1.79883996 -2.06491004 1.80976998 -2.07261004 0 P 0 ;0
L 1.80976998 -2.07261004 1.81753002 -2.07823002 0 P 0 ;0
L 1.81753002 -2.07823002 1.81896998 -2.07943002 0 P 0 ;0
L 1.81896998 -2.07943002 1.82033002 -2.08073002 0 P 0 ;0
L 1.82033002 -2.08073002 1.82156998 -2.08213996 0 P 0 ;0
L 1.82156998 -2.08213996 1.82186004 -2.08251004 0 P 0 ;0
L 1.82186004 -2.08251004 1.82211004 -2.0829 0 P 0 ;0
L 1.82211004 -2.0829 1.82233002 -2.08331004 0 P 0 ;0
L 1.82233002 -2.08331004 1.82253002 -2.08373996 0 P 0 ;0
L 1.82253002 -2.08373996 1.82268002 -2.08418002 0 P 0 ;0
L 1.82268002 -2.08418002 1.82281004 -2.08463002 0 P 0 ;0
L 1.82281004 -2.08463002 1.8229 -2.0851 0 P 0 ;0
L 1.8229 -2.0851 1.82293002 -2.08533996 0 P 0 ;0
L 1.82293002 -2.08533996 1.82293996 -2.08558996 0 P 0 ;0
L 1.82293996 -2.08558996 1.82291998 -2.08583996 0 P 0 ;0
L 1.82291998 -2.08583996 1.82288002 -2.08608002 0 P 0 ;0
L 1.82288002 -2.08608002 1.82283002 -2.08631998 0 P 0 ;0
L 1.82283002 -2.08631998 1.82275 -2.08656004 0 P 0 ;0
L 1.82275 -2.08656004 1.82265 -2.08678996 0 P 0 ;0
L 1.82265 -2.08678996 1.82253996 -2.087 0 P 0 ;0
L 1.82253996 -2.087 1.8224 -2.08721004 0 P 0 ;0
L 1.8224 -2.08721004 1.82225 -2.08741004 0 P 0 ;0
L 1.82225 -2.08741004 1.82208996 -2.08758996 0 P 0 ;0
L 1.82208996 -2.08758996 1.8216 -2.08803996 0 P 0 ;0
L 1.8216 -2.08803996 1.82106998 -2.08845 0 P 0 ;0
L 1.82106998 -2.08845 1.82051004 -2.08881004 0 P 0 ;0
L 1.82051004 -2.08881004 1.81991998 -2.08911998 0 P 0 ;0
L 1.81991998 -2.08911998 1.81931004 -2.08936998 0 P 0 ;0
L 1.81931004 -2.08936998 1.81868002 -2.08958002 0 P 0 ;0
L 1.81868002 -2.08958002 1.81803002 -2.08973002 0 P 0 ;0
L 1.81803002 -2.08973002 1.81736004 -2.08981998 0 P 0 ;0
L 1.81736004 -2.08981998 1.81293002 -2.09001998 0 P 0 ;0
L 1.81293002 -2.09001998 1.80846998 -2.08986004 0 P 0 ;0
L 1.80846998 -2.08986004 1.80256998 -2.08923002 0 P 0 ;0
L 1.80256998 -2.08923002 1.79668002 -2.08818996 0 P 0 ;0
L 1.79668002 -2.08818996 1.78223002 -2.08458002 0 P 0 ;0
L 1.78223002 -2.08458002 1.77788996 -2.08338002 0 P 0 ;0
L 1.77788996 -2.08338002 1.77415 -2.08246004 0 P 0 ;0
L 1.77415 -2.08246004 1.77095 -2.08175 0 P 0 ;0
L 1.77095 -2.08175 1.7709 -2.08173996 0 P 0 ;0
L 1.7709 -2.08173996 1.77076998 -2.08173996 0 P 0 ;0
L 1.77076998 -2.08173996 1.77068996 -2.08176004 0 P 0 ;0
L 1.77068996 -2.08176004 1.77053002 -2.08183996 0 P 0 ;0
L 1.77053002 -2.08183996 1.77043002 -2.08193996 0 P 0 ;0
L 1.77043002 -2.08193996 1.77036998 -2.08201998 0 P 0 ;0
L 1.77036998 -2.08201998 1.77031998 -2.08211998 0 P 0 ;0
L 1.77031998 -2.08211998 1.7703 -2.08216998 0 P 0 ;0
L 1.7703 -2.08216998 1.77028996 -2.08223002 0 P 0 ;0
L 1.77028996 -2.08223002 1.77028002 -2.08228002 0 P 0 ;0
L 1.77028002 -2.08228002 1.77028002 -2.08238996 0 P 0 ;0
L 1.77028002 -2.08238996 1.77056998 -2.08838996 0 P 0 ;0
L 1.77056998 -2.08838996 1.77096004 -2.09526004 0 P 0 ;0
L 1.77096004 -2.09526004 1.77153996 -2.1033 0 P 0 ;0
L 1.77153996 -2.1033 1.77236004 -2.11291004 0 P 0 ;0
L 1.77236004 -2.11291004 1.77311004 -2.1194 0 P 0 ;0
L 1.77311004 -2.1194 1.77383002 -2.12398002 0 P 0 ;0
L 1.77383002 -2.12398002 1.77386004 -2.12411004 0 P 0 ;0
L 1.77386004 -2.12411004 1.7739 -2.12423002 0 P 0 ;0
L 1.7739 -2.12423002 1.77395 -2.12436004 0 P 0 ;0
L 1.77395 -2.12436004 1.77401004 -2.12448002 0 P 0 ;0
L 1.77401004 -2.12448002 1.77408002 -2.12458996 0 P 0 ;0
L 1.77408002 -2.12458996 1.77416004 -2.1247 0 P 0 ;0
L 1.77416004 -2.1247 1.77425 -2.1248 0 P 0 ;0
L 1.77425 -2.1248 1.77435 -2.12488996 0 P 0 ;0
L 1.77435 -2.12488996 1.77445 -2.12496998 0 P 0 ;0
L 1.77445 -2.12496998 1.77456998 -2.12505 0 P 0 ;0
L 1.77456998 -2.12505 1.77571004 -2.12568996 0 P 0 ;0
L 1.77571004 -2.12568996 1.7769 -2.12623996 0 P 0 ;0
L 1.7769 -2.12623996 1.77813002 -2.12668996 0 P 0 ;0
L 1.77813002 -2.12668996 1.7794 -2.12703996 0 P 0 ;0
L 1.7794 -2.12703996 1.78068996 -2.12728996 0 P 0 ;0
L 1.78068996 -2.12728996 1.79791998 -2.12951004 0 P 0 ;0
L 1.79791998 -2.12951004 1.81536004 -2.13106004 0 P 0 ;0
L 1.81536004 -2.13106004 1.82125 -2.13123996 0 P 0 ;0
L 1.82125 -2.13123996 1.82716004 -2.13098996 0 P 0 ;0
L 1.82716004 -2.13098996 1.83583996 -2.12998002 0 P 0 ;0
L 1.83583996 -2.12998002 1.84445 -2.12836004 0 P 0 ;0
L 1.84445 -2.12836004 1.84911998 -2.12711004 0 P 0 ;0
L 1.84911998 -2.12711004 1.85366004 -2.12548002 0 P 0 ;0
L 1.85366004 -2.12548002 1.85806998 -2.12348002 0 P 0 ;0
L 1.85806998 -2.12348002 1.86078996 -2.12196998 0 P 0 ;0
L 1.86078996 -2.12196998 1.8634 -2.12026998 0 P 0 ;0
L 1.8634 -2.12026998 1.86586998 -2.11836998 0 P 0 ;0
L 1.86586998 -2.11836998 1.86821004 -2.11628002 0 P 0 ;0
L 1.86821004 -2.11628002 1.87026004 -2.11413002 0 P 0 ;0
L 1.87026004 -2.11413002 1.8721 -2.11181998 0 P 0 ;0
L 1.8721 -2.11181998 1.87375 -2.10936004 0 P 0 ;0
L 1.87375 -2.10936004 1.87516998 -2.10673996 0 P 0 ;0
L 1.87516998 -2.10673996 1.87605 -2.10483996 0 P 0 ;0
L 1.87605 -2.10483996 1.87683996 -2.10291004 0 P 0 ;0
L 1.87683996 -2.10291004 1.8772 -2.10188002 0 P 0 ;0
L 1.8772 -2.10188002 1.87748996 -2.10083002 0 P 0 ;0
L 1.87748996 -2.10083002 1.87771004 -2.09976998 0 P 0 ;0
L 1.87771004 -2.09976998 1.87798002 -2.09788996 0 P 0 ;0
L 1.87798002 -2.09788996 1.87811998 -2.09601004 0 P 0 ;0
L 1.87811998 -2.09601004 1.87821004 -2.08966998 0 P 0 ;0
L 1.87821004 -2.08966998 1.8781 -2.08353996 0 P 0 ;0
L 1.8781 -2.08353996 1.87798002 -2.08166004 0 P 0 ;0
L 1.87798002 -2.08166004 1.87773002 -2.07976998 0 P 0 ;0
L 1.87773002 -2.07976998 1.87753002 -2.07873996 0 P 0 ;0
L 1.87753002 -2.07873996 1.87726998 -2.07773996 0 P 0 ;0
L 1.87726998 -2.07773996 1.87695 -2.07673996 0 P 0 ;0
L 1.87695 -2.07673996 1.87628996 -2.07505 0 P 0 ;0
L 1.87628996 -2.07505 1.87553002 -2.07338002 0 P 0 ;0
L 1.87553002 -2.07338002 1.87441004 -2.07133996 0 P 0 ;0
L 1.87441004 -2.07133996 1.87313996 -2.06938002 0 P 0 ;0
L 1.87313996 -2.06938002 1.87171004 -2.06751004 0 P 0 ;0
L 1.87171004 -2.06751004 1.8688 -2.06416004 0 P 0 ;0
L 1.8688 -2.06416004 1.86566998 -2.06095 0 P 0 ;0
L 1.86566998 -2.06095 1.86181998 -2.05741998 0 P 0 ;0
L 1.86181998 -2.05741998 1.85778002 -2.05406998 0 P 0 ;0
L 1.85778002 -2.05406998 1.84833996 -2.04715 0 P 0 ;0
L 1.84833996 -2.04715 1.83913996 -2.0407 0 P 0 ;0
L 1.83913996 -2.0407 1.83686004 -2.0389 0 P 0 ;0
L 1.83686004 -2.0389 1.83471998 -2.03691998 0 P 0 ;0
L 1.83471998 -2.03691998 1.83428002 -2.03643002 0 P 0 ;0
L 1.83428002 -2.03643002 1.83386998 -2.0359 0 P 0 ;0
L 1.83386998 -2.0359 1.83351004 -2.03535 0 P 0 ;0
L 1.83351004 -2.03535 1.83318996 -2.03476004 0 P 0 ;0
L 1.83318996 -2.03476004 1.83291998 -2.03415 0 P 0 ;0
L 1.83291998 -2.03415 1.83283996 -2.03393996 0 P 0 ;0
L 1.83283996 -2.03393996 1.83278002 -2.03371004 0 P 0 ;0
L 1.83278002 -2.03371004 1.83273002 -2.03348996 0 P 0 ;0
L 1.83273002 -2.03348996 1.83271004 -2.03326004 0 P 0 ;0
L 1.83271004 -2.03326004 1.8327 -2.03303002 0 P 0 ;0
L 1.8327 -2.03303002 1.83271004 -2.0328 0 P 0 ;0
L 1.83271004 -2.0328 1.83275 -2.03258002 0 P 0 ;0
L 1.83275 -2.03258002 1.83278996 -2.03235 0 P 0 ;0
L 1.83278996 -2.03235 1.83286004 -2.03213002 0 P 0 ;0
L 1.83286004 -2.03213002 1.83293996 -2.03191998 0 P 0 ;0
L 1.83293996 -2.03191998 1.83305 -2.03171004 0 P 0 ;0
L 1.83305 -2.03171004 1.83325 -2.03135 0 P 0 ;0
L 1.83325 -2.03135 1.83348996 -2.03101998 0 P 0 ;0
L 1.83348996 -2.03101998 1.83375 -2.03071004 0 P 0 ;0
L 1.83375 -2.03071004 1.83403002 -2.03041004 0 P 0 ;0
L 1.83403002 -2.03041004 1.83433996 -2.03015 0 P 0 ;0
L 1.83433996 -2.03015 1.83466998 -2.02991004 0 P 0 ;0
L 1.83466998 -2.02991004 1.83501998 -2.02968996 0 P 0 ;0
L 1.83501998 -2.02968996 1.83538002 -2.02951004 0 P 0 ;0
L 1.83538002 -2.02951004 1.83576004 -2.02936004 0 P 0 ;0
L 1.83576004 -2.02936004 1.83615 -2.02923996 0 P 0 ;0
L 1.83615 -2.02923996 1.83655 -2.02915 0 P 0 ;0
L 1.83655 -2.02915 1.8392 -2.02873996 0 P 0 ;0
L 1.8392 -2.02873996 1.84188002 -2.0285 0 P 0 ;0
L 1.84188002 -2.0285 1.84458002 -2.02841004 0 P 0 ;0
L 1.84458002 -2.02841004 1.84993996 -2.02858002 0 P 0 ;0
L 1.84993996 -2.02858002 1.85526998 -2.02916004 0 P 0 ;0
L 1.85526998 -2.02916004 1.86155 -2.03023002 0 P 0 ;0
L 1.86155 -2.03023002 1.86778002 -2.03158002 0 P 0 ;0
L 1.86778002 -2.03158002 1.8713 -2.03238996 0 P 0 ;0
L 1.8713 -2.03238996 1.87428996 -2.03303002 0 P 0 ;0
L 1.87428996 -2.03303002 1.8769 -2.03356004 0 P 0 ;0
L 1.8769 -2.03356004 1.87691998 -2.03356998 0 P 0 ;0
L 1.87691998 -2.03356998 1.87696004 -2.03356998 0 P 0 ;0
L 1.87696004 -2.03356998 1.87696998 -2.03356004 0 P 0 ;0
L 1.87696998 -2.03356004 1.87701004 -2.03356004 0 P 0 ;0
L 1.87701004 -2.03356004 1.87703996 -2.03353996 0 P 0 ;0
L 1.87703996 -2.03353996 1.87706004 -2.03353002 0 P 0 ;0
L 1.87706004 -2.03353002 1.87706998 -2.03351998 0 P 0 ;0
L 1.87706998 -2.03351998 1.87708996 -2.03351004 0 P 0 ;0
L 1.87708996 -2.03351004 1.8771 -2.03348996 0 P 0 ;0
L 1.8771 -2.03348996 1.87711004 -2.03348002 0 P 0 ;0
L 1.87711004 -2.03348002 1.87721998 -2.0333 0 P 0 ;0
L 1.87721998 -2.0333 1.87731998 -2.0331 0 P 0 ;0
L 1.87731998 -2.0331 1.8774 -2.0329 0 P 0 ;0
L 1.8774 -2.0329 1.87746004 -2.03268996 0 P 0 ;0
L 1.87746004 -2.03268996 1.87751004 -2.03248002 0 P 0 ;0
L 1.87751004 -2.03248002 1.87753002 -2.03226998 0 P 0 ;0
L 1.87753002 -2.03226998 1.87753996 -2.03205 0 P 0 ;0
L 1.87753996 -2.03205 1.87753002 -2.03183002 0 P 0 ;0
L 1.87753002 -2.03183002 1.87565 -2.01323996 0 P 0 ;0
L 1.87565 -2.01323996 1.87371004 -1.99451998 0 P 0 ;0
L 1.87371004 -1.99451998 1.8737 -1.99438996 0 P 0 ;0
L 1.8737 -1.99438996 1.87366998 -1.99426998 0 P 0 ;0
L 1.87366998 -1.99426998 1.87363002 -1.99415 0 P 0 ;0
L 1.87363002 -1.99415 1.87358002 -1.99403002 0 P 0 ;0
L 1.87358002 -1.99403002 1.87351998 -1.99391004 0 P 0 ;0
L 1.87351998 -1.99391004 1.87346004 -1.9938 0 P 0 ;0
L 1.87346004 -1.9938 1.87338002 -1.9937 0 P 0 ;0
L 1.87338002 -1.9937 1.87328996 -1.9936 0 P 0 ;0
L 1.87328996 -1.9936 1.8732 -1.99351004 0 P 0 ;0
L 1.8732 -1.99351004 1.8731 -1.99343002 0 P 0 ;0
L 1.8731 -1.99343002 1.87298996 -1.99335 0 P 0 ;0
L 1.87298996 -1.99335 1.87248002 -1.99305 0 P 0 ;0
L 1.87248002 -1.99305 1.87193996 -1.99278002 0 P 0 ;0
L 1.87193996 -1.99278002 1.87136998 -1.99256998 0 P 0 ;0
L 1.87136998 -1.99256998 1.87078996 -1.99241004 0 P 0 ;0
L 1.87078996 -1.99241004 1.8702 -1.9923 0 P 0 ;0
L 1.8702 -1.9923 1.85876004 -1.99076004 0 P 0 ;0
L 1.85876004 -1.99076004 1.84691998 -1.98943002 0 P 0 ;0
L 1.84691998 -1.98943002 1.83693002 -1.98876004 0 P 0 ;0
L 1.83693002 -1.98876004 1.8318 -1.98863002 0 P 0 ;0
L 1.8318 -1.98863002 1.82623002 -1.98866998 0 P 0 ;0
L 1.82623002 -1.98866998 1.82106004 -1.98883996 0 P 0 ;0
L 1.82106004 -1.98883996 1.81726998 -1.98915 0 P 0 ;0
L 1.78061004 -2.12523996 1.84838002 -2.12523996 0 P 0 ;0
L 1.77733002 -2.12423996 1.85121004 -2.12423996 0 P 0 ;0
L 1.77573996 -2.12323996 1.85376998 -2.12323996 0 P 0 ;0
L 1.77558002 -2.12223996 1.85596998 -2.12223996 0 P 0 ;0
L 1.77541998 -2.12123996 1.85798996 -2.12123996 0 P 0 ;0
L 1.77526998 -2.12023996 1.85978996 -2.12023996 0 P 0 ;0
L 1.77511004 -2.11923996 1.86131998 -2.11923996 0 P 0 ;0
L 1.77498996 -2.11823996 1.86276004 -2.11823996 0 P 0 ;0
L 1.77486998 -2.11723996 1.86406998 -2.11723996 0 P 0 ;0
L 1.77475 -2.11623996 1.86526004 -2.11623996 0 P 0 ;0
L 1.77463996 -2.11523996 1.86638002 -2.11523996 0 P 0 ;0
L 1.77451998 -2.11423996 1.8674 -2.11423996 0 P 0 ;0
L 1.77441004 -2.11323996 1.86835 -2.11323996 0 P 0 ;0
L 1.77431004 -2.11223996 1.86921004 -2.11223996 0 P 0 ;0
L 1.77421998 -2.11123996 1.87001004 -2.11123996 0 P 0 ;0
L 1.77413996 -2.11023996 1.87075 -2.11023996 0 P 0 ;0
L 1.77405 -2.10923996 1.87141998 -2.10923996 0 P 0 ;0
L 1.77396998 -2.10823996 1.87208002 -2.10823996 0 P 0 ;0
L 1.77388002 -2.10723996 1.87261998 -2.10723996 0 P 0 ;0
L 1.7738 -2.10623996 1.87316998 -2.10623996 0 P 0 ;0
L 1.77371004 -2.10523996 1.87366004 -2.10523996 0 P 0 ;0
L 1.77363002 -2.10423996 1.87411998 -2.10423996 0 P 0 ;0
L 1.77353996 -2.10323996 1.87453996 -2.10323996 0 P 0 ;0
L 1.77346998 -2.10223996 1.87495 -2.10223996 0 P 0 ;0
L 1.7734 -2.10123996 1.8753 -2.10123996 0 P 0 ;0
L 1.77333002 -2.10023996 1.87556998 -2.10023996 0 P 0 ;0
L 1.77325 -2.09923996 1.87576998 -2.09923996 0 P 0 ;0
L 1.77318002 -2.09823996 1.87591998 -2.09823996 0 P 0 ;0
L 1.77311004 -2.09723996 1.87603002 -2.09723996 0 P 0 ;0
L 1.77303996 -2.09623996 1.8761 -2.09623996 0 P 0 ;0
L 1.77296998 -2.09523996 1.87613002 -2.09523996 0 P 0 ;0
L 1.77291004 -2.09423996 1.87613996 -2.09423996 0 P 0 ;0
L 1.77285 -2.09323996 1.87616004 -2.09323996 0 P 0 ;0
L 1.77278996 -2.09223996 1.87616998 -2.09223996 0 P 0 ;0
L 1.77273002 -2.09123996 1.80256998 -2.09123996 0 P 0 ;0
L 1.77268002 -2.09023996 1.7968 -2.09023996 0 P 0 ;0
L 1.77261998 -2.08923996 1.79263002 -2.08923996 0 P 0 ;0
L 1.77256004 -2.08823996 1.78861998 -2.08823996 0 P 0 ;0
L 1.77251004 -2.08723996 1.7846 -2.08723996 0 P 0 ;0
L 1.77246004 -2.08623996 1.7807 -2.08623996 0 P 0 ;0
L 1.77241998 -2.08523996 1.77705 -2.08523996 0 P 0 ;0
L 1.77236998 -2.08423996 1.77293996 -2.08423996 0 P 0 ;0
L 1.62463996 -2.18195 1.65948996 -2.18195 0 P 0 ;0
L 1.61963996 -2.18095 1.66483002 -2.18095 0 P 0 ;0
L 1.61818002 -1.99795 1.6724 -1.99795 0 P 0 ;0
L 1.61778996 -1.99695 1.67218002 -1.99695 0 P 0 ;0
L 1.6174 -1.99595 1.67196004 -1.99595 0 P 0 ;0
L 1.61701004 -1.99495 1.67173996 -1.99495 0 P 0 ;0
L 1.61391998 -2.15695 1.70026004 -2.15695 0 P 0 ;0
L 1.61386004 -2.15595 1.70088002 -2.15595 0 P 0 ;0
L 1.61381004 -2.15495 1.70151004 -2.15495 0 P 0 ;0
L 1.61375 -2.15395 1.70213996 -2.15395 0 P 0 ;0
L 1.6137 -2.15295 1.70276004 -2.15295 0 P 0 ;0
L 1.61365 -2.15195 1.70338996 -2.15195 0 P 0 ;0
L 1.6136 -2.15095 1.70401004 -2.15095 0 P 0 ;0
L 1.61355 -2.14995 1.70456998 -2.14995 0 P 0 ;0
L 1.61348996 -2.14895 1.70511998 -2.14895 0 P 0 ;0
L 1.61343996 -2.14795 1.61738002 -2.14795 0 P 0 ;0
L 1.55341004 -2.08286998 1.60538002 -2.08286998 0 P 0 ;0
L 1.55286004 -2.08186998 1.60526998 -2.08186998 0 P 0 ;0
L 1.5521 -2.08086998 1.6051 -2.08086998 0 P 0 ;0
L 1.55126998 -2.07986998 1.6049 -2.07986998 0 P 0 ;0
L 1.55033996 -2.07886998 1.60463996 -2.07886998 0 P 0 ;0
L 1.54928996 -2.07786998 1.60433002 -2.07786998 0 P 0 ;0
L 1.54806998 -2.07686998 1.60398996 -2.07686998 0 P 0 ;0
L 1.5467 -2.07586998 1.60356998 -2.07586998 0 P 0 ;0
L 1.54531004 -2.07486998 1.6031 -2.07486998 0 P 0 ;0
L 1.54391004 -2.07386998 1.60258996 -2.07386998 0 P 0 ;0
L 1.54251004 -2.07286998 1.60201004 -2.07286998 0 P 0 ;0
L 1.54111998 -2.07186998 1.60138002 -2.07186998 0 P 0 ;0
L 1.53971998 -2.07086998 1.60068002 -2.07086998 0 P 0 ;0
L 1.53833002 -2.06986998 1.59993002 -2.06986998 0 P 0 ;0
L 1.53693002 -2.06886998 1.59908002 -2.06886998 0 P 0 ;0
L 1.53556004 -2.06786998 1.59821004 -2.06786998 0 P 0 ;0
L 1.53418996 -2.06686998 1.59733996 -2.06686998 0 P 0 ;0
L 1.53281998 -2.06586998 1.59646998 -2.06586998 0 P 0 ;0
L 1.53145 -2.06486998 1.5955 -2.06486998 0 P 0 ;0
L 1.53008002 -2.06386998 1.59453002 -2.06386998 0 P 0 ;0
L 1.52871004 -2.06286998 1.59356004 -2.06286998 0 P 0 ;0
L 1.52733996 -2.06186998 1.59253002 -2.06186998 0 P 0 ;0
L 1.52596998 -2.06086998 1.59145 -2.06086998 0 P 0 ;0
L 1.5246 -2.05986998 1.59038002 -2.05986998 0 P 0 ;0
L 1.52323002 -2.05886998 1.5893 -2.05886998 0 P 0 ;0
L 1.52186004 -2.05786998 1.58813996 -2.05786998 0 P 0 ;0
L 1.52053996 -2.05686998 1.58696004 -2.05686998 0 P 0 ;0
L 1.51935 -2.05586998 1.58576998 -2.05586998 0 P 0 ;0
L 1.51816004 -2.05486998 1.58456998 -2.05486998 0 P 0 ;0
L 1.51706998 -2.05386998 1.58321004 -2.05386998 0 P 0 ;0
L 1.51603996 -2.05286998 1.58185 -2.05286998 0 P 0 ;0
L 1.51501998 -2.05186998 1.58048996 -2.05186998 0 P 0 ;0
L 1.51408996 -2.05086998 1.57913002 -2.05086998 0 P 0 ;0
L 1.5132 -2.04986998 1.57776998 -2.04986998 0 P 0 ;0
L 1.51231998 -2.04886998 1.57641998 -2.04886998 0 P 0 ;0
L 1.51151004 -2.04786998 1.57505 -2.04786998 0 P 0 ;0
L 1.51075 -2.04686998 1.57365 -2.04686998 0 P 0 ;0
L 1.51008002 -2.04586998 1.57223002 -2.04586998 0 P 0 ;0
L 1.50945 -2.04486998 1.57081004 -2.04486998 0 P 0 ;0
L 1.50888002 -2.04386998 1.56938996 -2.04386998 0 P 0 ;0
L 1.50836004 -2.04286998 1.56796998 -2.04286998 0 P 0 ;0
L 1.5079 -2.04186998 1.56655 -2.04186998 0 P 0 ;0
L 1.50748002 -2.04086998 1.56518996 -2.04086998 0 P 0 ;0
L 1.50708996 -2.03986998 1.564 -2.03986998 0 P 0 ;0
L 1.50676004 -2.03886998 1.56296998 -2.03886998 0 P 0 ;0
L 1.50641998 -2.03786998 1.56206004 -2.03786998 0 P 0 ;0
L 1.50616998 -2.03686998 1.56125 -2.03686998 0 P 0 ;0
L 1.50591004 -2.03586998 1.56066998 -2.03586998 0 P 0 ;0
L 1.5057 -2.03486998 1.56031998 -2.03486998 0 P 0 ;0
L 1.50551998 -2.03386998 1.56016004 -2.03386998 0 P 0 ;0
L 1.50533996 -2.03286998 1.56016998 -2.03286998 0 P 0 ;0
L 1.50523996 -2.03186998 1.56036004 -2.03186998 0 P 0 ;0
L 1.50513002 -2.03086998 1.56071998 -2.03086998 0 P 0 ;0
L 1.50506998 -2.02986998 1.56131004 -2.02986998 0 P 0 ;0
L 1.50503996 -2.02886998 1.5622 -2.02886998 0 P 0 ;0
L 1.50501004 -2.02786998 1.56355 -2.02786998 0 P 0 ;0
L 1.50501998 -2.02686998 1.5657 -2.02686998 0 P 0 ;0
L 1.50506998 -2.02586998 1.60378996 -2.02586998 0 P 0 ;0
L 1.50511998 -2.02486998 1.60371004 -2.02486998 0 P 0 ;0
L 1.50521004 -2.02386998 1.60363996 -2.02386998 0 P 0 ;0
L 1.50533996 -2.02286998 1.60356998 -2.02286998 0 P 0 ;0
L 1.50546998 -2.02186998 1.6035 -2.02186998 0 P 0 ;0
L 1.50563996 -2.02086998 1.60343002 -2.02086998 0 P 0 ;0
L 1.50585 -2.01986998 1.60336004 -2.01986998 0 P 0 ;0
L 1.50606004 -2.01886998 1.60328996 -2.01886998 0 P 0 ;0
L 1.50633002 -2.01786998 1.60321998 -2.01786998 0 P 0 ;0
L 1.50661998 -2.01686998 1.60315 -2.01686998 0 P 0 ;0
L 1.50691004 -2.01586998 1.60308002 -2.01586998 0 P 0 ;0
L 1.50726998 -2.01486998 1.603 -2.01486998 0 P 0 ;0
L 1.50766004 -2.01386998 1.60293002 -2.01386998 0 P 0 ;0
L 1.50808996 -2.01286998 1.60285 -2.01286998 0 P 0 ;0
L 1.50856998 -2.01186998 1.60278002 -2.01186998 0 P 0 ;0
L 1.50908996 -2.01086998 1.6027 -2.01086998 0 P 0 ;0
L 1.50966004 -2.00986998 1.60261998 -2.00986998 0 P 0 ;0
L 1.51028996 -2.00886998 1.60255 -2.00886998 0 P 0 ;0
L 1.51096998 -2.00786998 1.60246998 -2.00786998 0 P 0 ;0
L 1.51171998 -2.00686998 1.6024 -2.00686998 0 P 0 ;0
L 1.51253996 -2.00586998 1.60233002 -2.00586998 0 P 0 ;0
L 1.51343996 -2.00486998 1.60225 -2.00486998 0 P 0 ;0
L 1.5144 -2.00386998 1.60218002 -2.00386998 0 P 0 ;0
L 1.51551998 -2.00286998 1.6021 -2.00286998 0 P 0 ;0
L 1.51663996 -2.00186998 1.60203002 -2.00186998 0 P 0 ;0
L 1.51795 -2.00086998 1.60195 -2.00086998 0 P 0 ;0
L 1.51928996 -1.99986998 1.60183996 -1.99986998 0 P 0 ;0
L 1.52086998 -1.99886998 1.60173002 -1.99886998 0 P 0 ;0
L 1.52258996 -1.99786998 1.60156998 -1.99786998 0 P 0 ;0
L 1.52451004 -1.99686998 1.60138996 -1.99686998 0 P 0 ;0
L 1.52686998 -1.99586998 1.60106998 -1.99586998 0 P 0 ;0
L 1.52976004 -1.99486998 1.59943996 -1.99486998 0 P 0 ;0
L 1.53283002 -1.99386998 1.59543002 -1.99386998 0 P 0 ;0
L 1.53678996 -1.99286998 1.59003996 -1.99286998 0 P 0 ;0
L 1.54173996 -1.99186998 1.58073996 -1.99186998 0 P 0 ;0
L 1.55036998 -1.99086998 1.56493002 -1.99086998 0 P 0 ;0
L 1.6036 -2.03086998 1.60413996 -2.03086998 0 P 0 ;0
L 1.59891004 -2.02986998 1.60406998 -2.02986998 0 P 0 ;0
L 1.59435 -2.02886998 1.604 -2.02886998 0 P 0 ;0
L 1.58838996 -2.02786998 1.60393002 -2.02786998 0 P 0 ;0
L 1.57981004 -2.02686998 1.60386004 -2.02686998 0 P 0 ;0
L 1.54575 -1.98923996 1.53931998 -1.99021998 0 P 0 ;0
L 1.53931998 -1.99021998 1.53298996 -1.99171998 0 P 0 ;0
L 1.53298996 -1.99171998 1.52678996 -1.99373996 0 P 0 ;0
L 1.52678996 -1.99373996 1.52376998 -1.995 0 P 0 ;0
L 1.52376998 -1.995 1.52086998 -1.99651004 0 P 0 ;0
L 1.52086998 -1.99651004 1.5181 -1.99826004 0 P 0 ;0
L 1.5181 -1.99826004 1.51548002 -2.00023002 0 P 0 ;0
L 1.51548002 -2.00023002 1.51301004 -2.00243002 0 P 0 ;0
L 1.51301004 -2.00243002 1.51128996 -2.00423002 0 P 0 ;0
L 1.51128996 -2.00423002 1.50971998 -2.00616004 0 P 0 ;0
L 1.50971998 -2.00616004 1.50831004 -2.00821004 0 P 0 ;0
L 1.50831004 -2.00821004 1.50706998 -2.01036998 0 P 0 ;0
L 1.50706998 -2.01036998 1.50598996 -2.01261998 0 P 0 ;0
L 1.50598996 -2.01261998 1.50508996 -2.01496998 0 P 0 ;0
L 1.50508996 -2.01496998 1.5042 -2.01801004 0 P 0 ;0
L 1.5042 -2.01801004 1.50355 -2.02111004 0 P 0 ;0
L 1.50355 -2.02111004 1.50313996 -2.02426004 0 P 0 ;0
L 1.50313996 -2.02426004 1.50298996 -2.02743002 0 P 0 ;0
L 1.50298996 -2.02743002 1.50308996 -2.03063002 0 P 0 ;0
L 1.50308996 -2.03063002 1.50338002 -2.03326998 0 P 0 ;0
L 1.50338002 -2.03326998 1.50385 -2.03588002 0 P 0 ;0
L 1.50385 -2.03588002 1.50451004 -2.03845 0 P 0 ;0
L 1.50451004 -2.03845 1.50535 -2.04096998 0 P 0 ;0
L 1.50535 -2.04096998 1.50633002 -2.0433 0 P 0 ;0
L 1.50633002 -2.0433 1.5075 -2.04553002 0 P 0 ;0
L 1.5075 -2.04553002 1.50883996 -2.04766998 0 P 0 ;0
L 1.50883996 -2.04766998 1.51036998 -2.04968996 0 P 0 ;0
L 1.51036998 -2.04968996 1.51323002 -2.05291998 0 P 0 ;0
L 1.51323002 -2.05291998 1.51631998 -2.05593996 0 P 0 ;0
L 1.51631998 -2.05593996 1.51961998 -2.05871004 0 P 0 ;0
L 1.51961998 -2.05871004 1.53591004 -2.0706 0 P 0 ;0
L 1.53591004 -2.0706 1.54668002 -2.07831004 0 P 0 ;0
L 1.54668002 -2.07831004 1.54793996 -2.07933996 0 P 0 ;0
L 1.54793996 -2.07933996 1.54911998 -2.08046998 0 P 0 ;0
L 1.54911998 -2.08046998 1.55021004 -2.08168002 0 P 0 ;0
L 1.55021004 -2.08168002 1.5512 -2.08298996 0 P 0 ;0
L 1.5512 -2.08298996 1.55136004 -2.08323002 0 P 0 ;0
L 1.55136004 -2.08323002 1.5515 -2.08348002 0 P 0 ;0
L 1.5515 -2.08348002 1.55161004 -2.08373996 0 P 0 ;0
L 1.55161004 -2.08373996 1.5517 -2.08401998 0 P 0 ;0
L 1.5517 -2.08401998 1.55176998 -2.0843 0 P 0 ;0
L 1.55176998 -2.0843 1.55181004 -2.08458002 0 P 0 ;0
L 1.55181004 -2.08458002 1.55183002 -2.08486998 0 P 0 ;0
L 1.55183002 -2.08486998 1.55181998 -2.08516004 0 P 0 ;0
L 1.55181998 -2.08516004 1.55178996 -2.08545 0 P 0 ;0
L 1.55178996 -2.08545 1.55173996 -2.08573002 0 P 0 ;0
L 1.55173996 -2.08573002 1.55166004 -2.086 0 P 0 ;0
L 1.55166004 -2.086 1.55156004 -2.08628002 0 P 0 ;0
L 1.55156004 -2.08628002 1.55136998 -2.08666998 0 P 0 ;0
L 1.55136998 -2.08666998 1.55115 -2.08703996 0 P 0 ;0
L 1.55115 -2.08703996 1.5509 -2.08738996 0 P 0 ;0
L 1.5509 -2.08738996 1.55063002 -2.08771998 0 P 0 ;0
L 1.55063002 -2.08771998 1.55033002 -2.08803002 0 P 0 ;0
L 1.55033002 -2.08803002 1.55 -2.08831004 0 P 0 ;0
L 1.55 -2.08831004 1.54966004 -2.08856004 0 P 0 ;0
L 1.54966004 -2.08856004 1.54928996 -2.08878996 0 P 0 ;0
L 1.54928996 -2.08878996 1.5489 -2.08898996 0 P 0 ;0
L 1.5489 -2.08898996 1.54786004 -2.08941004 0 P 0 ;0
L 1.54786004 -2.08941004 1.54678996 -2.08973996 0 P 0 ;0
L 1.54678996 -2.08973996 1.54568002 -2.08998002 0 P 0 ;0
L 1.54568002 -2.08998002 1.54456998 -2.09011998 0 P 0 ;0
L 1.54456998 -2.09011998 1.54343996 -2.09016998 0 P 0 ;0
L 1.54343996 -2.09016998 1.53906998 -2.09003002 0 P 0 ;0
L 1.53906998 -2.09003002 1.53468002 -2.08961998 0 P 0 ;0
L 1.53468002 -2.08961998 1.52908996 -2.08878996 0 P 0 ;0
L 1.52908996 -2.08878996 1.52351004 -2.08766004 0 P 0 ;0
L 1.52351004 -2.08766004 1.51005 -2.08418996 0 P 0 ;0
L 1.51005 -2.08418996 1.50631004 -2.08318002 0 P 0 ;0
L 1.50631004 -2.08318002 1.50308002 -2.08238996 0 P 0 ;0
L 1.50308002 -2.08238996 1.50033996 -2.08183002 0 P 0 ;0
L 1.50033996 -2.08183002 1.5003 -2.08181998 0 P 0 ;0
L 1.5003 -2.08181998 1.50016004 -2.08181998 0 P 0 ;0
L 1.50016004 -2.08181998 1.50011998 -2.08183002 0 P 0 ;0
L 1.50011998 -2.08183002 1.50006998 -2.08183996 0 P 0 ;0
L 1.50006998 -2.08183996 1.50003002 -2.08186004 0 P 0 ;0
L 1.50003002 -2.08186004 1.49998996 -2.08186998 0 P 0 ;0
L 1.49998996 -2.08186998 1.49995 -2.08188996 0 P 0 ;0
L 1.49995 -2.08188996 1.49991004 -2.08191998 0 P 0 ;0
L 1.49991004 -2.08191998 1.49988002 -2.08195 0 P 0 ;0
L 1.49988002 -2.08195 1.49983996 -2.08198002 0 P 0 ;0
L 1.49983996 -2.08198002 1.4997 -2.08213996 0 P 0 ;0
L 1.4997 -2.08213996 1.49956004 -2.08231998 0 P 0 ;0
L 1.49956004 -2.08231998 1.49943996 -2.0825 0 P 0 ;0
L 1.49943996 -2.0825 1.49933996 -2.0827 0 P 0 ;0
L 1.49933996 -2.0827 1.49925 -2.0829 0 P 0 ;0
L 1.49925 -2.0829 1.49918996 -2.08311004 0 P 0 ;0
L 1.49918996 -2.08311004 1.49913996 -2.08333002 0 P 0 ;0
L 1.49913996 -2.08333002 1.49911004 -2.08355 0 P 0 ;0
L 1.49911004 -2.08355 1.4991 -2.08376998 0 P 0 ;0
L 1.4991 -2.08376998 1.49911004 -2.08398996 0 P 0 ;0
L 1.49911004 -2.08398996 1.50071004 -2.10395 0 P 0 ;0
L 1.50071004 -2.10395 1.5024 -2.12403996 0 P 0 ;0
L 1.5024 -2.12403996 1.50241998 -2.12418002 0 P 0 ;0
L 1.50241998 -2.12418002 1.50246004 -2.12431004 0 P 0 ;0
L 1.50246004 -2.12431004 1.50248996 -2.12445 0 P 0 ;0
L 1.50248996 -2.12445 1.50255 -2.12456998 0 P 0 ;0
L 1.50255 -2.12456998 1.50261004 -2.1247 0 P 0 ;0
L 1.50261004 -2.1247 1.50276998 -2.12491998 0 P 0 ;0
L 1.50276998 -2.12491998 1.50286004 -2.12501998 0 P 0 ;0
L 1.50286004 -2.12501998 1.50296998 -2.12511998 0 P 0 ;0
L 1.50296998 -2.12511998 1.50308002 -2.12521004 0 P 0 ;0
L 1.50308002 -2.12521004 1.50318996 -2.12528002 0 P 0 ;0
L 1.50318996 -2.12528002 1.50331998 -2.12535 0 P 0 ;0
L 1.50331998 -2.12535 1.50343996 -2.1254 0 P 0 ;0
L 1.50343996 -2.1254 1.50391998 -2.12556004 0 P 0 ;0
L 1.50391998 -2.12556004 1.5044 -2.12568996 0 P 0 ;0
L 1.5044 -2.12568996 1.50848002 -2.12648996 0 P 0 ;0
L 1.50848002 -2.12648996 1.51328996 -2.12738002 0 P 0 ;0
L 1.51328996 -2.12738002 1.51873996 -2.12833996 0 P 0 ;0
L 1.51873996 -2.12833996 1.52606004 -2.12945 0 P 0 ;0
L 1.52606004 -2.12945 1.53343996 -2.13023002 0 P 0 ;0
L 1.53343996 -2.13023002 1.54886998 -2.13086998 0 P 0 ;0
L 1.54886998 -2.13086998 1.56305 -2.1303 0 P 0 ;0
L 1.56305 -2.1303 1.56666004 -2.12988996 0 P 0 ;0
L 1.56666004 -2.12988996 1.57023002 -2.12926998 0 P 0 ;0
L 1.57023002 -2.12926998 1.5738 -2.12843002 0 P 0 ;0
L 1.5738 -2.12843002 1.57945 -2.12668996 0 P 0 ;0
L 1.57945 -2.12668996 1.58498002 -2.12456998 0 P 0 ;0
L 1.58498002 -2.12456998 1.58793996 -2.12318002 0 P 0 ;0
L 1.58793996 -2.12318002 1.59078996 -2.12156004 0 P 0 ;0
L 1.59078996 -2.12156004 1.59348996 -2.11971998 0 P 0 ;0
L 1.59348996 -2.11971998 1.59525 -2.11833002 0 P 0 ;0
L 1.59525 -2.11833002 1.5969 -2.11681998 0 P 0 ;0
L 1.5969 -2.11681998 1.59846004 -2.11521004 0 P 0 ;0
L 1.59846004 -2.11521004 1.59991004 -2.11348002 0 P 0 ;0
L 1.59991004 -2.11348002 1.60175 -2.11093996 0 P 0 ;0
L 1.60175 -2.11093996 1.60338002 -2.10826998 0 P 0 ;0
L 1.60338002 -2.10826998 1.60481004 -2.10548002 0 P 0 ;0
L 1.60481004 -2.10548002 1.60573002 -2.10321004 0 P 0 ;0
L 1.60573002 -2.10321004 1.60646004 -2.10088002 0 P 0 ;0
L 1.60646004 -2.10088002 1.60698002 -2.09848996 0 P 0 ;0
L 1.60698002 -2.09848996 1.60756004 -2.09421998 0 P 0 ;0
L 1.60756004 -2.09421998 1.6078 -2.08991004 0 P 0 ;0
L 1.6078 -2.08991004 1.60768996 -2.08565 0 P 0 ;0
L 1.60768996 -2.08565 1.60723002 -2.08141998 0 P 0 ;0
L 1.60723002 -2.08141998 1.60691998 -2.07968002 0 P 0 ;0
L 1.60691998 -2.07968002 1.60646998 -2.07796998 0 P 0 ;0
L 1.60646998 -2.07796998 1.60591998 -2.0763 0 P 0 ;0
L 1.60591998 -2.0763 1.60523002 -2.07466998 0 P 0 ;0
L 1.60523002 -2.07466998 1.60411998 -2.07246998 0 P 0 ;0
L 1.60411998 -2.07246998 1.60281004 -2.07038002 0 P 0 ;0
L 1.60281004 -2.07038002 1.60131998 -2.06838996 0 P 0 ;0
L 1.60131998 -2.06838996 1.59803996 -2.06461998 0 P 0 ;0
L 1.59803996 -2.06461998 1.59455 -2.06101998 0 P 0 ;0
L 1.59455 -2.06101998 1.59031998 -2.05708996 0 P 0 ;0
L 1.59031998 -2.05708996 1.58586004 -2.05333996 0 P 0 ;0
L 1.58586004 -2.05333996 1.57588002 -2.04598996 0 P 0 ;0
L 1.57588002 -2.04598996 1.56685 -2.03963996 0 P 0 ;0
L 1.56685 -2.03963996 1.56578002 -2.03878996 0 P 0 ;0
L 1.56578002 -2.03878996 1.56476998 -2.03786004 0 P 0 ;0
L 1.56476998 -2.03786004 1.56383002 -2.03686998 0 P 0 ;0
L 1.56383002 -2.03686998 1.56295 -2.0358 0 P 0 ;0
L 1.56295 -2.0358 1.56276998 -2.03555 0 P 0 ;0
L 1.56276998 -2.03555 1.56261004 -2.03528002 0 P 0 ;0
L 1.56261004 -2.03528002 1.56246998 -2.035 0 P 0 ;0
L 1.56246998 -2.035 1.56236004 -2.03471998 0 P 0 ;0
L 1.56236004 -2.03471998 1.56226998 -2.03441998 0 P 0 ;0
L 1.56226998 -2.03441998 1.5622 -2.03411998 0 P 0 ;0
L 1.5622 -2.03411998 1.56216004 -2.03381998 0 P 0 ;0
L 1.56216004 -2.03381998 1.56213996 -2.03351004 0 P 0 ;0
L 1.56213996 -2.03351004 1.56215 -2.0332 0 P 0 ;0
L 1.56215 -2.0332 1.56218002 -2.03288996 0 P 0 ;0
L 1.56218002 -2.03288996 1.56225 -2.03253996 0 P 0 ;0
L 1.56225 -2.03253996 1.56233996 -2.03221004 0 P 0 ;0
L 1.56233996 -2.03221004 1.56246004 -2.03186998 0 P 0 ;0
L 1.56246004 -2.03186998 1.56261004 -2.03156004 0 P 0 ;0
L 1.56261004 -2.03156004 1.56278996 -2.03125 0 P 0 ;0
L 1.56278996 -2.03125 1.56298002 -2.03096004 0 P 0 ;0
L 1.56298002 -2.03096004 1.56321004 -2.03068996 0 P 0 ;0
L 1.56321004 -2.03068996 1.56345 -2.03043996 0 P 0 ;0
L 1.56345 -2.03043996 1.56371004 -2.0302 0 P 0 ;0
L 1.56371004 -2.0302 1.56416004 -2.02986004 0 P 0 ;0
L 1.56416004 -2.02986004 1.56463002 -2.02955 0 P 0 ;0
L 1.56463002 -2.02955 1.56511998 -2.02928002 0 P 0 ;0
L 1.56511998 -2.02928002 1.56561998 -2.02903002 0 P 0 ;0
L 1.56561998 -2.02903002 1.56611998 -2.02883996 0 P 0 ;0
L 1.56611998 -2.02883996 1.56663996 -2.02866998 0 P 0 ;0
L 1.56663996 -2.02866998 1.56716004 -2.02855 0 P 0 ;0
L 1.56716004 -2.02855 1.5677 -2.02846998 0 P 0 ;0
L 1.5677 -2.02846998 1.56926998 -2.02835 0 P 0 ;0
L 1.56926998 -2.02835 1.57085 -2.02833996 0 P 0 ;0
L 1.57085 -2.02833996 1.57725 -2.02866998 0 P 0 ;0
L 1.57725 -2.02866998 1.58205 -2.02906004 0 P 0 ;0
L 1.58205 -2.02906004 1.58746998 -2.02975 0 P 0 ;0
L 1.58746998 -2.02975 1.59271004 -2.03056998 0 P 0 ;0
L 1.59271004 -2.03056998 1.59681004 -2.03143002 0 P 0 ;0
L 1.59681004 -2.03143002 1.60016004 -2.03221998 0 P 0 ;0
L 1.60016004 -2.03221998 1.60308002 -2.03281004 0 P 0 ;0
L 1.60308002 -2.03281004 1.60553996 -2.03323996 0 P 0 ;0
L 1.60553996 -2.03323996 1.60568996 -2.03323996 0 P 0 ;0
L 1.60568996 -2.03323996 1.60576998 -2.03321998 0 P 0 ;0
L 1.60576998 -2.03321998 1.60586004 -2.03316004 0 P 0 ;0
L 1.60586004 -2.03316004 1.6059 -2.03313996 0 P 0 ;0
L 1.6059 -2.03313996 1.60591998 -2.03311004 0 P 0 ;0
L 1.60591998 -2.03311004 1.60598996 -2.03303996 0 P 0 ;0
L 1.60598996 -2.03303996 1.60605 -2.03296998 0 P 0 ;0
L 1.60605 -2.03296998 1.6061 -2.03288996 0 P 0 ;0
L 1.6061 -2.03288996 1.60618002 -2.03273002 0 P 0 ;0
L 1.60618002 -2.03273002 1.60621004 -2.03263002 0 P 0 ;0
L 1.60621004 -2.03263002 1.60623002 -2.03253996 0 P 0 ;0
L 1.60623002 -2.03253996 1.60625 -2.03236004 0 P 0 ;0
L 1.60625 -2.03236004 1.60623996 -2.03226004 0 P 0 ;0
L 1.60623996 -2.03226004 1.60508002 -2.01578002 0 P 0 ;0
L 1.60508002 -2.01578002 1.60393996 -2.00068002 0 P 0 ;0
L 1.60393996 -2.00068002 1.60368002 -1.99833996 0 P 0 ;0
L 1.60368002 -1.99833996 1.60326998 -1.99601004 0 P 0 ;0
L 1.60326998 -1.99601004 1.60321004 -1.99576998 0 P 0 ;0
L 1.60321004 -1.99576998 1.60313996 -1.99553002 0 P 0 ;0
L 1.60313996 -1.99553002 1.60303996 -1.9953 0 P 0 ;0
L 1.60303996 -1.9953 1.60293002 -1.99508002 0 P 0 ;0
L 1.60293002 -1.99508002 1.60281004 -1.99486004 0 P 0 ;0
L 1.60281004 -1.99486004 1.60261998 -1.9946 0 P 0 ;0
L 1.60261998 -1.9946 1.60241004 -1.99435 0 P 0 ;0
L 1.60241004 -1.99435 1.60218002 -1.99411998 0 P 0 ;0
L 1.60218002 -1.99411998 1.60191998 -1.99391004 0 P 0 ;0
L 1.60191998 -1.99391004 1.60161004 -1.99368996 0 P 0 ;0
L 1.60161004 -1.99368996 1.60128996 -1.99348996 0 P 0 ;0
L 1.60128996 -1.99348996 1.60095 -1.99331998 0 P 0 ;0
L 1.60095 -1.99331998 1.6006 -1.99316004 0 P 0 ;0
L 1.6006 -1.99316004 1.59966004 -1.99283002 0 P 0 ;0
L 1.59966004 -1.99283002 1.59871004 -1.99255 0 P 0 ;0
L 1.59871004 -1.99255 1.5933 -1.99135 0 P 0 ;0
L 1.5933 -1.99135 1.5878 -1.9905 0 P 0 ;0
L 1.5878 -1.9905 1.57285 -1.98915 0 P 0 ;0
L 1.57285 -1.98915 1.55763996 -1.98861004 0 P 0 ;0
L 1.55763996 -1.98861004 1.55171004 -1.98876004 0 P 0 ;0
L 1.55171004 -1.98876004 1.54575 -1.98923996 0 P 0 ;0
L 1.53011998 -2.12786998 1.5666 -2.12786998 0 P 0 ;0
L 1.52236004 -2.12686998 1.57168002 -2.12686998 0 P 0 ;0
L 1.51621998 -2.12586998 1.5753 -2.12586998 0 P 0 ;0
L 1.51071004 -2.12486998 1.57856004 -2.12486998 0 P 0 ;0
L 1.50553002 -2.12386998 1.58121004 -2.12386998 0 P 0 ;0
L 1.50431004 -2.12286998 1.58381998 -2.12286998 0 P 0 ;0
L 1.50423002 -2.12186998 1.58601998 -2.12186998 0 P 0 ;0
L 1.50413996 -2.12086998 1.58796004 -2.12086998 0 P 0 ;0
L 1.50406004 -2.11986998 1.58971004 -2.11986998 0 P 0 ;0
L 1.50396998 -2.11886998 1.59118002 -2.11886998 0 P 0 ;0
L 1.50388996 -2.11786998 1.5926 -2.11786998 0 P 0 ;0
L 1.50381004 -2.11686998 1.59386004 -2.11686998 0 P 0 ;0
L 1.50371998 -2.11586998 1.59496998 -2.11586998 0 P 0 ;0
L 1.50363996 -2.11486998 1.59601004 -2.11486998 0 P 0 ;0
L 1.50355 -2.11386998 1.59696998 -2.11386998 0 P 0 ;0
L 1.50346998 -2.11286998 1.59781004 -2.11286998 0 P 0 ;0
L 1.50338002 -2.11186998 1.5986 -2.11186998 0 P 0 ;0
L 1.5033 -2.11086998 1.59933002 -2.11086998 0 P 0 ;0
L 1.50321004 -2.10986998 1.60005 -2.10986998 0 P 0 ;0
L 1.50313002 -2.10886998 1.60066998 -2.10886998 0 P 0 ;0
L 1.50305 -2.10786998 1.60128002 -2.10786998 0 P 0 ;0
L 1.50296004 -2.10686998 1.60185 -2.10686998 0 P 0 ;0
L 1.50288002 -2.10586998 1.60236004 -2.10586998 0 P 0 ;0
L 1.50278996 -2.10486998 1.60286998 -2.10486998 0 P 0 ;0
L 1.50271004 -2.10386998 1.6033 -2.10386998 0 P 0 ;0
L 1.50263002 -2.10286998 1.60371004 -2.10286998 0 P 0 ;0
L 1.50255 -2.10186998 1.60405 -2.10186998 0 P 0 ;0
L 1.50246998 -2.10086998 1.60436004 -2.10086998 0 P 0 ;0
L 1.50238996 -2.09986998 1.60463002 -2.09986998 0 P 0 ;0
L 1.50231004 -2.09886998 1.60485 -2.09886998 0 P 0 ;0
L 1.50223002 -2.09786998 1.60505 -2.09786998 0 P 0 ;0
L 1.50215 -2.09686998 1.60518002 -2.09686998 0 P 0 ;0
L 1.50206998 -2.09586998 1.60531998 -2.09586998 0 P 0 ;0
L 1.50198996 -2.09486998 1.60545 -2.09486998 0 P 0 ;0
L 1.50191004 -2.09386998 1.60558002 -2.09386998 0 P 0 ;0
L 1.50183002 -2.09286998 1.60563002 -2.09286998 0 P 0 ;0
L 1.50175 -2.09186998 1.53725 -2.09186998 0 P 0 ;0
L 1.54638996 -2.09186998 1.60568996 -2.09186998 0 P 0 ;0
L 1.50166998 -2.09086998 1.5295 -2.09086998 0 P 0 ;0
L 1.54956998 -2.09086998 1.60573996 -2.09086998 0 P 0 ;0
L 1.50158996 -2.08986998 1.52436004 -2.08986998 0 P 0 ;0
L 1.55125 -2.08986998 1.60578996 -2.08986998 0 P 0 ;0
L 1.50151004 -2.08886998 1.52021004 -2.08886998 0 P 0 ;0
L 1.55226998 -2.08886998 1.60576998 -2.08886998 0 P 0 ;0
L 1.50143002 -2.08786998 1.51633002 -2.08786998 0 P 0 ;0
L 1.55298002 -2.08786998 1.60573996 -2.08786998 0 P 0 ;0
L 1.50133996 -2.08686998 1.51246004 -2.08686998 0 P 0 ;0
L 1.55346998 -2.08686998 1.60571998 -2.08686998 0 P 0 ;0
L 1.50126998 -2.08586998 1.50861998 -2.08586998 0 P 0 ;0
L 1.55375 -2.08586998 1.60568996 -2.08586998 0 P 0 ;0
L 1.50118002 -2.08486998 1.50481004 -2.08486998 0 P 0 ;0
L 1.55383002 -2.08486998 1.60558996 -2.08486998 0 P 0 ;0
L 1.55371998 -2.08386998 1.60548996 -2.08386998 0 P 0 ;0
L 1.54886998 -2.12886998 1.53358996 -2.12823996 0 P 0 ;0
L 1.53358996 -2.12823996 1.52631998 -2.12746998 0 P 0 ;0
L 1.52631998 -2.12746998 1.51906004 -2.12636998 0 P 0 ;0
L 1.51906004 -2.12636998 1.51363002 -2.12541004 0 P 0 ;0
L 1.51363002 -2.12541004 1.50886998 -2.12451998 0 P 0 ;0
L 1.50886998 -2.12451998 1.50483996 -2.12373996 0 P 0 ;0
L 1.50483996 -2.12373996 1.50448996 -2.12365 0 P 0 ;0
L 1.50448996 -2.12365 1.50438002 -2.12361004 0 P 0 ;0
L 1.50438002 -2.12361004 1.5027 -2.10378002 0 P 0 ;0
L 1.5027 -2.10378002 1.50111998 -2.08403002 0 P 0 ;0
L 1.50111998 -2.08403002 1.50263996 -2.08433996 0 P 0 ;0
L 1.50263996 -2.08433996 1.50581004 -2.08511004 0 P 0 ;0
L 1.50581004 -2.08511004 1.50955 -2.08611998 0 P 0 ;0
L 1.50955 -2.08611998 1.52306004 -2.08961004 0 P 0 ;0
L 1.52306004 -2.08961004 1.52311004 -2.08961998 0 P 0 ;0
L 1.52311004 -2.08961998 1.52875 -2.09076004 0 P 0 ;0
L 1.52875 -2.09076004 1.5288 -2.09076004 0 P 0 ;0
L 1.5288 -2.09076004 1.53443996 -2.09161004 0 P 0 ;0
L 1.53443996 -2.09161004 1.53893996 -2.09203002 0 P 0 ;0
L 1.53893996 -2.09203002 1.54346004 -2.09216998 0 P 0 ;0
L 1.54346004 -2.09216998 1.54473996 -2.09211004 0 P 0 ;0
L 1.54473996 -2.09211004 1.54603002 -2.09195 0 P 0 ;0
L 1.54603002 -2.09195 1.54728996 -2.09166998 0 P 0 ;0
L 1.54728996 -2.09166998 1.54853002 -2.09128996 0 P 0 ;0
L 1.54853002 -2.09128996 1.54973002 -2.09081004 0 P 0 ;0
L 1.54973002 -2.09081004 1.55026998 -2.09053996 0 P 0 ;0
L 1.55026998 -2.09053996 1.55076998 -2.09023002 0 P 0 ;0
L 1.55076998 -2.09023002 1.55118002 -2.08991998 0 P 0 ;0
L 1.55118002 -2.08991998 1.55118002 -2.08991004 0 P 0 ;0
L 1.55118002 -2.08991004 1.5512 -2.08991004 0 P 0 ;0
L 1.5512 -2.08991004 1.55125 -2.08986998 0 P 0 ;0
L 1.55125 -2.08986998 1.55131004 -2.08981998 0 P 0 ;0
L 1.55131004 -2.08981998 1.55126998 -2.08978002 0 P 0 ;0
L 1.55126998 -2.08978002 1.55136004 -2.08978002 0 P 0 ;0
L 1.55136004 -2.08978002 1.5517 -2.08948996 0 P 0 ;0
L 1.5517 -2.08948996 1.55206004 -2.08911998 0 P 0 ;0
L 1.55206004 -2.08911998 1.55205 -2.08911004 0 P 0 ;0
L 1.55205 -2.08911004 1.55206004 -2.08911004 0 P 0 ;0
L 1.55206004 -2.08911004 1.55211998 -2.08906004 0 P 0 ;0
L 1.55211998 -2.08906004 1.55248996 -2.08861004 0 P 0 ;0
L 1.55248996 -2.08861004 1.55283996 -2.08811998 0 P 0 ;0
L 1.55283996 -2.08811998 1.55313996 -2.08761004 0 P 0 ;0
L 1.55313996 -2.08761004 1.5534 -2.08706998 0 P 0 ;0
L 1.5534 -2.08706998 1.55356004 -2.08663002 0 P 0 ;0
L 1.55356004 -2.08663002 1.55368996 -2.08618996 0 P 0 ;0
L 1.55368996 -2.08618996 1.55376998 -2.08573996 0 P 0 ;0
L 1.55376998 -2.08573996 1.55378002 -2.08565 0 P 0 ;0
L 1.55378002 -2.08565 1.55381998 -2.08528002 0 P 0 ;0
L 1.55381998 -2.08528002 1.55383002 -2.08481998 0 P 0 ;0
L 1.55383002 -2.08481998 1.5538 -2.08436998 0 P 0 ;0
L 1.5538 -2.08436998 1.55373002 -2.08391998 0 P 0 ;0
L 1.55373002 -2.08391998 1.55361998 -2.08346998 0 P 0 ;0
L 1.55361998 -2.08346998 1.55348002 -2.08303996 0 P 0 ;0
L 1.55348002 -2.08303996 1.5533 -2.08261004 0 P 0 ;0
L 1.5533 -2.08261004 1.55308996 -2.08221004 0 P 0 ;0
L 1.55308996 -2.08221004 1.55283996 -2.08183002 0 P 0 ;0
L 1.55283996 -2.08183002 1.55175 -2.0804 0 P 0 ;0
L 1.55175 -2.0804 1.55055 -2.07908002 0 P 0 ;0
L 1.55055 -2.07908002 1.54926004 -2.07783996 0 P 0 ;0
L 1.54926004 -2.07783996 1.54788996 -2.07671998 0 P 0 ;0
L 1.54788996 -2.07671998 1.53706998 -2.06898002 0 P 0 ;0
L 1.53706998 -2.06898002 1.52085 -2.05713996 0 P 0 ;0
L 1.52085 -2.05713996 1.51766004 -2.05445 0 P 0 ;0
L 1.51766004 -2.05445 1.51468002 -2.05153996 0 P 0 ;0
L 1.51468002 -2.05153996 1.51191998 -2.04841998 0 P 0 ;0
L 1.51191998 -2.04841998 1.51048996 -2.04651998 0 P 0 ;0
L 1.51048996 -2.04651998 1.50923002 -2.04453002 0 P 0 ;0
L 1.50923002 -2.04453002 1.50813996 -2.04245 0 P 0 ;0
L 1.50813996 -2.04245 1.50721998 -2.04026004 0 P 0 ;0
L 1.50721998 -2.04026004 1.50643002 -2.03788002 0 P 0 ;0
L 1.50643002 -2.03788002 1.50581004 -2.03545 0 P 0 ;0
L 1.50581004 -2.03545 1.50536004 -2.03298996 0 P 0 ;0
L 1.50536004 -2.03298996 1.50508996 -2.0305 0 P 0 ;0
L 1.50508996 -2.0305 1.50498996 -2.02745 0 P 0 ;0
L 1.50498996 -2.02745 1.50513996 -2.02443996 0 P 0 ;0
L 1.50513996 -2.02443996 1.50551998 -2.02145 0 P 0 ;0
L 1.50551998 -2.02145 1.50613996 -2.0185 0 P 0 ;0
L 1.50613996 -2.0185 1.50698996 -2.01561004 0 P 0 ;0
L 1.50698996 -2.01561004 1.50783002 -2.01341004 0 P 0 ;0
L 1.50783002 -2.01341004 1.50883002 -2.0113 0 P 0 ;0
L 1.50883002 -2.0113 1.51 -2.00928002 0 P 0 ;0
L 1.51 -2.00928002 1.51133002 -2.00736004 0 P 0 ;0
L 1.51133002 -2.00736004 1.5128 -2.00555 0 P 0 ;0
L 1.5128 -2.00555 1.5144 -2.00386004 0 P 0 ;0
L 1.5144 -2.00386004 1.51675 -2.00176998 0 P 0 ;0
L 1.51675 -2.00176998 1.51923002 -1.9999 0 P 0 ;0
L 1.51923002 -1.9999 1.52186004 -1.99823996 0 P 0 ;0
L 1.52186004 -1.99823996 1.52461998 -1.99681004 0 P 0 ;0
L 1.52461998 -1.99681004 1.52748996 -1.99561004 0 P 0 ;0
L 1.52748996 -1.99561004 1.53353002 -1.99363996 0 P 0 ;0
L 1.53353002 -1.99363996 1.5397 -1.99218002 0 P 0 ;0
L 1.5397 -1.99218002 1.54598002 -1.99123002 0 P 0 ;0
L 1.54598002 -1.99123002 1.55181004 -1.99075 0 P 0 ;0
L 1.55181004 -1.99075 1.55763002 -1.99061998 0 P 0 ;0
L 1.55763002 -1.99061998 1.57273002 -1.99113996 0 P 0 ;0
L 1.57273002 -1.99113996 1.58755 -1.99248996 0 P 0 ;0
L 1.58755 -1.99248996 1.59293002 -1.99331998 0 P 0 ;0
L 1.59293002 -1.99331998 1.59821004 -1.99448996 0 P 0 ;0
L 1.59821004 -1.99448996 1.59905 -1.99473002 0 P 0 ;0
L 1.59905 -1.99473002 1.59986004 -1.99501998 0 P 0 ;0
L 1.59986004 -1.99501998 1.60008002 -1.99511998 0 P 0 ;0
L 1.60008002 -1.99511998 1.6003 -1.99523002 0 P 0 ;0
L 1.6003 -1.99523002 1.60051004 -1.99536004 0 P 0 ;0
L 1.60051004 -1.99536004 1.60071004 -1.9955 0 P 0 ;0
L 1.60071004 -1.9955 1.60083002 -1.99561004 0 P 0 ;0
L 1.60083002 -1.99561004 1.60093996 -1.99571004 0 P 0 ;0
L 1.60093996 -1.99571004 1.60103996 -1.99583002 0 P 0 ;0
L 1.60103996 -1.99583002 1.60111998 -1.99595 0 P 0 ;0
L 1.60111998 -1.99595 1.60116998 -1.99601998 0 P 0 ;0
L 1.60116998 -1.99601998 1.60121004 -1.99611004 0 P 0 ;0
L 1.60121004 -1.99611004 1.60125 -1.99621004 0 P 0 ;0
L 1.60125 -1.99621004 1.60128002 -1.9963 0 P 0 ;0
L 1.60128002 -1.9963 1.60131004 -1.99641004 0 P 0 ;0
L 1.60131004 -1.99641004 1.6017 -1.99861998 0 P 0 ;0
L 1.6017 -1.99861998 1.60195 -2.00086998 0 P 0 ;0
L 1.60195 -2.00086998 1.60308002 -2.01593002 0 P 0 ;0
L 1.60308002 -2.01593002 1.60415 -2.03096998 0 P 0 ;0
L 1.60415 -2.03096998 1.60345 -2.03083996 0 P 0 ;0
L 1.60345 -2.03083996 1.60058996 -2.03026004 0 P 0 ;0
L 1.60058996 -2.03026004 1.59723002 -2.02948002 0 P 0 ;0
L 1.59723002 -2.02948002 1.59721998 -2.02948002 0 P 0 ;0
L 1.59721998 -2.02948002 1.59306998 -2.0286 0 P 0 ;0
L 1.59306998 -2.0286 1.58776004 -2.02776998 0 P 0 ;0
L 1.58776004 -2.02776998 1.58226004 -2.02708002 0 P 0 ;0
L 1.58226004 -2.02708002 1.57738002 -2.02666998 0 P 0 ;0
L 1.57738002 -2.02666998 1.5709 -2.02633996 0 P 0 ;0
L 1.5709 -2.02633996 1.56918996 -2.02635 0 P 0 ;0
L 1.56918996 -2.02635 1.56746998 -2.02648996 0 P 0 ;0
L 1.56746998 -2.02648996 1.56678996 -2.02658996 0 P 0 ;0
L 1.56678996 -2.02658996 1.56611998 -2.02673996 0 P 0 ;0
L 1.56611998 -2.02673996 1.56546004 -2.02695 0 P 0 ;0
L 1.56546004 -2.02695 1.56481998 -2.0272 0 P 0 ;0
L 1.56481998 -2.0272 1.56418996 -2.0275 0 P 0 ;0
L 1.56418996 -2.0275 1.56358002 -2.02785 0 P 0 ;0
L 1.56358002 -2.02785 1.563 -2.02823002 0 P 0 ;0
L 1.563 -2.02823002 1.56245 -2.02865 0 P 0 ;0
L 1.56245 -2.02865 1.56206998 -2.02898996 0 P 0 ;0
L 1.56206998 -2.02898996 1.56171004 -2.02936004 0 P 0 ;0
L 1.56171004 -2.02936004 1.56138002 -2.02976004 0 P 0 ;0
L 1.56138002 -2.02976004 1.56108996 -2.03018996 0 P 0 ;0
L 1.56108996 -2.03018996 1.56083002 -2.03063996 0 P 0 ;0
L 1.56083002 -2.03063996 1.56061998 -2.0311 0 P 0 ;0
L 1.56061998 -2.0311 1.56043996 -2.03158996 0 P 0 ;0
L 1.56043996 -2.03158996 1.5603 -2.03208002 0 P 0 ;0
L 1.5603 -2.03208002 1.5602 -2.0326 0 P 0 ;0
L 1.5602 -2.0326 1.56015 -2.03308002 0 P 0 ;0
L 1.56015 -2.03308002 1.56013996 -2.03353996 0 P 0 ;0
L 1.56013996 -2.03353996 1.56016004 -2.03391004 0 P 0 ;0
L 1.56016004 -2.03391004 1.56048002 -2.03391004 0 P 0 ;0
L 1.56048002 -2.03391004 1.56016004 -2.03393002 0 P 0 ;0
L 1.56016004 -2.03393002 1.56016998 -2.03401004 0 P 0 ;0
L 1.56016998 -2.03401004 1.56023002 -2.03448002 0 P 0 ;0
L 1.56023002 -2.03448002 1.56025 -2.03456004 0 P 0 ;0
L 1.56025 -2.03456004 1.56033002 -2.03493002 0 P 0 ;0
L 1.56033002 -2.03493002 1.56046998 -2.03538002 0 P 0 ;0
L 1.56046998 -2.03538002 1.56063996 -2.03581998 0 P 0 ;0
L 1.56063996 -2.03581998 1.56085 -2.03623996 0 P 0 ;0
L 1.56085 -2.03623996 1.56108996 -2.03663996 0 P 0 ;0
L 1.56108996 -2.03663996 1.56136004 -2.03701998 0 P 0 ;0
L 1.56136004 -2.03701998 1.56233002 -2.03818996 0 P 0 ;0
L 1.56233002 -2.03818996 1.56336998 -2.03928996 0 P 0 ;0
L 1.56336998 -2.03928996 1.56448002 -2.04031004 0 P 0 ;0
L 1.56448002 -2.04031004 1.56566004 -2.04123996 0 P 0 ;0
L 1.56566004 -2.04123996 1.57471004 -2.04761998 0 P 0 ;0
L 1.57471004 -2.04761998 1.58461998 -2.05491004 0 P 0 ;0
L 1.58461998 -2.05491004 1.58898996 -2.05858996 0 P 0 ;0
L 1.58898996 -2.05858996 1.59315 -2.06245 0 P 0 ;0
L 1.59315 -2.06245 1.59656998 -2.06596998 0 P 0 ;0
L 1.59656998 -2.06596998 1.59976004 -2.06965 0 P 0 ;0
L 1.59976004 -2.06965 1.60116004 -2.07151004 0 P 0 ;0
L 1.60116004 -2.07151004 1.60238002 -2.07346004 0 P 0 ;0
L 1.60238002 -2.07346004 1.60341998 -2.0755 0 P 0 ;0
L 1.60341998 -2.0755 1.60403996 -2.077 0 P 0 ;0
L 1.60403996 -2.077 1.60456004 -2.07853996 0 P 0 ;0
L 1.60456004 -2.07853996 1.60496004 -2.08011004 0 P 0 ;0
L 1.60496004 -2.08011004 1.60525 -2.0817 0 P 0 ;0
L 1.60525 -2.0817 1.60568996 -2.08578002 0 P 0 ;0
L 1.60568996 -2.08578002 1.60578996 -2.08988002 0 P 0 ;0
L 1.60578996 -2.08988002 1.60556998 -2.09403002 0 P 0 ;0
L 1.60556998 -2.09403002 1.60501004 -2.09813996 0 P 0 ;0
L 1.60501004 -2.09813996 1.60451998 -2.10036998 0 P 0 ;0
L 1.60451998 -2.10036998 1.60383996 -2.10253996 0 P 0 ;0
L 1.60383996 -2.10253996 1.60298996 -2.10465 0 P 0 ;0
L 1.60298996 -2.10465 1.60163996 -2.1073 0 P 0 ;0
L 1.60163996 -2.1073 1.60008002 -2.10983002 0 P 0 ;0
L 1.60008002 -2.10983002 1.59833002 -2.11225 0 P 0 ;0
L 1.59833002 -2.11225 1.59696998 -2.11386998 0 P 0 ;0
L 1.59696998 -2.11386998 1.59551004 -2.11538996 0 P 0 ;0
L 1.59551004 -2.11538996 1.59395 -2.1168 0 P 0 ;0
L 1.59395 -2.1168 1.59231004 -2.11811004 0 P 0 ;0
L 1.59231004 -2.11811004 1.58973002 -2.11986004 0 P 0 ;0
L 1.58973002 -2.11986004 1.58701998 -2.1214 0 P 0 ;0
L 1.58701998 -2.1214 1.5842 -2.12273002 0 P 0 ;0
L 1.5842 -2.12273002 1.5788 -2.1248 0 P 0 ;0
L 1.5788 -2.1248 1.57326998 -2.12648996 0 P 0 ;0
L 1.57326998 -2.12648996 1.56983002 -2.12731004 0 P 0 ;0
L 1.56983002 -2.12731004 1.56638002 -2.12791004 0 P 0 ;0
L 1.56638002 -2.12791004 1.56288996 -2.1283 0 P 0 ;0
L 1.56288996 -2.1283 1.54886998 -2.12886998 0 P 0 ;0
L 1.35851998 -2.06545 1.47866004 -2.06545 0 P 0 ;0
L 1.35936004 -2.06445 1.47871004 -2.06445 0 P 0 ;0
L 1.36041004 -2.06345 1.47875 -2.06345 0 P 0 ;0
L 1.36163996 -2.06245 1.4788 -2.06245 0 P 0 ;0
L 1.36293996 -2.06145 1.47883996 -2.06145 0 P 0 ;0
L 1.36436004 -2.06045 1.47888996 -2.06045 0 P 0 ;0
L 1.36598002 -2.05945 1.47893996 -2.05945 0 P 0 ;0
L 1.36776004 -2.05845 1.47898996 -2.05845 0 P 0 ;0
L 1.36971004 -2.05745 1.47903002 -2.05745 0 P 0 ;0
L 1.37166004 -2.05645 1.47908002 -2.05645 0 P 0 ;0
L 1.37391004 -2.05545 1.47911998 -2.05545 0 P 0 ;0
L 1.37616998 -2.05445 1.47916998 -2.05445 0 P 0 ;0
L 1.37873002 -2.05345 1.47921004 -2.05345 0 P 0 ;0
L 1.38136004 -2.05245 1.47926004 -2.05245 0 P 0 ;0
L 1.36875 -2.03345 1.37108996 -2.03345 0 P 0 ;0
L 1.36886004 -2.03245 1.37385 -2.03245 0 P 0 ;0
L 1.36896998 -2.03145 1.37678002 -2.03145 0 P 0 ;0
L 1.36908996 -2.03045 1.3797 -2.03045 0 P 0 ;0
L 1.36921004 -2.02945 1.38261998 -2.02945 0 P 0 ;0
L 1.36933002 -2.02845 1.38638996 -2.02845 0 P 0 ;0
L 1.36946004 -2.02745 1.39023996 -2.02745 0 P 0 ;0
L 1.36958002 -2.02645 1.39503002 -2.02645 0 P 0 ;0
L 1.3697 -2.02545 1.40068002 -2.02545 0 P 0 ;0
L 1.36981998 -2.02445 1.41053996 -2.02445 0 P 0 ;0
L 1.36993996 -2.02345 1.47993996 -2.02345 0 P 0 ;0
L 1.37008002 -2.02245 1.47988002 -2.02245 0 P 0 ;0
L 1.37021004 -2.02145 1.47978002 -2.02145 0 P 0 ;0
L 1.37033996 -2.02045 1.47968002 -2.02045 0 P 0 ;0
L 1.37046998 -2.01945 1.47953002 -2.01945 0 P 0 ;0
L 1.3706 -2.01845 1.47936004 -2.01845 0 P 0 ;0
L 1.37073002 -2.01745 1.47918002 -2.01745 0 P 0 ;0
L 1.37086004 -2.01645 1.47893002 -2.01645 0 P 0 ;0
L 1.37098996 -2.01545 1.47868002 -2.01545 0 P 0 ;0
L 1.37113002 -2.01445 1.4784 -2.01445 0 P 0 ;0
L 1.37126998 -2.01345 1.47806004 -2.01345 0 P 0 ;0
L 1.3714 -2.01245 1.47773002 -2.01245 0 P 0 ;0
L 1.37153996 -2.01145 1.47733002 -2.01145 0 P 0 ;0
L 1.37168002 -2.01045 1.47691004 -2.01045 0 P 0 ;0
L 1.37181004 -2.00945 1.47641004 -2.00945 0 P 0 ;0
L 1.37195 -2.00845 1.47588996 -2.00845 0 P 0 ;0
L 1.37208002 -2.00745 1.47528002 -2.00745 0 P 0 ;0
L 1.37221004 -2.00645 1.47463996 -2.00645 0 P 0 ;0
L 1.37235 -2.00545 1.47391998 -2.00545 0 P 0 ;0
L 1.37248996 -2.00445 1.47311004 -2.00445 0 P 0 ;0
L 1.37261998 -2.00345 1.47225 -2.00345 0 P 0 ;0
L 1.37276004 -2.00245 1.47126998 -2.00245 0 P 0 ;0
L 1.3729 -2.00145 1.4702 -2.00145 0 P 0 ;0
L 1.37303002 -2.00045 1.46903996 -2.00045 0 P 0 ;0
L 1.37316998 -1.99945 1.46775 -1.99945 0 P 0 ;0
L 1.3733 -1.99845 1.46625 -1.99845 0 P 0 ;0
L 1.37343996 -1.99745 1.46455 -1.99745 0 P 0 ;0
L 1.37356998 -1.99645 1.46253996 -1.99645 0 P 0 ;0
L 1.37753002 -1.99545 1.46041004 -1.99545 0 P 0 ;0
L 1.38218996 -1.99445 1.45781004 -1.99445 0 P 0 ;0
L 1.42925 -2.08345 1.47785 -2.08345 0 P 0 ;0
L 1.42931998 -2.08245 1.47788996 -2.08245 0 P 0 ;0
L 1.42938002 -2.08145 1.47793002 -2.08145 0 P 0 ;0
L 1.42945 -2.08045 1.47796998 -2.08045 0 P 0 ;0
L 1.42951004 -2.07945 1.47801004 -2.07945 0 P 0 ;0
L 1.42958002 -2.07845 1.47806004 -2.07845 0 P 0 ;0
L 1.42963996 -2.07745 1.4781 -2.07745 0 P 0 ;0
L 1.4297 -2.07645 1.47815 -2.07645 0 P 0 ;0
L 1.42976998 -2.07545 1.4782 -2.07545 0 P 0 ;0
L 1.42983002 -2.07445 1.47825 -2.07445 0 P 0 ;0
L 1.4299 -2.07345 1.47828996 -2.07345 0 P 0 ;0
L 1.42963996 -2.07245 1.47833996 -2.07245 0 P 0 ;0
L 1.42918996 -2.07145 1.47838002 -2.07145 0 P 0 ;0
L 1.38425 -2.05145 1.47931004 -2.05145 0 P 0 ;0
L 1.38731998 -2.05045 1.47933996 -2.05045 0 P 0 ;0
L 1.39088002 -2.04945 1.47938002 -2.04945 0 P 0 ;0
L 1.3947 -2.04845 1.47941004 -2.04845 0 P 0 ;0
L 1.39851004 -2.04745 1.47945 -2.04745 0 P 0 ;0
L 1.40233002 -2.04645 1.47948002 -2.04645 0 P 0 ;0
L 1.40608002 -2.04545 1.47951004 -2.04545 0 P 0 ;0
L 1.40983002 -2.04445 1.47955 -2.04445 0 P 0 ;0
L 1.41306998 -2.04345 1.47958996 -2.04345 0 P 0 ;0
L 1.41591998 -2.04245 1.47961998 -2.04245 0 P 0 ;0
L 1.41876998 -2.04145 1.47965 -2.04145 0 P 0 ;0
L 1.42133996 -2.04045 1.47968996 -2.04045 0 P 0 ;0
L 1.42361998 -2.03945 1.47971998 -2.03945 0 P 0 ;0
L 1.42591004 -2.03845 1.47975 -2.03845 0 P 0 ;0
L 1.42805 -2.03745 1.47978002 -2.03745 0 P 0 ;0
L 1.42936004 -2.03645 1.47981004 -2.03645 0 P 0 ;0
L 1.43003002 -2.03545 1.47983002 -2.03545 0 P 0 ;0
L 1.43081998 -2.03445 1.47986004 -2.03445 0 P 0 ;0
L 1.43121004 -2.03345 1.47988002 -2.03345 0 P 0 ;0
L 1.43141998 -2.03245 1.4799 -2.03245 0 P 0 ;0
L 1.43146998 -2.03145 1.47993002 -2.03145 0 P 0 ;0
L 1.43136004 -2.03045 1.47996004 -2.03045 0 P 0 ;0
L 1.43108002 -2.02945 1.47998002 -2.02945 0 P 0 ;0
L 1.4306 -2.02845 1.48001004 -2.02845 0 P 0 ;0
L 1.42986998 -2.02745 1.48001004 -2.02745 0 P 0 ;0
L 1.42875 -2.02645 1.47998996 -2.02645 0 P 0 ;0
L 1.42658996 -2.02545 1.47996998 -2.02545 0 P 0 ;0
L 1.42203996 -2.02445 1.47996004 -2.02445 0 P 0 ;0
L 1.38748002 -1.99345 1.45483002 -1.99345 0 P 0 ;0
L 1.39331998 -1.99245 1.45108996 -1.99245 0 P 0 ;0
L 1.40051004 -1.99145 1.44503002 -1.99145 0 P 0 ;0
L 1.38096998 -2.12745 1.4051 -2.12745 0 P 0 ;0
L 1.37671004 -2.12645 1.41113996 -2.12645 0 P 0 ;0
L 1.3736 -2.12545 1.41238996 -2.12545 0 P 0 ;0
L 1.37096998 -2.12445 1.41268002 -2.12445 0 P 0 ;0
L 1.36876998 -2.12345 1.41296998 -2.12345 0 P 0 ;0
L 1.36685 -2.12245 1.41326998 -2.12245 0 P 0 ;0
L 1.36516004 -2.12145 1.41356004 -2.12145 0 P 0 ;0
L 1.36366004 -2.12045 1.41385 -2.12045 0 P 0 ;0
L 1.36225 -2.11945 1.41413996 -2.11945 0 P 0 ;0
L 1.361 -2.11845 1.41443002 -2.11845 0 P 0 ;0
L 1.35983002 -2.11745 1.41471998 -2.11745 0 P 0 ;0
L 1.35876004 -2.11645 1.41501004 -2.11645 0 P 0 ;0
L 1.42661998 -2.12445 1.47693002 -2.12445 0 P 0 ;0
L 1.42665 -2.12345 1.47693002 -2.12345 0 P 0 ;0
L 1.4267 -2.12245 1.47693002 -2.12245 0 P 0 ;0
L 1.42675 -2.12145 1.47693002 -2.12145 0 P 0 ;0
L 1.42681004 -2.12045 1.47693002 -2.12045 0 P 0 ;0
L 1.42686998 -2.11945 1.47693002 -2.11945 0 P 0 ;0
L 1.42691998 -2.11845 1.47693002 -2.11845 0 P 0 ;0
L 1.42698996 -2.11745 1.47693002 -2.11745 0 P 0 ;0
L 1.42705 -2.11645 1.47693002 -2.11645 0 P 0 ;0
L 1.42711004 -2.11545 1.47693002 -2.11545 0 P 0 ;0
L 1.42716998 -2.11445 1.47693002 -2.11445 0 P 0 ;0
L 1.42723002 -2.11345 1.47693996 -2.11345 0 P 0 ;0
L 1.4273 -2.11245 1.47695 -2.11245 0 P 0 ;0
L 1.42736998 -2.11145 1.47696004 -2.11145 0 P 0 ;0
L 1.42743996 -2.11045 1.47698002 -2.11045 0 P 0 ;0
L 1.42751004 -2.10945 1.47698996 -2.10945 0 P 0 ;0
L 1.42758002 -2.10845 1.47701004 -2.10845 0 P 0 ;0
L 1.42765 -2.10745 1.47703002 -2.10745 0 P 0 ;0
L 1.42771004 -2.10645 1.47703996 -2.10645 0 P 0 ;0
L 1.42778002 -2.10545 1.47706998 -2.10545 0 P 0 ;0
L 1.42783996 -2.10445 1.4771 -2.10445 0 P 0 ;0
L 1.42791004 -2.10345 1.47713002 -2.10345 0 P 0 ;0
L 1.42798002 -2.10245 1.47716004 -2.10245 0 P 0 ;0
L 1.42805 -2.10145 1.4772 -2.10145 0 P 0 ;0
L 1.42811004 -2.10045 1.47723002 -2.10045 0 P 0 ;0
L 1.40953002 -2.09945 1.41973002 -2.09945 0 P 0 ;0
L 1.42818002 -2.09945 1.47726004 -2.09945 0 P 0 ;0
L 1.41618002 -2.09845 1.41996998 -2.09845 0 P 0 ;0
L 1.42825 -2.09845 1.47728996 -2.09845 0 P 0 ;0
L 1.42831998 -2.09745 1.47733002 -2.09745 0 P 0 ;0
L 1.42838996 -2.09645 1.47736004 -2.09645 0 P 0 ;0
L 1.42846004 -2.09545 1.47738996 -2.09545 0 P 0 ;0
L 1.42851998 -2.09445 1.47741998 -2.09445 0 P 0 ;0
L 1.42858996 -2.09345 1.47746004 -2.09345 0 P 0 ;0
L 1.42866004 -2.09245 1.4775 -2.09245 0 P 0 ;0
L 1.42873002 -2.09145 1.47753996 -2.09145 0 P 0 ;0
L 1.42878996 -2.09045 1.47758002 -2.09045 0 P 0 ;0
L 1.42886004 -2.08945 1.47761998 -2.08945 0 P 0 ;0
L 1.42893002 -2.08845 1.47766004 -2.08845 0 P 0 ;0
L 1.42898996 -2.08745 1.4777 -2.08745 0 P 0 ;0
L 1.42906004 -2.08645 1.47773002 -2.08645 0 P 0 ;0
L 1.42911998 -2.08545 1.47776998 -2.08545 0 P 0 ;0
L 1.42918996 -2.08445 1.47781004 -2.08445 0 P 0 ;0
L 1.61686004 -2.17995 1.66846004 -2.17995 0 P 0 ;0
L 1.61591004 -2.17895 1.67158996 -2.17895 0 P 0 ;0
L 1.61553996 -2.17795 1.67431998 -2.17795 0 P 0 ;0
L 1.61526998 -2.17695 1.67675 -2.17695 0 P 0 ;0
L 1.61508002 -2.17595 1.67903996 -2.17595 0 P 0 ;0
L 1.61496998 -2.17495 1.68108002 -2.17495 0 P 0 ;0
L 1.61491004 -2.17395 1.68295 -2.17395 0 P 0 ;0
L 1.61485 -2.17295 1.68458996 -2.17295 0 P 0 ;0
L 1.61478996 -2.17195 1.6861 -2.17195 0 P 0 ;0
L 1.61473002 -2.17095 1.6875 -2.17095 0 P 0 ;0
L 1.61466998 -2.16995 1.68876998 -2.16995 0 P 0 ;0
L 1.61461004 -2.16895 1.68998002 -2.16895 0 P 0 ;0
L 1.61455 -2.16795 1.69108002 -2.16795 0 P 0 ;0
L 1.61448996 -2.16695 1.69211998 -2.16695 0 P 0 ;0
L 1.61443002 -2.16595 1.69316004 -2.16595 0 P 0 ;0
L 1.61436998 -2.16495 1.69411998 -2.16495 0 P 0 ;0
L 1.61431004 -2.16395 1.69498996 -2.16395 0 P 0 ;0
L 1.61425 -2.16295 1.69586004 -2.16295 0 P 0 ;0
L 1.61418996 -2.16195 1.69673002 -2.16195 0 P 0 ;0
L 1.61413002 -2.16095 1.69746998 -2.16095 0 P 0 ;0
L 1.61406998 -2.15995 1.6982 -2.15995 0 P 0 ;0
L 1.61401998 -2.15895 1.69893996 -2.15895 0 P 0 ;0
L 1.61396998 -2.15795 1.69963002 -2.15795 0 P 0 ;0
L 1.64433002 -2.18295 1.63151004 -2.18271004 0 P 0 ;0
L 1.63151004 -2.18271004 1.62658002 -2.18226998 0 P 0 ;0
L 1.62658002 -2.18226998 1.62168996 -2.18146998 0 P 0 ;0
L 1.62168996 -2.18146998 1.6201 -2.1811 0 P 0 ;0
L 1.6201 -2.1811 1.61853996 -2.18061004 0 P 0 ;0
L 1.61853996 -2.18061004 1.61701004 -2.18001998 0 P 0 ;0
L 1.61701004 -2.18001998 1.61686004 -2.17995 0 P 0 ;0
L 1.61686004 -2.17995 1.61671004 -2.17986998 0 P 0 ;0
L 1.61671004 -2.17986998 1.61656998 -2.17976998 0 P 0 ;0
L 1.61656998 -2.17976998 1.61643996 -2.17966998 0 P 0 ;0
L 1.61643996 -2.17966998 1.61631998 -2.17955 0 P 0 ;0
L 1.61631998 -2.17955 1.61621004 -2.17943002 0 P 0 ;0
L 1.61621004 -2.17943002 1.6161 -2.1793 0 P 0 ;0
L 1.6161 -2.1793 1.61601004 -2.17915 0 P 0 ;0
L 1.61601004 -2.17915 1.61593002 -2.179 0 P 0 ;0
L 1.61593002 -2.179 1.61586004 -2.17885 0 P 0 ;0
L 1.61586004 -2.17885 1.61553002 -2.17791004 0 P 0 ;0
L 1.61553002 -2.17791004 1.61526998 -2.17696004 0 P 0 ;0
L 1.61526998 -2.17696004 1.61508996 -2.17598996 0 P 0 ;0
L 1.61508996 -2.17598996 1.61496998 -2.17496998 0 P 0 ;0
L 1.61496998 -2.17496998 1.61408002 -2.16011004 0 P 0 ;0
L 1.61408002 -2.16011004 1.61341998 -2.14758996 0 P 0 ;0
L 1.61341998 -2.14758996 1.6202 -2.14821004 0 P 0 ;0
L 1.6202 -2.14821004 1.62023002 -2.14821004 0 P 0 ;0
L 1.62023002 -2.14821004 1.63216998 -2.14893996 0 P 0 ;0
L 1.63216998 -2.14893996 1.6349 -2.14893002 0 P 0 ;0
L 1.6349 -2.14893002 1.63761998 -2.14873002 0 P 0 ;0
L 1.63761998 -2.14873002 1.64031998 -2.14835 0 P 0 ;0
L 1.64031998 -2.14835 1.64198996 -2.14798996 0 P 0 ;0
L 1.64198996 -2.14798996 1.64363002 -2.14751998 0 P 0 ;0
L 1.64363002 -2.14751998 1.64523002 -2.14693002 0 P 0 ;0
L 1.64523002 -2.14693002 1.64678996 -2.14623002 0 P 0 ;0
L 1.64678996 -2.14623002 1.64888002 -2.14506998 0 P 0 ;0
L 1.64888002 -2.14506998 1.65086998 -2.14376004 0 P 0 ;0
L 1.65086998 -2.14376004 1.65093996 -2.14371004 0 P 0 ;0
L 1.65093996 -2.14371004 1.65275 -2.14228996 0 P 0 ;0
L 1.65275 -2.14228996 1.6539 -2.14123996 0 P 0 ;0
L 1.6539 -2.14123996 1.65496004 -2.14011004 0 P 0 ;0
L 1.65496004 -2.14011004 1.65591998 -2.13891004 0 P 0 ;0
L 1.65591998 -2.13891004 1.65755 -2.13653996 0 P 0 ;0
L 1.65755 -2.13653996 1.65901998 -2.13415 0 P 0 ;0
L 1.65901998 -2.13415 1.65903002 -2.13413002 0 P 0 ;0
L 1.65903002 -2.13413002 1.66035 -2.13171998 0 P 0 ;0
L 1.66035 -2.13171998 1.66155 -2.12925 0 P 0 ;0
L 1.66155 -2.12925 1.66183996 -2.12851998 0 P 0 ;0
L 1.66183996 -2.12851998 1.66206998 -2.12776004 0 P 0 ;0
L 1.66206998 -2.12776004 1.66223996 -2.12696998 0 P 0 ;0
L 1.66223996 -2.12696998 1.66233996 -2.12618002 0 P 0 ;0
L 1.66233996 -2.12618002 1.66236998 -2.12538996 0 P 0 ;0
L 1.66236998 -2.12538996 1.66233002 -2.12436004 0 P 0 ;0
L 1.66233002 -2.12436004 1.66221004 -2.12335 0 P 0 ;0
L 1.66221004 -2.12335 1.662 -2.12235 0 P 0 ;0
L 1.662 -2.12235 1.66171004 -2.12141004 0 P 0 ;0
L 1.66171004 -2.12141004 1.64438996 -2.07113002 0 P 0 ;0
L 1.64438996 -2.07113002 1.62871998 -2.02606004 0 P 0 ;0
L 1.62871998 -2.02606004 1.62116004 -2.00558996 0 P 0 ;0
L 1.62116004 -2.00558996 1.62116004 -2.00556998 0 P 0 ;0
L 1.62116004 -2.00556998 1.61681004 -1.99443996 0 P 0 ;0
L 1.61681004 -1.99443996 1.67163002 -1.99443996 0 P 0 ;0
L 1.67163002 -1.99443996 1.67301004 -2.00076004 0 P 0 ;0
L 1.67301004 -2.00076004 1.67613002 -2.01341998 0 P 0 ;0
L 1.67613002 -2.01341998 1.68331004 -2.03931998 0 P 0 ;0
L 1.68331004 -2.03931998 1.69153002 -2.06856998 0 P 0 ;0
L 1.69153002 -2.06856998 1.6916 -2.06876004 0 P 0 ;0
L 1.6916 -2.06876004 1.69168996 -2.06896998 0 P 0 ;0
L 1.69168996 -2.06896998 1.69181004 -2.06918002 0 P 0 ;0
L 1.69181004 -2.06918002 1.69193002 -2.06936998 0 P 0 ;0
L 1.69193002 -2.06936998 1.69208002 -2.06956004 0 P 0 ;0
L 1.69208002 -2.06956004 1.69223996 -2.06973002 0 P 0 ;0
L 1.69223996 -2.06973002 1.69241998 -2.06988002 0 P 0 ;0
L 1.69241998 -2.06988002 1.6926 -2.07001998 0 P 0 ;0
L 1.6926 -2.07001998 1.6928 -2.07015 0 P 0 ;0
L 1.6928 -2.07015 1.69301004 -2.07025 0 P 0 ;0
L 1.69301004 -2.07025 1.69323002 -2.07033996 0 P 0 ;0
L 1.69323002 -2.07033996 1.69346004 -2.07041004 0 P 0 ;0
L 1.69346004 -2.07041004 1.69368002 -2.07045 0 P 0 ;0
L 1.69368002 -2.07045 1.69391998 -2.07048002 0 P 0 ;0
L 1.69391998 -2.07048002 1.69413996 -2.07048996 0 P 0 ;0
L 1.69413996 -2.07048996 1.6944 -2.07048002 0 P 0 ;0
L 1.6944 -2.07048002 1.69465 -2.07045 0 P 0 ;0
L 1.69465 -2.07045 1.69488996 -2.07038996 0 P 0 ;0
L 1.69488996 -2.07038996 1.69513996 -2.07031998 0 P 0 ;0
L 1.69513996 -2.07031998 1.69536998 -2.07021998 0 P 0 ;0
L 1.69536998 -2.07021998 1.69558996 -2.0701 0 P 0 ;0
L 1.69558996 -2.0701 1.69581004 -2.06996998 0 P 0 ;0
L 1.69581004 -2.06996998 1.69601004 -2.06981998 0 P 0 ;0
L 1.69601004 -2.06981998 1.6962 -2.06965 0 P 0 ;0
L 1.6962 -2.06965 1.69636998 -2.06946004 0 P 0 ;0
L 1.69636998 -2.06946004 1.69653002 -2.06926004 0 P 0 ;0
L 1.69653002 -2.06926004 1.69666004 -2.06905 0 P 0 ;0
L 1.69666004 -2.06905 1.69678996 -2.06883002 0 P 0 ;0
L 1.69678996 -2.06883002 1.69688002 -2.0686 0 P 0 ;0
L 1.69688002 -2.0686 1.69695 -2.0684 0 P 0 ;0
L 1.69695 -2.0684 1.70426004 -2.04365 0 P 0 ;0
L 1.70426004 -2.04365 1.70426004 -2.04363002 0 P 0 ;0
L 1.70426004 -2.04363002 1.71066998 -2.0213 0 P 0 ;0
L 1.71066998 -2.0213 1.71068002 -2.02126004 0 P 0 ;0
L 1.71068002 -2.02126004 1.71431998 -2.00693996 0 P 0 ;0
L 1.71431998 -2.00693996 1.71706004 -1.99496998 0 P 0 ;0
L 1.71706004 -1.99496998 1.74335 -1.9947 0 P 0 ;0
L 1.74335 -1.9947 1.75403002 -1.99461004 0 P 0 ;0
L 1.75403002 -1.99461004 1.76301004 -1.99465 0 P 0 ;0
L 1.76301004 -1.99465 1.76886004 -1.99471004 0 P 0 ;0
L 1.76886004 -1.99471004 1.76883996 -1.99476004 0 P 0 ;0
L 1.76883996 -1.99476004 1.74021004 -2.06556004 0 P 0 ;0
L 1.74021004 -2.06556004 1.71298002 -2.13276998 0 P 0 ;0
L 1.71298002 -2.13276998 1.70836998 -2.14293996 0 P 0 ;0
L 1.70836998 -2.14293996 1.70413996 -2.15076004 0 P 0 ;0
L 1.70413996 -2.15076004 1.69941998 -2.15828996 0 P 0 ;0
L 1.69941998 -2.15828996 1.6967 -2.16198996 0 P 0 ;0
L 1.6967 -2.16198996 1.6937 -2.16541998 0 P 0 ;0
L 1.6937 -2.16541998 1.69041998 -2.1686 0 P 0 ;0
L 1.69041998 -2.1686 1.68793996 -2.17063002 0 P 0 ;0
L 1.68793996 -2.17063002 1.68535 -2.17248002 0 P 0 ;0
L 1.68535 -2.17248002 1.68263996 -2.17413996 0 P 0 ;0
L 1.68263996 -2.17413996 1.67981004 -2.17561004 0 P 0 ;0
L 1.67981004 -2.17561004 1.67525 -2.17761004 0 P 0 ;0
L 1.67525 -2.17761004 1.6706 -2.17931998 0 P 0 ;0
L 1.6706 -2.17931998 1.66586004 -2.18073002 0 P 0 ;0
L 1.66586004 -2.18073002 1.66141998 -2.1817 0 P 0 ;0
L 1.66141998 -2.1817 1.65691998 -2.18228996 0 P 0 ;0
L 1.65691998 -2.18228996 1.64433002 -2.18295 0 P 0 ;0
L 1.61928996 -2.00628002 1.62683996 -2.02673002 0 P 0 ;0
L 1.62683996 -2.02673002 1.6425 -2.07178002 0 P 0 ;0
L 1.6425 -2.07178002 1.65981004 -2.12201998 0 P 0 ;0
L 1.65981004 -2.12201998 1.66006004 -2.12283996 0 P 0 ;0
L 1.66006004 -2.12283996 1.66023002 -2.12368002 0 P 0 ;0
L 1.66023002 -2.12368002 1.66033996 -2.12451998 0 P 0 ;0
L 1.66033996 -2.12451998 1.66036998 -2.12538002 0 P 0 ;0
L 1.66036998 -2.12538002 1.66033996 -2.12601004 0 P 0 ;0
L 1.66033996 -2.12601004 1.66026998 -2.12663996 0 P 0 ;0
L 1.66026998 -2.12663996 1.66013996 -2.12725 0 P 0 ;0
L 1.66013996 -2.12725 1.65995 -2.12786004 0 P 0 ;0
L 1.65995 -2.12786004 1.65971004 -2.12843996 0 P 0 ;0
L 1.65971004 -2.12843996 1.65856998 -2.1308 0 P 0 ;0
L 1.65856998 -2.1308 1.6573 -2.13313002 0 P 0 ;0
L 1.6573 -2.13313002 1.65586998 -2.13545 0 P 0 ;0
L 1.65586998 -2.13545 1.65431004 -2.13771998 0 P 0 ;0
L 1.65431004 -2.13771998 1.65343996 -2.1388 0 P 0 ;0
L 1.65343996 -2.1388 1.65248996 -2.13981998 0 P 0 ;0
L 1.65248996 -2.13981998 1.65146004 -2.14076004 0 P 0 ;0
L 1.65146004 -2.14076004 1.64971004 -2.14213002 0 P 0 ;0
L 1.64971004 -2.14213002 1.64785 -2.14336004 0 P 0 ;0
L 1.64785 -2.14336004 1.64588996 -2.14443996 0 P 0 ;0
L 1.64588996 -2.14443996 1.64446998 -2.14508002 0 P 0 ;0
L 1.64446998 -2.14508002 1.64301004 -2.14561998 0 P 0 ;0
L 1.64301004 -2.14561998 1.64151004 -2.14605 0 P 0 ;0
L 1.64151004 -2.14605 1.63996998 -2.14636998 0 P 0 ;0
L 1.63996998 -2.14636998 1.63741004 -2.14673996 0 P 0 ;0
L 1.63741004 -2.14673996 1.63483002 -2.14693002 0 P 0 ;0
L 1.63483002 -2.14693002 1.63223002 -2.14693996 0 P 0 ;0
L 1.63223002 -2.14693996 1.62036004 -2.14621998 0 P 0 ;0
L 1.62036004 -2.14621998 1.6113 -2.14538002 0 P 0 ;0
L 1.6113 -2.14538002 1.61208996 -2.16023002 0 P 0 ;0
L 1.61208996 -2.16023002 1.61298002 -2.17515 0 P 0 ;0
L 1.61298002 -2.17515 1.6131 -2.17628002 0 P 0 ;0
L 1.6131 -2.17628002 1.61331998 -2.17741004 0 P 0 ;0
L 1.61331998 -2.17741004 1.61361998 -2.17851004 0 P 0 ;0
L 1.61361998 -2.17851004 1.614 -2.17958996 0 P 0 ;0
L 1.614 -2.17958996 1.61413996 -2.17988996 0 P 0 ;0
L 1.61413996 -2.17988996 1.61428996 -2.18018002 0 P 0 ;0
L 1.61428996 -2.18018002 1.61446998 -2.18045 0 P 0 ;0
L 1.61446998 -2.18045 1.61466998 -2.18071004 0 P 0 ;0
L 1.61466998 -2.18071004 1.61488996 -2.18095 0 P 0 ;0
L 1.61488996 -2.18095 1.61511998 -2.18116998 0 P 0 ;0
L 1.61511998 -2.18116998 1.61538002 -2.18138002 0 P 0 ;0
L 1.61538002 -2.18138002 1.61565 -2.18156004 0 P 0 ;0
L 1.61565 -2.18156004 1.61593002 -2.18173002 0 P 0 ;0
L 1.61593002 -2.18173002 1.61623002 -2.18186004 0 P 0 ;0
L 1.61623002 -2.18186004 1.61788002 -2.1825 0 P 0 ;0
L 1.61788002 -2.1825 1.61956998 -2.18301998 0 P 0 ;0
L 1.61956998 -2.18301998 1.6213 -2.18343002 0 P 0 ;0
L 1.6213 -2.18343002 1.62633002 -2.18426004 0 P 0 ;0
L 1.62633002 -2.18426004 1.6314 -2.18471004 0 P 0 ;0
L 1.6314 -2.18471004 1.64436004 -2.18495 0 P 0 ;0
L 1.64436004 -2.18495 1.65711004 -2.18428002 0 P 0 ;0
L 1.65711004 -2.18428002 1.66176998 -2.18366998 0 P 0 ;0
L 1.66176998 -2.18366998 1.66636004 -2.18266998 0 P 0 ;0
L 1.66636004 -2.18266998 1.67123002 -2.18121004 0 P 0 ;0
L 1.67123002 -2.18121004 1.676 -2.17946998 0 P 0 ;0
L 1.676 -2.17946998 1.68068002 -2.17741998 0 P 0 ;0
L 1.68068002 -2.17741998 1.68361998 -2.17588002 0 P 0 ;0
L 1.68361998 -2.17588002 1.68646004 -2.17415 0 P 0 ;0
L 1.68646004 -2.17415 1.68916004 -2.17221998 0 P 0 ;0
L 1.68916004 -2.17221998 1.69175 -2.17008996 0 P 0 ;0
L 1.69175 -2.17008996 1.69515 -2.1668 0 P 0 ;0
L 1.69515 -2.1668 1.69826004 -2.16323996 0 P 0 ;0
L 1.69826004 -2.16323996 1.70108002 -2.15941998 0 P 0 ;0
L 1.70108002 -2.15941998 1.70586004 -2.15176998 0 P 0 ;0
L 1.70586004 -2.15176998 1.71016004 -2.14383002 0 P 0 ;0
L 1.71016004 -2.14383002 1.71481998 -2.13356004 0 P 0 ;0
L 1.71481998 -2.13356004 1.74206998 -2.06631004 0 P 0 ;0
L 1.74206998 -2.06631004 1.77071004 -1.99548002 0 P 0 ;0
L 1.77071004 -1.99548002 1.77088002 -1.99498996 0 P 0 ;0
L 1.77088002 -1.99498996 1.77101998 -1.99448996 0 P 0 ;0
L 1.77101998 -1.99448996 1.77111998 -1.99398996 0 P 0 ;0
L 1.77111998 -1.99398996 1.77118002 -1.99346998 0 P 0 ;0
L 1.77118002 -1.99346998 1.7712 -1.99295 0 P 0 ;0
L 1.7712 -1.99295 1.7712 -1.99293002 0 P 0 ;0
L 1.7712 -1.99293002 1.77118996 -1.99286998 0 P 0 ;0
L 1.77118996 -1.99286998 1.77118002 -1.99286004 0 P 0 ;0
L 1.77118002 -1.99286004 1.77118002 -1.99283996 0 P 0 ;0
L 1.77118002 -1.99283996 1.77111004 -1.99276998 0 P 0 ;0
L 1.77111004 -1.99276998 1.77106998 -1.99275 0 P 0 ;0
L 1.77106998 -1.99275 1.77106004 -1.99273996 0 P 0 ;0
L 1.77106004 -1.99273996 1.771 -1.99273002 0 P 0 ;0
L 1.771 -1.99273002 1.77098002 -1.99273002 0 P 0 ;0
L 1.77098002 -1.99273002 1.76301004 -1.99265 0 P 0 ;0
L 1.76301004 -1.99265 1.75401998 -1.99261004 0 P 0 ;0
L 1.75401998 -1.99261004 1.74333002 -1.9927 0 P 0 ;0
L 1.74333002 -1.9927 1.71546004 -1.99298996 0 P 0 ;0
L 1.71546004 -1.99298996 1.71236998 -2.00646998 0 P 0 ;0
L 1.71236998 -2.00646998 1.70873996 -2.02078002 0 P 0 ;0
L 1.70873996 -2.02078002 1.70233996 -2.04308002 0 P 0 ;0
L 1.70233996 -2.04308002 1.69505 -2.0678 0 P 0 ;0
L 1.69505 -2.0678 1.69501998 -2.06788002 0 P 0 ;0
L 1.69501998 -2.06788002 1.69498996 -2.06795 0 P 0 ;0
L 1.69498996 -2.06795 1.69495 -2.06801998 0 P 0 ;0
L 1.69495 -2.06801998 1.69485 -2.06816004 0 P 0 ;0
L 1.69485 -2.06816004 1.69478996 -2.06821998 0 P 0 ;0
L 1.69478996 -2.06821998 1.69466998 -2.06831998 0 P 0 ;0
L 1.69466998 -2.06831998 1.69453002 -2.0684 0 P 0 ;0
L 1.69453002 -2.0684 1.69445 -2.06843002 0 P 0 ;0
L 1.69445 -2.06843002 1.69438002 -2.06846004 0 P 0 ;0
L 1.69438002 -2.06846004 1.69428996 -2.06846998 0 P 0 ;0
L 1.69428996 -2.06846998 1.69421004 -2.06848996 0 P 0 ;0
L 1.69421004 -2.06848996 1.69406998 -2.06848996 0 P 0 ;0
L 1.69406998 -2.06848996 1.69395 -2.06846998 0 P 0 ;0
L 1.69395 -2.06846998 1.69383002 -2.06843002 0 P 0 ;0
L 1.69383002 -2.06843002 1.69373002 -2.06836998 0 P 0 ;0
L 1.69373002 -2.06836998 1.69363002 -2.06828996 0 P 0 ;0
L 1.69363002 -2.06828996 1.69358996 -2.06823996 0 P 0 ;0
L 1.69358996 -2.06823996 1.69355 -2.0682 0 P 0 ;0
L 1.69355 -2.0682 1.69351998 -2.06815 0 P 0 ;0
L 1.69351998 -2.06815 1.69346004 -2.06803996 0 P 0 ;0
L 1.69346004 -2.06803996 1.69343996 -2.06798002 0 P 0 ;0
L 1.69343996 -2.06798002 1.68523002 -2.03878002 0 P 0 ;0
L 1.68523002 -2.03878002 1.67806998 -2.01291998 0 P 0 ;0
L 1.67806998 -2.01291998 1.67496004 -2.00031004 0 P 0 ;0
L 1.67496004 -2.00031004 1.67323002 -1.99243996 0 P 0 ;0
L 1.67323002 -1.99243996 1.61388002 -1.99243996 0 P 0 ;0
L 1.61388002 -1.99243996 1.61928996 -2.00628002 0 P 0 ;0
L 1.35018002 -2.08345 1.39488996 -2.08345 0 P 0 ;0
L 1.35026004 -2.08245 1.39586004 -2.08245 0 P 0 ;0
L 1.35041004 -2.08145 1.39708996 -2.08145 0 P 0 ;0
L 1.35058996 -2.08045 1.39853002 -2.08045 0 P 0 ;0
L 1.35083996 -2.07945 1.40031998 -2.07945 0 P 0 ;0
L 1.35116998 -2.07845 1.40271004 -2.07845 0 P 0 ;0
L 1.35158002 -2.07745 1.40561998 -2.07745 0 P 0 ;0
L 1.35203002 -2.07645 1.4092 -2.07645 0 P 0 ;0
L 1.35248002 -2.07545 1.41288996 -2.07545 0 P 0 ;0
L 1.35293002 -2.07445 1.4164 -2.07445 0 P 0 ;0
L 1.35338996 -2.07345 1.41975 -2.07345 0 P 0 ;0
L 1.35393996 -2.07245 1.42293996 -2.07245 0 P 0 ;0
L 1.35448996 -2.07145 1.42606998 -2.07145 0 P 0 ;0
L 1.35505 -2.07045 1.47843002 -2.07045 0 P 0 ;0
L 1.3557 -2.06945 1.47846998 -2.06945 0 P 0 ;0
L 1.35635 -2.06845 1.47851998 -2.06845 0 P 0 ;0
L 1.35701998 -2.06745 1.47856998 -2.06745 0 P 0 ;0
L 1.35776998 -2.06645 1.47861004 -2.06645 0 P 0 ;0
L 1.29346998 -2.00516004 1.33388996 -2.00516004 0 P 0 ;0
L 1.29448996 -2.00416004 1.33385 -2.00416004 0 P 0 ;0
L 1.29551004 -2.00316004 1.33381004 -2.00316004 0 P 0 ;0
L 1.29653996 -2.00216004 1.33376004 -2.00216004 0 P 0 ;0
L 1.29756004 -2.00116004 1.33371004 -2.00116004 0 P 0 ;0
L 1.29861998 -2.00016004 1.33366004 -2.00016004 0 P 0 ;0
L 1.29973002 -1.99916004 1.3336 -1.99916004 0 P 0 ;0
L 1.30101004 -1.99816004 1.33355 -1.99816004 0 P 0 ;0
L 1.30238996 -1.99716004 1.3335 -1.99716004 0 P 0 ;0
L 1.30393996 -1.99616004 1.33345 -1.99616004 0 P 0 ;0
L 1.30571004 -1.99516004 1.33338996 -1.99516004 0 P 0 ;0
L 1.3077 -1.99416004 1.33333002 -1.99416004 0 P 0 ;0
L 1.31001004 -1.99316004 1.33328002 -1.99316004 0 P 0 ;0
L 1.31288002 -1.99216004 1.33321998 -1.99216004 0 P 0 ;0
L 1.31688996 -1.99116004 1.33316004 -1.99116004 0 P 0 ;0
L 1.39798996 -1.98971998 1.39326998 -1.99043002 0 P 0 ;0
L 1.39326998 -1.99043002 1.38806998 -1.9913 0 P 0 ;0
L 1.38806998 -1.9913 1.38316004 -1.9922 0 P 0 ;0
L 1.38316004 -1.9922 1.37946004 -1.99296998 0 P 0 ;0
L 1.37946004 -1.99296998 1.3718 -1.99466998 0 P 0 ;0
L 1.3718 -1.99466998 1.36896004 -2.01553996 0 P 0 ;0
L 1.36896004 -2.01553996 1.36791004 -2.02358996 0 P 0 ;0
L 1.36791004 -2.02358996 1.36708002 -2.03043002 0 P 0 ;0
L 1.36708002 -2.03043002 1.36638996 -2.03646004 0 P 0 ;0
L 1.36638996 -2.03646004 1.36638002 -2.03648996 0 P 0 ;0
L 1.36638002 -2.03648996 1.36638996 -2.03653002 0 P 0 ;0
L 1.36638996 -2.03653002 1.36638996 -2.03656998 0 P 0 ;0
L 1.36638996 -2.03656998 1.3664 -2.03663996 0 P 0 ;0
L 1.3664 -2.03663996 1.36641998 -2.03666998 0 P 0 ;0
L 1.36641998 -2.03666998 1.36643002 -2.03671004 0 P 0 ;0
L 1.36643002 -2.03671004 1.36648996 -2.0368 0 P 0 ;0
L 1.36648996 -2.0368 1.36656004 -2.03686004 0 P 0 ;0
L 1.36656004 -2.03686004 1.3666 -2.03688996 0 P 0 ;0
L 1.3666 -2.03688996 1.36663002 -2.03691004 0 P 0 ;0
L 1.36663002 -2.03691004 1.36666004 -2.03691004 0 P 0 ;0
L 1.36666004 -2.03691004 1.36671004 -2.03693002 0 P 0 ;0
L 1.36671004 -2.03693002 1.36676998 -2.03693002 0 P 0 ;0
L 1.36676998 -2.03693002 1.36685 -2.03691998 0 P 0 ;0
L 1.36685 -2.03691998 1.36895 -2.03628002 0 P 0 ;0
L 1.36895 -2.03628002 1.37143002 -2.03545 0 P 0 ;0
L 1.37143002 -2.03545 1.37428996 -2.03441004 0 P 0 ;0
L 1.37428996 -2.03441004 1.38346004 -2.03126998 0 P 0 ;0
L 1.38346004 -2.03126998 1.39251998 -2.02891998 0 P 0 ;0
L 1.39251998 -2.02891998 1.40156004 -2.02731998 0 P 0 ;0
L 1.40156004 -2.02731998 1.41068002 -2.02643996 0 P 0 ;0
L 1.41068002 -2.02643996 1.41566998 -2.02628002 0 P 0 ;0
L 1.41566998 -2.02628002 1.42066004 -2.02633996 0 P 0 ;0
L 1.42066004 -2.02633996 1.42221004 -2.02646998 0 P 0 ;0
L 1.42221004 -2.02646998 1.42375 -2.02671998 0 P 0 ;0
L 1.42375 -2.02671998 1.42525 -2.0271 0 P 0 ;0
L 1.42525 -2.0271 1.42671998 -2.02761004 0 P 0 ;0
L 1.42671998 -2.02761004 1.42706004 -2.02776004 0 P 0 ;0
L 1.42706004 -2.02776004 1.42738002 -2.02793002 0 P 0 ;0
L 1.42738002 -2.02793002 1.42768002 -2.02813996 0 P 0 ;0
L 1.42768002 -2.02813996 1.42796998 -2.02836004 0 P 0 ;0
L 1.42796998 -2.02836004 1.42823002 -2.02861004 0 P 0 ;0
L 1.42823002 -2.02861004 1.42848002 -2.02888996 0 P 0 ;0
L 1.42848002 -2.02888996 1.4287 -2.02918002 0 P 0 ;0
L 1.4287 -2.02918002 1.42888996 -2.02948996 0 P 0 ;0
L 1.42888996 -2.02948996 1.42906004 -2.02981004 0 P 0 ;0
L 1.42906004 -2.02981004 1.4292 -2.03015 0 P 0 ;0
L 1.4292 -2.03015 1.42931998 -2.0305 0 P 0 ;0
L 1.42931998 -2.0305 1.4294 -2.03086004 0 P 0 ;0
L 1.4294 -2.03086004 1.42945 -2.03121998 0 P 0 ;0
L 1.42945 -2.03121998 1.42946998 -2.03158002 0 P 0 ;0
L 1.42946998 -2.03158002 1.42946004 -2.03195 0 P 0 ;0
L 1.42946004 -2.03195 1.42941998 -2.03231004 0 P 0 ;0
L 1.42941998 -2.03231004 1.42935 -2.03266998 0 P 0 ;0
L 1.42935 -2.03266998 1.42925 -2.03301998 0 P 0 ;0
L 1.42925 -2.03301998 1.42911998 -2.03336004 0 P 0 ;0
L 1.42911998 -2.03336004 1.42896004 -2.03368996 0 P 0 ;0
L 1.42896004 -2.03368996 1.42875 -2.03405 0 P 0 ;0
L 1.42875 -2.03405 1.42851004 -2.03438996 0 P 0 ;0
L 1.42851004 -2.03438996 1.42825 -2.03471004 0 P 0 ;0
L 1.42825 -2.03471004 1.42796004 -2.03501004 0 P 0 ;0
L 1.42796004 -2.03501004 1.42765 -2.03528996 0 P 0 ;0
L 1.42765 -2.03528996 1.42731998 -2.03553996 0 P 0 ;0
L 1.42731998 -2.03553996 1.42696998 -2.03576004 0 P 0 ;0
L 1.42696998 -2.03576004 1.4266 -2.03596004 0 P 0 ;0
L 1.4266 -2.03596004 1.41951004 -2.03906004 0 P 0 ;0
L 1.41951004 -2.03906004 1.4109 -2.04208996 0 P 0 ;0
L 1.4109 -2.04208996 1.40178002 -2.04451998 0 P 0 ;0
L 1.40178002 -2.04451998 1.3878 -2.04818996 0 P 0 ;0
L 1.3878 -2.04818996 1.38176998 -2.05015 0 P 0 ;0
L 1.38176998 -2.05015 1.3758 -2.05243002 0 P 0 ;0
L 1.3758 -2.05243002 1.37086998 -2.0546 0 P 0 ;0
L 1.37086998 -2.0546 1.36603996 -2.05708002 0 P 0 ;0
L 1.36603996 -2.05708002 1.36356004 -2.05856004 0 P 0 ;0
L 1.36356004 -2.05856004 1.36118996 -2.06023002 0 P 0 ;0
L 1.36118996 -2.06023002 1.35895 -2.06206004 0 P 0 ;0
L 1.35895 -2.06206004 1.35805 -2.06291004 0 P 0 ;0
L 1.35805 -2.06291004 1.35721998 -2.06385 0 P 0 ;0
L 1.35721998 -2.06385 1.35518996 -2.06655 0 P 0 ;0
L 1.35518996 -2.06655 1.3532 -2.06961998 0 P 0 ;0
L 1.3532 -2.06961998 1.35156004 -2.07263002 0 P 0 ;0
L 1.35156004 -2.07263002 1.34951004 -2.07718002 0 P 0 ;0
L 1.34951004 -2.07718002 1.34911004 -2.07825 0 P 0 ;0
L 1.34911004 -2.07825 1.34878996 -2.07935 0 P 0 ;0
L 1.34878996 -2.07935 1.34853002 -2.08046998 0 P 0 ;0
L 1.34853002 -2.08046998 1.34825 -2.08238002 0 P 0 ;0
L 1.34825 -2.08238002 1.34811998 -2.08431004 0 P 0 ;0
L 1.34811998 -2.08431004 1.348 -2.09128996 0 P 0 ;0
L 1.348 -2.09128996 1.3481 -2.09761004 0 P 0 ;0
L 1.3481 -2.09761004 1.34823002 -2.09961004 0 P 0 ;0
L 1.34823002 -2.09961004 1.34846998 -2.10161004 0 P 0 ;0
L 1.34846998 -2.10161004 1.34876998 -2.10321998 0 P 0 ;0
L 1.34876998 -2.10321998 1.3492 -2.10478996 0 P 0 ;0
L 1.3492 -2.10478996 1.3498 -2.10648996 0 P 0 ;0
L 1.3498 -2.10648996 1.3505 -2.10815 0 P 0 ;0
L 1.3505 -2.10815 1.35178996 -2.11066004 0 P 0 ;0
L 1.35178996 -2.11066004 1.35328002 -2.11305 0 P 0 ;0
L 1.35328002 -2.11305 1.35496998 -2.1153 0 P 0 ;0
L 1.35496998 -2.1153 1.35685 -2.1174 0 P 0 ;0
L 1.35685 -2.1174 1.35891998 -2.11933996 0 P 0 ;0
L 1.35891998 -2.11933996 1.36126998 -2.12121998 0 P 0 ;0
L 1.36126998 -2.12121998 1.36373996 -2.12293002 0 P 0 ;0
L 1.36373996 -2.12293002 1.36633002 -2.12446004 0 P 0 ;0
L 1.36633002 -2.12446004 1.36901004 -2.1258 0 P 0 ;0
L 1.36901004 -2.1258 1.3718 -2.12695 0 P 0 ;0
L 1.3718 -2.12695 1.37578996 -2.12828002 0 P 0 ;0
L 1.37578996 -2.12828002 1.37986998 -2.12928996 0 P 0 ;0
L 1.37986998 -2.12928996 1.38401998 -2.12998996 0 P 0 ;0
L 1.38401998 -2.12998996 1.3882 -2.13036004 0 P 0 ;0
L 1.3882 -2.13036004 1.39443002 -2.13045 0 P 0 ;0
L 1.39443002 -2.13045 1.40066004 -2.13006998 0 P 0 ;0
L 1.40066004 -2.13006998 1.40685 -2.12923002 0 P 0 ;0
L 1.40685 -2.12923002 1.41371004 -2.12801998 0 P 0 ;0
L 1.41371004 -2.12801998 1.41583002 -2.12081004 0 P 0 ;0
L 1.41583002 -2.12081004 1.41953996 -2.10798996 0 P 0 ;0
L 1.41953996 -2.10798996 1.42135 -2.10126998 0 P 0 ;0
L 1.42135 -2.10126998 1.42236998 -2.097 0 P 0 ;0
L 1.42236998 -2.097 1.42238996 -2.09691004 0 P 0 ;0
L 1.42238996 -2.09691004 1.4224 -2.09681998 0 P 0 ;0
L 1.4224 -2.09681998 1.4224 -2.09673996 0 P 0 ;0
L 1.4224 -2.09673996 1.42238002 -2.09656004 0 P 0 ;0
L 1.42238002 -2.09656004 1.42235 -2.09648002 0 P 0 ;0
L 1.42235 -2.09648002 1.42233002 -2.09638996 0 P 0 ;0
L 1.42233002 -2.09638996 1.42225 -2.09623002 0 P 0 ;0
L 1.42225 -2.09623002 1.4222 -2.09616004 0 P 0 ;0
L 1.4222 -2.09616004 1.42213996 -2.09608996 0 P 0 ;0
L 1.42213996 -2.09608996 1.42208996 -2.09601998 0 P 0 ;0
L 1.42208996 -2.09601998 1.42203996 -2.09598996 0 P 0 ;0
L 1.42203996 -2.09598996 1.42198996 -2.09595 0 P 0 ;0
L 1.42198996 -2.09595 1.42188996 -2.09588996 0 P 0 ;0
L 1.42188996 -2.09588996 1.42183002 -2.09586004 0 P 0 ;0
L 1.42183002 -2.09586004 1.42178002 -2.09585 0 P 0 ;0
L 1.42178002 -2.09585 1.42171998 -2.09583002 0 P 0 ;0
L 1.42171998 -2.09583002 1.42166004 -2.09581998 0 P 0 ;0
L 1.42166004 -2.09581998 1.42153996 -2.09581998 0 P 0 ;0
L 1.42153996 -2.09581998 1.41978002 -2.09591004 0 P 0 ;0
L 1.41978002 -2.09591004 1.41763996 -2.09615 0 P 0 ;0
L 1.41763996 -2.09615 1.41521998 -2.09658002 0 P 0 ;0
L 1.41521998 -2.09658002 1.4107 -2.09733002 0 P 0 ;0
L 1.4107 -2.09733002 1.40613002 -2.09775 0 P 0 ;0
L 1.40613002 -2.09775 1.40481004 -2.09778002 0 P 0 ;0
L 1.40481004 -2.09778002 1.40348996 -2.09771998 0 P 0 ;0
L 1.40348996 -2.09771998 1.40216998 -2.09756004 0 P 0 ;0
L 1.40216998 -2.09756004 1.40086998 -2.0973 0 P 0 ;0
L 1.40086998 -2.0973 1.39958996 -2.09695 0 P 0 ;0
L 1.39958996 -2.09695 1.39895 -2.09671998 0 P 0 ;0
L 1.39895 -2.09671998 1.39831998 -2.09643002 0 P 0 ;0
L 1.39831998 -2.09643002 1.39773002 -2.0961 0 P 0 ;0
L 1.39773002 -2.0961 1.39716004 -2.09571004 0 P 0 ;0
L 1.39716004 -2.09571004 1.39663002 -2.09528002 0 P 0 ;0
L 1.39663002 -2.09528002 1.39613996 -2.0948 0 P 0 ;0
L 1.39613996 -2.0948 1.39568002 -2.09428002 0 P 0 ;0
L 1.39568002 -2.09428002 1.39533996 -2.09381998 0 P 0 ;0
L 1.39533996 -2.09381998 1.39505 -2.09333996 0 P 0 ;0
L 1.39505 -2.09333996 1.39478996 -2.09281998 0 P 0 ;0
L 1.39478996 -2.09281998 1.39456998 -2.09228996 0 P 0 ;0
L 1.39456998 -2.09228996 1.3944 -2.09173996 0 P 0 ;0
L 1.3944 -2.09173996 1.39428002 -2.09118996 0 P 0 ;0
L 1.39428002 -2.09118996 1.39421004 -2.09061998 0 P 0 ;0
L 1.39421004 -2.09061998 1.39418002 -2.09003996 0 P 0 ;0
L 1.39418002 -2.09003996 1.39421004 -2.08943002 0 P 0 ;0
L 1.39421004 -2.08943002 1.39428002 -2.08883002 0 P 0 ;0
L 1.39428002 -2.08883002 1.39441004 -2.08823002 0 P 0 ;0
L 1.39441004 -2.08823002 1.3946 -2.08765 0 P 0 ;0
L 1.3946 -2.08765 1.39483002 -2.08708002 0 P 0 ;0
L 1.39483002 -2.08708002 1.39511004 -2.08653996 0 P 0 ;0
L 1.39511004 -2.08653996 1.39555 -2.08583996 0 P 0 ;0
L 1.39555 -2.08583996 1.39603996 -2.08518002 0 P 0 ;0
L 1.39603996 -2.08518002 1.39658002 -2.08456004 0 P 0 ;0
L 1.39658002 -2.08456004 1.39716004 -2.08396998 0 P 0 ;0
L 1.39716004 -2.08396998 1.39778002 -2.08343002 0 P 0 ;0
L 1.39778002 -2.08343002 1.39878996 -2.08266998 0 P 0 ;0
L 1.39878996 -2.08266998 1.39985 -2.08196998 0 P 0 ;0
L 1.39985 -2.08196998 1.40096004 -2.08135 0 P 0 ;0
L 1.40096004 -2.08135 1.40211998 -2.08081004 0 P 0 ;0
L 1.40211998 -2.08081004 1.40503002 -2.07971004 0 P 0 ;0
L 1.40503002 -2.07971004 1.40801998 -2.07881998 0 P 0 ;0
L 1.40801998 -2.07881998 1.41128996 -2.07796004 0 P 0 ;0
L 1.41128996 -2.07796004 1.41506004 -2.07691998 0 P 0 ;0
L 1.41506004 -2.07691998 1.41871998 -2.07585 0 P 0 ;0
L 1.41871998 -2.07585 1.42165 -2.07495 0 P 0 ;0
L 1.42165 -2.07495 1.42791998 -2.07295 0 P 0 ;0
L 1.42791998 -2.07295 1.42731998 -2.08241004 0 P 0 ;0
L 1.42731998 -2.08241004 1.42701004 -2.08708002 0 P 0 ;0
L 1.42701004 -2.08708002 1.42658002 -2.09353996 0 P 0 ;0
L 1.42658002 -2.09353996 1.4261 -2.10055 0 P 0 ;0
L 1.4261 -2.10055 1.42566998 -2.10706004 0 P 0 ;0
L 1.42566998 -2.10706004 1.42525 -2.11306004 0 P 0 ;0
L 1.42525 -2.11306004 1.42491998 -2.11851998 0 P 0 ;0
L 1.42491998 -2.11851998 1.42466004 -2.1231 0 P 0 ;0
L 1.42466004 -2.1231 1.42461004 -2.12471004 0 P 0 ;0
L 1.42461004 -2.12471004 1.4246 -2.12716004 0 P 0 ;0
L 1.4246 -2.12716004 1.47893002 -2.12716004 0 P 0 ;0
L 1.47893002 -2.12716004 1.47893002 -2.11358002 0 P 0 ;0
L 1.47893002 -2.11358002 1.47905 -2.10616998 0 P 0 ;0
L 1.47905 -2.10616998 1.47943996 -2.09385 0 P 0 ;0
L 1.47943996 -2.09385 1.48 -2.07968996 0 P 0 ;0
L 1.48 -2.07968996 1.48066004 -2.0655 0 P 0 ;0
L 1.48066004 -2.0655 1.4813 -2.05168996 0 P 0 ;0
L 1.4813 -2.05168996 1.48175 -2.03873996 0 P 0 ;0
L 1.48175 -2.03873996 1.48201998 -2.02785 0 P 0 ;0
L 1.48201998 -2.02785 1.48191998 -2.02286004 0 P 0 ;0
L 1.48191998 -2.02286004 1.48165 -2.01995 0 P 0 ;0
L 1.48165 -2.01995 1.48115 -2.01708002 0 P 0 ;0
L 1.48115 -2.01708002 1.48043996 -2.01425 0 P 0 ;0
L 1.48043996 -2.01425 1.47951004 -2.01146998 0 P 0 ;0
L 1.47951004 -2.01146998 1.47866998 -2.00946998 0 P 0 ;0
L 1.47866998 -2.00946998 1.47768002 -2.00753996 0 P 0 ;0
L 1.47768002 -2.00753996 1.47655 -2.00568002 0 P 0 ;0
L 1.47655 -2.00568002 1.47528002 -2.00391998 0 P 0 ;0
L 1.47528002 -2.00391998 1.47388002 -2.00225 0 P 0 ;0
L 1.47388002 -2.00225 1.47228996 -2.00063002 0 P 0 ;0
L 1.47228996 -2.00063002 1.4706 -1.99911998 0 P 0 ;0
L 1.4706 -1.99911998 1.4688 -1.99773002 0 P 0 ;0
L 1.4688 -1.99773002 1.46691004 -1.99648002 0 P 0 ;0
L 1.46691004 -1.99648002 1.46491998 -1.99535 0 P 0 ;0
L 1.46491998 -1.99535 1.46098996 -1.99351004 0 P 0 ;0
L 1.46098996 -1.99351004 1.45693002 -1.99196998 0 P 0 ;0
L 1.45693002 -1.99196998 1.45276004 -1.99076004 0 P 0 ;0
L 1.45276004 -1.99076004 1.44953996 -1.99006004 0 P 0 ;0
L 1.44953996 -1.99006004 1.44628996 -1.98956004 0 P 0 ;0
L 1.44628996 -1.98956004 1.44298002 -1.98923996 0 P 0 ;0
L 1.44298002 -1.98923996 1.42695 -1.98856998 0 P 0 ;0
L 1.42695 -1.98856998 1.41038996 -1.98865 0 P 0 ;0
L 1.41038996 -1.98865 1.4042 -1.98901004 0 P 0 ;0
L 1.4042 -1.98901004 1.39798996 -1.98971998 0 P 0 ;0
L 1.35778996 -2.11545 1.4153 -2.11545 0 P 0 ;0
L 1.35688996 -2.11445 1.41558996 -2.11445 0 P 0 ;0
L 1.35608002 -2.11345 1.41588002 -2.11345 0 P 0 ;0
L 1.35533002 -2.11245 1.41616998 -2.11245 0 P 0 ;0
L 1.35463996 -2.11145 1.41646004 -2.11145 0 P 0 ;0
L 1.35401004 -2.11045 1.41675 -2.11045 0 P 0 ;0
L 1.35341004 -2.10945 1.41703996 -2.10945 0 P 0 ;0
L 1.3529 -2.10845 1.41733002 -2.10845 0 P 0 ;0
L 1.35238002 -2.10745 1.41761998 -2.10745 0 P 0 ;0
L 1.35195 -2.10645 1.41788002 -2.10645 0 P 0 ;0
L 1.35155 -2.10545 1.41816004 -2.10545 0 P 0 ;0
L 1.3512 -2.10445 1.41841998 -2.10445 0 P 0 ;0
L 1.35091004 -2.10345 1.41868996 -2.10345 0 P 0 ;0
L 1.35066004 -2.10245 1.41896004 -2.10245 0 P 0 ;0
L 1.35046998 -2.10145 1.41923002 -2.10145 0 P 0 ;0
L 1.35033996 -2.10045 1.41948996 -2.10045 0 P 0 ;0
L 1.35021998 -2.09945 1.40141004 -2.09945 0 P 0 ;0
L 1.35016004 -2.09845 1.39791004 -2.09845 0 P 0 ;0
L 1.3501 -2.09745 1.39616004 -2.09745 0 P 0 ;0
L 1.35008002 -2.09645 1.39496004 -2.09645 0 P 0 ;0
L 1.35006998 -2.09545 1.39406004 -2.09545 0 P 0 ;0
L 1.35005 -2.09445 1.39338002 -2.09445 0 P 0 ;0
L 1.35003996 -2.09345 1.39288002 -2.09345 0 P 0 ;0
L 1.35001998 -2.09245 1.39253002 -2.09245 0 P 0 ;0
L 1.35001004 -2.09145 1.3923 -2.09145 0 P 0 ;0
L 1.35001998 -2.09045 1.3922 -2.09045 0 P 0 ;0
L 1.35003002 -2.08945 1.3922 -2.08945 0 P 0 ;0
L 1.35005 -2.08845 1.39231998 -2.08845 0 P 0 ;0
L 1.35006998 -2.08745 1.39256004 -2.08745 0 P 0 ;0
L 1.35008002 -2.08645 1.39293002 -2.08645 0 P 0 ;0
L 1.3501 -2.08545 1.39343002 -2.08545 0 P 0 ;0
L 1.35011004 -2.08445 1.39408996 -2.08445 0 P 0 ;0
L 1.39438002 -2.12845 1.3883 -2.12836004 0 P 0 ;0
L 1.3883 -2.12836004 1.38426998 -2.128 0 P 0 ;0
L 1.38426998 -2.128 1.38028002 -2.12733002 0 P 0 ;0
L 1.38028002 -2.12733002 1.37635 -2.12636004 0 P 0 ;0
L 1.37635 -2.12636004 1.37248996 -2.12508002 0 P 0 ;0
L 1.37248996 -2.12508002 1.36983996 -2.12398002 0 P 0 ;0
L 1.36983996 -2.12398002 1.36728996 -2.1227 0 P 0 ;0
L 1.36728996 -2.1227 1.36481998 -2.12123996 0 P 0 ;0
L 1.36481998 -2.12123996 1.36246004 -2.11961004 0 P 0 ;0
L 1.36246004 -2.11961004 1.36023002 -2.11781998 0 P 0 ;0
L 1.36023002 -2.11781998 1.35828996 -2.116 0 P 0 ;0
L 1.35828996 -2.116 1.35651998 -2.11403002 0 P 0 ;0
L 1.35651998 -2.11403002 1.35493002 -2.11191004 0 P 0 ;0
L 1.35493002 -2.11191004 1.35353002 -2.10966998 0 P 0 ;0
L 1.35353002 -2.10966998 1.35231004 -2.10731004 0 P 0 ;0
L 1.35231004 -2.10731004 1.35166998 -2.10576998 0 P 0 ;0
L 1.35166998 -2.10576998 1.35111004 -2.1042 0 P 0 ;0
L 1.35111004 -2.1042 1.35071998 -2.10276004 0 P 0 ;0
L 1.35071998 -2.10276004 1.35045 -2.1013 0 P 0 ;0
L 1.35045 -2.1013 1.35021998 -2.09943002 0 P 0 ;0
L 1.35021998 -2.09943002 1.3501 -2.09753002 0 P 0 ;0
L 1.3501 -2.09753002 1.35001004 -2.09128002 0 P 0 ;0
L 1.35001004 -2.09128002 1.35011998 -2.0844 0 P 0 ;0
L 1.35011998 -2.0844 1.35023996 -2.08258996 0 P 0 ;0
L 1.35023996 -2.08258996 1.3505 -2.08083996 0 P 0 ;0
L 1.3505 -2.08083996 1.35071998 -2.07985 0 P 0 ;0
L 1.35071998 -2.07985 1.35101004 -2.07888002 0 P 0 ;0
L 1.35101004 -2.07888002 1.35136004 -2.07793002 0 P 0 ;0
L 1.35136004 -2.07793002 1.35335 -2.07351998 0 P 0 ;0
L 1.35335 -2.07351998 1.35491998 -2.07065 0 P 0 ;0
L 1.35491998 -2.07065 1.35683002 -2.0677 0 P 0 ;0
L 1.35683002 -2.0677 1.35876998 -2.06511004 0 P 0 ;0
L 1.35876998 -2.06511004 1.35948996 -2.0643 0 P 0 ;0
L 1.35948996 -2.0643 1.36026998 -2.06356004 0 P 0 ;0
L 1.36026998 -2.06356004 1.3624 -2.06181998 0 P 0 ;0
L 1.3624 -2.06181998 1.36465 -2.06023996 0 P 0 ;0
L 1.36465 -2.06023996 1.36701004 -2.05883002 0 P 0 ;0
L 1.36701004 -2.05883002 1.37173002 -2.05641004 0 P 0 ;0
L 1.37173002 -2.05641004 1.37656004 -2.05426998 0 P 0 ;0
L 1.37656004 -2.05426998 1.38243002 -2.05203996 0 P 0 ;0
L 1.38243002 -2.05203996 1.38836004 -2.0501 0 P 0 ;0
L 1.38836004 -2.0501 1.4023 -2.04645 0 P 0 ;0
L 1.4023 -2.04645 1.41148996 -2.044 0 P 0 ;0
L 1.41148996 -2.044 1.42016998 -2.04095 0 P 0 ;0
L 1.42016998 -2.04095 1.42016998 -2.04093996 0 P 0 ;0
L 1.42016998 -2.04093996 1.42021004 -2.04093996 0 P 0 ;0
L 1.42021004 -2.04093996 1.42023996 -2.04093002 0 P 0 ;0
L 1.42023996 -2.04093002 1.42746998 -2.03776004 0 P 0 ;0
L 1.42746998 -2.03776004 1.42753002 -2.03773002 0 P 0 ;0
L 1.42753002 -2.03773002 1.42796998 -2.03748996 0 P 0 ;0
L 1.42796998 -2.03748996 1.42846004 -2.03718996 0 P 0 ;0
L 1.42846004 -2.03718996 1.42891998 -2.03683996 0 P 0 ;0
L 1.42891998 -2.03683996 1.42935 -2.03646004 0 P 0 ;0
L 1.42935 -2.03646004 1.42975 -2.03603996 0 P 0 ;0
L 1.42975 -2.03603996 1.43011004 -2.0356 0 P 0 ;0
L 1.43011004 -2.0356 1.43016004 -2.03553002 0 P 0 ;0
L 1.43016004 -2.03553002 1.4299 -2.03535 0 P 0 ;0
L 1.4299 -2.03535 1.43028002 -2.03535 0 P 0 ;0
L 1.43028002 -2.03535 1.43043996 -2.03513002 0 P 0 ;0
L 1.43043996 -2.03513002 1.43048002 -2.03506004 0 P 0 ;0
L 1.43048002 -2.03506004 1.43041998 -2.03501998 0 P 0 ;0
L 1.43041998 -2.03501998 1.4305 -2.03501998 0 P 0 ;0
L 1.4305 -2.03501998 1.43073002 -2.03463002 0 P 0 ;0
L 1.43073002 -2.03463002 1.43096004 -2.03415 0 P 0 ;0
L 1.43096004 -2.03415 1.43115 -2.03365 0 P 0 ;0
L 1.43115 -2.03365 1.4313 -2.03313002 0 P 0 ;0
L 1.4313 -2.03313002 1.4314 -2.03261004 0 P 0 ;0
L 1.4314 -2.03261004 1.43146004 -2.03208002 0 P 0 ;0
L 1.43146004 -2.03208002 1.43146998 -2.03155 0 P 0 ;0
L 1.43146998 -2.03155 1.43143996 -2.03101004 0 P 0 ;0
L 1.43143996 -2.03101004 1.43143002 -2.03093002 0 P 0 ;0
L 1.43143002 -2.03093002 1.43136004 -2.03048996 0 P 0 ;0
L 1.43136004 -2.03048996 1.43125 -2.02996998 0 P 0 ;0
L 1.43125 -2.02996998 1.43108002 -2.02946004 0 P 0 ;0
L 1.43108002 -2.02946004 1.43086998 -2.02896004 0 P 0 ;0
L 1.43086998 -2.02896004 1.43063002 -2.02848996 0 P 0 ;0
L 1.43063002 -2.02848996 1.43033996 -2.02803996 0 P 0 ;0
L 1.43033996 -2.02803996 1.43001998 -2.02761004 0 P 0 ;0
L 1.43001998 -2.02761004 1.42966004 -2.02721004 0 P 0 ;0
L 1.42966004 -2.02721004 1.42928002 -2.02685 0 P 0 ;0
L 1.42928002 -2.02685 1.42886004 -2.02651998 0 P 0 ;0
L 1.42886004 -2.02651998 1.42841998 -2.02623002 0 P 0 ;0
L 1.42841998 -2.02623002 1.42795 -2.02596998 0 P 0 ;0
L 1.42795 -2.02596998 1.42746004 -2.02575 0 P 0 ;0
L 1.42746004 -2.02575 1.42583002 -2.02518002 0 P 0 ;0
L 1.42583002 -2.02518002 1.42416004 -2.02476004 0 P 0 ;0
L 1.42416004 -2.02476004 1.42245 -2.02448002 0 P 0 ;0
L 1.42245 -2.02448002 1.42075 -2.02435 0 P 0 ;0
L 1.42075 -2.02435 1.41565 -2.02428002 0 P 0 ;0
L 1.41565 -2.02428002 1.4156 -2.02428002 0 P 0 ;0
L 1.4156 -2.02428002 1.41055 -2.02445 0 P 0 ;0
L 1.41055 -2.02445 1.41048002 -2.02445 0 P 0 ;0
L 1.41048002 -2.02445 1.40128996 -2.02533996 0 P 0 ;0
L 1.40128996 -2.02533996 1.39208996 -2.02696998 0 P 0 ;0
L 1.39208996 -2.02696998 1.38288002 -2.02936004 0 P 0 ;0
L 1.38288002 -2.02936004 1.37363002 -2.03251998 0 P 0 ;0
L 1.37363002 -2.03251998 1.37076998 -2.03356004 0 P 0 ;0
L 1.37076998 -2.03356004 1.36865 -2.03426998 0 P 0 ;0
L 1.36865 -2.03426998 1.36906004 -2.03066998 0 P 0 ;0
L 1.36906004 -2.03066998 1.36988996 -2.02383996 0 P 0 ;0
L 1.36988996 -2.02383996 1.37095 -2.01581004 0 P 0 ;0
L 1.37095 -2.01581004 1.37358996 -1.99631998 0 P 0 ;0
L 1.37358996 -1.99631998 1.37988002 -1.99491998 0 P 0 ;0
L 1.37988002 -1.99491998 1.38353996 -1.99416998 0 P 0 ;0
L 1.38353996 -1.99416998 1.38841998 -1.99326998 0 P 0 ;0
L 1.38841998 -1.99326998 1.39358002 -1.9924 0 P 0 ;0
L 1.39358002 -1.9924 1.39825 -1.9917 0 P 0 ;0
L 1.39825 -1.9917 1.40436998 -1.991 0 P 0 ;0
L 1.40436998 -1.991 1.41045 -1.99065 0 P 0 ;0
L 1.41045 -1.99065 1.42691004 -1.99056998 0 P 0 ;0
L 1.42691004 -1.99056998 1.44283996 -1.99123996 0 P 0 ;0
L 1.44283996 -1.99123996 1.44603996 -1.99153996 0 P 0 ;0
L 1.44603996 -1.99153996 1.44918002 -1.99203002 0 P 0 ;0
L 1.44918002 -1.99203002 1.45226004 -1.9927 0 P 0 ;0
L 1.45226004 -1.9927 1.4563 -1.99386998 0 P 0 ;0
L 1.4563 -1.99386998 1.46021004 -1.99535 0 P 0 ;0
L 1.46021004 -1.99535 1.464 -1.99713002 0 P 0 ;0
L 1.464 -1.99713002 1.46586004 -1.99818996 0 P 0 ;0
L 1.46586004 -1.99818996 1.46763996 -1.99936004 0 P 0 ;0
L 1.46763996 -1.99936004 1.46931998 -2.00066004 0 P 0 ;0
L 1.46931998 -2.00066004 1.47091004 -2.00206998 0 P 0 ;0
L 1.47091004 -2.00206998 1.47238996 -2.00358996 0 P 0 ;0
L 1.47238996 -2.00358996 1.4737 -2.00515 0 P 0 ;0
L 1.4737 -2.00515 1.47488002 -2.00678996 0 P 0 ;0
L 1.47488002 -2.00678996 1.47593996 -2.00851004 0 P 0 ;0
L 1.47593996 -2.00851004 1.47686004 -2.01031004 0 P 0 ;0
L 1.47686004 -2.01031004 1.47763996 -2.01216998 0 P 0 ;0
L 1.47763996 -2.01216998 1.47851998 -2.01481004 0 P 0 ;0
L 1.47851998 -2.01481004 1.47918996 -2.01748996 0 P 0 ;0
L 1.47918996 -2.01748996 1.47966004 -2.02021998 0 P 0 ;0
L 1.47966004 -2.02021998 1.47993002 -2.02296998 0 P 0 ;0
L 1.47993002 -2.02296998 1.48001998 -2.02783996 0 P 0 ;0
L 1.48001998 -2.02783996 1.47975 -2.03868996 0 P 0 ;0
L 1.47975 -2.03868996 1.4793 -2.05161004 0 P 0 ;0
L 1.4793 -2.05161004 1.47866004 -2.06543002 0 P 0 ;0
L 1.47866004 -2.06543002 1.47801004 -2.07961004 0 P 0 ;0
L 1.47801004 -2.07961004 1.47743996 -2.09378996 0 P 0 ;0
L 1.47743996 -2.09378996 1.47705 -2.10613002 0 P 0 ;0
L 1.47705 -2.10613002 1.47693002 -2.11356004 0 P 0 ;0
L 1.47693002 -2.11356004 1.47693002 -2.12516004 0 P 0 ;0
L 1.47693002 -2.12516004 1.42661004 -2.12516004 0 P 0 ;0
L 1.42661004 -2.12516004 1.42661004 -2.12473996 0 P 0 ;0
L 1.42661004 -2.12473996 1.42666004 -2.12318002 0 P 0 ;0
L 1.42666004 -2.12318002 1.42691004 -2.11863996 0 P 0 ;0
L 1.42691004 -2.11863996 1.42725 -2.1132 0 P 0 ;0
L 1.42725 -2.1132 1.42766004 -2.1072 0 P 0 ;0
L 1.42766004 -2.1072 1.42766004 -2.10718996 0 P 0 ;0
L 1.42766004 -2.10718996 1.4281 -2.10068996 0 P 0 ;0
L 1.4281 -2.10068996 1.42858002 -2.09368002 0 P 0 ;0
L 1.42858002 -2.09368002 1.42901004 -2.08721004 0 P 0 ;0
L 1.42901004 -2.08721004 1.42901004 -2.0872 0 P 0 ;0
L 1.42901004 -2.0872 1.42931004 -2.08256004 0 P 0 ;0
L 1.42931004 -2.08256004 1.42991998 -2.07308002 0 P 0 ;0
L 1.42991998 -2.07308002 1.42916004 -2.07136998 0 P 0 ;0
L 1.42916004 -2.07136998 1.42731998 -2.07105 0 P 0 ;0
L 1.42731998 -2.07105 1.42105 -2.07303996 0 P 0 ;0
L 1.42105 -2.07303996 1.41815 -2.07393002 0 P 0 ;0
L 1.41815 -2.07393002 1.41451004 -2.075 0 P 0 ;0
L 1.41451004 -2.075 1.41076004 -2.07603002 0 P 0 ;0
L 1.41076004 -2.07603002 1.40748002 -2.0769 0 P 0 ;0
L 1.40748002 -2.0769 1.40438996 -2.07781004 0 P 0 ;0
L 1.40438996 -2.07781004 1.40431998 -2.07783996 0 P 0 ;0
L 1.40431998 -2.07783996 1.40133996 -2.07896998 0 P 0 ;0
L 1.40133996 -2.07896998 1.40005 -2.07956998 0 P 0 ;0
L 1.40005 -2.07956998 1.39881998 -2.08026004 0 P 0 ;0
L 1.39881998 -2.08026004 1.39763996 -2.08103002 0 P 0 ;0
L 1.39763996 -2.08103002 1.39651998 -2.08188002 0 P 0 ;0
L 1.39651998 -2.08188002 1.39578996 -2.08251004 0 P 0 ;0
L 1.39578996 -2.08251004 1.39573996 -2.08256004 0 P 0 ;0
L 1.39573996 -2.08256004 1.3951 -2.08318996 0 P 0 ;0
L 1.3951 -2.08318996 1.39446998 -2.08393002 0 P 0 ;0
L 1.39446998 -2.08393002 1.3939 -2.08471004 0 P 0 ;0
L 1.3939 -2.08471004 1.39336998 -2.08553996 0 P 0 ;0
L 1.39336998 -2.08553996 1.39301004 -2.08623996 0 P 0 ;0
L 1.39301004 -2.08623996 1.39271004 -2.08696998 0 P 0 ;0
L 1.39271004 -2.08696998 1.39248002 -2.08771998 0 P 0 ;0
L 1.39248002 -2.08771998 1.39231004 -2.08848996 0 P 0 ;0
L 1.39231004 -2.08848996 1.39221004 -2.08926004 0 P 0 ;0
L 1.39221004 -2.08926004 1.39218002 -2.09003996 0 P 0 ;0
L 1.39218002 -2.09003996 1.39221004 -2.0908 0 P 0 ;0
L 1.39221004 -2.0908 1.39231004 -2.09153002 0 P 0 ;0
L 1.39231004 -2.09153002 1.39246998 -2.09226004 0 P 0 ;0
L 1.39246998 -2.09226004 1.39268996 -2.09296998 0 P 0 ;0
L 1.39268996 -2.09296998 1.39296004 -2.09365 0 P 0 ;0
L 1.39296004 -2.09365 1.3933 -2.09431004 0 P 0 ;0
L 1.3933 -2.09431004 1.39368996 -2.09493996 0 P 0 ;0
L 1.39368996 -2.09493996 1.39411998 -2.09553996 0 P 0 ;0
L 1.39411998 -2.09553996 1.39468996 -2.09618002 0 P 0 ;0
L 1.39468996 -2.09618002 1.3953 -2.09678002 0 P 0 ;0
L 1.3953 -2.09678002 1.39596004 -2.09731998 0 P 0 ;0
L 1.39596004 -2.09731998 1.39666998 -2.0978 0 P 0 ;0
L 1.39666998 -2.0978 1.39673996 -2.09783996 0 P 0 ;0
L 1.39673996 -2.09783996 1.39741004 -2.09821998 0 P 0 ;0
L 1.39741004 -2.09821998 1.39748996 -2.09825 0 P 0 ;0
L 1.39748996 -2.09825 1.39818996 -2.09856998 0 P 0 ;0
L 1.39818996 -2.09856998 1.39898996 -2.09886004 0 P 0 ;0
L 1.39898996 -2.09886004 1.39906998 -2.09888002 0 P 0 ;0
L 1.39906998 -2.09888002 1.40043996 -2.09888002 0 P 0 ;0
L 1.40043996 -2.09888002 1.40033996 -2.09923002 0 P 0 ;0
L 1.40033996 -2.09923002 1.40041998 -2.09925 0 P 0 ;0
L 1.40041998 -2.09925 1.40186004 -2.09953002 0 P 0 ;0
L 1.40186004 -2.09953002 1.40331004 -2.09971004 0 P 0 ;0
L 1.40331004 -2.09971004 1.40478002 -2.09978002 0 P 0 ;0
L 1.40478002 -2.09978002 1.40625 -2.09975 0 P 0 ;0
L 1.40625 -2.09975 1.41096004 -2.09931004 0 P 0 ;0
L 1.41096004 -2.09931004 1.41556998 -2.09855 0 P 0 ;0
L 1.41556998 -2.09855 1.41791998 -2.09813002 0 P 0 ;0
L 1.41791998 -2.09813002 1.41995 -2.09791004 0 P 0 ;0
L 1.41995 -2.09791004 1.4201 -2.0979 0 P 0 ;0
L 1.4201 -2.0979 1.41941004 -2.10078002 0 P 0 ;0
L 1.41941004 -2.10078002 1.41761004 -2.10745 0 P 0 ;0
L 1.41761004 -2.10745 1.41391004 -2.12025 0 P 0 ;0
L 1.41391004 -2.12025 1.41215 -2.12626998 0 P 0 ;0
L 1.41215 -2.12626998 1.40655 -2.12725 0 P 0 ;0
L 1.40655 -2.12725 1.40046004 -2.12808002 0 P 0 ;0
L 1.40046004 -2.12808002 1.39438002 -2.12845 0 P 0 ;0
L 1.15303002 -2.08283002 1.20788996 -2.08283002 0 P 0 ;0
L 1.15398996 -2.08183002 1.20795 -2.08183002 0 P 0 ;0
L 1.15483002 -2.08083002 1.208 -2.08083002 0 P 0 ;0
L 1.15555 -2.07983002 1.20805 -2.07983002 0 P 0 ;0
L 1.15621998 -2.07883002 1.2081 -2.07883002 0 P 0 ;0
L 1.15681998 -2.07783002 1.20816004 -2.07783002 0 P 0 ;0
L 1.15733002 -2.07683002 1.20821004 -2.07683002 0 P 0 ;0
L 1.15778996 -2.07583002 1.20826004 -2.07583002 0 P 0 ;0
L 1.15818002 -2.07483002 1.20831004 -2.07483002 0 P 0 ;0
L 1.15853996 -2.07383002 1.20836998 -2.07383002 0 P 0 ;0
L 1.15881998 -2.07283002 1.20841998 -2.07283002 0 P 0 ;0
L 1.1591 -2.07183002 1.20846998 -2.07183002 0 P 0 ;0
L 1.15938002 -2.07083002 1.20853002 -2.07083002 0 P 0 ;0
L 1.1596 -2.06983002 1.20858002 -2.06983002 0 P 0 ;0
L 1.15981004 -2.06883002 1.20863996 -2.06883002 0 P 0 ;0
L 1.16001004 -2.06783002 1.20868996 -2.06783002 0 P 0 ;0
L 1.1602 -2.06683002 1.20875 -2.06683002 0 P 0 ;0
L 1.16033996 -2.06583002 1.2088 -2.06583002 0 P 0 ;0
L 1.16048996 -2.06483002 1.20886004 -2.06483002 0 P 0 ;0
L 1.16063996 -2.06383002 1.20891998 -2.06383002 0 P 0 ;0
L 1.16078002 -2.06283002 1.20896998 -2.06283002 0 P 0 ;0
L 1.16088996 -2.06183002 1.20903002 -2.06183002 0 P 0 ;0
L 1.16098996 -2.06083002 1.20908002 -2.06083002 0 P 0 ;0
L 1.16108996 -2.05983002 1.20913996 -2.05983002 0 P 0 ;0
L 1.16118002 -2.05883002 1.20918996 -2.05883002 0 P 0 ;0
L 1.16128002 -2.05783002 1.20925 -2.05783002 0 P 0 ;0
L 1.16133996 -2.05683002 1.2093 -2.05683002 0 P 0 ;0
L 1.1614 -2.05583002 1.20936004 -2.05583002 0 P 0 ;0
L 1.16146004 -2.05483002 1.20941004 -2.05483002 0 P 0 ;0
L 1.16151998 -2.05383002 1.20946998 -2.05383002 0 P 0 ;0
L 1.16158002 -2.05283002 1.20951998 -2.05283002 0 P 0 ;0
L 1.16163996 -2.05183002 1.20958002 -2.05183002 0 P 0 ;0
L 1.1617 -2.05083002 1.20963996 -2.05083002 0 P 0 ;0
L 1.16175 -2.04983002 1.2097 -2.04983002 0 P 0 ;0
L 1.16181004 -2.04883002 1.20975 -2.04883002 0 P 0 ;0
L 1.16186998 -2.04783002 1.20981004 -2.04783002 0 P 0 ;0
L 1.16193002 -2.04683002 1.20986998 -2.04683002 0 P 0 ;0
L 1.16198996 -2.04583002 1.20993002 -2.04583002 0 P 0 ;0
L 1.16205 -2.04483002 1.20998996 -2.04483002 0 P 0 ;0
L 1.16211004 -2.04383002 1.21005 -2.04383002 0 P 0 ;0
L 1.16215 -2.04283002 1.2101 -2.04283002 0 P 0 ;0
L 1.1622 -2.04183002 1.21016004 -2.04183002 0 P 0 ;0
L 1.16225 -2.04083002 1.21021998 -2.04083002 0 P 0 ;0
L 1.16228996 -2.03983002 1.21028002 -2.03983002 0 P 0 ;0
L 1.16233996 -2.03883002 1.21033996 -2.03883002 0 P 0 ;0
L 1.16238002 -2.03783002 1.2104 -2.03783002 0 P 0 ;0
L 1.16243002 -2.03683002 1.21046004 -2.03683002 0 P 0 ;0
L 1.16246998 -2.03583002 1.21051004 -2.03583002 0 P 0 ;0
L 1.16251998 -2.03483002 1.21056998 -2.03483002 0 P 0 ;0
L 1.16256998 -2.03383002 1.21063996 -2.03383002 0 P 0 ;0
L 1.16261004 -2.03283002 1.2107 -2.03283002 0 P 0 ;0
L 1.16266004 -2.03183002 1.21076004 -2.03183002 0 P 0 ;0
L 1.1627 -2.03083002 1.21083002 -2.03083002 0 P 0 ;0
L 1.16015 -1.97631004 1.17066004 -1.97631004 0 P 0 ;0
L 1.15961998 -1.97531004 1.17026004 -1.97531004 0 P 0 ;0
L 1.1591 -1.97431004 1.16986998 -1.97431004 0 P 0 ;0
L 1.15856998 -1.97331004 1.16946998 -1.97331004 0 P 0 ;0
L 1.15803996 -1.97231004 1.16903002 -1.97231004 0 P 0 ;0
L 1.15746998 -1.97131004 1.16858996 -1.97131004 0 P 0 ;0
L 1.1569 -1.97031004 1.16815 -1.97031004 0 P 0 ;0
L 1.15631998 -1.96931004 1.16771004 -1.96931004 0 P 0 ;0
L 1.15573996 -1.96831004 1.16726998 -1.96831004 0 P 0 ;0
L 1.15516004 -1.96731004 1.16681998 -1.96731004 0 P 0 ;0
L 1.15458996 -1.96631004 1.16638002 -1.96631004 0 P 0 ;0
L 1.15398002 -1.96531004 1.16593996 -1.96531004 0 P 0 ;0
L 1.1533 -1.96431004 1.16548996 -1.96431004 0 P 0 ;0
L 1.15261998 -1.96331004 1.16503002 -1.96331004 0 P 0 ;0
L 1.15193996 -1.96231004 1.16448002 -1.96231004 0 P 0 ;0
L 1.15126004 -1.96131004 1.16393002 -1.96131004 0 P 0 ;0
L 1.15058002 -1.96031004 1.16338002 -1.96031004 0 P 0 ;0
L 1.1499 -1.95931004 1.16283002 -1.95931004 0 P 0 ;0
L 1.1491 -1.95831004 1.16228996 -1.95831004 0 P 0 ;0
L 1.14831004 -1.95731004 1.16173996 -1.95731004 0 P 0 ;0
L 1.14751004 -1.95631004 1.16118996 -1.95631004 0 P 0 ;0
L 1.14671004 -1.95531004 1.16063996 -1.95531004 0 P 0 ;0
L 1.14591998 -1.95431004 1.16008996 -1.95431004 0 P 0 ;0
L 1.14511998 -1.95331004 1.15943996 -1.95331004 0 P 0 ;0
L 1.1442 -1.95231004 1.15878002 -1.95231004 0 P 0 ;0
L 1.14326998 -1.95131004 1.15811004 -1.95131004 0 P 0 ;0
L 1.14233996 -1.95031004 1.15745 -1.95031004 0 P 0 ;0
L 1.14141004 -1.94931004 1.15678002 -1.94931004 0 P 0 ;0
L 1.14048996 -1.94831004 1.15611998 -1.94831004 0 P 0 ;0
L 1.1395 -1.94731004 1.15545 -1.94731004 0 P 0 ;0
L 1.13843002 -1.94631004 1.15478996 -1.94631004 0 P 0 ;0
L 1.13736004 -1.94531004 1.15411998 -1.94531004 0 P 0 ;0
L 1.13628996 -1.94431004 1.15333002 -1.94431004 0 P 0 ;0
L 1.13521004 -1.94331004 1.15253002 -1.94331004 0 P 0 ;0
L 1.13413996 -1.94231004 1.15173996 -1.94231004 0 P 0 ;0
L 1.13306998 -1.94131004 1.15093996 -1.94131004 0 P 0 ;0
L 1.132 -1.94031004 1.15013996 -1.94031004 0 P 0 ;0
L 1.13081004 -1.93931004 1.14935 -1.93931004 0 P 0 ;0
L 1.12958002 -1.93831004 1.14855 -1.93831004 0 P 0 ;0
L 1.12833996 -1.93731004 1.14775 -1.93731004 0 P 0 ;0
L 1.1271 -1.93631004 1.14688996 -1.93631004 0 P 0 ;0
L 1.12586004 -1.93531004 1.14593996 -1.93531004 0 P 0 ;0
L 1.12461998 -1.93431004 1.14498996 -1.93431004 0 P 0 ;0
L 1.12338002 -1.93331004 1.14405 -1.93331004 0 P 0 ;0
L 1.12203002 -1.93231004 1.1431 -1.93231004 0 P 0 ;0
L 1.1206 -1.93131004 1.14216004 -1.93131004 0 P 0 ;0
L 1.11916004 -1.93031004 1.14121004 -1.93031004 0 P 0 ;0
L 1.11771998 -1.92931004 1.14026998 -1.92931004 0 P 0 ;0
L 1.11628996 -1.92831004 1.13931998 -1.92831004 0 P 0 ;0
L 1.11483996 -1.92731004 1.13838002 -1.92731004 0 P 0 ;0
L 1.11338996 -1.92631004 1.13743002 -1.92631004 0 P 0 ;0
L 1.11171998 -1.92531004 1.13648996 -1.92531004 0 P 0 ;0
L 1.11005 -1.92431004 1.13538002 -1.92431004 0 P 0 ;0
L 1.10838002 -1.92331004 1.13426998 -1.92331004 0 P 0 ;0
L 1.1067 -1.92231004 1.13315 -1.92231004 0 P 0 ;0
L 1.10503002 -1.92131004 1.13203002 -1.92131004 0 P 0 ;0
L 1.10336004 -1.92031004 1.13091998 -1.92031004 0 P 0 ;0
L 1.1015 -1.91931004 1.1298 -1.91931004 0 P 0 ;0
L 1.09955 -1.91831004 1.12868002 -1.91831004 0 P 0 ;0
L 1.16275 -2.02983002 1.21088996 -2.02983002 0 P 0 ;0
L 1.16278996 -2.02883002 1.21095 -2.02883002 0 P 0 ;0
L 1.16283996 -2.02783002 1.21101004 -2.02783002 0 P 0 ;0
L 1.16226998 -2.02683002 1.21108002 -2.02683002 0 P 0 ;0
L 1.16153996 -2.02583002 1.21113996 -2.02583002 0 P 0 ;0
L 1.15846004 -2.02483002 1.2112 -2.02483002 0 P 0 ;0
L 1.10036004 -2.00383002 1.21255 -2.00383002 0 P 0 ;0
L 1.10226004 -2.00283002 1.2126 -2.00283002 0 P 0 ;0
L 1.10433996 -2.00183002 1.21266998 -2.00183002 0 P 0 ;0
L 1.1065 -2.00083002 1.21273002 -2.00083002 0 P 0 ;0
L 1.10886998 -1.99983002 1.21278996 -1.99983002 0 P 0 ;0
L 1.11138002 -1.99883002 1.21285 -1.99883002 0 P 0 ;0
L 1.11436998 -1.99783002 1.21288002 -1.99783002 0 P 0 ;0
L 1.11748996 -1.99683002 1.21255 -1.99683002 0 P 0 ;0
L 1.12061998 -1.99583002 1.2089 -1.99583002 0 P 0 ;0
L 1.12433996 -1.99483002 1.2036 -1.99483002 0 P 0 ;0
L 1.12863996 -1.99383002 1.19728002 -1.99383002 0 P 0 ;0
L 1.13295 -1.99283002 1.19096998 -1.99283002 0 P 0 ;0
L 1.13985 -1.99183002 1.18111998 -1.99183002 0 P 0 ;0
L 1.14948002 -1.99083002 1.1651 -1.99083002 0 P 0 ;0
L 1.24218002 -2.08316004 1.29143996 -2.08316004 0 P 0 ;0
L 1.24223002 -2.08216004 1.29151004 -2.08216004 0 P 0 ;0
L 1.24228002 -2.08116004 1.29158996 -2.08116004 0 P 0 ;0
L 1.24233996 -2.08016004 1.29166004 -2.08016004 0 P 0 ;0
L 1.24238996 -2.07916004 1.29173002 -2.07916004 0 P 0 ;0
L 1.24245 -2.07816004 1.29181004 -2.07816004 0 P 0 ;0
L 1.2425 -2.07716004 1.29188002 -2.07716004 0 P 0 ;0
L 1.24256004 -2.07616004 1.29195 -2.07616004 0 P 0 ;0
L 1.24261004 -2.07516004 1.29203002 -2.07516004 0 P 0 ;0
L 1.24266998 -2.07416004 1.2921 -2.07416004 0 P 0 ;0
L 1.24271998 -2.07316004 1.29216998 -2.07316004 0 P 0 ;0
L 1.24278002 -2.07216004 1.29223996 -2.07216004 0 P 0 ;0
L 1.24283002 -2.07116004 1.29231998 -2.07116004 0 P 0 ;0
L 1.24288002 -2.07016004 1.29238996 -2.07016004 0 P 0 ;0
L 1.24293002 -2.06916004 1.29246004 -2.06916004 0 P 0 ;0
L 1.24296998 -2.06816004 1.29253002 -2.06816004 0 P 0 ;0
L 1.24301998 -2.06716004 1.29261004 -2.06716004 0 P 0 ;0
L 1.24306004 -2.06616004 1.2927 -2.06616004 0 P 0 ;0
L 1.24311004 -2.06516004 1.29281004 -2.06516004 0 P 0 ;0
L 1.24315 -2.06416004 1.29291998 -2.06416004 0 P 0 ;0
L 1.2432 -2.06316004 1.29303002 -2.06316004 0 P 0 ;0
L 1.24323996 -2.06216004 1.29315 -2.06216004 0 P 0 ;0
L 1.24328996 -2.06116004 1.29331998 -2.06116004 0 P 0 ;0
L 1.24333002 -2.06016004 1.2935 -2.06016004 0 P 0 ;0
L 1.24338002 -2.05916004 1.29366998 -2.05916004 0 P 0 ;0
L 1.24341998 -2.05816004 1.29385 -2.05816004 0 P 0 ;0
L 1.24346998 -2.05716004 1.29408996 -2.05716004 0 P 0 ;0
L 1.24351004 -2.05616004 1.29433996 -2.05616004 0 P 0 ;0
L 1.24355 -2.05516004 1.29458996 -2.05516004 0 P 0 ;0
L 1.2436 -2.05416004 1.29485 -2.05416004 0 P 0 ;0
L 1.24363996 -2.05316004 1.29516998 -2.05316004 0 P 0 ;0
L 1.24368996 -2.05216004 1.29551998 -2.05216004 0 P 0 ;0
L 1.24373002 -2.05116004 1.29586004 -2.05116004 0 P 0 ;0
L 1.24378002 -2.05016004 1.29621004 -2.05016004 0 P 0 ;0
L 1.24383002 -2.04916004 1.29663996 -2.04916004 0 P 0 ;0
L 1.24386998 -2.04816004 1.29708002 -2.04816004 0 P 0 ;0
L 1.24391004 -2.04716004 1.29753002 -2.04716004 0 P 0 ;0
L 1.24396004 -2.04616004 1.29796998 -2.04616004 0 P 0 ;0
L 1.244 -2.04516004 1.29851004 -2.04516004 0 P 0 ;0
L 1.24405 -2.04416004 1.2991 -2.04416004 0 P 0 ;0
L 1.24408996 -2.04316004 1.29975 -2.04316004 0 P 0 ;0
L 1.24413996 -2.04216004 1.3005 -2.04216004 0 P 0 ;0
L 1.24418002 -2.04116004 1.30131998 -2.04116004 0 P 0 ;0
L 1.24423002 -2.04016004 1.30223002 -2.04016004 0 P 0 ;0
L 1.24426998 -2.03916004 1.30326998 -2.03916004 0 P 0 ;0
L 1.24431998 -2.03816004 1.30446004 -2.03816004 0 P 0 ;0
L 1.24436004 -2.03716004 1.30581998 -2.03716004 0 P 0 ;0
L 1.24441004 -2.03616004 1.30738002 -2.03616004 0 P 0 ;0
L 1.24445 -2.03516004 1.30923002 -2.03516004 0 P 0 ;0
L 1.24448996 -2.03416004 1.31156004 -2.03416004 0 P 0 ;0
L 1.24453996 -2.03316004 1.31478996 -2.03316004 0 P 0 ;0
L 1.24458996 -2.03216004 1.32013002 -2.03216004 0 P 0 ;0
L 1.24461998 -2.03116004 1.33481004 -2.03116004 0 P 0 ;0
L 1.24463996 -2.03016004 1.33478002 -2.03016004 0 P 0 ;0
L 1.24466004 -2.02916004 1.33473996 -2.02916004 0 P 0 ;0
L 1.24468002 -2.02816004 1.33471004 -2.02816004 0 P 0 ;0
L 1.2447 -2.02716004 1.33468002 -2.02716004 0 P 0 ;0
L 1.24471998 -2.02616004 1.33463996 -2.02616004 0 P 0 ;0
L 1.24473996 -2.02516004 1.3346 -2.02516004 0 P 0 ;0
L 1.24476004 -2.02416004 1.33456998 -2.02416004 0 P 0 ;0
L 1.24478002 -2.02316004 1.33453002 -2.02316004 0 P 0 ;0
L 1.2448 -2.02216004 1.3345 -2.02216004 0 P 0 ;0
L 1.24481998 -2.02116004 1.33446998 -2.02116004 0 P 0 ;0
L 1.24483996 -2.02016004 1.33443002 -2.02016004 0 P 0 ;0
L 1.24486004 -2.01916004 1.3344 -2.01916004 0 P 0 ;0
L 1.24488002 -2.01816004 1.33436004 -2.01816004 0 P 0 ;0
L 1.2449 -2.01716004 1.33433002 -2.01716004 0 P 0 ;0
L 1.24491998 -2.01616004 1.33428996 -2.01616004 0 P 0 ;0
L 1.24493996 -2.01516004 1.33426004 -2.01516004 0 P 0 ;0
L 1.24496004 -2.01416004 1.33421998 -2.01416004 0 P 0 ;0
L 1.24498002 -2.01316004 1.33418996 -2.01316004 0 P 0 ;0
L 1.245 -2.01216004 1.33415 -2.01216004 0 P 0 ;0
L 1.24501998 -2.01116004 1.33411998 -2.01116004 0 P 0 ;0
L 1.24503996 -2.01016004 1.33408002 -2.01016004 0 P 0 ;0
L 1.24506004 -2.00916004 1.33403996 -2.00916004 0 P 0 ;0
L 1.24508002 -2.00816004 1.334 -2.00816004 0 P 0 ;0
L 1.2451 -2.00716004 1.33396004 -2.00716004 0 P 0 ;0
L 1.24511998 -2.00616004 1.33393002 -2.00616004 0 P 0 ;0
L 1.24513996 -2.00516004 1.29098996 -2.00516004 0 P 0 ;0
L 1.24513996 -2.00416004 1.29033002 -2.00416004 0 P 0 ;0
L 1.24513996 -2.00316004 1.29005 -2.00316004 0 P 0 ;0
L 1.24513996 -2.00216004 1.29005 -2.00216004 0 P 0 ;0
L 1.24513996 -2.00116004 1.29005 -2.00116004 0 P 0 ;0
L 1.24515 -2.00016004 1.29005 -2.00016004 0 P 0 ;0
L 1.24515 -1.99916004 1.29005 -1.99916004 0 P 0 ;0
L 1.24515 -1.99816004 1.29005 -1.99816004 0 P 0 ;0
L 1.24515 -1.99716004 1.29005 -1.99716004 0 P 0 ;0
L 1.24515 -1.99616004 1.29005 -1.99616004 0 P 0 ;0
L 1.24515 -1.99516004 1.29005 -1.99516004 0 P 0 ;0
L 1.16085 -2.02753002 1.1601 -2.04393002 0 P 0 ;0
L 1.1601 -2.04393002 1.15928996 -2.05771998 0 P 0 ;0
L 1.15928996 -2.05771998 1.15883996 -2.06228002 0 P 0 ;0
L 1.15883996 -2.06228002 1.15818002 -2.06681998 0 P 0 ;0
L 1.15818002 -2.06681998 1.15751004 -2.07006998 0 P 0 ;0
L 1.15751004 -2.07006998 1.15661004 -2.07328996 0 P 0 ;0
L 1.15661004 -2.07328996 1.15616004 -2.07453996 0 P 0 ;0
L 1.15616004 -2.07453996 1.15563002 -2.07576998 0 P 0 ;0
L 1.15563002 -2.07576998 1.15501998 -2.07696004 0 P 0 ;0
L 1.15501998 -2.07696004 1.15433002 -2.0781 0 P 0 ;0
L 1.15433002 -2.0781 1.1534 -2.07941998 0 P 0 ;0
L 1.1534 -2.07941998 1.15236004 -2.08066004 0 P 0 ;0
L 1.15236004 -2.08066004 1.15123002 -2.08181998 0 P 0 ;0
L 1.15123002 -2.08181998 1.15001004 -2.08286998 0 P 0 ;0
L 1.15001004 -2.08286998 1.14871004 -2.08383002 0 P 0 ;0
L 1.14871004 -2.08383002 1.14733002 -2.08468002 0 P 0 ;0
L 1.14733002 -2.08468002 1.14591004 -2.0854 0 P 0 ;0
L 1.14591004 -2.0854 1.14443996 -2.086 0 P 0 ;0
L 1.14443996 -2.086 1.14291004 -2.08648002 0 P 0 ;0
L 1.14291004 -2.08648002 1.14136004 -2.08683002 0 P 0 ;0
L 1.14136004 -2.08683002 1.13976998 -2.08703996 0 P 0 ;0
L 1.13976998 -2.08703996 1.13816004 -2.08713002 0 P 0 ;0
L 1.13816004 -2.08713002 1.13656998 -2.08708002 0 P 0 ;0
L 1.13656998 -2.08708002 1.13498996 -2.0869 0 P 0 ;0
L 1.13498996 -2.0869 1.13341998 -2.08658996 0 P 0 ;0
L 1.13341998 -2.08658996 1.13188996 -2.08615 0 P 0 ;0
L 1.13188996 -2.08615 1.1304 -2.08558996 0 P 0 ;0
L 1.1304 -2.08558996 1.12895 -2.08488996 0 P 0 ;0
L 1.12895 -2.08488996 1.12756998 -2.08408002 0 P 0 ;0
L 1.12756998 -2.08408002 1.12625 -2.08315 0 P 0 ;0
L 1.12625 -2.08315 1.12501004 -2.08211998 0 P 0 ;0
L 1.12501004 -2.08211998 1.12386004 -2.081 0 P 0 ;0
L 1.12386004 -2.081 1.12281004 -2.07978002 0 P 0 ;0
L 1.12281004 -2.07978002 1.12183996 -2.07846998 0 P 0 ;0
L 1.12183996 -2.07846998 1.1211 -2.07726004 0 P 0 ;0
L 1.1211 -2.07726004 1.12046998 -2.07598996 0 P 0 ;0
L 1.12046998 -2.07598996 1.11996004 -2.07466998 0 P 0 ;0
L 1.11996004 -2.07466998 1.11955 -2.07331004 0 P 0 ;0
L 1.11955 -2.07331004 1.11926998 -2.07191004 0 P 0 ;0
L 1.11926998 -2.07191004 1.11868002 -2.06693996 0 P 0 ;0
L 1.11868002 -2.06693996 1.11848002 -2.06191004 0 P 0 ;0
L 1.11848002 -2.06191004 1.11871004 -2.05668002 0 P 0 ;0
L 1.11871004 -2.05668002 1.11936004 -2.05148002 0 P 0 ;0
L 1.11936004 -2.05148002 1.11978996 -2.04936998 0 P 0 ;0
L 1.11978996 -2.04936998 1.12036998 -2.0473 0 P 0 ;0
L 1.12036998 -2.0473 1.12108996 -2.04528002 0 P 0 ;0
L 1.12108996 -2.04528002 1.12196004 -2.04331998 0 P 0 ;0
L 1.12196004 -2.04331998 1.1229 -2.04153996 0 P 0 ;0
L 1.1229 -2.04153996 1.12396998 -2.03985 0 P 0 ;0
L 1.12396998 -2.03985 1.12516998 -2.03823002 0 P 0 ;0
L 1.12516998 -2.03823002 1.12735 -2.03573996 0 P 0 ;0
L 1.12735 -2.03573996 1.12973002 -2.03345 0 P 0 ;0
L 1.12973002 -2.03345 1.13223996 -2.03141998 0 P 0 ;0
L 1.13223996 -2.03141998 1.13491998 -2.02961004 0 P 0 ;0
L 1.13491998 -2.02961004 1.13611004 -2.02893002 0 P 0 ;0
L 1.13611004 -2.02893002 1.13735 -2.02833996 0 P 0 ;0
L 1.13735 -2.02833996 1.13861998 -2.02781998 0 P 0 ;0
L 1.13861998 -2.02781998 1.13993996 -2.0274 0 P 0 ;0
L 1.13993996 -2.0274 1.14191004 -2.02693002 0 P 0 ;0
L 1.14191004 -2.02693002 1.14391004 -2.02663002 0 P 0 ;0
L 1.14391004 -2.02663002 1.14935 -2.02626004 0 P 0 ;0
L 1.14935 -2.02626004 1.15471004 -2.0263 0 P 0 ;0
L 1.15471004 -2.0263 1.15591004 -2.02638996 0 P 0 ;0
L 1.15591004 -2.02638996 1.1571 -2.02656998 0 P 0 ;0
L 1.1571 -2.02656998 1.15828002 -2.02683996 0 P 0 ;0
L 1.15828002 -2.02683996 1.16085 -2.02753002 0 P 0 ;0
L 1.13876998 -2.14783002 1.20233002 -2.14783002 0 P 0 ;0
L 1.14236998 -2.14683002 1.20266004 -2.14683002 0 P 0 ;0
L 1.14481004 -2.14583002 1.20296004 -2.14583002 0 P 0 ;0
L 1.1467 -2.14483002 1.20325 -2.14483002 0 P 0 ;0
L 1.14826004 -2.14383002 1.20353002 -2.14383002 0 P 0 ;0
L 1.1496 -2.14283002 1.20373996 -2.14283002 0 P 0 ;0
L 1.15078996 -2.14183002 1.20395 -2.14183002 0 P 0 ;0
L 1.15186004 -2.14083002 1.20415 -2.14083002 0 P 0 ;0
L 1.15278996 -2.13983002 1.20431998 -2.13983002 0 P 0 ;0
L 1.15361998 -2.13883002 1.20446004 -2.13883002 0 P 0 ;0
L 1.15436004 -2.13783002 1.20458002 -2.13783002 0 P 0 ;0
L 1.155 -2.13683002 1.20466998 -2.13683002 0 P 0 ;0
L 1.15556998 -2.13583002 1.20475 -2.13583002 0 P 0 ;0
L 1.15608996 -2.13483002 1.20481998 -2.13483002 0 P 0 ;0
L 1.15653996 -2.13383002 1.20488996 -2.13383002 0 P 0 ;0
L 1.15691004 -2.13283002 1.20496004 -2.13283002 0 P 0 ;0
L 1.15723996 -2.13183002 1.20503002 -2.13183002 0 P 0 ;0
L 1.15751998 -2.13083002 1.2051 -2.13083002 0 P 0 ;0
L 1.15773002 -2.12983002 1.20516004 -2.12983002 0 P 0 ;0
L 1.15793002 -2.12883002 1.20523002 -2.12883002 0 P 0 ;0
L 1.15806004 -2.12783002 1.2053 -2.12783002 0 P 0 ;0
L 1.15816998 -2.12683002 1.20536998 -2.12683002 0 P 0 ;0
L 1.15821004 -2.12583002 1.20543996 -2.12583002 0 P 0 ;0
L 1.11716004 -2.12483002 1.12726004 -2.12483002 0 P 0 ;0
L 1.15823996 -2.12483002 1.20551004 -2.12483002 0 P 0 ;0
L 1.10911998 -2.12383002 1.1352 -2.12383002 0 P 0 ;0
L 1.15821998 -2.12383002 1.20556998 -2.12383002 0 P 0 ;0
L 1.10468996 -2.12283002 1.14018996 -2.12283002 0 P 0 ;0
L 1.1582 -2.12283002 1.20563996 -2.12283002 0 P 0 ;0
L 1.10131004 -2.12183002 1.14366998 -2.12183002 0 P 0 ;0
L 1.15818002 -2.12183002 1.2057 -2.12183002 0 P 0 ;0
L 1.15808996 -2.12083002 1.20576004 -2.12083002 0 P 0 ;0
L 1.15781004 -2.11983002 1.20583002 -2.11983002 0 P 0 ;0
L 1.15721004 -2.11883002 1.20588002 -2.11883002 0 P 0 ;0
L 1.14146004 -2.08883002 1.20758002 -2.08883002 0 P 0 ;0
L 1.14525 -2.08783002 1.20763002 -2.08783002 0 P 0 ;0
L 1.14751004 -2.08683002 1.20768002 -2.08683002 0 P 0 ;0
L 1.14928002 -2.08583002 1.20773002 -2.08583002 0 P 0 ;0
L 1.15073002 -2.08483002 1.20778996 -2.08483002 0 P 0 ;0
L 1.15196004 -2.08383002 1.20783996 -2.08383002 0 P 0 ;0
L 1.13818996 -2.08913002 1.13826998 -2.08913002 0 P 0 ;0
L 1.13826998 -2.08913002 1.13988002 -2.08903996 0 P 0 ;0
L 1.13988002 -2.08903996 1.13996004 -2.08903996 0 P 0 ;0
L 1.13996004 -2.08903996 1.14001004 -2.08903002 0 P 0 ;0
L 1.14001004 -2.08903002 1.14005 -2.08901998 0 P 0 ;0
L 1.14005 -2.08901998 1.14163002 -2.08881004 0 P 0 ;0
L 1.14163002 -2.08881004 1.14166998 -2.0888 0 P 0 ;0
L 1.14166998 -2.0888 1.14171004 -2.0888 0 P 0 ;0
L 1.14171004 -2.0888 1.14178996 -2.08878002 0 P 0 ;0
L 1.14178996 -2.08878002 1.14335 -2.08843002 0 P 0 ;0
L 1.14335 -2.08843002 1.14351004 -2.08838996 0 P 0 ;0
L 1.14351004 -2.08838996 1.14503002 -2.08791004 0 P 0 ;0
L 1.14503002 -2.08791004 1.14511004 -2.08788996 0 P 0 ;0
L 1.14511004 -2.08788996 1.14515 -2.08786998 0 P 0 ;0
L 1.14515 -2.08786998 1.14518996 -2.08786004 0 P 0 ;0
L 1.14518996 -2.08786004 1.14666004 -2.08725 0 P 0 ;0
L 1.14666004 -2.08725 1.14673996 -2.08721998 0 P 0 ;0
L 1.14673996 -2.08721998 1.14678002 -2.0872 0 P 0 ;0
L 1.14678002 -2.0872 1.14681998 -2.08718996 0 P 0 ;0
L 1.14681998 -2.08718996 1.14823996 -2.08646998 0 P 0 ;0
L 1.14823996 -2.08646998 1.14826998 -2.08645 0 P 0 ;0
L 1.14826998 -2.08645 1.14835 -2.08641004 0 P 0 ;0
L 1.14835 -2.08641004 1.14838002 -2.08638002 0 P 0 ;0
L 1.14838002 -2.08638002 1.14976004 -2.08553002 0 P 0 ;0
L 1.14976004 -2.08553002 1.14978996 -2.08551004 0 P 0 ;0
L 1.14978996 -2.08551004 1.14983002 -2.08548996 0 P 0 ;0
L 1.14983002 -2.08548996 1.14988996 -2.08543996 0 P 0 ;0
L 1.14988996 -2.08543996 1.1512 -2.08448996 0 P 0 ;0
L 1.1512 -2.08448996 1.15126004 -2.08443996 0 P 0 ;0
L 1.15126004 -2.08443996 1.15128996 -2.08441004 0 P 0 ;0
L 1.15128996 -2.08441004 1.15131998 -2.08438996 0 P 0 ;0
L 1.15131998 -2.08438996 1.15253996 -2.08333002 0 P 0 ;0
L 1.15253996 -2.08333002 1.15256998 -2.0833 0 P 0 ;0
L 1.15256998 -2.0833 1.1526 -2.08328002 0 P 0 ;0
L 1.1526 -2.08328002 1.15263002 -2.08323996 0 P 0 ;0
L 1.15263002 -2.08323996 1.15266004 -2.08321998 0 P 0 ;0
L 1.15266004 -2.08321998 1.15378996 -2.08206004 0 P 0 ;0
L 1.15378996 -2.08206004 1.15376004 -2.08203996 0 P 0 ;0
L 1.15376004 -2.08203996 1.15381998 -2.08203996 0 P 0 ;0
L 1.15381998 -2.08203996 1.15383996 -2.082 0 P 0 ;0
L 1.15383996 -2.082 1.15386998 -2.08196998 0 P 0 ;0
L 1.15386998 -2.08196998 1.1539 -2.08195 0 P 0 ;0
L 1.1539 -2.08195 1.15493002 -2.08071004 0 P 0 ;0
L 1.15493002 -2.08071004 1.15493002 -2.0807 0 P 0 ;0
L 1.15493002 -2.0807 1.15496004 -2.08066998 0 P 0 ;0
L 1.15496004 -2.08066998 1.15498002 -2.08063996 0 P 0 ;0
L 1.15498002 -2.08063996 1.15501004 -2.08061004 0 P 0 ;0
L 1.15501004 -2.08061004 1.15503002 -2.08058002 0 P 0 ;0
L 1.15503002 -2.08058002 1.15596004 -2.07926004 0 P 0 ;0
L 1.15596004 -2.07926004 1.15603996 -2.07913996 0 P 0 ;0
L 1.15603996 -2.07913996 1.15673002 -2.07798996 0 P 0 ;0
L 1.15673002 -2.07798996 1.15676998 -2.07793002 0 P 0 ;0
L 1.15676998 -2.07793002 1.15678996 -2.07786998 0 P 0 ;0
L 1.15678996 -2.07786998 1.15741004 -2.07668996 0 P 0 ;0
L 1.15741004 -2.07668996 1.15743996 -2.07663002 0 P 0 ;0
L 1.15743996 -2.07663002 1.15746004 -2.07656998 0 P 0 ;0
L 1.15746004 -2.07656998 1.15746998 -2.07656998 0 P 0 ;0
L 1.15746998 -2.07656998 1.158 -2.07533996 0 P 0 ;0
L 1.158 -2.07533996 1.15801004 -2.07531004 0 P 0 ;0
L 1.15801004 -2.07531004 1.15803002 -2.07528002 0 P 0 ;0
L 1.15803002 -2.07528002 1.15805 -2.07521998 0 P 0 ;0
L 1.15805 -2.07521998 1.15848996 -2.07396004 0 P 0 ;0
L 1.15848996 -2.07396004 1.15841004 -2.07393002 0 P 0 ;0
L 1.15841004 -2.07393002 1.15851004 -2.07393002 0 P 0 ;0
L 1.15851004 -2.07393002 1.15851998 -2.0739 0 P 0 ;0
L 1.15851998 -2.0739 1.15853002 -2.07386004 0 P 0 ;0
L 1.15853002 -2.07386004 1.15853996 -2.07383002 0 P 0 ;0
L 1.15853996 -2.07383002 1.15943996 -2.07061004 0 P 0 ;0
L 1.15943996 -2.07061004 1.15945 -2.07058002 0 P 0 ;0
L 1.15945 -2.07058002 1.15946004 -2.07053996 0 P 0 ;0
L 1.15946004 -2.07053996 1.15946998 -2.07051004 0 P 0 ;0
L 1.15946998 -2.07051004 1.15946998 -2.07046998 0 P 0 ;0
L 1.15946998 -2.07046998 1.16013996 -2.06723002 0 P 0 ;0
L 1.16013996 -2.06723002 1.16013996 -2.0672 0 P 0 ;0
L 1.16013996 -2.0672 1.16016004 -2.06713996 0 P 0 ;0
L 1.16016004 -2.06713996 1.16016004 -2.06711004 0 P 0 ;0
L 1.16016004 -2.06711004 1.16081998 -2.06256004 0 P 0 ;0
L 1.16081998 -2.06256004 1.16081998 -2.06253996 0 P 0 ;0
L 1.16081998 -2.06253996 1.16083002 -2.0625 0 P 0 ;0
L 1.16083002 -2.0625 1.16083002 -2.06246998 0 P 0 ;0
L 1.16083002 -2.06246998 1.16126998 -2.05791004 0 P 0 ;0
L 1.16126998 -2.05791004 1.16128002 -2.0579 0 P 0 ;0
L 1.16128002 -2.0579 1.16128002 -2.05783996 0 P 0 ;0
L 1.16128002 -2.05783996 1.1621 -2.04405 0 P 0 ;0
L 1.1621 -2.04405 1.1621 -2.04401998 0 P 0 ;0
L 1.1621 -2.04401998 1.16285 -2.02761998 0 P 0 ;0
L 1.16285 -2.02761998 1.16136998 -2.0256 0 P 0 ;0
L 1.16136998 -2.0256 1.15878996 -2.02491004 0 P 0 ;0
L 1.15878996 -2.02491004 1.15878002 -2.0249 0 P 0 ;0
L 1.15878002 -2.0249 1.15871998 -2.02488996 0 P 0 ;0
L 1.15871998 -2.02488996 1.15755 -2.02461998 0 P 0 ;0
L 1.15755 -2.02461998 1.15746998 -2.0246 0 P 0 ;0
L 1.15746998 -2.0246 1.1574 -2.0246 0 P 0 ;0
L 1.1574 -2.0246 1.15621004 -2.02441004 0 P 0 ;0
L 1.15621004 -2.02441004 1.15616998 -2.02441004 0 P 0 ;0
L 1.15616998 -2.02441004 1.1561 -2.0244 0 P 0 ;0
L 1.1561 -2.0244 1.15606004 -2.02438996 0 P 0 ;0
L 1.15606004 -2.02438996 1.15486004 -2.0243 0 P 0 ;0
L 1.15486004 -2.0243 1.15471998 -2.0243 0 P 0 ;0
L 1.15471998 -2.0243 1.14936004 -2.02426004 0 P 0 ;0
L 1.14936004 -2.02426004 1.14928996 -2.02426004 0 P 0 ;0
L 1.14928996 -2.02426004 1.14925 -2.02426998 0 P 0 ;0
L 1.14925 -2.02426998 1.14921004 -2.02426998 0 P 0 ;0
L 1.14921004 -2.02426998 1.14376998 -2.02463996 0 P 0 ;0
L 1.14376998 -2.02463996 1.1437 -2.02463996 0 P 0 ;0
L 1.1437 -2.02463996 1.14365 -2.02465 0 P 0 ;0
L 1.14365 -2.02465 1.14361004 -2.02465 0 P 0 ;0
L 1.14361004 -2.02465 1.14161998 -2.02495 0 P 0 ;0
L 1.14161998 -2.02495 1.14161004 -2.02495 0 P 0 ;0
L 1.14161004 -2.02495 1.14153002 -2.02496998 0 P 0 ;0
L 1.14153002 -2.02496998 1.14148996 -2.02496998 0 P 0 ;0
L 1.14148996 -2.02496998 1.14143996 -2.02498996 0 P 0 ;0
L 1.14143996 -2.02498996 1.13946998 -2.02545 0 P 0 ;0
L 1.13946998 -2.02545 1.13943996 -2.02546998 0 P 0 ;0
L 1.13943996 -2.02546998 1.1394 -2.02546998 0 P 0 ;0
L 1.1394 -2.02546998 1.13933002 -2.0255 0 P 0 ;0
L 1.13933002 -2.0255 1.13801004 -2.02591998 0 P 0 ;0
L 1.13801004 -2.02591998 1.13798002 -2.02593002 0 P 0 ;0
L 1.13798002 -2.02593002 1.13793996 -2.02593996 0 P 0 ;0
L 1.13793996 -2.02593996 1.13788002 -2.02596998 0 P 0 ;0
L 1.13788002 -2.02596998 1.1366 -2.02648002 0 P 0 ;0
L 1.1366 -2.02648002 1.13653996 -2.0265 0 P 0 ;0
L 1.13653996 -2.0265 1.13648002 -2.02653002 0 P 0 ;0
L 1.13648002 -2.02653002 1.13523996 -2.02713002 0 P 0 ;0
L 1.13523996 -2.02713002 1.13518002 -2.02716004 0 P 0 ;0
L 1.13518002 -2.02716004 1.13515 -2.02716998 0 P 0 ;0
L 1.13515 -2.02716998 1.13511998 -2.02718996 0 P 0 ;0
L 1.13511998 -2.02718996 1.13393002 -2.02786998 0 P 0 ;0
L 1.13393002 -2.02786998 1.13388996 -2.02788996 0 P 0 ;0
L 1.13388996 -2.02788996 1.1338 -2.02795 0 P 0 ;0
L 1.1338 -2.02795 1.13111998 -2.02976004 0 P 0 ;0
L 1.13111998 -2.02976004 1.13105 -2.02981004 0 P 0 ;0
L 1.13105 -2.02981004 1.13101004 -2.02983996 0 P 0 ;0
L 1.13101004 -2.02983996 1.13098002 -2.02986004 0 P 0 ;0
L 1.13098002 -2.02986004 1.12846998 -2.03188996 0 P 0 ;0
L 1.12846998 -2.03188996 1.12838002 -2.03198002 0 P 0 ;0
L 1.12838002 -2.03198002 1.12833996 -2.03201004 0 P 0 ;0
L 1.12833996 -2.03201004 1.12596004 -2.0343 0 P 0 ;0
L 1.12596004 -2.0343 1.12593996 -2.03433002 0 P 0 ;0
L 1.12593996 -2.03433002 1.1259 -2.03436004 0 P 0 ;0
L 1.1259 -2.03436004 1.12588002 -2.03438996 0 P 0 ;0
L 1.12588002 -2.03438996 1.12585 -2.03443002 0 P 0 ;0
L 1.12585 -2.03443002 1.12366998 -2.03691004 0 P 0 ;0
L 1.12366998 -2.03691004 1.12363996 -2.03695 0 P 0 ;0
L 1.12363996 -2.03695 1.12361998 -2.03698002 0 P 0 ;0
L 1.12361998 -2.03698002 1.12358996 -2.03701004 0 P 0 ;0
L 1.12358996 -2.03701004 1.12356998 -2.03703996 0 P 0 ;0
L 1.12356998 -2.03703996 1.12236998 -2.03865 0 P 0 ;0
L 1.12236998 -2.03865 1.12233996 -2.03868996 0 P 0 ;0
L 1.12233996 -2.03868996 1.12233002 -2.03871004 0 P 0 ;0
L 1.12233002 -2.03871004 1.12228996 -2.03878002 0 P 0 ;0
L 1.12228996 -2.03878002 1.12121004 -2.04046998 0 P 0 ;0
L 1.12121004 -2.04046998 1.12118996 -2.0405 0 P 0 ;0
L 1.12118996 -2.0405 1.12116998 -2.04053996 0 P 0 ;0
L 1.12116998 -2.04053996 1.12115 -2.04056998 0 P 0 ;0
L 1.12115 -2.04056998 1.12113996 -2.04061004 0 P 0 ;0
L 1.12113996 -2.04061004 1.12018996 -2.04238002 0 P 0 ;0
L 1.12018996 -2.04238002 1.12016004 -2.04245 0 P 0 ;0
L 1.12016004 -2.04245 1.12013996 -2.04248002 0 P 0 ;0
L 1.12013996 -2.04248002 1.12013002 -2.04251004 0 P 0 ;0
L 1.12013002 -2.04251004 1.11926004 -2.04446998 0 P 0 ;0
L 1.11926004 -2.04446998 1.11925 -2.0445 0 P 0 ;0
L 1.11925 -2.0445 1.11923002 -2.04453996 0 P 0 ;0
L 1.11923002 -2.04453996 1.11921998 -2.04458002 0 P 0 ;0
L 1.11921998 -2.04458002 1.11921004 -2.04461004 0 P 0 ;0
L 1.11921004 -2.04461004 1.11848002 -2.04663002 0 P 0 ;0
L 1.11848002 -2.04663002 1.11846998 -2.04666004 0 P 0 ;0
L 1.11846998 -2.04666004 1.11846004 -2.0467 0 P 0 ;0
L 1.11846004 -2.0467 1.11843996 -2.04676998 0 P 0 ;0
L 1.11843996 -2.04676998 1.11786004 -2.04883996 0 P 0 ;0
L 1.11786004 -2.04883996 1.11785 -2.04886998 0 P 0 ;0
L 1.11785 -2.04886998 1.11783996 -2.04891004 0 P 0 ;0
L 1.11783996 -2.04891004 1.11783996 -2.04893996 0 P 0 ;0
L 1.11783996 -2.04893996 1.11783002 -2.04896998 0 P 0 ;0
L 1.11783002 -2.04896998 1.11783002 -2.04898002 0 P 0 ;0
L 1.11783002 -2.04898002 1.1174 -2.05108002 0 P 0 ;0
L 1.1174 -2.05108002 1.1174 -2.05111998 0 P 0 ;0
L 1.1174 -2.05111998 1.11738996 -2.05116004 0 P 0 ;0
L 1.11738996 -2.05116004 1.11738002 -2.05118996 0 P 0 ;0
L 1.11738002 -2.05118996 1.11738002 -2.05123002 0 P 0 ;0
L 1.11738002 -2.05123002 1.11673002 -2.05643002 0 P 0 ;0
L 1.11673002 -2.05643002 1.11671998 -2.05646998 0 P 0 ;0
L 1.11671998 -2.05646998 1.11671998 -2.05655 0 P 0 ;0
L 1.11671998 -2.05655 1.11671004 -2.05658996 0 P 0 ;0
L 1.11671004 -2.05658996 1.11648996 -2.06181998 0 P 0 ;0
L 1.11648996 -2.06181998 1.11648002 -2.06186998 0 P 0 ;0
L 1.11648002 -2.06186998 1.11648002 -2.06195 0 P 0 ;0
L 1.11648002 -2.06195 1.11648996 -2.06198996 0 P 0 ;0
L 1.11648996 -2.06198996 1.11668002 -2.06696998 0 P 0 ;0
L 1.11668002 -2.06696998 1.11768002 -2.06696998 0 P 0 ;0
L 1.11768002 -2.06696998 1.11668002 -2.06701004 0 P 0 ;0
L 1.11668002 -2.06701004 1.11668002 -2.06713002 0 P 0 ;0
L 1.11668002 -2.06713002 1.11668996 -2.06716998 0 P 0 ;0
L 1.11668996 -2.06716998 1.11728002 -2.07215 0 P 0 ;0
L 1.11728002 -2.07215 1.11728996 -2.07218996 0 P 0 ;0
L 1.11728996 -2.07218996 1.11728996 -2.07223002 0 P 0 ;0
L 1.11728996 -2.07223002 1.11731004 -2.07231004 0 P 0 ;0
L 1.11731004 -2.07231004 1.11758996 -2.07371004 0 P 0 ;0
L 1.11758996 -2.07371004 1.1176 -2.07375 0 P 0 ;0
L 1.1176 -2.07375 1.11761004 -2.0738 0 P 0 ;0
L 1.11761004 -2.0738 1.11761998 -2.07383996 0 P 0 ;0
L 1.11761998 -2.07383996 1.11763996 -2.07388002 0 P 0 ;0
L 1.11763996 -2.07388002 1.11803996 -2.07523996 0 P 0 ;0
L 1.11803996 -2.07523996 1.11806004 -2.07531998 0 P 0 ;0
L 1.11806004 -2.07531998 1.11808002 -2.07536004 0 P 0 ;0
L 1.11808002 -2.07536004 1.11808996 -2.07541004 0 P 0 ;0
L 1.11808996 -2.07541004 1.11861004 -2.07673002 0 P 0 ;0
L 1.11861004 -2.07673002 1.11863996 -2.07681004 0 P 0 ;0
L 1.11863996 -2.07681004 1.11866004 -2.07683996 0 P 0 ;0
L 1.11866004 -2.07683996 1.11868002 -2.07688002 0 P 0 ;0
L 1.11868002 -2.07688002 1.11931004 -2.07815 0 P 0 ;0
L 1.11931004 -2.07815 1.11935 -2.07823002 0 P 0 ;0
L 1.11935 -2.07823002 1.1194 -2.0783 0 P 0 ;0
L 1.1194 -2.0783 1.12013996 -2.07951998 0 P 0 ;0
L 1.12013996 -2.07951998 1.12021004 -2.07961998 0 P 0 ;0
L 1.12021004 -2.07961998 1.12023002 -2.07965 0 P 0 ;0
L 1.12023002 -2.07965 1.12023002 -2.07966004 0 P 0 ;0
L 1.12023002 -2.07966004 1.1212 -2.08096998 0 P 0 ;0
L 1.1212 -2.08096998 1.12123996 -2.08103002 0 P 0 ;0
L 1.12123996 -2.08103002 1.12126998 -2.08106004 0 P 0 ;0
L 1.12126998 -2.08106004 1.12128996 -2.08108996 0 P 0 ;0
L 1.12128996 -2.08108996 1.12235 -2.08231004 0 P 0 ;0
L 1.12235 -2.08231004 1.12238002 -2.08233996 0 P 0 ;0
L 1.12238002 -2.08233996 1.1224 -2.08236998 0 P 0 ;0
L 1.1224 -2.08236998 1.12246004 -2.08243002 0 P 0 ;0
L 1.12246004 -2.08243002 1.12361004 -2.08355 0 P 0 ;0
L 1.12361004 -2.08355 1.12366998 -2.08361004 0 P 0 ;0
L 1.12366998 -2.08361004 1.1237 -2.08363002 0 P 0 ;0
L 1.1237 -2.08363002 1.12373002 -2.08366004 0 P 0 ;0
L 1.12373002 -2.08366004 1.12496998 -2.08468996 0 P 0 ;0
L 1.12496998 -2.08468996 1.125 -2.08471004 0 P 0 ;0
L 1.125 -2.08471004 1.12503002 -2.08473996 0 P 0 ;0
L 1.12503002 -2.08473996 1.12506998 -2.08476004 0 P 0 ;0
L 1.12506998 -2.08476004 1.1251 -2.08478996 0 P 0 ;0
L 1.1251 -2.08478996 1.12641998 -2.08571004 0 P 0 ;0
L 1.12641998 -2.08571004 1.12645 -2.08573002 0 P 0 ;0
L 1.12645 -2.08573002 1.12648002 -2.08576004 0 P 0 ;0
L 1.12648002 -2.08576004 1.12651004 -2.08578002 0 P 0 ;0
L 1.12651004 -2.08578002 1.12655 -2.0858 0 P 0 ;0
L 1.12655 -2.0858 1.12793996 -2.08661004 0 P 0 ;0
L 1.12793996 -2.08661004 1.12801004 -2.08665 0 P 0 ;0
L 1.12801004 -2.08665 1.12805 -2.08666998 0 P 0 ;0
L 1.12805 -2.08666998 1.12808002 -2.08668996 0 P 0 ;0
L 1.12808002 -2.08668996 1.12808996 -2.08668996 0 P 0 ;0
L 1.12808996 -2.08668996 1.12953996 -2.08738996 0 P 0 ;0
L 1.12953996 -2.08738996 1.12961998 -2.08743002 0 P 0 ;0
L 1.12961998 -2.08743002 1.12965 -2.08743996 0 P 0 ;0
L 1.12965 -2.08743996 1.1297 -2.08746004 0 P 0 ;0
L 1.1297 -2.08746004 1.13118002 -2.08801998 0 P 0 ;0
L 1.13118002 -2.08801998 1.13133996 -2.08808002 0 P 0 ;0
L 1.13133996 -2.08808002 1.13286998 -2.08851004 0 P 0 ;0
L 1.13286998 -2.08851004 1.13295 -2.08853996 0 P 0 ;0
L 1.13295 -2.08853996 1.13303996 -2.08855 0 P 0 ;0
L 1.13303996 -2.08855 1.1346 -2.08886004 0 P 0 ;0
L 1.1346 -2.08886004 1.13471998 -2.08888996 0 P 0 ;0
L 1.13471998 -2.08888996 1.13476004 -2.08888996 0 P 0 ;0
L 1.13476004 -2.08888996 1.13633996 -2.08906998 0 P 0 ;0
L 1.13633996 -2.08906998 1.13638996 -2.08908002 0 P 0 ;0
L 1.13638996 -2.08908002 1.13651004 -2.08908002 0 P 0 ;0
L 1.13651004 -2.08908002 1.1381 -2.08913002 0 P 0 ;0
L 1.1381 -2.08913002 1.13818996 -2.08913002 0 P 0 ;0
L 1.31623996 -1.98923996 1.3135 -1.98988002 0 P 0 ;0
L 1.3135 -1.98988002 1.31078996 -1.99071004 0 P 0 ;0
L 1.31078996 -1.99071004 1.30813002 -1.99175 0 P 0 ;0
L 1.30813002 -1.99175 1.30553996 -1.99296998 0 P 0 ;0
L 1.30553996 -1.99296998 1.30308996 -1.99431998 0 P 0 ;0
L 1.30308996 -1.99431998 1.30073996 -1.99585 0 P 0 ;0
L 1.30073996 -1.99585 1.29863996 -1.99746004 0 P 0 ;0
L 1.29863996 -1.99746004 1.29666004 -1.99923996 0 P 0 ;0
L 1.29666004 -1.99923996 1.29205 -2.00375 0 P 0 ;0
L 1.29205 -2.00375 1.29205 -1.99243996 0 P 0 ;0
L 1.29205 -1.99243996 1.24316004 -1.99243996 0 P 0 ;0
L 1.24316004 -1.99243996 1.24313996 -2.00521004 0 P 0 ;0
L 1.24313996 -2.00521004 1.24261004 -2.03151004 0 P 0 ;0
L 1.24261004 -2.03151004 1.24086998 -2.07046004 0 P 0 ;0
L 1.24086998 -2.07046004 1.23873996 -2.10921004 0 P 0 ;0
L 1.23873996 -2.10921004 1.23811998 -2.11641998 0 P 0 ;0
L 1.23811998 -2.11641998 1.23711998 -2.12361998 0 P 0 ;0
L 1.23711998 -2.12361998 1.23655 -2.12716004 0 P 0 ;0
L 1.23655 -2.12716004 1.29205 -2.12716004 0 P 0 ;0
L 1.29205 -2.12716004 1.29206998 -2.11766004 0 P 0 ;0
L 1.29206998 -2.11766004 1.29238996 -2.10283996 0 P 0 ;0
L 1.29238996 -2.10283996 1.29336004 -2.08431004 0 P 0 ;0
L 1.29336004 -2.08431004 1.29463996 -2.06673002 0 P 0 ;0
L 1.29463996 -2.06673002 1.29511004 -2.06253002 0 P 0 ;0
L 1.29511004 -2.06253002 1.29583996 -2.05836004 0 P 0 ;0
L 1.29583996 -2.05836004 1.29683002 -2.05446998 0 P 0 ;0
L 1.29683002 -2.05446998 1.29813996 -2.05068996 0 P 0 ;0
L 1.29813996 -2.05068996 1.29978002 -2.04701998 0 P 0 ;0
L 1.29978002 -2.04701998 1.30056998 -2.04556998 0 P 0 ;0
L 1.30056998 -2.04556998 1.30146998 -2.04418996 0 P 0 ;0
L 1.30146998 -2.04418996 1.30246998 -2.04288002 0 P 0 ;0
L 1.30246998 -2.04288002 1.30356998 -2.04165 0 P 0 ;0
L 1.30356998 -2.04165 1.30475 -2.0405 0 P 0 ;0
L 1.30475 -2.0405 1.30603996 -2.03945 0 P 0 ;0
L 1.30603996 -2.03945 1.30773996 -2.03826004 0 P 0 ;0
L 1.30773996 -2.03826004 1.30953002 -2.03723002 0 P 0 ;0
L 1.30953002 -2.03723002 1.31141004 -2.03635 0 P 0 ;0
L 1.31141004 -2.03635 1.31335 -2.03563002 0 P 0 ;0
L 1.31335 -2.03563002 1.31535 -2.03508002 0 P 0 ;0
L 1.31535 -2.03508002 1.31973996 -2.03423002 0 P 0 ;0
L 1.31973996 -2.03423002 1.32416004 -2.03366998 0 P 0 ;0
L 1.32416004 -2.03366998 1.32863002 -2.0334 0 P 0 ;0
L 1.32863002 -2.0334 1.33688002 -2.03318002 0 P 0 ;0
L 1.33688002 -2.03318002 1.33613002 -2.01151004 0 P 0 ;0
L 1.33613002 -2.01151004 1.33581004 -2.00315 0 P 0 ;0
L 1.33581004 -2.00315 1.33543996 -1.99596004 0 P 0 ;0
L 1.33543996 -1.99596004 1.33508002 -1.98971004 0 P 0 ;0
L 1.33508002 -1.98971004 1.33503996 -1.98945 0 P 0 ;0
L 1.33503996 -1.98945 1.335 -1.98931998 0 P 0 ;0
L 1.335 -1.98931998 1.33496004 -1.9892 0 P 0 ;0
L 1.33496004 -1.9892 1.3349 -1.98908002 0 P 0 ;0
L 1.3349 -1.98908002 1.33483996 -1.98896998 0 P 0 ;0
L 1.33483996 -1.98896998 1.33476998 -1.98886004 0 P 0 ;0
L 1.33476998 -1.98886004 1.33468996 -1.98876004 0 P 0 ;0
L 1.33468996 -1.98876004 1.3346 -1.98866998 0 P 0 ;0
L 1.3346 -1.98866998 1.33451004 -1.98858996 0 P 0 ;0
L 1.33451004 -1.98858996 1.3344 -1.98851998 0 P 0 ;0
L 1.3344 -1.98851998 1.3343 -1.98845 0 P 0 ;0
L 1.3343 -1.98845 1.33418002 -1.98838996 0 P 0 ;0
L 1.33418002 -1.98838996 1.33406998 -1.98833996 0 P 0 ;0
L 1.33406998 -1.98833996 1.33395 -1.9883 0 P 0 ;0
L 1.33395 -1.9883 1.33383002 -1.98828002 0 P 0 ;0
L 1.33383002 -1.98828002 1.3337 -1.98826004 0 P 0 ;0
L 1.3337 -1.98826004 1.33356998 -1.98825 0 P 0 ;0
L 1.33356998 -1.98825 1.32756998 -1.98823002 0 P 0 ;0
L 1.32756998 -1.98823002 1.32135 -1.98853996 0 P 0 ;0
L 1.32135 -1.98853996 1.31878996 -1.98881998 0 P 0 ;0
L 1.31878996 -1.98881998 1.31623996 -1.98923996 0 P 0 ;0
L 1.2389 -2.12516004 1.29006004 -2.12516004 0 P 0 ;0
L 1.23906998 -2.12416004 1.29006004 -2.12416004 0 P 0 ;0
L 1.23921004 -2.12316004 1.29006004 -2.12316004 0 P 0 ;0
L 1.23933996 -2.12216004 1.29006004 -2.12216004 0 P 0 ;0
L 1.23948996 -2.12116004 1.29006004 -2.12116004 0 P 0 ;0
L 1.23961998 -2.12016004 1.29006998 -2.12016004 0 P 0 ;0
L 1.23976004 -2.11916004 1.29006998 -2.11916004 0 P 0 ;0
L 1.2399 -2.11816004 1.29006998 -2.11816004 0 P 0 ;0
L 1.24003996 -2.11716004 1.29008002 -2.11716004 0 P 0 ;0
L 1.24015 -2.11616004 1.2901 -2.11616004 0 P 0 ;0
L 1.24023996 -2.11516004 1.29011998 -2.11516004 0 P 0 ;0
L 1.24033002 -2.11416004 1.29013996 -2.11416004 0 P 0 ;0
L 1.24041004 -2.11316004 1.29016004 -2.11316004 0 P 0 ;0
L 1.24048996 -2.11216004 1.29018996 -2.11216004 0 P 0 ;0
L 1.24058002 -2.11116004 1.29021004 -2.11116004 0 P 0 ;0
L 1.24066998 -2.11016004 1.29023002 -2.11016004 0 P 0 ;0
L 1.24075 -2.10916004 1.29025 -2.10916004 0 P 0 ;0
L 1.2408 -2.10816004 1.29026998 -2.10816004 0 P 0 ;0
L 1.24086004 -2.10716004 1.29028996 -2.10716004 0 P 0 ;0
L 1.24091004 -2.10616004 1.29031998 -2.10616004 0 P 0 ;0
L 1.24096998 -2.10516004 1.29033996 -2.10516004 0 P 0 ;0
L 1.24101998 -2.10416004 1.29036004 -2.10416004 0 P 0 ;0
L 1.24108002 -2.10316004 1.29038002 -2.10316004 0 P 0 ;0
L 1.24113002 -2.10216004 1.29041998 -2.10216004 0 P 0 ;0
L 1.24118002 -2.10116004 1.29046998 -2.10116004 0 P 0 ;0
L 1.24123996 -2.10016004 1.29053002 -2.10016004 0 P 0 ;0
L 1.24128996 -2.09916004 1.29058002 -2.09916004 0 P 0 ;0
L 1.24135 -2.09816004 1.29063002 -2.09816004 0 P 0 ;0
L 1.2414 -2.09716004 1.29068002 -2.09716004 0 P 0 ;0
L 1.24146004 -2.09616004 1.29073996 -2.09616004 0 P 0 ;0
L 1.24151004 -2.09516004 1.29078996 -2.09516004 0 P 0 ;0
L 1.24156998 -2.09416004 1.29083996 -2.09416004 0 P 0 ;0
L 1.24161998 -2.09316004 1.2909 -2.09316004 0 P 0 ;0
L 1.24168002 -2.09216004 1.29095 -2.09216004 0 P 0 ;0
L 1.24173002 -2.09116004 1.291 -2.09116004 0 P 0 ;0
L 1.24178996 -2.09016004 1.29105 -2.09016004 0 P 0 ;0
L 1.24183996 -2.08916004 1.2911 -2.08916004 0 P 0 ;0
L 1.2419 -2.08816004 1.29116004 -2.08816004 0 P 0 ;0
L 1.24196004 -2.08716004 1.29121004 -2.08716004 0 P 0 ;0
L 1.24201004 -2.08616004 1.29126998 -2.08616004 0 P 0 ;0
L 1.24206998 -2.08516004 1.29131998 -2.08516004 0 P 0 ;0
L 1.24211998 -2.08416004 1.29136998 -2.08416004 0 P 0 ;0
L 1.2389 -2.12516004 1.2391 -2.12393002 0 P 0 ;0
L 1.2391 -2.12393002 1.2391 -2.1239 0 P 0 ;0
L 1.2391 -2.1239 1.24011004 -2.11665 0 P 0 ;0
L 1.24011004 -2.11665 1.24073002 -2.10935 0 P 0 ;0
L 1.24073002 -2.10935 1.24073996 -2.10931998 0 P 0 ;0
L 1.24073996 -2.10931998 1.24286004 -2.07056004 0 P 0 ;0
L 1.24286004 -2.07056004 1.24461004 -2.03158002 0 P 0 ;0
L 1.24461004 -2.03158002 1.24513996 -2.00523002 0 P 0 ;0
L 1.24513996 -2.00523002 1.24515 -1.99443996 0 P 0 ;0
L 1.24515 -1.99443996 1.29005 -1.99443996 0 P 0 ;0
L 1.29005 -1.99443996 1.29005 -2.00375 0 P 0 ;0
L 1.29005 -2.00375 1.29128002 -2.0056 0 P 0 ;0
L 1.29128002 -2.0056 1.29345 -2.00518002 0 P 0 ;0
L 1.29345 -2.00518002 1.29803002 -2.0007 0 P 0 ;0
L 1.29803002 -2.0007 1.29991998 -1.999 0 P 0 ;0
L 1.29991998 -1.999 1.30188996 -1.99748996 0 P 0 ;0
L 1.30188996 -1.99748996 1.30411998 -1.99603996 0 P 0 ;0
L 1.30411998 -1.99603996 1.30645 -1.99475 0 P 0 ;0
L 1.30645 -1.99475 1.30891998 -1.99358996 0 P 0 ;0
L 1.30891998 -1.99358996 1.31145 -1.9926 0 P 0 ;0
L 1.31145 -1.9926 1.31401998 -1.99181004 0 P 0 ;0
L 1.31401998 -1.99181004 1.31663996 -1.9912 0 P 0 ;0
L 1.31663996 -1.9912 1.31906004 -1.9908 0 P 0 ;0
L 1.31906004 -1.9908 1.32151004 -1.99053002 0 P 0 ;0
L 1.32151004 -1.99053002 1.32761998 -1.99023002 0 P 0 ;0
L 1.32761998 -1.99023002 1.3331 -1.99025 0 P 0 ;0
L 1.3331 -1.99025 1.33345 -1.99608002 0 P 0 ;0
L 1.33345 -1.99608002 1.33381004 -2.00323002 0 P 0 ;0
L 1.33381004 -2.00323002 1.33413002 -2.01158996 0 P 0 ;0
L 1.33413002 -2.01158996 1.33413002 -2.0116 0 P 0 ;0
L 1.33413002 -2.0116 1.33481998 -2.03123002 0 P 0 ;0
L 1.33481998 -2.03123002 1.32853996 -2.0314 0 P 0 ;0
L 1.32853996 -2.0314 1.32398002 -2.03166998 0 P 0 ;0
L 1.32398002 -2.03166998 1.31941998 -2.03225 0 P 0 ;0
L 1.31941998 -2.03225 1.31488996 -2.03313002 0 P 0 ;0
L 1.31488996 -2.03313002 1.31273996 -2.03373002 0 P 0 ;0
L 1.31273996 -2.03373002 1.31063996 -2.0345 0 P 0 ;0
L 1.31063996 -2.0345 1.3086 -2.03545 0 P 0 ;0
L 1.3086 -2.03545 1.30666004 -2.03656998 0 P 0 ;0
L 1.30666004 -2.03656998 1.30658996 -2.03661998 0 P 0 ;0
L 1.30658996 -2.03661998 1.30483002 -2.03786004 0 P 0 ;0
L 1.30483002 -2.03786004 1.30341998 -2.03901004 0 P 0 ;0
L 1.30341998 -2.03901004 1.30336998 -2.03906004 0 P 0 ;0
L 1.30336998 -2.03906004 1.30211998 -2.04026004 0 P 0 ;0
L 1.30211998 -2.04026004 1.30093002 -2.0416 0 P 0 ;0
L 1.30093002 -2.0416 1.29983002 -2.04303996 0 P 0 ;0
L 1.29983002 -2.04303996 1.29978996 -2.0431 0 P 0 ;0
L 1.29978996 -2.0431 1.29885 -2.04453996 0 P 0 ;0
L 1.29885 -2.04453996 1.29798996 -2.04613002 0 P 0 ;0
L 1.29798996 -2.04613002 1.29631998 -2.04986998 0 P 0 ;0
L 1.29631998 -2.04986998 1.29628002 -2.04995 0 P 0 ;0
L 1.29628002 -2.04995 1.29625 -2.05003002 0 P 0 ;0
L 1.29625 -2.05003002 1.29491998 -2.0539 0 P 0 ;0
L 1.29491998 -2.0539 1.29388996 -2.05793996 0 P 0 ;0
L 1.29388996 -2.05793996 1.29386998 -2.05801998 0 P 0 ;0
L 1.29386998 -2.05801998 1.29313996 -2.06221004 0 P 0 ;0
L 1.29313996 -2.06221004 1.29313002 -2.06223996 0 P 0 ;0
L 1.29313002 -2.06223996 1.29311998 -2.0623 0 P 0 ;0
L 1.29311998 -2.0623 1.29265 -2.06655 0 P 0 ;0
L 1.29265 -2.06655 1.29136998 -2.08418996 0 P 0 ;0
L 1.29136998 -2.08418996 1.29038996 -2.10276998 0 P 0 ;0
L 1.29038996 -2.10276998 1.29006998 -2.11763002 0 P 0 ;0
L 1.29006998 -2.11763002 1.29006004 -2.12516004 0 P 0 ;0
L 1.29006004 -2.12516004 1.2389 -2.12516004 0 P 0 ;0
L 1.09846998 -2.00483002 1.21248002 -2.00483002 0 P 0 ;0
L 1.09838002 -2.12083002 1.14708002 -2.12083002 0 P 0 ;0
L 1.11933002 -2.18283002 1.15161998 -2.18283002 0 P 0 ;0
L 1.11001998 -2.18183002 1.15838002 -2.18183002 0 P 0 ;0
L 1.10246998 -2.18083002 1.16333996 -2.18083002 0 P 0 ;0
L 1.04061004 -1.89731004 1.09978002 -1.89731004 0 P 0 ;0
L 1.03565 -1.89631004 1.09821004 -1.89631004 0 P 0 ;0
L 1.03068996 -1.89531004 1.09661004 -1.89531004 0 P 0 ;0
L 1.02573002 -1.89431004 1.09475 -1.89431004 0 P 0 ;0
L 1.019 -1.89331004 1.09288002 -1.89331004 0 P 0 ;0
L 1.01163996 -1.89231004 1.09101998 -1.89231004 0 P 0 ;0
L 0.99518996 -1.89131004 1.08916004 -1.89131004 0 P 0 ;0
L 0.87011998 -1.88331004 1.07278996 -1.88331004 0 P 0 ;0
L 0.86963996 -1.88231004 1.07053002 -1.88231004 0 P 0 ;0
L 0.86916004 -1.88131004 1.06828002 -1.88131004 0 P 0 ;0
L 0.86863002 -1.88031004 1.06603002 -1.88031004 0 P 0 ;0
L 0.86806998 -1.87931004 1.06351004 -1.87931004 0 P 0 ;0
L 0.8675 -1.87831004 1.06076998 -1.87831004 0 P 0 ;0
L 0.86693002 -1.87731004 1.05803996 -1.87731004 0 P 0 ;0
L 0.86631004 -1.87631004 1.05531004 -1.87631004 0 P 0 ;0
L 0.86563996 -1.87531004 1.05256998 -1.87531004 0 P 0 ;0
L 0.86498002 -1.87431004 1.04983996 -1.87431004 0 P 0 ;0
L 0.86431998 -1.87331004 1.0471 -1.87331004 0 P 0 ;0
L 0.86356004 -1.87231004 1.04376004 -1.87231004 0 P 0 ;0
L 0.86278996 -1.87131004 1.04041998 -1.87131004 0 P 0 ;0
L 0.86203002 -1.87031004 1.03708002 -1.87031004 0 P 0 ;0
L 0.86118996 -1.86931004 1.03373996 -1.86931004 0 P 0 ;0
L 0.8603 -1.86831004 1.0304 -1.86831004 0 P 0 ;0
L 0.85941004 -1.86731004 1.02656998 -1.86731004 0 P 0 ;0
L 0.8585 -1.86631004 1.02231998 -1.86631004 0 P 0 ;0
L 0.85756998 -1.86531004 1.01806998 -1.86531004 0 P 0 ;0
L 0.85663002 -1.86431004 1.01381998 -1.86431004 0 P 0 ;0
L 0.85568996 -1.86331004 1.00931998 -1.86331004 0 P 0 ;0
L 0.85481004 -1.86231004 1.00335 -1.86231004 0 P 0 ;0
L 0.85916998 -1.86131004 0.99738002 -1.86131004 0 P 0 ;0
L 0.86716998 -1.86031004 0.99141998 -1.86031004 0 P 0 ;0
L 0.87476998 -1.89731004 0.89943002 -1.89731004 0 P 0 ;0
L 0.87453996 -1.89631004 0.90426004 -1.89631004 0 P 0 ;0
L 0.87431004 -1.89531004 0.9097 -1.89531004 0 P 0 ;0
L 0.87406998 -1.89431004 0.91608002 -1.89431004 0 P 0 ;0
L 0.87383002 -1.89331004 0.92246004 -1.89331004 0 P 0 ;0
L 0.87355 -1.89231004 0.93086004 -1.89231004 0 P 0 ;0
L 0.87323002 -1.89131004 0.95553002 -1.89131004 0 P 0 ;0
L 0.87291004 -1.89031004 1.08728996 -1.89031004 0 P 0 ;0
L 0.87258996 -1.88931004 1.08543002 -1.88931004 0 P 0 ;0
L 0.87223002 -1.88831004 1.08356998 -1.88831004 0 P 0 ;0
L 0.87183002 -1.88731004 1.0817 -1.88731004 0 P 0 ;0
L 0.87143002 -1.88631004 1.07955 -1.88631004 0 P 0 ;0
L 0.87103002 -1.88531004 1.07728996 -1.88531004 0 P 0 ;0
L 0.8706 -1.88431004 1.07503996 -1.88431004 0 P 0 ;0
L 0.87525 -1.85931004 0.98545 -1.85931004 0 P 0 ;0
L 0.88421004 -1.85831004 0.97621004 -1.85831004 0 P 0 ;0
L 0.89393002 -1.85731004 0.96606998 -1.85731004 0 P 0 ;0
L 0.9106 -1.85631004 0.95203002 -1.85631004 0 P 0 ;0
L 1.08716004 -1.91231004 1.12151004 -1.91231004 0 P 0 ;0
L 1.08486004 -1.91131004 1.12018996 -1.91131004 0 P 0 ;0
L 1.08256004 -1.91031004 1.11886004 -1.91031004 0 P 0 ;0
L 1.08023002 -1.90931004 1.11753996 -1.90931004 0 P 0 ;0
L 1.07738002 -1.90831004 1.11621004 -1.90831004 0 P 0 ;0
L 1.07453002 -1.90731004 1.11488996 -1.90731004 0 P 0 ;0
L 1.07168996 -1.90631004 1.11356998 -1.90631004 0 P 0 ;0
L 1.06883996 -1.90531004 1.11223996 -1.90531004 0 P 0 ;0
L 1.066 -1.90431004 1.11076998 -1.90431004 0 P 0 ;0
L 1.06315 -1.90331004 1.1092 -1.90331004 0 P 0 ;0
L 1.0599 -1.90231004 1.10763002 -1.90231004 0 P 0 ;0
L 1.05611998 -1.90131004 1.10606004 -1.90131004 0 P 0 ;0
L 1.05235 -1.90031004 1.10448996 -1.90031004 0 P 0 ;0
L 1.04856998 -1.89931004 1.10291998 -1.89931004 0 P 0 ;0
L 1.04478996 -1.89831004 1.10135 -1.89831004 0 P 0 ;0
L 0.98815 -2.08316004 1.03726998 -2.08316004 0 P 0 ;0
L 0.98818002 -2.08216004 1.03731004 -2.08216004 0 P 0 ;0
L 0.98821998 -2.08116004 1.03735 -2.08116004 0 P 0 ;0
L 0.98825 -2.08016004 1.03738996 -2.08016004 0 P 0 ;0
L 0.98828002 -2.07916004 1.03743002 -2.07916004 0 P 0 ;0
L 0.98831998 -2.07816004 1.03746998 -2.07816004 0 P 0 ;0
L 0.98835 -2.07716004 1.03751004 -2.07716004 0 P 0 ;0
L 0.98838002 -2.07616004 1.03755 -2.07616004 0 P 0 ;0
L 0.98841998 -2.07516004 1.03758002 -2.07516004 0 P 0 ;0
L 0.98845 -2.07416004 1.03761004 -2.07416004 0 P 0 ;0
L 0.98848002 -2.07316004 1.03763996 -2.07316004 0 P 0 ;0
L 0.98851004 -2.07216004 1.03768002 -2.07216004 0 P 0 ;0
L 0.98855 -2.07116004 1.03771004 -2.07116004 0 P 0 ;0
L 0.98858002 -2.07016004 1.03773996 -2.07016004 0 P 0 ;0
L 0.98858996 -2.06916004 1.03776998 -2.06916004 0 P 0 ;0
L 0.98858996 -2.06816004 1.0378 -2.06816004 0 P 0 ;0
L 0.98858996 -2.06716004 1.03783002 -2.06716004 0 P 0 ;0
L 0.98858002 -2.06616004 1.03786004 -2.06616004 0 P 0 ;0
L 0.98856998 -2.06516004 1.0379 -2.06516004 0 P 0 ;0
L 0.98856998 -2.06416004 1.03793002 -2.06416004 0 P 0 ;0
L 0.98856998 -2.06316004 1.03796004 -2.06316004 0 P 0 ;0
L 0.98856004 -2.06216004 1.03798996 -2.06216004 0 P 0 ;0
L 0.98855 -2.06116004 1.03801998 -2.06116004 0 P 0 ;0
L 0.98855 -2.06016004 1.03805 -2.06016004 0 P 0 ;0
L 0.98853996 -2.05916004 1.03808002 -2.05916004 0 P 0 ;0
L 0.98853996 -2.05816004 1.0381 -2.05816004 0 P 0 ;0
L 0.98853002 -2.05716004 1.03811998 -2.05716004 0 P 0 ;0
L 0.98848002 -2.05616004 1.03815 -2.05616004 0 P 0 ;0
L 0.98841004 -2.05516004 1.03818002 -2.05516004 0 P 0 ;0
L 0.98835 -2.05416004 1.0382 -2.05416004 0 P 0 ;0
L 0.98828002 -2.05316004 1.03821998 -2.05316004 0 P 0 ;0
L 0.98821004 -2.05216004 1.03825 -2.05216004 0 P 0 ;0
L 0.98815 -2.05116004 1.03826998 -2.05116004 0 P 0 ;0
L 0.98808996 -2.05016004 1.03828996 -2.05016004 0 P 0 ;0
L 0.98801998 -2.04916004 1.03831998 -2.04916004 0 P 0 ;0
L 0.98796004 -2.04816004 1.03833996 -2.04816004 0 P 0 ;0
L 0.98788996 -2.04716004 1.03836004 -2.04716004 0 P 0 ;0
L 0.98783002 -2.04616004 1.03838996 -2.04616004 0 P 0 ;0
L 0.98768996 -2.04516004 1.0384 -2.04516004 0 P 0 ;0
L 0.98756004 -2.04416004 1.03841004 -2.04416004 0 P 0 ;0
L 0.98738002 -2.04316004 1.03841998 -2.04316004 0 P 0 ;0
L 0.98716004 -2.04216004 1.03843002 -2.04216004 0 P 0 ;0
L 0.98691998 -2.04116004 1.03843996 -2.04116004 0 P 0 ;0
L 0.98661998 -2.04016004 1.03845 -2.04016004 0 P 0 ;0
L 0.98631998 -2.03916004 1.03846004 -2.03916004 0 P 0 ;0
L 0.98593996 -2.03816004 1.03846998 -2.03816004 0 P 0 ;0
L 0.98546998 -2.03716004 1.03848002 -2.03716004 0 P 0 ;0
L 0.98491004 -2.03616004 1.03846998 -2.03616004 0 P 0 ;0
L 0.98425 -2.03516004 1.03846004 -2.03516004 0 P 0 ;0
L 0.98346004 -2.03416004 1.03846004 -2.03416004 0 P 0 ;0
L 0.98251998 -2.03316004 1.03843996 -2.03316004 0 P 0 ;0
L 0.98138002 -2.03216004 1.03843002 -2.03216004 0 P 0 ;0
L 0.97998996 -2.03116004 1.03841998 -2.03116004 0 P 0 ;0
L 0.97813996 -2.03016004 1.03841004 -2.03016004 0 P 0 ;0
L 0.97491004 -2.02916004 1.0384 -2.02916004 0 P 0 ;0
L 0.94763996 -2.00716004 1.03293996 -2.00716004 0 P 0 ;0
L 0.94978996 -2.00616004 1.03231998 -2.00616004 0 P 0 ;0
L 0.95081004 -2.00516004 1.0317 -2.00516004 0 P 0 ;0
L 0.95183002 -2.00416004 1.03098002 -2.00416004 0 P 0 ;0
L 0.95285 -2.00316004 1.03023002 -2.00316004 0 P 0 ;0
L 0.95388996 -2.00216004 1.02936004 -2.00216004 0 P 0 ;0
L 0.95498002 -2.00116004 1.02841998 -2.00116004 0 P 0 ;0
L 0.95621998 -2.00016004 1.02738996 -2.00016004 0 P 0 ;0
L 0.95761998 -1.99916004 1.0262 -1.99916004 0 P 0 ;0
L 0.9592 -1.99816004 1.02486004 -1.99816004 0 P 0 ;0
L 0.96083996 -1.99716004 1.02335 -1.99716004 0 P 0 ;0
L 0.9627 -1.99616004 1.02161004 -1.99616004 0 P 0 ;0
L 0.96468996 -1.99516004 1.01951998 -1.99516004 0 P 0 ;0
L 0.96685 -1.99416004 1.01683002 -1.99416004 0 P 0 ;0
L 0.96936998 -1.99316004 1.01378002 -1.99316004 0 P 0 ;0
L 0.97236998 -1.99216004 1.00981004 -1.99216004 0 P 0 ;0
L 0.97676004 -1.99116004 1.00456998 -1.99116004 0 P 0 ;0
L 1.06713996 -2.08283002 1.12288002 -2.08283002 0 P 0 ;0
L 1.06698996 -2.08183002 1.12193996 -2.08183002 0 P 0 ;0
L 1.06686004 -2.08083002 1.12108996 -2.08083002 0 P 0 ;0
L 1.06673996 -2.07983002 1.12036004 -2.07983002 0 P 0 ;0
L 1.06661998 -2.07883002 1.11971998 -2.07883002 0 P 0 ;0
L 1.06653002 -2.07783002 1.11916004 -2.07783002 0 P 0 ;0
L 1.06648002 -2.07683002 1.11866004 -2.07683002 0 P 0 ;0
L 1.06641998 -2.07583002 1.11826004 -2.07583002 0 P 0 ;0
L 1.06636998 -2.07483002 1.11791998 -2.07483002 0 P 0 ;0
L 1.06631998 -2.07383002 1.11761998 -2.07383002 0 P 0 ;0
L 1.06626004 -2.07283002 1.11741998 -2.07283002 0 P 0 ;0
L 1.06621004 -2.07183002 1.11723996 -2.07183002 0 P 0 ;0
L 1.06616004 -2.07083002 1.11711998 -2.07083002 0 P 0 ;0
L 1.06616004 -2.06983002 1.11701004 -2.06983002 0 P 0 ;0
L 1.06616004 -2.06883002 1.11688996 -2.06883002 0 P 0 ;0
L 1.06616998 -2.06783002 1.11676998 -2.06783002 0 P 0 ;0
L 1.06618002 -2.06683002 1.11666998 -2.06683002 0 P 0 ;0
L 1.06618996 -2.06583002 1.11663002 -2.06583002 0 P 0 ;0
L 1.0662 -2.06483002 1.11658996 -2.06483002 0 P 0 ;0
L 1.06621004 -2.06383002 1.11656004 -2.06383002 0 P 0 ;0
L 1.06623002 -2.06283002 1.11651998 -2.06283002 0 P 0 ;0
L 1.06631004 -2.06183002 1.11648996 -2.06183002 0 P 0 ;0
L 1.06638002 -2.06083002 1.11653002 -2.06083002 0 P 0 ;0
L 1.06645 -2.05983002 1.11656998 -2.05983002 0 P 0 ;0
L 1.06651998 -2.05883002 1.11661998 -2.05883002 0 P 0 ;0
L 1.06658996 -2.05783002 1.11666004 -2.05783002 0 P 0 ;0
L 1.06666998 -2.05683002 1.11671004 -2.05683002 0 P 0 ;0
L 1.06673996 -2.05583002 1.11681004 -2.05583002 0 P 0 ;0
L 1.06686004 -2.05483002 1.11693002 -2.05483002 0 P 0 ;0
L 1.067 -2.05383002 1.11705 -2.05383002 0 P 0 ;0
L 1.06713996 -2.05283002 1.11718002 -2.05283002 0 P 0 ;0
L 1.06728002 -2.05183002 1.11731004 -2.05183002 0 P 0 ;0
L 1.06741998 -2.05083002 1.11746004 -2.05083002 0 P 0 ;0
L 1.06756004 -2.04983002 1.11766004 -2.04983002 0 P 0 ;0
L 1.0677 -2.04883002 1.11786004 -2.04883002 0 P 0 ;0
L 1.06786004 -2.04783002 1.11813996 -2.04783002 0 P 0 ;0
L 1.06806998 -2.04683002 1.11841998 -2.04683002 0 P 0 ;0
L 1.06828002 -2.04583002 1.11876998 -2.04583002 0 P 0 ;0
L 1.06848996 -2.04483002 1.11913002 -2.04483002 0 P 0 ;0
L 1.06871004 -2.04383002 1.11955 -2.04383002 0 P 0 ;0
L 1.06898996 -2.04283002 1.11998996 -2.04283002 0 P 0 ;0
L 1.06928002 -2.04183002 1.12048002 -2.04183002 0 P 0 ;0
L 1.06956004 -2.04083002 1.12101004 -2.04083002 0 P 0 ;0
L 1.06985 -2.03983002 1.12161998 -2.03983002 0 P 0 ;0
L 1.07021004 -2.03883002 1.12225 -2.03883002 0 P 0 ;0
L 1.07056998 -2.03783002 1.12298002 -2.03783002 0 P 0 ;0
L 1.07093002 -2.03683002 1.12373996 -2.03683002 0 P 0 ;0
L 1.07128996 -2.03583002 1.12461998 -2.03583002 0 P 0 ;0
L 1.07173002 -2.03483002 1.12548996 -2.03483002 0 P 0 ;0
L 1.07216998 -2.03383002 1.12646004 -2.03383002 0 P 0 ;0
L 1.07261998 -2.03283002 1.12748996 -2.03283002 0 P 0 ;0
L 1.07308002 -2.03183002 1.12855 -2.03183002 0 P 0 ;0
L 1.07361998 -2.03083002 1.12978996 -2.03083002 0 P 0 ;0
L 1.09761004 -1.91731004 1.12756998 -1.91731004 0 P 0 ;0
L 1.09566004 -1.91631004 1.12645 -1.91631004 0 P 0 ;0
L 1.09371004 -1.91531004 1.12533002 -1.91531004 0 P 0 ;0
L 1.09176004 -1.91431004 1.12416004 -1.91431004 0 P 0 ;0
L 1.08946004 -1.91331004 1.12283996 -1.91331004 0 P 0 ;0
L 1.07415 -2.02983002 1.13101998 -2.02983002 0 P 0 ;0
L 1.07468996 -2.02883002 1.13248996 -2.02883002 0 P 0 ;0
L 1.07528996 -2.02783002 1.134 -2.02783002 0 P 0 ;0
L 1.07591998 -2.02683002 1.13586004 -2.02683002 0 P 0 ;0
L 1.07656004 -2.02583002 1.13828996 -2.02583002 0 P 0 ;0
L 1.07721004 -2.02483002 1.14243002 -2.02483002 0 P 0 ;0
L 1.07795 -2.02383002 1.21126998 -2.02383002 0 P 0 ;0
L 1.07868002 -2.02283002 1.21133002 -2.02283002 0 P 0 ;0
L 1.07941998 -2.02183002 1.2114 -2.02183002 0 P 0 ;0
L 1.08021004 -2.02083002 1.21146004 -2.02083002 0 P 0 ;0
L 1.08103996 -2.01983002 1.21153002 -2.01983002 0 P 0 ;0
L 1.08186998 -2.01883002 1.2116 -2.01883002 0 P 0 ;0
L 1.08273002 -2.01783002 1.21166004 -2.01783002 0 P 0 ;0
L 1.08366998 -2.01683002 1.21173002 -2.01683002 0 P 0 ;0
L 1.0846 -2.01583002 1.2118 -2.01583002 0 P 0 ;0
L 1.08555 -2.01483002 1.21186004 -2.01483002 0 P 0 ;0
L 1.08661004 -2.01383002 1.21193002 -2.01383002 0 P 0 ;0
L 1.08766998 -2.01283002 1.21198996 -2.01283002 0 P 0 ;0
L 1.08873002 -2.01183002 1.21205 -2.01183002 0 P 0 ;0
L 1.0898 -2.01083002 1.21211998 -2.01083002 0 P 0 ;0
L 1.09098996 -2.00983002 1.21218002 -2.00983002 0 P 0 ;0
L 1.09225 -2.00883002 1.21223996 -2.00883002 0 P 0 ;0
L 1.09358996 -2.00783002 1.2123 -2.00783002 0 P 0 ;0
L 1.09506998 -2.00683002 1.21236004 -2.00683002 0 P 0 ;0
L 1.09668996 -2.00583002 1.21241998 -2.00583002 0 P 0 ;0
L 0.98546998 -2.12516004 1.03548996 -2.12516004 0 P 0 ;0
L 0.98558996 -2.12416004 1.03553996 -2.12416004 0 P 0 ;0
L 0.9857 -2.12316004 1.03558002 -2.12316004 0 P 0 ;0
L 0.98581004 -2.12216004 1.03561998 -2.12216004 0 P 0 ;0
L 0.98591004 -2.12116004 1.03566998 -2.12116004 0 P 0 ;0
L 0.98598996 -2.12016004 1.03571004 -2.12016004 0 P 0 ;0
L 0.98608002 -2.11916004 1.03575 -2.11916004 0 P 0 ;0
L 0.98616998 -2.11816004 1.0358 -2.11816004 0 P 0 ;0
L 0.98625 -2.11716004 1.03583996 -2.11716004 0 P 0 ;0
L 0.98633996 -2.11616004 1.03588002 -2.11616004 0 P 0 ;0
L 0.98641998 -2.11516004 1.03593002 -2.11516004 0 P 0 ;0
L 0.98651004 -2.11416004 1.03596998 -2.11416004 0 P 0 ;0
L 0.9866 -2.11316004 1.03601004 -2.11316004 0 P 0 ;0
L 0.98668002 -2.11216004 1.03605 -2.11216004 0 P 0 ;0
L 0.98676998 -2.11116004 1.0361 -2.11116004 0 P 0 ;0
L 0.98685 -2.11016004 1.03613996 -2.11016004 0 P 0 ;0
L 0.98693996 -2.10916004 1.03618002 -2.10916004 0 P 0 ;0
L 0.987 -2.10816004 1.03623002 -2.10816004 0 P 0 ;0
L 0.98705 -2.10716004 1.03626998 -2.10716004 0 P 0 ;0
L 0.9871 -2.10616004 1.03631004 -2.10616004 0 P 0 ;0
L 0.98716004 -2.10516004 1.03636004 -2.10516004 0 P 0 ;0
L 0.9872 -2.10416004 1.0364 -2.10416004 0 P 0 ;0
L 0.98725 -2.10316004 1.03643996 -2.10316004 0 P 0 ;0
L 0.98731004 -2.10216004 1.03648002 -2.10216004 0 P 0 ;0
L 0.98735 -2.10116004 1.03653002 -2.10116004 0 P 0 ;0
L 0.9874 -2.10016004 1.03656998 -2.10016004 0 P 0 ;0
L 0.98746004 -2.09916004 1.03661004 -2.09916004 0 P 0 ;0
L 0.98751004 -2.09816004 1.03666004 -2.09816004 0 P 0 ;0
L 0.98755 -2.09716004 1.0367 -2.09716004 0 P 0 ;0
L 0.9876 -2.09616004 1.03673996 -2.09616004 0 P 0 ;0
L 0.98766004 -2.09516004 1.03678996 -2.09516004 0 P 0 ;0
L 0.9877 -2.09416004 1.03683002 -2.09416004 0 P 0 ;0
L 0.98775 -2.09316004 1.03686998 -2.09316004 0 P 0 ;0
L 0.98781004 -2.09216004 1.03691998 -2.09216004 0 P 0 ;0
L 0.98785 -2.09116004 1.03696004 -2.09116004 0 P 0 ;0
L 0.9879 -2.09016004 1.037 -2.09016004 0 P 0 ;0
L 0.98796004 -2.08916004 1.03703996 -2.08916004 0 P 0 ;0
L 0.98798996 -2.08816004 1.03706998 -2.08816004 0 P 0 ;0
L 0.98801998 -2.08716004 1.03711004 -2.08716004 0 P 0 ;0
L 0.98805 -2.08616004 1.03715 -2.08616004 0 P 0 ;0
L 0.98808996 -2.08516004 1.03718996 -2.08516004 0 P 0 ;0
L 0.98811998 -2.08416004 1.03723002 -2.08416004 0 P 0 ;0
L 1.08216998 -2.15683002 1.19803996 -2.15683002 0 P 0 ;0
L 1.0821 -2.15583002 1.19861004 -2.15583002 0 P 0 ;0
L 1.08201998 -2.15483002 1.19918002 -2.15483002 0 P 0 ;0
L 1.08195 -2.15383002 1.1997 -2.15383002 0 P 0 ;0
L 1.08188996 -2.15283002 1.20018002 -2.15283002 0 P 0 ;0
L 1.08183002 -2.15183002 1.20066004 -2.15183002 0 P 0 ;0
L 1.08176998 -2.15083002 1.20113996 -2.15083002 0 P 0 ;0
L 1.08171998 -2.14983002 1.20153996 -2.14983002 0 P 0 ;0
L 1.08166004 -2.14883002 1.20193002 -2.14883002 0 P 0 ;0
L 1.0816 -2.14783002 1.11538996 -2.14783002 0 P 0 ;0
L 1.08155 -2.14683002 1.10903002 -2.14683002 0 P 0 ;0
L 1.0815 -2.14583002 1.10415 -2.14583002 0 P 0 ;0
L 1.08146004 -2.14483002 1.09953002 -2.14483002 0 P 0 ;0
L 1.08141004 -2.14383002 1.09563996 -2.14383002 0 P 0 ;0
L 1.08136004 -2.14283002 1.09183996 -2.14283002 0 P 0 ;0
L 1.08131004 -2.14183002 1.08821004 -2.14183002 0 P 0 ;0
L 1.08133002 -2.14083002 1.08471998 -2.14083002 0 P 0 ;0
L 1.09586998 -2.11983002 1.14965 -2.11983002 0 P 0 ;0
L 1.09361998 -2.11883002 1.15221998 -2.11883002 0 P 0 ;0
L 1.09158996 -2.11783002 1.20595 -2.11783002 0 P 0 ;0
L 1.08988002 -2.11683002 1.20601004 -2.11683002 0 P 0 ;0
L 1.08823996 -2.11583002 1.20606998 -2.11583002 0 P 0 ;0
L 1.08678996 -2.11483002 1.20613002 -2.11483002 0 P 0 ;0
L 1.08541004 -2.11383002 1.20618996 -2.11383002 0 P 0 ;0
L 1.08416998 -2.11283002 1.20625 -2.11283002 0 P 0 ;0
L 1.08295 -2.11183002 1.20631004 -2.11183002 0 P 0 ;0
L 1.08188002 -2.11083002 1.20638002 -2.11083002 0 P 0 ;0
L 1.08081998 -2.10983002 1.20643996 -2.10983002 0 P 0 ;0
L 1.07986004 -2.10883002 1.2065 -2.10883002 0 P 0 ;0
L 1.07895 -2.10783002 1.20656004 -2.10783002 0 P 0 ;0
L 1.07803002 -2.10683002 1.20661998 -2.10683002 0 P 0 ;0
L 1.07723996 -2.10583002 1.20666998 -2.10583002 0 P 0 ;0
L 1.07646004 -2.10483002 1.20671998 -2.10483002 0 P 0 ;0
L 1.07568002 -2.10383002 1.20678002 -2.10383002 0 P 0 ;0
L 1.075 -2.10283002 1.20683002 -2.10283002 0 P 0 ;0
L 1.07433002 -2.10183002 1.20688002 -2.10183002 0 P 0 ;0
L 1.07366998 -2.10083002 1.20693996 -2.10083002 0 P 0 ;0
L 1.07308996 -2.09983002 1.20698996 -2.09983002 0 P 0 ;0
L 1.07253002 -2.09883002 1.20705 -2.09883002 0 P 0 ;0
L 1.07198002 -2.09783002 1.2071 -2.09783002 0 P 0 ;0
L 1.07146998 -2.09683002 1.20715 -2.09683002 0 P 0 ;0
L 1.07101998 -2.09583002 1.2072 -2.09583002 0 P 0 ;0
L 1.07056998 -2.09483002 1.20726004 -2.09483002 0 P 0 ;0
L 1.07013002 -2.09383002 1.20731004 -2.09383002 0 P 0 ;0
L 1.06976998 -2.09283002 1.20736004 -2.09283002 0 P 0 ;0
L 1.06941998 -2.09183002 1.20741998 -2.09183002 0 P 0 ;0
L 1.06906004 -2.09083002 1.20746998 -2.09083002 0 P 0 ;0
L 1.06876004 -2.08983002 1.20753002 -2.08983002 0 P 0 ;0
L 1.06848996 -2.08883002 1.13443002 -2.08883002 0 P 0 ;0
L 1.06821998 -2.08783002 1.13068002 -2.08783002 0 P 0 ;0
L 1.06795 -2.08683002 1.12836998 -2.08683002 0 P 0 ;0
L 1.06771998 -2.08583002 1.1266 -2.08583002 0 P 0 ;0
L 1.06753002 -2.08483002 1.12516004 -2.08483002 0 P 0 ;0
L 1.06733002 -2.08383002 1.12393996 -2.08383002 0 P 0 ;0
L 0.90273996 -1.85456998 0.89068996 -1.85558002 0 P 0 ;0
L 0.89068996 -1.85558002 0.87421004 -1.85741998 0 P 0 ;0
L 0.87421004 -1.85741998 0.85783002 -1.85946998 0 P 0 ;0
L 0.85783002 -1.85946998 0.85526998 -1.8599 0 P 0 ;0
L 0.85526998 -1.8599 0.85276004 -1.86055 0 P 0 ;0
L 0.85276004 -1.86055 0.85255 -1.86063996 0 P 0 ;0
L 0.85255 -1.86063996 0.85248996 -1.86068996 0 P 0 ;0
L 0.85248996 -1.86068996 0.85243002 -1.86073002 0 P 0 ;0
L 0.85243002 -1.86073002 0.85238002 -1.86078002 0 P 0 ;0
L 0.85238002 -1.86078002 0.85233002 -1.86083996 0 P 0 ;0
L 0.85233002 -1.86083996 0.85225 -1.86096004 0 P 0 ;0
L 0.85225 -1.86096004 0.85218002 -1.8611 0 P 0 ;0
L 0.85218002 -1.8611 0.85216004 -1.86116998 0 P 0 ;0
L 0.85216004 -1.86116998 0.85215 -1.86123996 0 P 0 ;0
L 0.85215 -1.86123996 0.85213996 -1.86136998 0 P 0 ;0
L 0.85213996 -1.86136998 0.85213002 -1.86148996 0 P 0 ;0
L 0.85213002 -1.86148996 0.85213996 -1.86161998 0 P 0 ;0
L 0.85213996 -1.86161998 0.85215 -1.86173996 0 P 0 ;0
L 0.85215 -1.86173996 0.85218002 -1.86186998 0 P 0 ;0
L 0.85218002 -1.86186998 0.85221004 -1.86198996 0 P 0 ;0
L 0.85221004 -1.86198996 0.85225 -1.8621 0 P 0 ;0
L 0.85225 -1.8621 0.85231004 -1.86221998 0 P 0 ;0
L 0.85231004 -1.86221998 0.85236998 -1.86233002 0 P 0 ;0
L 0.85236998 -1.86233002 0.85281998 -1.863 0 P 0 ;0
L 0.85281998 -1.863 0.8533 -1.86363996 0 P 0 ;0
L 0.8533 -1.86363996 0.85383002 -1.86425 0 P 0 ;0
L 0.85383002 -1.86425 0.85736004 -1.86801998 0 P 0 ;0
L 0.85736004 -1.86801998 0.86013002 -1.87113002 0 P 0 ;0
L 0.86013002 -1.87113002 0.86266004 -1.87443002 0 P 0 ;0
L 0.86266004 -1.87443002 0.86501004 -1.87798996 0 P 0 ;0
L 0.86501004 -1.87798996 0.86711998 -1.88171004 0 P 0 ;0
L 0.86711998 -1.88171004 0.86896998 -1.88553996 0 P 0 ;0
L 0.86896998 -1.88553996 0.87055 -1.8895 0 P 0 ;0
L 0.87055 -1.8895 0.8718 -1.89343002 0 P 0 ;0
L 0.8718 -1.89343002 0.87276004 -1.89745 0 P 0 ;0
L 0.87276004 -1.89745 0.87371004 -1.90195 0 P 0 ;0
L 0.87371004 -1.90195 0.87383002 -1.90236004 0 P 0 ;0
L 0.87383002 -1.90236004 0.87396998 -1.90276004 0 P 0 ;0
L 0.87396998 -1.90276004 0.87416004 -1.90313996 0 P 0 ;0
L 0.87416004 -1.90313996 0.87436998 -1.90351004 0 P 0 ;0
L 0.87436998 -1.90351004 0.87443002 -1.9036 0 P 0 ;0
L 0.87443002 -1.9036 0.87456998 -1.90376004 0 P 0 ;0
L 0.87456998 -1.90376004 0.87465 -1.90381998 0 P 0 ;0
L 0.87465 -1.90381998 0.87473002 -1.90388996 0 P 0 ;0
L 0.87473002 -1.90388996 0.87481998 -1.90393996 0 P 0 ;0
L 0.87481998 -1.90393996 0.87491998 -1.90398996 0 P 0 ;0
L 0.87491998 -1.90398996 0.87501004 -1.90403002 0 P 0 ;0
L 0.87501004 -1.90403002 0.87521004 -1.90408996 0 P 0 ;0
L 0.87521004 -1.90408996 0.87531998 -1.9041 0 P 0 ;0
L 0.87531998 -1.9041 0.87573002 -1.90413002 0 P 0 ;0
L 0.87573002 -1.90413002 0.87613996 -1.90411998 0 P 0 ;0
L 0.87613996 -1.90411998 0.87653996 -1.90408002 0 P 0 ;0
L 0.87653996 -1.90408002 0.87695 -1.90401004 0 P 0 ;0
L 0.87695 -1.90401004 0.90756004 -1.89766998 0 P 0 ;0
L 0.90756004 -1.89766998 0.92603996 -1.89478002 0 P 0 ;0
L 0.92603996 -1.89478002 0.93486004 -1.89393996 0 P 0 ;0
L 0.93486004 -1.89393996 0.94371004 -1.8935 0 P 0 ;0
L 0.94371004 -1.8935 0.97045 -1.89308002 0 P 0 ;0
L 0.97045 -1.89308002 0.99468996 -1.89328996 0 P 0 ;0
L 0.99468996 -1.89328996 1.01021004 -1.89413996 0 P 0 ;0
L 1.01021004 -1.89413996 1.0241 -1.89601998 0 P 0 ;0
L 1.0241 -1.89601998 1.04188002 -1.89961004 0 P 0 ;0
L 1.04188002 -1.89961004 1.06095 -1.90466004 0 P 0 ;0
L 1.06095 -1.90466004 1.07963996 -1.91123002 0 P 0 ;0
L 1.07963996 -1.91123002 1.09093996 -1.91613002 0 P 0 ;0
L 1.09093996 -1.91613002 1.10186998 -1.92175 0 P 0 ;0
L 1.10186998 -1.92175 1.11243996 -1.92806998 0 P 0 ;0
L 1.11243996 -1.92806998 1.12163002 -1.93446998 0 P 0 ;0
L 1.12163002 -1.93446998 1.13033002 -1.94148996 0 P 0 ;0
L 1.13033002 -1.94148996 1.1385 -1.94911004 0 P 0 ;0
L 1.1385 -1.94911004 1.14358996 -1.9546 0 P 0 ;0
L 1.14358996 -1.9546 1.14825 -1.96045 0 P 0 ;0
L 1.14825 -1.96045 1.15246998 -1.96663002 0 P 0 ;0
L 1.15246998 -1.96663002 1.15623002 -1.97316004 0 P 0 ;0
L 1.15623002 -1.97316004 1.15895 -1.97831004 0 P 0 ;0
L 1.15895 -1.97831004 1.17358996 -1.97831004 0 P 0 ;0
L 1.17358996 -1.97831004 1.17135 -1.9726 0 P 0 ;0
L 1.17135 -1.9726 1.16696004 -1.96266998 0 P 0 ;0
L 1.16696004 -1.96266998 1.16171998 -1.95313002 0 P 0 ;0
L 1.16171998 -1.95313002 1.1557 -1.94406998 0 P 0 ;0
L 1.1557 -1.94406998 1.14885 -1.93548002 0 P 0 ;0
L 1.14885 -1.93548002 1.13778996 -1.92378002 0 P 0 ;0
L 1.13778996 -1.92378002 1.12576998 -1.91301998 0 P 0 ;0
L 1.12576998 -1.91301998 1.11283996 -1.90326004 0 P 0 ;0
L 1.11283996 -1.90326004 1.09783002 -1.89368996 0 P 0 ;0
L 1.09783002 -1.89368996 1.08213002 -1.88526998 0 P 0 ;0
L 1.08213002 -1.88526998 1.06576998 -1.87801004 0 P 0 ;0
L 1.06576998 -1.87801004 1.04776004 -1.87141998 0 P 0 ;0
L 1.04776004 -1.87141998 1.02938002 -1.86591998 0 P 0 ;0
L 1.02938002 -1.86591998 1.01058002 -1.8615 0 P 0 ;0
L 1.01058002 -1.8615 0.98441998 -1.85711004 0 P 0 ;0
L 0.98441998 -1.85711004 0.95781004 -1.85448996 0 P 0 ;0
L 0.95781004 -1.85448996 0.93061004 -1.85366004 0 P 0 ;0
L 0.93061004 -1.85366004 0.90273996 -1.85456998 0 P 0 ;0
L 1.16015 -1.97631004 1.15798002 -1.97218996 0 P 0 ;0
L 1.15798002 -1.97218996 1.15796004 -1.97216004 0 P 0 ;0
L 1.15796004 -1.97216004 1.15416004 -1.96556998 0 P 0 ;0
L 1.15416004 -1.96556998 1.15411998 -1.96551004 0 P 0 ;0
L 1.15411998 -1.96551004 1.14986004 -1.95926004 0 P 0 ;0
L 1.14986004 -1.95926004 1.14981998 -1.95921004 0 P 0 ;0
L 1.14981998 -1.95921004 1.14511004 -1.9533 0 P 0 ;0
L 1.14511004 -1.9533 1.13991998 -1.9477 0 P 0 ;0
L 1.13991998 -1.9477 1.13986004 -1.94765 0 P 0 ;0
L 1.13986004 -1.94765 1.13163996 -1.93998002 0 P 0 ;0
L 1.13163996 -1.93998002 1.12283002 -1.93286004 0 P 0 ;0
L 1.12283002 -1.93286004 1.11351998 -1.92638996 0 P 0 ;0
L 1.11351998 -1.92638996 1.10283996 -1.92 0 P 0 ;0
L 1.10283996 -1.92 1.0918 -1.91433002 0 P 0 ;0
L 1.0918 -1.91433002 1.08036998 -1.90936004 0 P 0 ;0
L 1.08036998 -1.90936004 1.06153002 -1.90273996 0 P 0 ;0
L 1.06153002 -1.90273996 1.06146004 -1.90273002 0 P 0 ;0
L 1.06146004 -1.90273002 1.04233002 -1.89766004 0 P 0 ;0
L 1.04233002 -1.89766004 1.02443002 -1.89405 0 P 0 ;0
L 1.02443002 -1.89405 1.0104 -1.89213996 0 P 0 ;0
L 1.0104 -1.89213996 0.99475 -1.89128996 0 P 0 ;0
L 0.99475 -1.89128996 0.97045 -1.89108002 0 P 0 ;0
L 0.97045 -1.89108002 0.94365 -1.8915 0 P 0 ;0
L 0.94365 -1.8915 0.94361998 -1.8915 0 P 0 ;0
L 0.94361998 -1.8915 0.93471998 -1.89195 0 P 0 ;0
L 0.93471998 -1.89195 0.92578996 -1.89278996 0 P 0 ;0
L 0.92578996 -1.89278996 0.9072 -1.89571004 0 P 0 ;0
L 0.9072 -1.89571004 0.87656998 -1.90203996 0 P 0 ;0
L 0.87656998 -1.90203996 0.87626998 -1.9021 0 P 0 ;0
L 0.87626998 -1.9021 0.87601998 -1.90211998 0 P 0 ;0
L 0.87601998 -1.90211998 0.87588996 -1.90213002 0 P 0 ;0
L 0.87588996 -1.90213002 0.87583002 -1.90198996 0 P 0 ;0
L 0.87583002 -1.90198996 0.87573002 -1.90175 0 P 0 ;0
L 0.87573002 -1.90175 0.87566004 -1.90146998 0 P 0 ;0
L 0.87566004 -1.90146998 0.87471004 -1.89701004 0 P 0 ;0
L 0.87471004 -1.89701004 0.8747 -1.89698996 0 P 0 ;0
L 0.8747 -1.89698996 0.87373002 -1.89288996 0 P 0 ;0
L 0.87373002 -1.89288996 0.87243002 -1.88881998 0 P 0 ;0
L 0.87243002 -1.88881998 0.8724 -1.88876004 0 P 0 ;0
L 0.8724 -1.88876004 0.8708 -1.88473996 0 P 0 ;0
L 0.8708 -1.88473996 0.8689 -1.88078002 0 P 0 ;0
L 0.8689 -1.88078002 0.86671998 -1.87693996 0 P 0 ;0
L 0.86671998 -1.87693996 0.86428996 -1.87326004 0 P 0 ;0
L 0.86428996 -1.87326004 0.86166998 -1.86985 0 P 0 ;0
L 0.86166998 -1.86985 0.85883996 -1.86668002 0 P 0 ;0
L 0.85883996 -1.86668002 0.85883002 -1.86666004 0 P 0 ;0
L 0.85883002 -1.86666004 0.85531998 -1.86291004 0 P 0 ;0
L 0.85531998 -1.86291004 0.85486004 -1.86238002 0 P 0 ;0
L 0.85486004 -1.86238002 0.85466004 -1.86211998 0 P 0 ;0
L 0.85466004 -1.86211998 0.8557 -1.86186004 0 P 0 ;0
L 0.8557 -1.86186004 0.85811998 -1.86145 0 P 0 ;0
L 0.85811998 -1.86145 0.87443996 -1.85941004 0 P 0 ;0
L 0.87443996 -1.85941004 0.89088996 -1.85756998 0 P 0 ;0
L 0.89088996 -1.85756998 0.90286004 -1.85656998 0 P 0 ;0
L 0.90286004 -1.85656998 0.93061004 -1.85566004 0 P 0 ;0
L 0.93061004 -1.85566004 0.95768002 -1.85648996 0 P 0 ;0
L 0.95768002 -1.85648996 0.98416004 -1.8591 0 P 0 ;0
L 0.98416004 -1.8591 1.01018996 -1.86346004 0 P 0 ;0
L 1.01018996 -1.86346004 1.02886004 -1.86785 0 P 0 ;0
L 1.02886004 -1.86785 1.04711998 -1.87331998 0 P 0 ;0
L 1.04711998 -1.87331998 1.06501004 -1.87986004 0 P 0 ;0
L 1.06501004 -1.87986004 1.08125 -1.88706998 0 P 0 ;0
L 1.08125 -1.88706998 1.09681004 -1.89541998 0 P 0 ;0
L 1.09681004 -1.89541998 1.1117 -1.9049 0 P 0 ;0
L 1.1117 -1.9049 1.1245 -1.91456998 0 P 0 ;0
L 1.1245 -1.91456998 1.13638996 -1.92521004 0 P 0 ;0
L 1.13638996 -1.92521004 1.14733996 -1.93678996 0 P 0 ;0
L 1.14733996 -1.93678996 1.15408002 -1.94525 0 P 0 ;0
L 1.15408002 -1.94525 1.16001004 -1.95416998 0 P 0 ;0
L 1.16001004 -1.95416998 1.16516004 -1.96355 0 P 0 ;0
L 1.16516004 -1.96355 1.1695 -1.97336998 0 P 0 ;0
L 1.1695 -1.97336998 1.17066004 -1.97631004 0 P 0 ;0
L 1.17066004 -1.97631004 1.16015 -1.97631004 0 P 0 ;0
L 0.87563002 -1.90131004 0.8801 -1.90131004 0 P 0 ;0
L 0.87541004 -1.90031004 0.88493996 -1.90031004 0 P 0 ;0
L 0.8752 -1.89931004 0.88976998 -1.89931004 0 P 0 ;0
L 0.87498996 -1.89831004 0.8946 -1.89831004 0 P 0 ;0
L 0.89423002 -2.08316004 0.94355 -2.08316004 0 P 0 ;0
L 0.89428996 -2.08216004 0.9436 -2.08216004 0 P 0 ;0
L 0.89435 -2.08116004 0.94365 -2.08116004 0 P 0 ;0
L 0.89441004 -2.08016004 0.9437 -2.08016004 0 P 0 ;0
L 0.89446004 -2.07916004 0.94375 -2.07916004 0 P 0 ;0
L 0.89451998 -2.07816004 0.94378996 -2.07816004 0 P 0 ;0
L 0.89458002 -2.07716004 0.94383996 -2.07716004 0 P 0 ;0
L 0.89463996 -2.07616004 0.94388996 -2.07616004 0 P 0 ;0
L 0.8947 -2.07516004 0.94393996 -2.07516004 0 P 0 ;0
L 0.89475 -2.07416004 0.94398002 -2.07416004 0 P 0 ;0
L 0.89481004 -2.07316004 0.94403002 -2.07316004 0 P 0 ;0
L 0.89486998 -2.07216004 0.94408002 -2.07216004 0 P 0 ;0
L 0.89493002 -2.07116004 0.94415 -2.07116004 0 P 0 ;0
L 0.89498996 -2.07016004 0.94426004 -2.07016004 0 P 0 ;0
L 0.89505 -2.06916004 0.94436998 -2.06916004 0 P 0 ;0
L 0.8951 -2.06816004 0.94448002 -2.06816004 0 P 0 ;0
L 0.89516004 -2.06716004 0.94458996 -2.06716004 0 P 0 ;0
L 0.89521998 -2.06616004 0.9447 -2.06616004 0 P 0 ;0
L 0.89526998 -2.06516004 0.94481004 -2.06516004 0 P 0 ;0
L 0.89531004 -2.06416004 0.94491998 -2.06416004 0 P 0 ;0
L 0.89535 -2.06316004 0.94503002 -2.06316004 0 P 0 ;0
L 0.8954 -2.06216004 0.94513996 -2.06216004 0 P 0 ;0
L 0.89543996 -2.06116004 0.94531998 -2.06116004 0 P 0 ;0
L 0.89548996 -2.06016004 0.94551004 -2.06016004 0 P 0 ;0
L 0.89553002 -2.05916004 0.9457 -2.05916004 0 P 0 ;0
L 0.89558002 -2.05816004 0.94588996 -2.05816004 0 P 0 ;0
L 0.89561998 -2.05716004 0.94608002 -2.05716004 0 P 0 ;0
L 0.89566998 -2.05616004 0.94626998 -2.05616004 0 P 0 ;0
L 0.89571004 -2.05516004 0.94646998 -2.05516004 0 P 0 ;0
L 0.89575 -2.05416004 0.94666004 -2.05416004 0 P 0 ;0
L 0.8958 -2.05316004 0.94685 -2.05316004 0 P 0 ;0
L 0.89583996 -2.05216004 0.94708002 -2.05216004 0 P 0 ;0
L 0.89588996 -2.05116004 0.94735 -2.05116004 0 P 0 ;0
L 0.89593996 -2.05016004 0.94761998 -2.05016004 0 P 0 ;0
L 0.89598002 -2.04916004 0.9479 -2.04916004 0 P 0 ;0
L 0.89601998 -2.04816004 0.94825 -2.04816004 0 P 0 ;0
L 0.89606998 -2.04716004 0.94858996 -2.04716004 0 P 0 ;0
L 0.89611004 -2.04616004 0.94893002 -2.04616004 0 P 0 ;0
L 0.89616004 -2.04516004 0.94935 -2.04516004 0 P 0 ;0
L 0.8962 -2.04416004 0.94976998 -2.04416004 0 P 0 ;0
L 0.89625 -2.04316004 0.9502 -2.04316004 0 P 0 ;0
L 0.89628002 -2.04216004 0.95068996 -2.04216004 0 P 0 ;0
L 0.89631004 -2.04116004 0.95118996 -2.04116004 0 P 0 ;0
L 0.89633996 -2.04016004 0.95168996 -2.04016004 0 P 0 ;0
L 0.89638002 -2.03916004 0.95228002 -2.03916004 0 P 0 ;0
L 0.89641004 -2.03816004 0.95291004 -2.03816004 0 P 0 ;0
L 0.89643996 -2.03716004 0.95363002 -2.03716004 0 P 0 ;0
L 0.89646998 -2.03616004 0.95445 -2.03616004 0 P 0 ;0
L 0.89651004 -2.03516004 0.95535 -2.03516004 0 P 0 ;0
L 0.89653996 -2.03416004 0.95636998 -2.03416004 0 P 0 ;0
L 0.89656998 -2.03316004 0.95756998 -2.03316004 0 P 0 ;0
L 0.8966 -2.03216004 0.95893996 -2.03216004 0 P 0 ;0
L 0.89663996 -2.03116004 0.96055 -2.03116004 0 P 0 ;0
L 0.89666998 -2.03016004 0.96278002 -2.03016004 0 P 0 ;0
L 0.8967 -2.02916004 0.96676004 -2.02916004 0 P 0 ;0
L 0.89673996 -2.02816004 1.03838996 -2.02816004 0 P 0 ;0
L 0.89676998 -2.02716004 1.03838002 -2.02716004 0 P 0 ;0
L 0.8968 -2.02616004 1.03833996 -2.02616004 0 P 0 ;0
L 0.89683996 -2.02516004 1.03828996 -2.02516004 0 P 0 ;0
L 0.89686998 -2.02416004 1.03823002 -2.02416004 0 P 0 ;0
L 0.8969 -2.02316004 1.03816004 -2.02316004 0 P 0 ;0
L 0.89693996 -2.02216004 1.0381 -2.02216004 0 P 0 ;0
L 0.89696998 -2.02116004 1.03803996 -2.02116004 0 P 0 ;0
L 0.897 -2.02016004 1.0379 -2.02016004 0 P 0 ;0
L 0.89703002 -2.01916004 1.03773996 -2.01916004 0 P 0 ;0
L 0.89706004 -2.01816004 1.03751998 -2.01816004 0 P 0 ;0
L 0.89708996 -2.01716004 1.03728002 -2.01716004 0 P 0 ;0
L 0.89711998 -2.01616004 1.03698996 -2.01616004 0 P 0 ;0
L 0.89713996 -2.01516004 1.03668002 -2.01516004 0 P 0 ;0
L 0.89716998 -2.01416004 1.03631004 -2.01416004 0 P 0 ;0
L 0.8972 -2.01316004 1.03591998 -2.01316004 0 P 0 ;0
L 0.89721998 -2.01216004 1.03548996 -2.01216004 0 P 0 ;0
L 0.89725 -2.01116004 1.03505 -2.01116004 0 P 0 ;0
L 0.89726998 -2.01016004 1.03458002 -2.01016004 0 P 0 ;0
L 0.8973 -2.00916004 1.03405 -2.00916004 0 P 0 ;0
L 0.89733002 -2.00816004 1.03351998 -2.00816004 0 P 0 ;0
L 0.89736004 -2.00716004 0.94676004 -2.00716004 0 P 0 ;0
L 0.89738002 -2.00616004 0.9461 -2.00616004 0 P 0 ;0
L 0.89741004 -2.00516004 0.94563996 -2.00516004 0 P 0 ;0
L 0.89743996 -2.00416004 0.94563996 -2.00416004 0 P 0 ;0
L 0.89746004 -2.00316004 0.94563996 -2.00316004 0 P 0 ;0
L 0.89748996 -2.00216004 0.94563996 -2.00216004 0 P 0 ;0
L 0.89751004 -2.00116004 0.94563996 -2.00116004 0 P 0 ;0
L 0.89753996 -2.00016004 0.94563996 -2.00016004 0 P 0 ;0
L 0.89756998 -1.99916004 0.94563996 -1.99916004 0 P 0 ;0
L 0.8976 -1.99816004 0.94563996 -1.99816004 0 P 0 ;0
L 0.89761998 -1.99716004 0.94563996 -1.99716004 0 P 0 ;0
L 0.89765 -1.99616004 0.94563996 -1.99616004 0 P 0 ;0
L 0.89768002 -1.99516004 0.94563996 -1.99516004 0 P 0 ;0
L 0.97546998 -1.98933996 0.97236998 -1.99006004 0 P 0 ;0
L 0.97236998 -1.99006004 0.96931998 -1.99103002 0 P 0 ;0
L 0.96931998 -1.99103002 0.96603002 -1.99233002 0 P 0 ;0
L 0.96603002 -1.99233002 0.96281004 -1.99383002 0 P 0 ;0
L 0.96281004 -1.99383002 0.95976004 -1.99546998 0 P 0 ;0
L 0.95976004 -1.99546998 0.95681004 -1.99728996 0 P 0 ;0
L 0.95681004 -1.99728996 0.95521004 -1.99841004 0 P 0 ;0
L 0.95521004 -1.99841004 0.95368996 -1.99963002 0 P 0 ;0
L 0.95368996 -1.99963002 0.95223996 -2.00095 0 P 0 ;0
L 0.95223996 -2.00095 0.94763996 -2.00546998 0 P 0 ;0
L 0.94763996 -2.00546998 0.94763996 -1.99243996 0 P 0 ;0
L 0.94763996 -1.99243996 0.89575 -1.99243996 0 P 0 ;0
L 0.89575 -1.99243996 0.89505 -2.01878002 0 P 0 ;0
L 0.89505 -2.01878002 0.89423996 -2.04316004 0 P 0 ;0
L 0.89423996 -2.04316004 0.89321998 -2.0661 0 P 0 ;0
L 0.89321998 -2.0661 0.89198996 -2.08728996 0 P 0 ;0
L 0.89198996 -2.08728996 0.89055 -2.1063 0 P 0 ;0
L 0.89055 -2.1063 0.88993996 -2.11358002 0 P 0 ;0
L 0.88993996 -2.11358002 0.88943002 -2.11988002 0 P 0 ;0
L 0.88943002 -2.11988002 0.88898996 -2.12533996 0 P 0 ;0
L 0.88898996 -2.12533996 0.88896004 -2.12613002 0 P 0 ;0
L 0.88896004 -2.12613002 0.88896998 -2.12621004 0 P 0 ;0
L 0.88896998 -2.12621004 0.88898002 -2.12625 0 P 0 ;0
L 0.88898002 -2.12625 0.88898996 -2.12628002 0 P 0 ;0
L 0.88898996 -2.12628002 0.88901998 -2.12636004 0 P 0 ;0
L 0.88901998 -2.12636004 0.88903996 -2.12638996 0 P 0 ;0
L 0.88903996 -2.12638996 0.88906998 -2.12641998 0 P 0 ;0
L 0.88906998 -2.12641998 0.88908996 -2.12645 0 P 0 ;0
L 0.88908996 -2.12645 0.88911998 -2.12646998 0 P 0 ;0
L 0.88911998 -2.12646998 0.88915 -2.1265 0 P 0 ;0
L 0.88915 -2.1265 0.88921004 -2.12653996 0 P 0 ;0
L 0.88921004 -2.12653996 0.88925 -2.12655 0 P 0 ;0
L 0.88925 -2.12655 0.88928002 -2.12656004 0 P 0 ;0
L 0.88928002 -2.12656004 0.88931998 -2.12658002 0 P 0 ;0
L 0.88931998 -2.12658002 0.8894 -2.12658002 0 P 0 ;0
L 0.8894 -2.12658002 0.89648002 -2.12686998 0 P 0 ;0
L 0.89648002 -2.12686998 0.90518996 -2.1271 0 P 0 ;0
L 0.90518996 -2.1271 0.9165 -2.12716004 0 P 0 ;0
L 0.9165 -2.12716004 0.94403996 -2.12716004 0 P 0 ;0
L 0.94403996 -2.12716004 0.94468996 -2.10135 0 P 0 ;0
L 0.94468996 -2.10135 0.9461 -2.07171998 0 P 0 ;0
L 0.9461 -2.07171998 0.94713002 -2.06233002 0 P 0 ;0
L 0.94713002 -2.06233002 0.9489 -2.05308002 0 P 0 ;0
L 0.9489 -2.05308002 0.94975 -2.04995 0 P 0 ;0
L 0.94975 -2.04995 0.9508 -2.04688996 0 P 0 ;0
L 0.9508 -2.04688996 0.95205 -2.0439 0 P 0 ;0
L 0.95205 -2.0439 0.95351004 -2.041 0 P 0 ;0
L 0.95351004 -2.041 0.9544 -2.03951004 0 P 0 ;0
L 0.9544 -2.03951004 0.95541998 -2.03811004 0 P 0 ;0
L 0.95541998 -2.03811004 0.95655 -2.03678996 0 P 0 ;0
L 0.95655 -2.03678996 0.95778996 -2.03556998 0 P 0 ;0
L 0.95778996 -2.03556998 0.95911998 -2.03446998 0 P 0 ;0
L 0.95911998 -2.03446998 0.96056998 -2.03346998 0 P 0 ;0
L 0.96056998 -2.03346998 0.96151004 -2.03291004 0 P 0 ;0
L 0.96151004 -2.03291004 0.96248996 -2.03243002 0 P 0 ;0
L 0.96248996 -2.03243002 0.96351004 -2.03201998 0 P 0 ;0
L 0.96351004 -2.03201998 0.96455 -2.03168996 0 P 0 ;0
L 0.96455 -2.03168996 0.96613002 -2.0313 0 P 0 ;0
L 0.96613002 -2.0313 0.96773002 -2.03101998 0 P 0 ;0
L 0.96773002 -2.03101998 0.96935 -2.03086004 0 P 0 ;0
L 0.96935 -2.03086004 0.97095 -2.03081004 0 P 0 ;0
L 0.97095 -2.03081004 0.97255 -2.03086998 0 P 0 ;0
L 0.97255 -2.03086998 0.97413002 -2.03105 0 P 0 ;0
L 0.97413002 -2.03105 0.97513002 -2.03123996 0 P 0 ;0
L 0.97513002 -2.03123996 0.9761 -2.03151004 0 P 0 ;0
L 0.9761 -2.03151004 0.97706004 -2.03186004 0 P 0 ;0
L 0.97706004 -2.03186004 0.97796998 -2.0323 0 P 0 ;0
L 0.97796998 -2.0323 0.97885 -2.0328 0 P 0 ;0
L 0.97885 -2.0328 0.97968002 -2.03336998 0 P 0 ;0
L 0.97968002 -2.03336998 0.98046998 -2.03398996 0 P 0 ;0
L 0.98046998 -2.03398996 0.98121998 -2.03468002 0 P 0 ;0
L 0.98121998 -2.03468002 0.98191004 -2.03541998 0 P 0 ;0
L 0.98191004 -2.03541998 0.98253996 -2.0362 0 P 0 ;0
L 0.98253996 -2.0362 0.9831 -2.03703002 0 P 0 ;0
L 0.9831 -2.03703002 0.9836 -2.03788996 0 P 0 ;0
L 0.9836 -2.03788996 0.98403996 -2.0388 0 P 0 ;0
L 0.98403996 -2.0388 0.9844 -2.03973996 0 P 0 ;0
L 0.9844 -2.03973996 0.98505 -2.04188996 0 P 0 ;0
L 0.98505 -2.04188996 0.98553002 -2.04408002 0 P 0 ;0
L 0.98553002 -2.04408002 0.98583002 -2.0463 0 P 0 ;0
L 0.98583002 -2.0463 0.98653002 -2.05705 0 P 0 ;0
L 0.98653002 -2.05705 0.9866 -2.06961004 0 P 0 ;0
L 0.9866 -2.06961004 0.98596004 -2.08908002 0 P 0 ;0
L 0.98596004 -2.08908002 0.98498002 -2.10858002 0 P 0 ;0
L 0.98498002 -2.10858002 0.98388002 -2.12146998 0 P 0 ;0
L 0.98388002 -2.12146998 0.98323002 -2.12716004 0 P 0 ;0
L 0.98323002 -2.12716004 1.03741004 -2.12716004 0 P 0 ;0
L 1.03741004 -2.12716004 1.03896004 -2.09103002 0 P 0 ;0
L 1.03896004 -2.09103002 1.03956004 -2.0759 0 P 0 ;0
L 1.03956004 -2.0759 1.04005 -2.06025 0 P 0 ;0
L 1.04005 -2.06025 1.04038996 -2.04626004 0 P 0 ;0
L 1.04038996 -2.04626004 1.04048002 -2.03698996 0 P 0 ;0
L 1.04048002 -2.03698996 1.04036998 -2.02651998 0 P 0 ;0
L 1.04036998 -2.02651998 1.04003996 -2.02096998 0 P 0 ;0
L 1.04003996 -2.02096998 1.03975 -2.01895 0 P 0 ;0
L 1.03975 -2.01895 1.0393 -2.01693996 0 P 0 ;0
L 1.0393 -2.01693996 1.03868996 -2.01483996 0 P 0 ;0
L 1.03868996 -2.01483996 1.03793996 -2.01278002 0 P 0 ;0
L 1.03793996 -2.01278002 1.03658996 -2.00968002 0 P 0 ;0
L 1.03658996 -2.00968002 1.03501004 -2.00668996 0 P 0 ;0
L 1.03501004 -2.00668996 1.0332 -2.0038 0 P 0 ;0
L 1.0332 -2.0038 1.03186998 -2.002 0 P 0 ;0
L 1.03186998 -2.002 1.0304 -2.0003 0 P 0 ;0
L 1.0304 -2.0003 1.0288 -1.99873002 0 P 0 ;0
L 1.0288 -1.99873002 1.02708002 -1.99728996 0 P 0 ;0
L 1.02708002 -1.99728996 1.02518002 -1.99593002 0 P 0 ;0
L 1.02518002 -1.99593002 1.02318002 -1.99471998 0 P 0 ;0
L 1.02318002 -1.99471998 1.0211 -1.99365 0 P 0 ;0
L 1.0211 -1.99365 1.01893002 -1.99273996 0 P 0 ;0
L 1.01893002 -1.99273996 1.01358996 -1.99098996 0 P 0 ;0
L 1.01358996 -1.99098996 1.0081 -1.98971004 0 P 0 ;0
L 1.0081 -1.98971004 1.00428996 -1.98908996 0 P 0 ;0
L 1.00428996 -1.98908996 1.00043996 -1.98868002 0 P 0 ;0
L 1.00043996 -1.98868002 0.99138002 -1.98826004 0 P 0 ;0
L 0.99138002 -1.98826004 0.98251998 -1.98846998 0 P 0 ;0
L 0.98251998 -1.98846998 0.97898996 -1.98878996 0 P 0 ;0
L 0.97898996 -1.98878996 0.97546998 -1.98933996 0 P 0 ;0
L 0.91651004 -2.12516004 0.94208996 -2.12516004 0 P 0 ;0
L 0.8911 -2.12416004 0.94211004 -2.12416004 0 P 0 ;0
L 0.89118002 -2.12316004 0.94213996 -2.12316004 0 P 0 ;0
L 0.89125 -2.12216004 0.94216004 -2.12216004 0 P 0 ;0
L 0.89133002 -2.12116004 0.94218996 -2.12116004 0 P 0 ;0
L 0.89141004 -2.12016004 0.94221004 -2.12016004 0 P 0 ;0
L 0.89148996 -2.11916004 0.94223996 -2.11916004 0 P 0 ;0
L 0.89156998 -2.11816004 0.94226998 -2.11816004 0 P 0 ;0
L 0.89166004 -2.11716004 0.94228996 -2.11716004 0 P 0 ;0
L 0.89173996 -2.11616004 0.94231004 -2.11616004 0 P 0 ;0
L 0.89181998 -2.11516004 0.94233996 -2.11516004 0 P 0 ;0
L 0.8919 -2.11416004 0.94236004 -2.11416004 0 P 0 ;0
L 0.89198002 -2.11316004 0.94238996 -2.11316004 0 P 0 ;0
L 0.89206998 -2.11216004 0.94241998 -2.11216004 0 P 0 ;0
L 0.89215 -2.11116004 0.94243996 -2.11116004 0 P 0 ;0
L 0.89223002 -2.11016004 0.94246998 -2.11016004 0 P 0 ;0
L 0.89231998 -2.10916004 0.94248996 -2.10916004 0 P 0 ;0
L 0.8924 -2.10816004 0.94251998 -2.10816004 0 P 0 ;0
L 0.89248002 -2.10716004 0.94255 -2.10716004 0 P 0 ;0
L 0.89256998 -2.10616004 0.94256998 -2.10616004 0 P 0 ;0
L 0.89263996 -2.10516004 0.94258996 -2.10516004 0 P 0 ;0
L 0.89271004 -2.10416004 0.94261998 -2.10416004 0 P 0 ;0
L 0.89278996 -2.10316004 0.94263996 -2.10316004 0 P 0 ;0
L 0.89286998 -2.10216004 0.94266998 -2.10216004 0 P 0 ;0
L 0.89293996 -2.10116004 0.9427 -2.10116004 0 P 0 ;0
L 0.89301998 -2.10016004 0.94275 -2.10016004 0 P 0 ;0
L 0.89308996 -2.09916004 0.94278996 -2.09916004 0 P 0 ;0
L 0.89316998 -2.09816004 0.94283996 -2.09816004 0 P 0 ;0
L 0.89325 -2.09716004 0.94288996 -2.09716004 0 P 0 ;0
L 0.89331998 -2.09616004 0.94293996 -2.09616004 0 P 0 ;0
L 0.8934 -2.09516004 0.94298002 -2.09516004 0 P 0 ;0
L 0.89346998 -2.09416004 0.94303002 -2.09416004 0 P 0 ;0
L 0.89355 -2.09316004 0.94308002 -2.09316004 0 P 0 ;0
L 0.89361998 -2.09216004 0.94313002 -2.09216004 0 P 0 ;0
L 0.8937 -2.09116004 0.94318002 -2.09116004 0 P 0 ;0
L 0.89378002 -2.09016004 0.94321998 -2.09016004 0 P 0 ;0
L 0.89385 -2.08916004 0.94326998 -2.08916004 0 P 0 ;0
L 0.89393002 -2.08816004 0.94331998 -2.08816004 0 P 0 ;0
L 0.894 -2.08716004 0.94336004 -2.08716004 0 P 0 ;0
L 0.89406004 -2.08616004 0.94341004 -2.08616004 0 P 0 ;0
L 0.89411998 -2.08516004 0.94346004 -2.08516004 0 P 0 ;0
L 0.89418002 -2.08416004 0.94351004 -2.08416004 0 P 0 ;0
L 0.91651004 -2.12516004 0.90521998 -2.1251 0 P 0 ;0
L 0.90521998 -2.1251 0.89655 -2.12486998 0 P 0 ;0
L 0.89655 -2.12486998 0.89106004 -2.12465 0 P 0 ;0
L 0.89106004 -2.12465 0.89141998 -2.12003996 0 P 0 ;0
L 0.89141998 -2.12003996 0.89193996 -2.11373996 0 P 0 ;0
L 0.89193996 -2.11373996 0.89253996 -2.10645 0 P 0 ;0
L 0.89253996 -2.10645 0.89398002 -2.08741998 0 P 0 ;0
L 0.89398002 -2.08741998 0.89521998 -2.06621998 0 P 0 ;0
L 0.89521998 -2.06621998 0.89521998 -2.06618996 0 P 0 ;0
L 0.89521998 -2.06618996 0.89623996 -2.04323002 0 P 0 ;0
L 0.89623996 -2.04323002 0.89703996 -2.01883002 0 P 0 ;0
L 0.89703996 -2.01883002 0.8977 -1.99443996 0 P 0 ;0
L 0.8977 -1.99443996 0.94563996 -1.99443996 0 P 0 ;0
L 0.94563996 -1.99443996 0.94563996 -2.00546998 0 P 0 ;0
L 0.94563996 -2.00546998 0.94686004 -2.00731004 0 P 0 ;0
L 0.94686004 -2.00731004 0.94903002 -2.00688996 0 P 0 ;0
L 0.94903002 -2.00688996 0.95361998 -2.00241004 0 P 0 ;0
L 0.95361998 -2.00241004 0.95498996 -2.00115 0 P 0 ;0
L 0.95498996 -2.00115 0.95641998 -2.00001004 0 P 0 ;0
L 0.95641998 -2.00001004 0.9579 -1.99896004 0 P 0 ;0
L 0.9579 -1.99896004 0.96076004 -1.9972 0 P 0 ;0
L 0.96076004 -1.9972 0.9637 -1.99561998 0 P 0 ;0
L 0.9637 -1.99561998 0.96683002 -1.99416998 0 P 0 ;0
L 0.96683002 -1.99416998 0.96998996 -1.99291998 0 P 0 ;0
L 0.96998996 -1.99291998 0.9729 -1.99198996 0 P 0 ;0
L 0.9729 -1.99198996 0.97586004 -1.9913 0 P 0 ;0
L 0.97586004 -1.9913 0.97923002 -1.99076998 0 P 0 ;0
L 0.97923002 -1.99076998 0.98263002 -1.99046998 0 P 0 ;0
L 0.98263002 -1.99046998 0.99136004 -1.99026004 0 P 0 ;0
L 0.99136004 -1.99026004 1.00028996 -1.99066998 0 P 0 ;0
L 1.00028996 -1.99066998 1.00403002 -1.99108002 0 P 0 ;0
L 1.00403002 -1.99108002 1.00771004 -1.99166998 0 P 0 ;0
L 1.00771004 -1.99166998 1.01305 -1.99291998 0 P 0 ;0
L 1.01305 -1.99291998 1.01823002 -1.99461998 0 P 0 ;0
L 1.01823002 -1.99461998 1.02026004 -1.99546998 0 P 0 ;0
L 1.02026004 -1.99546998 1.02221004 -1.99646998 0 P 0 ;0
L 1.02221004 -1.99646998 1.02408002 -1.9976 0 P 0 ;0
L 1.02408002 -1.9976 1.02585 -1.99886998 0 P 0 ;0
L 1.02585 -1.99886998 1.02746004 -2.00021004 0 P 0 ;0
L 1.02746004 -2.00021004 1.02893996 -2.00166998 0 P 0 ;0
L 1.02893996 -2.00166998 1.03031004 -2.00325 0 P 0 ;0
L 1.03031004 -2.00325 1.03155 -2.00493002 0 P 0 ;0
L 1.03155 -2.00493002 1.03326998 -2.00768002 0 P 0 ;0
L 1.03326998 -2.00768002 1.03478002 -2.01055 0 P 0 ;0
L 1.03478002 -2.01055 1.03608002 -2.01351998 0 P 0 ;0
L 1.03608002 -2.01351998 1.03678996 -2.01546998 0 P 0 ;0
L 1.03678996 -2.01546998 1.03736004 -2.01743002 0 P 0 ;0
L 1.03736004 -2.01743002 1.03778002 -2.0193 0 P 0 ;0
L 1.03778002 -2.0193 1.03805 -2.02116998 0 P 0 ;0
L 1.03805 -2.02116998 1.03836998 -2.02658996 0 P 0 ;0
L 1.03836998 -2.02658996 1.03848002 -2.03698996 0 P 0 ;0
L 1.03848002 -2.03698996 1.03838996 -2.04623002 0 P 0 ;0
L 1.03838996 -2.04623002 1.03805 -2.06018996 0 P 0 ;0
L 1.03805 -2.06018996 1.03756004 -2.07583002 0 P 0 ;0
L 1.03756004 -2.07583002 1.03696998 -2.09095 0 P 0 ;0
L 1.03696998 -2.09095 1.03548996 -2.12516004 0 P 0 ;0
L 1.03548996 -2.12516004 0.98546998 -2.12516004 0 P 0 ;0
L 0.98546998 -2.12516004 0.98586998 -2.12166004 0 P 0 ;0
L 0.98586998 -2.12166004 0.98696998 -2.10871998 0 P 0 ;0
L 0.98696998 -2.10871998 0.98796004 -2.08916004 0 P 0 ;0
L 0.98796004 -2.08916004 0.9886 -2.06963002 0 P 0 ;0
L 0.9886 -2.06963002 0.98853002 -2.05698002 0 P 0 ;0
L 0.98853002 -2.05698002 0.98781998 -2.0461 0 P 0 ;0
L 0.98781998 -2.0461 0.9875 -2.04373002 0 P 0 ;0
L 0.9875 -2.04373002 0.98748002 -2.04365 0 P 0 ;0
L 0.98748002 -2.04365 0.98698996 -2.04138996 0 P 0 ;0
L 0.98698996 -2.04138996 0.9863 -2.03908002 0 P 0 ;0
L 0.9863 -2.03908002 0.98588002 -2.038 0 P 0 ;0
L 0.98588002 -2.038 0.98538002 -2.03696004 0 P 0 ;0
L 0.98538002 -2.03696004 0.9848 -2.03596004 0 P 0 ;0
L 0.9848 -2.03596004 0.98413996 -2.03501004 0 P 0 ;0
L 0.98413996 -2.03501004 0.98341998 -2.03411004 0 P 0 ;0
L 0.98341998 -2.03411004 0.98336998 -2.03405 0 P 0 ;0
L 0.98336998 -2.03405 0.98263002 -2.03326004 0 P 0 ;0
L 0.98263002 -2.03326004 0.98176998 -2.03246998 0 P 0 ;0
L 0.98176998 -2.03246998 0.98086998 -2.03175 0 P 0 ;0
L 0.98086998 -2.03175 0.97991004 -2.0311 0 P 0 ;0
L 0.97991004 -2.0311 0.9789 -2.03051998 0 P 0 ;0
L 0.9789 -2.03051998 0.97783002 -2.03001998 0 P 0 ;0
L 0.97783002 -2.03001998 0.97673002 -2.02961004 0 P 0 ;0
L 0.97673002 -2.02961004 0.97663996 -2.02958002 0 P 0 ;0
L 0.97663996 -2.02958002 0.97558996 -2.02928996 0 P 0 ;0
L 0.97558996 -2.02928996 0.97443002 -2.02906998 0 P 0 ;0
L 0.97443002 -2.02906998 0.9727 -2.02888002 0 P 0 ;0
L 0.9727 -2.02888002 0.97261998 -2.02886998 0 P 0 ;0
L 0.97261998 -2.02886998 0.97096004 -2.02881004 0 P 0 ;0
L 0.97096004 -2.02881004 0.96921004 -2.02886004 0 P 0 ;0
L 0.96921004 -2.02886004 0.96745 -2.02903996 0 P 0 ;0
L 0.96745 -2.02903996 0.96571004 -2.02933996 0 P 0 ;0
L 0.96571004 -2.02933996 0.964 -2.02976004 0 P 0 ;0
L 0.964 -2.02976004 0.96283002 -2.03013996 0 P 0 ;0
L 0.96283002 -2.03013996 0.96168002 -2.0306 0 P 0 ;0
L 0.96168002 -2.0306 0.96056998 -2.03115 0 P 0 ;0
L 0.96056998 -2.03115 0.95948996 -2.03178002 0 P 0 ;0
L 0.95948996 -2.03178002 0.95791004 -2.03286998 0 P 0 ;0
L 0.95791004 -2.03286998 0.95645 -2.03408996 0 P 0 ;0
L 0.95645 -2.03408996 0.95508996 -2.03541998 0 P 0 ;0
L 0.95508996 -2.03541998 0.95383996 -2.03686998 0 P 0 ;0
L 0.95383996 -2.03686998 0.9538 -2.03693002 0 P 0 ;0
L 0.9538 -2.03693002 0.95273002 -2.03841004 0 P 0 ;0
L 0.95273002 -2.03841004 0.95175 -2.04003996 0 P 0 ;0
L 0.95175 -2.04003996 0.95023002 -2.04306004 0 P 0 ;0
L 0.95023002 -2.04306004 0.94896004 -2.04611004 0 P 0 ;0
L 0.94896004 -2.04611004 0.94893002 -2.04616998 0 P 0 ;0
L 0.94893002 -2.04616998 0.94783002 -2.04936004 0 P 0 ;0
L 0.94783002 -2.04936004 0.94695 -2.05263002 0 P 0 ;0
L 0.94695 -2.05263002 0.94515 -2.06203002 0 P 0 ;0
L 0.94515 -2.06203002 0.9441 -2.07156004 0 P 0 ;0
L 0.9441 -2.07156004 0.9427 -2.10128002 0 P 0 ;0
L 0.9427 -2.10128002 0.94208996 -2.12516004 0 P 0 ;0
L 0.94208996 -2.12516004 0.91651004 -2.12516004 0 P 0 ;0
L 0.93143002 -2.21261998 1.00578996 -2.21261998 0 P 0 ;0
L 0.94051004 -2.21161998 1.00803002 -2.21161998 0 P 0 ;0
L 0.94941998 -2.21061998 1.01026004 -2.21061998 0 P 0 ;0
L 0.9555 -2.20961998 1.0125 -2.20961998 0 P 0 ;0
L 0.96158002 -2.20861998 1.01473996 -2.20861998 0 P 0 ;0
L 0.96766004 -2.20761998 1.01696998 -2.20761998 0 P 0 ;0
L 0.97373002 -2.20661998 1.01921004 -2.20661998 0 P 0 ;0
L 0.97981004 -2.20561998 1.02145 -2.20561998 0 P 0 ;0
L 0.98498996 -2.20461998 1.02368996 -2.20461998 0 P 0 ;0
L 0.98973996 -2.20361998 1.02591998 -2.20361998 0 P 0 ;0
L 0.99448996 -2.20261998 1.02816004 -2.20261998 0 P 0 ;0
L 0.99923996 -2.20161998 1.0304 -2.20161998 0 P 0 ;0
L 1.00398996 -2.20061998 1.03243996 -2.20061998 0 P 0 ;0
L 1.00875 -2.19961998 1.0344 -2.19961998 0 P 0 ;0
L 1.01348996 -2.19861998 1.03636998 -2.19861998 0 P 0 ;0
L 1.0178 -2.19761998 1.03833996 -2.19761998 0 P 0 ;0
L 1.02168996 -2.19661998 1.04031004 -2.19661998 0 P 0 ;0
L 1.02558002 -2.19561998 1.04228002 -2.19561998 0 P 0 ;0
L 1.02946998 -2.19461998 1.04415 -2.19461998 0 P 0 ;0
L 1.03336004 -2.19361998 1.04596998 -2.19361998 0 P 0 ;0
L 1.03725 -2.19261998 1.04778996 -2.19261998 0 P 0 ;0
L 1.04113996 -2.19161998 1.0496 -2.19161998 0 P 0 ;0
L 1.14356998 -1.98926998 1.13261004 -1.99086004 0 P 0 ;0
L 1.13261004 -1.99086004 1.12165 -1.9934 0 P 0 ;0
L 1.12165 -1.9934 1.11125 -1.99673002 0 P 0 ;0
L 1.11125 -1.99673002 1.10658002 -1.99858996 0 P 0 ;0
L 1.10658002 -1.99858996 1.10198996 -2.00071004 0 P 0 ;0
L 1.10198996 -2.00071004 1.09653002 -2.00358996 0 P 0 ;0
L 1.09653002 -2.00358996 1.09436998 -2.00488996 0 P 0 ;0
L 1.09436998 -2.00488996 1.09226004 -2.00631004 0 P 0 ;0
L 1.09226004 -2.00631004 1.09028002 -2.00781004 0 P 0 ;0
L 1.09028002 -2.00781004 1.08836998 -2.00941998 0 P 0 ;0
L 1.08836998 -2.00941998 1.08405 -2.0135 0 P 0 ;0
L 1.08405 -2.0135 1.08096998 -2.01678996 0 P 0 ;0
L 1.08096998 -2.01678996 1.07808002 -2.02026998 0 P 0 ;0
L 1.07808002 -2.02026998 1.0754 -2.02393002 0 P 0 ;0
L 1.0754 -2.02393002 1.07313996 -2.02748002 0 P 0 ;0
L 1.07313996 -2.02748002 1.07116004 -2.03118996 0 P 0 ;0
L 1.07116004 -2.03118996 1.06943996 -2.03505 0 P 0 ;0
L 1.06943996 -2.03505 1.06795 -2.03918996 0 P 0 ;0
L 1.06795 -2.03918996 1.06673996 -2.04343996 0 P 0 ;0
L 1.06673996 -2.04343996 1.06583002 -2.04778002 0 P 0 ;0
L 1.06583002 -2.04778002 1.06476998 -2.05538996 0 P 0 ;0
L 1.06476998 -2.05538996 1.06421004 -2.06306004 0 P 0 ;0
L 1.06421004 -2.06306004 1.06415 -2.07076004 0 P 0 ;0
L 1.06415 -2.07076004 1.06456998 -2.0785 0 P 0 ;0
L 1.06456998 -2.0785 1.06508996 -2.08276004 0 P 0 ;0
L 1.06508996 -2.08276004 1.06591004 -2.08696004 0 P 0 ;0
L 1.06591004 -2.08696004 1.06703002 -2.09108002 0 P 0 ;0
L 1.06703002 -2.09108002 1.06833002 -2.09473002 0 P 0 ;0
L 1.06833002 -2.09473002 1.06991998 -2.09823996 0 P 0 ;0
L 1.06991998 -2.09823996 1.0718 -2.10161998 0 P 0 ;0
L 1.0718 -2.10161998 1.07398002 -2.10491998 0 P 0 ;0
L 1.07398002 -2.10491998 1.07641998 -2.10803002 0 P 0 ;0
L 1.07641998 -2.10803002 1.07908996 -2.11095 0 P 0 ;0
L 1.07908996 -2.11095 1.08175 -2.11345 0 P 0 ;0
L 1.08175 -2.11345 1.08458996 -2.11573996 0 P 0 ;0
L 1.08458996 -2.11573996 1.08758996 -2.1178 0 P 0 ;0
L 1.08758996 -2.1178 1.09073002 -2.11963996 0 P 0 ;0
L 1.09073002 -2.11963996 1.094 -2.12123996 0 P 0 ;0
L 1.094 -2.12123996 1.0986 -2.12306998 0 P 0 ;0
L 1.0986 -2.12306998 1.10331004 -2.12456004 0 P 0 ;0
L 1.10331004 -2.12456004 1.10811004 -2.12568996 0 P 0 ;0
L 1.10811004 -2.12568996 1.11298002 -2.12646998 0 P 0 ;0
L 1.11298002 -2.12646998 1.1182 -2.12693002 0 P 0 ;0
L 1.1182 -2.12693002 1.12343996 -2.12703002 0 P 0 ;0
L 1.12343996 -2.12703002 1.12866998 -2.12676004 0 P 0 ;0
L 1.12866998 -2.12676004 1.13388002 -2.12613002 0 P 0 ;0
L 1.13388002 -2.12613002 1.14086004 -2.12473996 0 P 0 ;0
L 1.14086004 -2.12473996 1.1477 -2.12273996 0 P 0 ;0
L 1.1477 -2.12273996 1.15433996 -2.12015 0 P 0 ;0
L 1.15433996 -2.12015 1.1545 -2.12008996 0 P 0 ;0
L 1.1545 -2.12008996 1.15466004 -2.12003996 0 P 0 ;0
L 1.15466004 -2.12003996 1.15483002 -2.12001004 0 P 0 ;0
L 1.15483002 -2.12001004 1.15498996 -2.11998996 0 P 0 ;0
L 1.15498996 -2.11998996 1.15533002 -2.11998996 0 P 0 ;0
L 1.15533002 -2.11998996 1.15538996 -2.12 0 P 0 ;0
L 1.15538996 -2.12 1.15545 -2.12001998 0 P 0 ;0
L 1.15545 -2.12001998 1.15551004 -2.12003002 0 P 0 ;0
L 1.15551004 -2.12003002 1.15556004 -2.12006004 0 P 0 ;0
L 1.15556004 -2.12006004 1.15561004 -2.12008002 0 P 0 ;0
L 1.15561004 -2.12008002 1.15566004 -2.12011004 0 P 0 ;0
L 1.15566004 -2.12011004 1.15571004 -2.12015 0 P 0 ;0
L 1.15571004 -2.12015 1.15575 -2.12018996 0 P 0 ;0
L 1.15575 -2.12018996 1.15578996 -2.12023996 0 P 0 ;0
L 1.15578996 -2.12023996 1.15583002 -2.12028002 0 P 0 ;0
L 1.15583002 -2.12028002 1.15586004 -2.12033996 0 P 0 ;0
L 1.15586004 -2.12033996 1.15588002 -2.12038996 0 P 0 ;0
L 1.15588002 -2.12038996 1.15591004 -2.12043996 0 P 0 ;0
L 1.15591004 -2.12043996 1.15601998 -2.12076004 0 P 0 ;0
L 1.15601998 -2.12076004 1.1561 -2.12108002 0 P 0 ;0
L 1.1561 -2.12108002 1.15616004 -2.12141998 0 P 0 ;0
L 1.15616004 -2.12141998 1.15618002 -2.12175 0 P 0 ;0
L 1.15618002 -2.12175 1.15623996 -2.12505 0 P 0 ;0
L 1.15623996 -2.12505 1.15616004 -2.12688002 0 P 0 ;0
L 1.15616004 -2.12688002 1.15593002 -2.12871004 0 P 0 ;0
L 1.15593002 -2.12871004 1.15553996 -2.13051998 0 P 0 ;0
L 1.15553996 -2.13051998 1.15516004 -2.1318 0 P 0 ;0
L 1.15516004 -2.1318 1.1547 -2.13305 0 P 0 ;0
L 1.1547 -2.13305 1.15415 -2.13426004 0 P 0 ;0
L 1.15415 -2.13426004 1.15351004 -2.13545 0 P 0 ;0
L 1.15351004 -2.13545 1.15278996 -2.1366 0 P 0 ;0
L 1.15278996 -2.1366 1.15198002 -2.13768996 0 P 0 ;0
L 1.15198002 -2.13768996 1.15111004 -2.13873002 0 P 0 ;0
L 1.15111004 -2.13873002 1.15016004 -2.13971004 0 P 0 ;0
L 1.15016004 -2.13971004 1.14876004 -2.14096004 0 P 0 ;0
L 1.14876004 -2.14096004 1.14726004 -2.1421 0 P 0 ;0
L 1.14726004 -2.1421 1.14566998 -2.14311004 0 P 0 ;0
L 1.14566998 -2.14311004 1.144 -2.144 0 P 0 ;0
L 1.144 -2.144 1.14226004 -2.14476004 0 P 0 ;0
L 1.14226004 -2.14476004 1.14046004 -2.14536998 0 P 0 ;0
L 1.14046004 -2.14536998 1.13863002 -2.14583002 0 P 0 ;0
L 1.13863002 -2.14583002 1.13676004 -2.14613996 0 P 0 ;0
L 1.13676004 -2.14613996 1.13041998 -2.14663996 0 P 0 ;0
L 1.13041998 -2.14663996 1.12403996 -2.1466 0 P 0 ;0
L 1.12403996 -2.1466 1.11621998 -2.14593996 0 P 0 ;0
L 1.11621998 -2.14593996 1.10843996 -2.14471004 0 P 0 ;0
L 1.10843996 -2.14471004 1.09946998 -2.14276998 0 P 0 ;0
L 1.09946998 -2.14276998 1.0905 -2.14041004 0 P 0 ;0
L 1.0905 -2.14041004 1.07963996 -2.13728996 0 P 0 ;0
L 1.07963996 -2.13728996 1.07936004 -2.1401 0 P 0 ;0
L 1.07936004 -2.1401 1.07931004 -2.14103996 0 P 0 ;0
L 1.07931004 -2.14103996 1.07931998 -2.14198002 0 P 0 ;0
L 1.07931998 -2.14198002 1.07956998 -2.14735 0 P 0 ;0
L 1.07956998 -2.14735 1.07993996 -2.15375 0 P 0 ;0
L 1.07993996 -2.15375 1.08045 -2.16081998 0 P 0 ;0
L 1.08045 -2.16081998 1.08181004 -2.17873002 0 P 0 ;0
L 1.08181004 -2.17873002 1.08996004 -2.18061004 0 P 0 ;0
L 1.08996004 -2.18061004 1.09951004 -2.18246004 0 P 0 ;0
L 1.09951004 -2.18246004 1.11243996 -2.18416998 0 P 0 ;0
L 1.11243996 -2.18416998 1.1254 -2.18543002 0 P 0 ;0
L 1.1254 -2.18543002 1.13508002 -2.18583002 0 P 0 ;0
L 1.13508002 -2.18583002 1.14765 -2.18528996 0 P 0 ;0
L 1.14765 -2.18528996 1.15368002 -2.18461004 0 P 0 ;0
L 1.15368002 -2.18461004 1.15971004 -2.18363996 0 P 0 ;0
L 1.15971004 -2.18363996 1.16521004 -2.18248002 0 P 0 ;0
L 1.16521004 -2.18248002 1.17063996 -2.18103002 0 P 0 ;0
L 1.17063996 -2.18103002 1.17528996 -2.17946998 0 P 0 ;0
L 1.17528996 -2.17946998 1.17978002 -2.17753996 0 P 0 ;0
L 1.17978002 -2.17753996 1.18216998 -2.1763 0 P 0 ;0
L 1.18216998 -2.1763 1.18446004 -2.17488996 0 P 0 ;0
L 1.18446004 -2.17488996 1.18663996 -2.17331004 0 P 0 ;0
L 1.18663996 -2.17331004 1.18871004 -2.17156004 0 P 0 ;0
L 1.18871004 -2.17156004 1.19161004 -2.16871998 0 P 0 ;0
L 1.19161004 -2.16871998 1.19431004 -2.16568996 0 P 0 ;0
L 1.19431004 -2.16568996 1.19678996 -2.16246998 0 P 0 ;0
L 1.19678996 -2.16246998 1.19908996 -2.15901998 0 P 0 ;0
L 1.19908996 -2.15901998 1.20113996 -2.15543996 0 P 0 ;0
L 1.20113996 -2.15543996 1.20295 -2.15171004 0 P 0 ;0
L 1.20295 -2.15171004 1.20435 -2.14815 0 P 0 ;0
L 1.20435 -2.14815 1.20543996 -2.14448996 0 P 0 ;0
L 1.20543996 -2.14448996 1.20621004 -2.14073996 0 P 0 ;0
L 1.20621004 -2.14073996 1.20651998 -2.13855 0 P 0 ;0
L 1.20651998 -2.13855 1.20671998 -2.13633996 0 P 0 ;0
L 1.20671998 -2.13633996 1.20761998 -2.12321004 0 P 0 ;0
L 1.20761998 -2.12321004 1.20858002 -2.10753996 0 P 0 ;0
L 1.20858002 -2.10753996 1.20951004 -2.09021998 0 P 0 ;0
L 1.20951004 -2.09021998 1.21048002 -2.07166004 0 P 0 ;0
L 1.21048002 -2.07166004 1.21156004 -2.05228002 0 P 0 ;0
L 1.21156004 -2.05228002 1.21258002 -2.03478996 0 P 0 ;0
L 1.21258002 -2.03478996 1.21333002 -2.02286004 0 P 0 ;0
L 1.21333002 -2.02286004 1.21393996 -2.01373996 0 P 0 ;0
L 1.21393996 -2.01373996 1.21443996 -2.00568996 0 P 0 ;0
L 1.21443996 -2.00568996 1.21485 -1.99883996 0 P 0 ;0
L 1.21485 -1.99883996 1.2149 -1.99721004 0 P 0 ;0
L 1.2149 -1.99721004 1.21488996 -1.99703996 0 P 0 ;0
L 1.21488996 -1.99703996 1.21486998 -1.99686004 0 P 0 ;0
L 1.21486998 -1.99686004 1.21483996 -1.99668996 0 P 0 ;0
L 1.21483996 -1.99668996 1.21478996 -1.99653002 0 P 0 ;0
L 1.21478996 -1.99653002 1.21473002 -1.99636998 0 P 0 ;0
L 1.21473002 -1.99636998 1.21466004 -1.99621004 0 P 0 ;0
L 1.21466004 -1.99621004 1.21458002 -1.99606004 0 P 0 ;0
L 1.21458002 -1.99606004 1.21448002 -1.99591004 0 P 0 ;0
L 1.21448002 -1.99591004 1.21433002 -1.99571998 0 P 0 ;0
L 1.21433002 -1.99571998 1.21416998 -1.99553996 0 P 0 ;0
L 1.21416998 -1.99553996 1.21398996 -1.99538002 0 P 0 ;0
L 1.21398996 -1.99538002 1.21378996 -1.99523996 0 P 0 ;0
L 1.21378996 -1.99523996 1.21358002 -1.99511004 0 P 0 ;0
L 1.21358002 -1.99511004 1.21336004 -1.995 0 P 0 ;0
L 1.21336004 -1.995 1.21261004 -1.99468996 0 P 0 ;0
L 1.21261004 -1.99468996 1.21183996 -1.99443996 0 P 0 ;0
L 1.21183996 -1.99443996 1.21105 -1.99423002 0 P 0 ;0
L 1.21105 -1.99423002 1.20593996 -1.99318002 0 P 0 ;0
L 1.20593996 -1.99318002 1.18996998 -1.99065 0 P 0 ;0
L 1.18996998 -1.99065 1.17318996 -1.98908002 0 P 0 ;0
L 1.17318996 -1.98908002 1.15718996 -1.98858002 0 P 0 ;0
L 1.15718996 -1.98858002 1.1504 -1.98876004 0 P 0 ;0
L 1.1504 -1.98876004 1.14356998 -1.98926998 0 P 0 ;0
L 1.04503996 -2.19061998 1.05141998 -2.19061998 0 P 0 ;0
L 1.04893002 -2.18961998 1.05323002 -2.18961998 0 P 0 ;0
L 1.05263002 -2.18861998 1.05503996 -2.18861998 0 P 0 ;0
L 1.05628996 -2.18761998 1.05676004 -2.18761998 0 P 0 ;0
L 1.09645 -2.17983002 1.16738002 -2.17983002 0 P 0 ;0
L 1.09126004 -2.17883002 1.17091004 -2.17883002 0 P 0 ;0
L 1.0868 -2.17783002 1.17386998 -2.17783002 0 P 0 ;0
L 1.08368002 -2.17683002 1.17636004 -2.17683002 0 P 0 ;0
L 1.0836 -2.17583002 1.1787 -2.17583002 0 P 0 ;0
L 1.08351998 -2.17483002 1.18066998 -2.17483002 0 P 0 ;0
L 1.08345 -2.17383002 1.18236998 -2.17383002 0 P 0 ;0
L 1.08336998 -2.17283002 1.1839 -2.17283002 0 P 0 ;0
L 1.08328996 -2.17183002 1.18526998 -2.17183002 0 P 0 ;0
L 1.08321998 -2.17083002 1.18646998 -2.17083002 0 P 0 ;0
L 1.08313996 -2.16983002 1.18761998 -2.16983002 0 P 0 ;0
L 1.08306998 -2.16883002 1.18863996 -2.16883002 0 P 0 ;0
L 1.08298996 -2.16783002 1.18966004 -2.16783002 0 P 0 ;0
L 1.08291998 -2.16683002 1.19061004 -2.16683002 0 P 0 ;0
L 1.08283996 -2.16583002 1.1915 -2.16583002 0 P 0 ;0
L 1.08276004 -2.16483002 1.19238996 -2.16483002 0 P 0 ;0
L 1.08268996 -2.16383002 1.19321004 -2.16383002 0 P 0 ;0
L 1.08261004 -2.16283002 1.19398002 -2.16283002 0 P 0 ;0
L 1.08253002 -2.16183002 1.19476004 -2.16183002 0 P 0 ;0
L 1.08246004 -2.16083002 1.19548002 -2.16083002 0 P 0 ;0
L 1.08238002 -2.15983002 1.19613996 -2.15983002 0 P 0 ;0
L 1.08231004 -2.15883002 1.19681004 -2.15883002 0 P 0 ;0
L 1.08223996 -2.15783002 1.19746004 -2.15783002 0 P 0 ;0
L 1.13506998 -2.18383002 1.12553002 -2.18343996 0 P 0 ;0
L 1.12553002 -2.18343996 1.11266004 -2.18218002 0 P 0 ;0
L 1.11266004 -2.18218002 1.09983002 -2.18048002 0 P 0 ;0
L 1.09983002 -2.18048002 1.09036998 -2.17866004 0 P 0 ;0
L 1.09036998 -2.17866004 1.0837 -2.17711004 0 P 0 ;0
L 1.0837 -2.17711004 1.08245 -2.16066998 0 P 0 ;0
L 1.08245 -2.16066998 1.08193996 -2.15361998 0 P 0 ;0
L 1.08193996 -2.15361998 1.08156998 -2.14726004 0 P 0 ;0
L 1.08156998 -2.14726004 1.08131998 -2.14191004 0 P 0 ;0
L 1.08131998 -2.14191004 1.08131004 -2.14108996 0 P 0 ;0
L 1.08131004 -2.14108996 1.08136004 -2.14026004 0 P 0 ;0
L 1.08136004 -2.14026004 1.0814 -2.13986998 0 P 0 ;0
L 1.0814 -2.13986998 1.08996004 -2.14233002 0 P 0 ;0
L 1.08996004 -2.14233002 1.08996998 -2.14233996 0 P 0 ;0
L 1.08996998 -2.14233996 1.08998996 -2.14233996 0 P 0 ;0
L 1.08998996 -2.14233996 1.099 -2.14471998 0 P 0 ;0
L 1.099 -2.14471998 1.10806998 -2.14668002 0 P 0 ;0
L 1.10806998 -2.14668002 1.11598002 -2.14791998 0 P 0 ;0
L 1.11598002 -2.14791998 1.12395 -2.1486 0 P 0 ;0
L 1.12395 -2.1486 1.13048996 -2.14863996 0 P 0 ;0
L 1.13048996 -2.14863996 1.137 -2.14811998 0 P 0 ;0
L 1.137 -2.14811998 1.13903002 -2.14778996 0 P 0 ;0
L 1.13903002 -2.14778996 1.14103002 -2.14728996 0 P 0 ;0
L 1.14103002 -2.14728996 1.14298002 -2.14661998 0 P 0 ;0
L 1.14298002 -2.14661998 1.14486998 -2.14581004 0 P 0 ;0
L 1.14486998 -2.14581004 1.14668002 -2.14483996 0 P 0 ;0
L 1.14668002 -2.14483996 1.1484 -2.14373996 0 P 0 ;0
L 1.1484 -2.14373996 1.15003002 -2.1425 0 P 0 ;0
L 1.15003002 -2.1425 1.15155 -2.14115 0 P 0 ;0
L 1.15155 -2.14115 1.1526 -2.14006998 0 P 0 ;0
L 1.1526 -2.14006998 1.15263996 -2.14001998 0 P 0 ;0
L 1.15263996 -2.14001998 1.15356004 -2.13893002 0 P 0 ;0
L 1.15356004 -2.13893002 1.15443996 -2.13771998 0 P 0 ;0
L 1.15443996 -2.13771998 1.15523002 -2.13646004 0 P 0 ;0
L 1.15523002 -2.13646004 1.15593996 -2.13515 0 P 0 ;0
L 1.15593996 -2.13515 1.15655 -2.13381004 0 P 0 ;0
L 1.15655 -2.13381004 1.15706004 -2.13243002 0 P 0 ;0
L 1.15706004 -2.13243002 1.15748002 -2.13101004 0 P 0 ;0
L 1.15748002 -2.13101004 1.1579 -2.12905 0 P 0 ;0
L 1.1579 -2.12905 1.15816004 -2.12706004 0 P 0 ;0
L 1.15816004 -2.12706004 1.15825 -2.12506998 0 P 0 ;0
L 1.15825 -2.12506998 1.15818002 -2.12165 0 P 0 ;0
L 1.15818002 -2.12165 1.15813996 -2.12118002 0 P 0 ;0
L 1.15813996 -2.12118002 1.15813002 -2.1211 0 P 0 ;0
L 1.15813002 -2.1211 1.15806004 -2.12068002 0 P 0 ;0
L 1.15806004 -2.12068002 1.15793996 -2.12018996 0 P 0 ;0
L 1.15793996 -2.12018996 1.15778002 -2.11973002 0 P 0 ;0
L 1.15778002 -2.11973002 1.1577 -2.11953002 0 P 0 ;0
L 1.1577 -2.11953002 1.15758996 -2.11933002 0 P 0 ;0
L 1.15758996 -2.11933002 1.15746998 -2.11913996 0 P 0 ;0
L 1.15746998 -2.11913996 1.15733002 -2.11895 0 P 0 ;0
L 1.15733002 -2.11895 1.15716998 -2.11878002 0 P 0 ;0
L 1.15716998 -2.11878002 1.157 -2.11863002 0 P 0 ;0
L 1.157 -2.11863002 1.15681998 -2.11848996 0 P 0 ;0
L 1.15681998 -2.11848996 1.15663002 -2.11836004 0 P 0 ;0
L 1.15663002 -2.11836004 1.15641998 -2.11825 0 P 0 ;0
L 1.15641998 -2.11825 1.15621004 -2.11816004 0 P 0 ;0
L 1.15621004 -2.11816004 1.15598996 -2.11808996 0 P 0 ;0
L 1.15598996 -2.11808996 1.15576998 -2.11803996 0 P 0 ;0
L 1.15576998 -2.11803996 1.15553002 -2.118 0 P 0 ;0
L 1.15553002 -2.118 1.15518002 -2.11798002 0 P 0 ;0
L 1.15518002 -2.11798002 1.15483996 -2.11798996 0 P 0 ;0
L 1.15483996 -2.11798996 1.15451004 -2.11803002 0 P 0 ;0
L 1.15451004 -2.11803002 1.15418002 -2.1181 0 P 0 ;0
L 1.15418002 -2.1181 1.15386004 -2.1182 0 P 0 ;0
L 1.15386004 -2.1182 1.15361004 -2.11828996 0 P 0 ;0
L 1.15361004 -2.11828996 1.14705 -2.12083996 0 P 0 ;0
L 1.14705 -2.12083996 1.14038996 -2.12278996 0 P 0 ;0
L 1.14038996 -2.12278996 1.13356004 -2.12416004 0 P 0 ;0
L 1.13356004 -2.12416004 1.1285 -2.12476998 0 P 0 ;0
L 1.1285 -2.12476998 1.12341004 -2.12501998 0 P 0 ;0
L 1.12341004 -2.12501998 1.11831004 -2.12493002 0 P 0 ;0
L 1.11831004 -2.12493002 1.11323002 -2.12448996 0 P 0 ;0
L 1.11323002 -2.12448996 1.10848996 -2.12373002 0 P 0 ;0
L 1.10848996 -2.12373002 1.10383996 -2.12263002 0 P 0 ;0
L 1.10383996 -2.12263002 1.09926998 -2.12118996 0 P 0 ;0
L 1.09926998 -2.12118996 1.09481004 -2.11941004 0 P 0 ;0
L 1.09481004 -2.11941004 1.09168002 -2.11788002 0 P 0 ;0
L 1.09168002 -2.11788002 1.08866004 -2.11611998 0 P 0 ;0
L 1.08866004 -2.11611998 1.08578002 -2.11413002 0 P 0 ;0
L 1.08578002 -2.11413002 1.08306998 -2.11193996 0 P 0 ;0
L 1.08306998 -2.11193996 1.08051998 -2.10955 0 P 0 ;0
L 1.08051998 -2.10955 1.07793996 -2.10673002 0 P 0 ;0
L 1.07793996 -2.10673002 1.07561004 -2.10373996 0 P 0 ;0
L 1.07561004 -2.10373996 1.07351004 -2.10058002 0 P 0 ;0
L 1.07351004 -2.10058002 1.07171004 -2.09733996 0 P 0 ;0
L 1.07171004 -2.09733996 1.07018002 -2.09396998 0 P 0 ;0
L 1.07018002 -2.09396998 1.06893996 -2.09048002 0 P 0 ;0
L 1.06893996 -2.09048002 1.06786004 -2.0865 0 P 0 ;0
L 1.06786004 -2.0865 1.06706004 -2.08243996 0 P 0 ;0
L 1.06706004 -2.08243996 1.06656004 -2.07833002 0 P 0 ;0
L 1.06656004 -2.07833002 1.06615 -2.07071004 0 P 0 ;0
L 1.06615 -2.07071004 1.06621004 -2.06313996 0 P 0 ;0
L 1.06621004 -2.06313996 1.06675 -2.0556 0 P 0 ;0
L 1.06675 -2.0556 1.0678 -2.04813002 0 P 0 ;0
L 1.0678 -2.04813002 1.06868996 -2.04391998 0 P 0 ;0
L 1.06868996 -2.04391998 1.06985 -2.03981004 0 P 0 ;0
L 1.06985 -2.03981004 1.0713 -2.03578996 0 P 0 ;0
L 1.0713 -2.03578996 1.07296004 -2.03206998 0 P 0 ;0
L 1.07296004 -2.03206998 1.07486998 -2.02848996 0 P 0 ;0
L 1.07486998 -2.02848996 1.07705 -2.02506004 0 P 0 ;0
L 1.07705 -2.02506004 1.07966004 -2.0215 0 P 0 ;0
L 1.07966004 -2.0215 1.08246998 -2.01811004 0 P 0 ;0
L 1.08246998 -2.01811004 1.08546998 -2.01491004 0 P 0 ;0
L 1.08546998 -2.01491004 1.0897 -2.01091004 0 P 0 ;0
L 1.0897 -2.01091004 1.09153002 -2.00936998 0 P 0 ;0
L 1.09153002 -2.00936998 1.09341998 -2.00793996 0 P 0 ;0
L 1.09341998 -2.00793996 1.09545 -2.00658002 0 P 0 ;0
L 1.09545 -2.00658002 1.09751004 -2.00533996 0 P 0 ;0
L 1.09751004 -2.00533996 1.10288002 -2.0025 0 P 0 ;0
L 1.10288002 -2.0025 1.10736998 -2.00043002 0 P 0 ;0
L 1.10736998 -2.00043002 1.11193002 -1.99861004 0 P 0 ;0
L 1.11193002 -1.99861004 1.12218002 -1.99533002 0 P 0 ;0
L 1.12218002 -1.99533002 1.13298002 -1.99281998 0 P 0 ;0
L 1.13298002 -1.99281998 1.14378996 -1.99126004 0 P 0 ;0
L 1.14378996 -1.99126004 1.1505 -1.99075 0 P 0 ;0
L 1.1505 -1.99075 1.15718002 -1.99058996 0 P 0 ;0
L 1.15718002 -1.99058996 1.17306998 -1.99108002 0 P 0 ;0
L 1.17306998 -1.99108002 1.18971998 -1.99263002 0 P 0 ;0
L 1.18971998 -1.99263002 1.20558002 -1.99515 0 P 0 ;0
L 1.20558002 -1.99515 1.21058996 -1.99618002 0 P 0 ;0
L 1.21058996 -1.99618002 1.21126998 -1.99636004 0 P 0 ;0
L 1.21126998 -1.99636004 1.21191998 -1.99656998 0 P 0 ;0
L 1.21191998 -1.99656998 1.21253002 -1.99681998 0 P 0 ;0
L 1.21253002 -1.99681998 1.21261004 -1.99686004 0 P 0 ;0
L 1.21261004 -1.99686004 1.21266004 -1.99688996 0 P 0 ;0
L 1.21266004 -1.99688996 1.21271998 -1.99693002 0 P 0 ;0
L 1.21271998 -1.99693002 1.21281998 -1.99703002 0 P 0 ;0
L 1.21281998 -1.99703002 1.21286004 -1.99708996 0 P 0 ;0
L 1.21286004 -1.99708996 1.21288002 -1.99711004 0 P 0 ;0
L 1.21288002 -1.99711004 1.21288002 -1.99711998 0 P 0 ;0
L 1.21288002 -1.99711998 1.21288996 -1.99715 0 P 0 ;0
L 1.21288996 -1.99715 1.2129 -1.99716998 0 P 0 ;0
L 1.2129 -1.99716998 1.2129 -1.99721998 0 P 0 ;0
L 1.2129 -1.99721998 1.21285 -1.99875 0 P 0 ;0
L 1.21285 -1.99875 1.21243996 -2.00556998 0 P 0 ;0
L 1.21243996 -2.00556998 1.21193996 -2.01361004 0 P 0 ;0
L 1.21193996 -2.01361004 1.21133996 -2.02273002 0 P 0 ;0
L 1.21133996 -2.02273002 1.21133996 -2.02273996 0 P 0 ;0
L 1.21133996 -2.02273996 1.21058996 -2.03468002 0 P 0 ;0
L 1.21058996 -2.03468002 1.20956004 -2.05216998 0 P 0 ;0
L 1.20956004 -2.05216998 1.20848996 -2.07156004 0 P 0 ;0
L 1.20848996 -2.07156004 1.20848996 -2.07156998 0 P 0 ;0
L 1.20848996 -2.07156998 1.20751004 -2.09011004 0 P 0 ;0
L 1.20751004 -2.09011004 1.20658996 -2.10743996 0 P 0 ;0
L 1.20658996 -2.10743996 1.20561998 -2.12308996 0 P 0 ;0
L 1.20561998 -2.12308996 1.20473002 -2.13618996 0 P 0 ;0
L 1.20473002 -2.13618996 1.20453002 -2.13831998 0 P 0 ;0
L 1.20453002 -2.13831998 1.20423996 -2.14041004 0 P 0 ;0
L 1.20423996 -2.14041004 1.2035 -2.144 0 P 0 ;0
L 1.2035 -2.144 1.20246004 -2.1475 0 P 0 ;0
L 1.20246004 -2.1475 1.20111998 -2.1509 0 P 0 ;0
L 1.20111998 -2.1509 1.19936998 -2.1545 0 P 0 ;0
L 1.19936998 -2.1545 1.19738002 -2.15796998 0 P 0 ;0
L 1.19738002 -2.15796998 1.19516004 -2.1613 0 P 0 ;0
L 1.19516004 -2.1613 1.19276998 -2.16441004 0 P 0 ;0
L 1.19276998 -2.16441004 1.19016004 -2.16733996 0 P 0 ;0
L 1.19016004 -2.16733996 1.18736004 -2.17008002 0 P 0 ;0
L 1.18736004 -2.17008002 1.1854 -2.17173996 0 P 0 ;0
L 1.1854 -2.17173996 1.18335 -2.17323002 0 P 0 ;0
L 1.18335 -2.17323002 1.18118002 -2.17456004 0 P 0 ;0
L 1.18118002 -2.17456004 1.17893002 -2.17573002 0 P 0 ;0
L 1.17893002 -2.17573002 1.17456998 -2.1776 0 P 0 ;0
L 1.17456998 -2.1776 1.17006998 -2.17911998 0 P 0 ;0
L 1.17006998 -2.17911998 1.16473996 -2.18053002 0 P 0 ;0
L 1.16473996 -2.18053002 1.15935 -2.18166998 0 P 0 ;0
L 1.15935 -2.18166998 1.15341998 -2.18263002 0 P 0 ;0
L 1.15341998 -2.18263002 1.1475 -2.18328996 0 P 0 ;0
L 1.1475 -2.18328996 1.13506998 -2.18383002 0 P 0 ;0
L 0.90491998 -2.21461998 1.00131004 -2.21461998 0 P 0 ;0
L 0.92235 -2.21361998 1.00355 -2.21361998 0 P 0 ;0
L 0.76925 -1.8965 0.85586998 -1.8965 0 P 0 ;0
L 0.76958996 -1.8955 0.85556004 -1.8955 0 P 0 ;0
L 0.76995 -1.8945 0.85521004 -1.8945 0 P 0 ;0
L 0.77031004 -1.8935 0.85486004 -1.8935 0 P 0 ;0
L 0.77071004 -1.8925 0.85443996 -1.8925 0 P 0 ;0
L 0.77115 -1.8915 0.85401004 -1.8915 0 P 0 ;0
L 0.7716 -1.8905 0.85355 -1.8905 0 P 0 ;0
L 0.77206004 -1.8895 0.85303002 -1.8895 0 P 0 ;0
L 0.7726 -1.8885 0.85251004 -1.8885 0 P 0 ;0
L 0.77313996 -1.8875 0.85198996 -1.8875 0 P 0 ;0
L 0.77368996 -1.8865 0.85138002 -1.8865 0 P 0 ;0
L 0.77433002 -1.8855 0.85073996 -1.8855 0 P 0 ;0
L 0.77496004 -1.8845 0.85011004 -1.8845 0 P 0 ;0
L 0.77561998 -1.8835 0.84943002 -1.8835 0 P 0 ;0
L 0.77636004 -1.8825 0.84866998 -1.8825 0 P 0 ;0
L 0.77711004 -1.8815 0.84791004 -1.8815 0 P 0 ;0
L 0.7779 -1.8805 0.84713002 -1.8805 0 P 0 ;0
L 0.77876998 -1.8795 0.84623002 -1.8795 0 P 0 ;0
L 0.77963996 -1.8785 0.84533002 -1.8785 0 P 0 ;0
L 0.7806 -1.8775 0.8444 -1.8775 0 P 0 ;0
L 0.78161004 -1.8765 0.84335 -1.8765 0 P 0 ;0
L 0.78265 -1.8755 0.84228996 -1.8755 0 P 0 ;0
L 0.78381998 -1.8745 0.84108996 -1.8745 0 P 0 ;0
L 0.78498996 -1.8735 0.83986998 -1.8735 0 P 0 ;0
L 0.78635 -1.8725 0.83848002 -1.8725 0 P 0 ;0
L 0.78773002 -1.8715 0.83706004 -1.8715 0 P 0 ;0
L 0.78933002 -1.8705 0.83541998 -1.8705 0 P 0 ;0
L 0.791 -1.8695 0.83366004 -1.8695 0 P 0 ;0
L 0.793 -1.8685 0.83171998 -1.8685 0 P 0 ;0
L 0.79525 -1.8675 0.82941998 -1.8675 0 P 0 ;0
L 0.79791998 -1.8665 0.82671004 -1.8665 0 P 0 ;0
L 0.80143996 -1.8655 0.82328996 -1.8655 0 P 0 ;0
L 0.80705 -1.8645 0.81776004 -1.8645 0 P 0 ;0
L 0.74543002 -1.89661998 0.75033002 -1.89661998 0 P 0 ;0
L 0.74751004 -1.89561998 0.75058996 -1.89561998 0 P 0 ;0
L 0.74958996 -1.89461998 0.75086004 -1.89461998 0 P 0 ;0
L 0.76733996 -1.9125 0.85751998 -1.9125 0 P 0 ;0
L 0.76728996 -1.9115 0.85756004 -1.9115 0 P 0 ;0
L 0.76723996 -1.9105 0.85758996 -1.9105 0 P 0 ;0
L 0.76721998 -1.9095 0.85763002 -1.9095 0 P 0 ;0
L 0.76725 -1.9085 0.85761004 -1.9085 0 P 0 ;0
L 0.76728002 -1.9075 0.85756998 -1.9075 0 P 0 ;0
L 0.76731004 -1.9065 0.85753002 -1.9065 0 P 0 ;0
L 0.76741998 -1.9055 0.85748996 -1.9055 0 P 0 ;0
L 0.76753996 -1.9045 0.85738002 -1.9045 0 P 0 ;0
L 0.76766004 -1.9035 0.85726004 -1.9035 0 P 0 ;0
L 0.76781998 -1.9025 0.85713996 -1.9025 0 P 0 ;0
L 0.76801998 -1.9015 0.85701004 -1.9015 0 P 0 ;0
L 0.76821004 -1.9005 0.85683002 -1.9005 0 P 0 ;0
L 0.76841998 -1.8995 0.85661998 -1.8995 0 P 0 ;0
L 0.7687 -1.8985 0.85641004 -1.8985 0 P 0 ;0
L 0.76896998 -1.8975 0.85613996 -1.8975 0 P 0 ;0
L 0.76751004 -2.08325 0.8416 -2.08325 0 P 0 ;0
L 0.76761998 -2.08225 0.84161998 -2.08225 0 P 0 ;0
L 0.76773996 -2.08125 0.84166998 -2.08125 0 P 0 ;0
L 0.76786004 -2.08025 0.84171998 -2.08025 0 P 0 ;0
L 0.76796998 -2.07925 0.84176998 -2.07925 0 P 0 ;0
L 0.76808002 -2.07825 0.84181004 -2.07825 0 P 0 ;0
L 0.76818002 -2.07725 0.84186004 -2.07725 0 P 0 ;0
L 0.76828996 -2.07625 0.8419 -2.07625 0 P 0 ;0
L 0.76838996 -2.07525 0.84195 -2.07525 0 P 0 ;0
L 0.76848996 -2.07425 0.842 -2.07425 0 P 0 ;0
L 0.7686 -2.07325 0.84205 -2.07325 0 P 0 ;0
L 0.7687 -2.07225 0.84208996 -2.07225 0 P 0 ;0
L 0.7688 -2.07125 0.84213996 -2.07125 0 P 0 ;0
L 0.7689 -2.07025 0.84218002 -2.07025 0 P 0 ;0
L 0.76901004 -2.06925 0.84223002 -2.06925 0 P 0 ;0
L 0.76911004 -2.06825 0.84228002 -2.06825 0 P 0 ;0
L 0.76921004 -2.06725 0.84233002 -2.06725 0 P 0 ;0
L 0.76931998 -2.06625 0.84236998 -2.06625 0 P 0 ;0
L 0.76941998 -2.06525 0.84241998 -2.06525 0 P 0 ;0
L 0.76948996 -2.06425 0.84246004 -2.06425 0 P 0 ;0
L 0.76956004 -2.06325 0.84251004 -2.06325 0 P 0 ;0
L 0.76963002 -2.06225 0.84256004 -2.06225 0 P 0 ;0
L 0.7697 -2.06125 0.8426 -2.06125 0 P 0 ;0
L 0.76976998 -2.06025 0.84265 -2.06025 0 P 0 ;0
L 0.76983996 -2.05925 0.8427 -2.05925 0 P 0 ;0
L 0.76991004 -2.05825 0.84273996 -2.05825 0 P 0 ;0
L 0.76996998 -2.05725 0.84278996 -2.05725 0 P 0 ;0
L 0.77001004 -2.05625 0.84283996 -2.05625 0 P 0 ;0
L 0.77003996 -2.05525 0.84288002 -2.05525 0 P 0 ;0
L 0.77008002 -2.05425 0.84295 -2.05425 0 P 0 ;0
L 0.77011998 -2.05325 0.84303996 -2.05325 0 P 0 ;0
L 0.77016004 -2.05225 0.84311998 -2.05225 0 P 0 ;0
L 0.77018996 -2.05125 0.84321004 -2.05125 0 P 0 ;0
L 0.77023002 -2.05025 0.8433 -2.05025 0 P 0 ;0
L 0.77026998 -2.04925 0.84338002 -2.04925 0 P 0 ;0
L 0.77031004 -2.04825 0.84346998 -2.04825 0 P 0 ;0
L 0.77033996 -2.04725 0.84356004 -2.04725 0 P 0 ;0
L 0.77038002 -2.04625 0.84363996 -2.04625 0 P 0 ;0
L 0.77041004 -2.04525 0.84373002 -2.04525 0 P 0 ;0
L 0.77043996 -2.04425 0.84381004 -2.04425 0 P 0 ;0
L 0.77046004 -2.04325 0.8439 -2.04325 0 P 0 ;0
L 0.77048002 -2.04225 0.84398996 -2.04225 0 P 0 ;0
L 0.77051004 -2.04125 0.84406998 -2.04125 0 P 0 ;0
L 0.77053002 -2.04025 0.84416004 -2.04025 0 P 0 ;0
L 0.77055 -2.03925 0.84425 -2.03925 0 P 0 ;0
L 0.77058002 -2.03825 0.84433002 -2.03825 0 P 0 ;0
L 0.7706 -2.03725 0.84441998 -2.03725 0 P 0 ;0
L 0.77061998 -2.03625 0.84451004 -2.03625 0 P 0 ;0
L 0.77065 -2.03525 0.84458996 -2.03525 0 P 0 ;0
L 0.77066998 -2.03425 0.84468002 -2.03425 0 P 0 ;0
L 0.7707 -2.03325 0.84476998 -2.03325 0 P 0 ;0
L 0.77071998 -2.03225 0.84485 -2.03225 0 P 0 ;0
L 0.77073002 -2.03125 0.84493996 -2.03125 0 P 0 ;0
L 0.77073996 -2.03025 0.84503002 -2.03025 0 P 0 ;0
L 0.79986004 -1.8638 0.79643996 -1.86486998 0 P 0 ;0
L 0.79643996 -1.86486998 0.79311998 -1.86621004 0 P 0 ;0
L 0.79311998 -1.86621004 0.78991004 -1.86781004 0 P 0 ;0
L 0.78991004 -1.86781004 0.78683996 -1.86966998 0 P 0 ;0
L 0.78683996 -1.86966998 0.78391998 -1.87178002 0 P 0 ;0
L 0.78391998 -1.87178002 0.78111998 -1.87416998 0 P 0 ;0
L 0.78111998 -1.87416998 0.7785 -1.87676004 0 P 0 ;0
L 0.7785 -1.87676004 0.77608002 -1.87953996 0 P 0 ;0
L 0.77608002 -1.87953996 0.77386998 -1.8825 0 P 0 ;0
L 0.77386998 -1.8825 0.77188002 -1.88561998 0 P 0 ;0
L 0.77188002 -1.88561998 0.77013996 -1.88886004 0 P 0 ;0
L 0.77013996 -1.88886004 0.76863996 -1.89221004 0 P 0 ;0
L 0.76863996 -1.89221004 0.7674 -1.89566998 0 P 0 ;0
L 0.7674 -1.89566998 0.76643002 -1.89921004 0 P 0 ;0
L 0.76643002 -1.89921004 0.76571004 -1.90283996 0 P 0 ;0
L 0.76571004 -1.90283996 0.76531004 -1.90636004 0 P 0 ;0
L 0.76531004 -1.90636004 0.7652 -1.90991004 0 P 0 ;0
L 0.7652 -1.90991004 0.76538996 -1.91345 0 P 0 ;0
L 0.76538996 -1.91345 0.76586998 -1.91696998 0 P 0 ;0
L 0.76586998 -1.91696998 0.76663996 -1.92046004 0 P 0 ;0
L 0.76663996 -1.92046004 0.76803002 -1.92493996 0 P 0 ;0
L 0.76803002 -1.92493996 0.76978002 -1.9293 0 P 0 ;0
L 0.76978002 -1.9293 0.77106998 -1.93193996 0 P 0 ;0
L 0.77106998 -1.93193996 0.77253002 -1.93448002 0 P 0 ;0
L 0.77253002 -1.93448002 0.77416004 -1.93693996 0 P 0 ;0
L 0.77416004 -1.93693996 0.77593002 -1.93923002 0 P 0 ;0
L 0.77593002 -1.93923002 0.77783996 -1.94141004 0 P 0 ;0
L 0.77783996 -1.94141004 0.77988996 -1.94345 0 P 0 ;0
L 0.77988996 -1.94345 0.78216004 -1.94545 0 P 0 ;0
L 0.78216004 -1.94545 0.78453996 -1.9473 0 P 0 ;0
L 0.78453996 -1.9473 0.78703002 -1.94901998 0 P 0 ;0
L 0.78703002 -1.94901998 0.79016998 -1.95088002 0 P 0 ;0
L 0.79016998 -1.95088002 0.79343996 -1.95248996 0 P 0 ;0
L 0.79343996 -1.95248996 0.79683002 -1.95383996 0 P 0 ;0
L 0.79683002 -1.95383996 0.80031998 -1.95491998 0 P 0 ;0
L 0.80031998 -1.95491998 0.80391004 -1.95573996 0 P 0 ;0
L 0.80391004 -1.95573996 0.80751998 -1.95626004 0 P 0 ;0
L 0.80751998 -1.95626004 0.81116004 -1.9565 0 P 0 ;0
L 0.81116004 -1.9565 0.81481004 -1.95646004 0 P 0 ;0
L 0.81481004 -1.95646004 0.81843996 -1.95613002 0 P 0 ;0
L 0.81843996 -1.95613002 0.82205 -1.95551004 0 P 0 ;0
L 0.82205 -1.95551004 0.82561998 -1.95461004 0 P 0 ;0
L 0.82561998 -1.95461004 0.82911004 -1.95345 0 P 0 ;0
L 0.82911004 -1.95345 0.83248996 -1.95201004 0 P 0 ;0
L 0.83248996 -1.95201004 0.83576004 -1.95031998 0 P 0 ;0
L 0.83576004 -1.95031998 0.83891998 -1.94836004 0 P 0 ;0
L 0.83891998 -1.94836004 0.84191998 -1.94616998 0 P 0 ;0
L 0.84191998 -1.94616998 0.84475 -1.94375 0 P 0 ;0
L 0.84475 -1.94375 0.84738996 -1.94113996 0 P 0 ;0
L 0.84738996 -1.94113996 0.84983002 -1.93833996 0 P 0 ;0
L 0.84983002 -1.93833996 0.85206998 -1.93533996 0 P 0 ;0
L 0.85206998 -1.93533996 0.8536 -1.93291998 0 P 0 ;0
L 0.8536 -1.93291998 0.85496004 -1.93041004 0 P 0 ;0
L 0.85496004 -1.93041004 0.85613996 -1.9278 0 P 0 ;0
L 0.85613996 -1.9278 0.85711998 -1.92511004 0 P 0 ;0
L 0.85711998 -1.92511004 0.85823002 -1.92123002 0 P 0 ;0
L 0.85823002 -1.92123002 0.85901998 -1.91726998 0 P 0 ;0
L 0.85901998 -1.91726998 0.85948996 -1.91323996 0 P 0 ;0
L 0.85948996 -1.91323996 0.85963996 -1.90918002 0 P 0 ;0
L 0.85963996 -1.90918002 0.85946998 -1.90513002 0 P 0 ;0
L 0.85946998 -1.90513002 0.85898002 -1.9011 0 P 0 ;0
L 0.85898002 -1.9011 0.85841998 -1.89826004 0 P 0 ;0
L 0.85841998 -1.89826004 0.85766004 -1.89546004 0 P 0 ;0
L 0.85766004 -1.89546004 0.85671004 -1.89273002 0 P 0 ;0
L 0.85671004 -1.89273002 0.85556998 -1.89006004 0 P 0 ;0
L 0.85556998 -1.89006004 0.85361998 -1.88631004 0 P 0 ;0
L 0.85361998 -1.88631004 0.85136004 -1.88273996 0 P 0 ;0
L 0.85136004 -1.88273996 0.84881004 -1.87938002 0 P 0 ;0
L 0.84881004 -1.87938002 0.84596998 -1.87623002 0 P 0 ;0
L 0.84596998 -1.87623002 0.84355 -1.87393996 0 P 0 ;0
L 0.84355 -1.87393996 0.84096998 -1.87181998 0 P 0 ;0
L 0.84096998 -1.87181998 0.83826004 -1.86988996 0 P 0 ;0
L 0.83826004 -1.86988996 0.83541004 -1.86815 0 P 0 ;0
L 0.83541004 -1.86815 0.83243996 -1.86661004 0 P 0 ;0
L 0.83243996 -1.86661004 0.82938996 -1.86531004 0 P 0 ;0
L 0.82938996 -1.86531004 0.82625 -1.86423002 0 P 0 ;0
L 0.82625 -1.86423002 0.82303996 -1.86336004 0 P 0 ;0
L 0.82303996 -1.86336004 0.81978002 -1.86273002 0 P 0 ;0
L 0.81978002 -1.86273002 0.81646998 -1.86233002 0 P 0 ;0
L 0.81646998 -1.86233002 0.81228996 -1.86215 0 P 0 ;0
L 0.81228996 -1.86215 0.80811004 -1.86233996 0 P 0 ;0
L 0.80811004 -1.86233996 0.80396004 -1.86288996 0 P 0 ;0
L 0.80396004 -1.86288996 0.79986004 -1.8638 0 P 0 ;0
L 0.80308996 -1.9535 0.82186004 -1.9535 0 P 0 ;0
L 0.79926004 -1.9525 0.82563996 -1.9525 0 P 0 ;0
L 0.79636004 -1.9515 0.82856998 -1.9515 0 P 0 ;0
L 0.79393002 -1.9505 0.83093996 -1.9505 0 P 0 ;0
L 0.7919 -1.9495 0.83298996 -1.9495 0 P 0 ;0
L 0.79008002 -1.9485 0.8349 -1.9485 0 P 0 ;0
L 0.78838996 -1.9475 0.83651004 -1.9475 0 P 0 ;0
L 0.7869 -1.9465 0.83806998 -1.9465 0 P 0 ;0
L 0.78548002 -1.9455 0.83943996 -1.9455 0 P 0 ;0
L 0.7842 -1.9445 0.84078996 -1.9445 0 P 0 ;0
L 0.78298002 -1.9435 0.84196998 -1.9435 0 P 0 ;0
L 0.78183996 -1.9425 0.84313996 -1.9425 0 P 0 ;0
L 0.78076998 -1.9415 0.84418996 -1.9415 0 P 0 ;0
L 0.77976004 -1.9405 0.8452 -1.9405 0 P 0 ;0
L 0.77883002 -1.9395 0.84616998 -1.9395 0 P 0 ;0
L 0.77793996 -1.9385 0.84703996 -1.9385 0 P 0 ;0
L 0.77711998 -1.9375 0.84791004 -1.9375 0 P 0 ;0
L 0.77635 -1.9365 0.84871004 -1.9365 0 P 0 ;0
L 0.77561004 -1.9355 0.84945 -1.9355 0 P 0 ;0
L 0.77493996 -1.9345 0.8502 -1.9345 0 P 0 ;0
L 0.77428002 -1.9335 0.85086998 -1.9335 0 P 0 ;0
L 0.7737 -1.9325 0.8515 -1.9325 0 P 0 ;0
L 0.77311998 -1.9315 0.8521 -1.9315 0 P 0 ;0
L 0.77258996 -1.9305 0.85263996 -1.9305 0 P 0 ;0
L 0.7721 -1.9295 0.85318002 -1.9295 0 P 0 ;0
L 0.77161004 -1.9285 0.85363002 -1.9285 0 P 0 ;0
L 0.77121004 -1.9275 0.85408002 -1.9275 0 P 0 ;0
L 0.77081004 -1.9265 0.85448002 -1.9265 0 P 0 ;0
L 0.77041004 -1.9255 0.85485 -1.9255 0 P 0 ;0
L 0.77001004 -1.9245 0.85521998 -1.9245 0 P 0 ;0
L 0.76968002 -1.9235 0.8555 -1.9235 0 P 0 ;0
L 0.76936998 -1.9225 0.85578996 -1.9225 0 P 0 ;0
L 0.76906004 -1.9215 0.85606998 -1.9215 0 P 0 ;0
L 0.76875 -1.9205 0.85633002 -1.9205 0 P 0 ;0
L 0.76848002 -1.9195 0.85653002 -1.9195 0 P 0 ;0
L 0.76826004 -1.9185 0.85673002 -1.9185 0 P 0 ;0
L 0.76803002 -1.9175 0.85693002 -1.9175 0 P 0 ;0
L 0.76783002 -1.9165 0.85708996 -1.9165 0 P 0 ;0
L 0.76768996 -1.9155 0.85721004 -1.9155 0 P 0 ;0
L 0.76755 -1.9145 0.85733002 -1.9145 0 P 0 ;0
L 0.76741998 -1.9135 0.85745 -1.9135 0 P 0 ;0
L 0.81121004 -1.9545 0.80773002 -1.95426998 0 P 0 ;0
L 0.80773002 -1.95426998 0.80426998 -1.95376998 0 P 0 ;0
L 0.80426998 -1.95376998 0.80083996 -1.95298996 0 P 0 ;0
L 0.80083996 -1.95298996 0.7975 -1.95195 0 P 0 ;0
L 0.7975 -1.95195 0.79426004 -1.95066004 0 P 0 ;0
L 0.79426004 -1.95066004 0.79111998 -1.94911998 0 P 0 ;0
L 0.79111998 -1.94911998 0.78811004 -1.94733002 0 P 0 ;0
L 0.78811004 -1.94733002 0.78573002 -1.94568996 0 P 0 ;0
L 0.78573002 -1.94568996 0.78343996 -1.9439 0 P 0 ;0
L 0.78343996 -1.9439 0.78126004 -1.94198996 0 P 0 ;0
L 0.78126004 -1.94198996 0.7793 -1.94003996 0 P 0 ;0
L 0.7793 -1.94003996 0.77746998 -1.93796004 0 P 0 ;0
L 0.77746998 -1.93796004 0.77578996 -1.93576998 0 P 0 ;0
L 0.77578996 -1.93576998 0.77423002 -1.93343002 0 P 0 ;0
L 0.77423002 -1.93343002 0.77283996 -1.931 0 P 0 ;0
L 0.77283996 -1.931 0.77161004 -1.92848996 0 P 0 ;0
L 0.77161004 -1.92848996 0.76991998 -1.92426998 0 P 0 ;0
L 0.76991998 -1.92426998 0.76858002 -1.91993996 0 P 0 ;0
L 0.76858002 -1.91993996 0.76783996 -1.91661998 0 P 0 ;0
L 0.76783996 -1.91661998 0.76738002 -1.91326998 0 P 0 ;0
L 0.76738002 -1.91326998 0.76721004 -1.90988996 0 P 0 ;0
L 0.76721004 -1.90988996 0.76731004 -1.90651004 0 P 0 ;0
L 0.76731004 -1.90651004 0.7677 -1.90315 0 P 0 ;0
L 0.7677 -1.90315 0.76838002 -1.89966998 0 P 0 ;0
L 0.76838002 -1.89966998 0.76931004 -1.89626998 0 P 0 ;0
L 0.76931004 -1.89626998 0.7705 -1.89296004 0 P 0 ;0
L 0.7705 -1.89296004 0.77193996 -1.88973996 0 P 0 ;0
L 0.77193996 -1.88973996 0.7736 -1.88663996 0 P 0 ;0
L 0.7736 -1.88663996 0.77551004 -1.88363996 0 P 0 ;0
L 0.77551004 -1.88363996 0.77763002 -1.8808 0 P 0 ;0
L 0.77763002 -1.8808 0.77996004 -1.87813002 0 P 0 ;0
L 0.77996004 -1.87813002 0.78246998 -1.87565 0 P 0 ;0
L 0.78246998 -1.87565 0.78516004 -1.87336004 0 P 0 ;0
L 0.78516004 -1.87336004 0.78795 -1.87133996 0 P 0 ;0
L 0.78795 -1.87133996 0.79088002 -1.86956004 0 P 0 ;0
L 0.79088002 -1.86956004 0.79393996 -1.86803002 0 P 0 ;0
L 0.79393996 -1.86803002 0.79711004 -1.86675 0 P 0 ;0
L 0.79711004 -1.86675 0.80038002 -1.86573002 0 P 0 ;0
L 0.80038002 -1.86573002 0.80431004 -1.86486004 0 P 0 ;0
L 0.80431004 -1.86486004 0.80828996 -1.86433996 0 P 0 ;0
L 0.80828996 -1.86433996 0.8123 -1.86416004 0 P 0 ;0
L 0.8123 -1.86416004 0.81631004 -1.86431998 0 P 0 ;0
L 0.81631004 -1.86431998 0.81946998 -1.86471004 0 P 0 ;0
L 0.81946998 -1.86471004 0.82258996 -1.86531004 0 P 0 ;0
L 0.82258996 -1.86531004 0.82566004 -1.86613996 0 P 0 ;0
L 0.82566004 -1.86613996 0.82866998 -1.86718002 0 P 0 ;0
L 0.82866998 -1.86718002 0.83158996 -1.86843002 0 P 0 ;0
L 0.83158996 -1.86843002 0.83443002 -1.86988996 0 P 0 ;0
L 0.83443002 -1.86988996 0.83716004 -1.87156004 0 P 0 ;0
L 0.83716004 -1.87156004 0.83976004 -1.87341004 0 P 0 ;0
L 0.83976004 -1.87341004 0.84223002 -1.87543996 0 P 0 ;0
L 0.84223002 -1.87543996 0.84453996 -1.87763002 0 P 0 ;0
L 0.84453996 -1.87763002 0.84726998 -1.88065 0 P 0 ;0
L 0.84726998 -1.88065 0.84971998 -1.88388002 0 P 0 ;0
L 0.84971998 -1.88388002 0.85188996 -1.88731004 0 P 0 ;0
L 0.85188996 -1.88731004 0.85376004 -1.89091004 0 P 0 ;0
L 0.85376004 -1.89091004 0.85483996 -1.89345 0 P 0 ;0
L 0.85483996 -1.89345 0.85575 -1.89605 0 P 0 ;0
L 0.85575 -1.89605 0.85646998 -1.89871004 0 P 0 ;0
L 0.85646998 -1.89871004 0.857 -1.90141004 0 P 0 ;0
L 0.857 -1.90141004 0.85748002 -1.9053 0 P 0 ;0
L 0.85748002 -1.9053 0.85763996 -1.90918996 0 P 0 ;0
L 0.85763996 -1.90918996 0.8575 -1.91308002 0 P 0 ;0
L 0.8575 -1.91308002 0.85703996 -1.91696004 0 P 0 ;0
L 0.85703996 -1.91696004 0.85628002 -1.92076004 0 P 0 ;0
L 0.85628002 -1.92076004 0.85521998 -1.92448996 0 P 0 ;0
L 0.85521998 -1.92448996 0.85428002 -1.92705 0 P 0 ;0
L 0.85428002 -1.92705 0.85316998 -1.92951998 0 P 0 ;0
L 0.85316998 -1.92951998 0.85188002 -1.93191004 0 P 0 ;0
L 0.85188002 -1.93191004 0.85041998 -1.9342 0 P 0 ;0
L 0.85041998 -1.9342 0.84826998 -1.93708002 0 P 0 ;0
L 0.84826998 -1.93708002 0.84593002 -1.93976998 0 P 0 ;0
L 0.84593002 -1.93976998 0.8434 -1.94228002 0 P 0 ;0
L 0.8434 -1.94228002 0.84068002 -1.9446 0 P 0 ;0
L 0.84068002 -1.9446 0.8378 -1.9467 0 P 0 ;0
L 0.8378 -1.9467 0.83476998 -1.94858002 0 P 0 ;0
L 0.83476998 -1.94858002 0.83163996 -1.9502 0 P 0 ;0
L 0.83163996 -1.9502 0.8284 -1.95158002 0 P 0 ;0
L 0.8284 -1.95158002 0.82506004 -1.95268996 0 P 0 ;0
L 0.82506004 -1.95268996 0.82163996 -1.95356004 0 P 0 ;0
L 0.82163996 -1.95356004 0.81818002 -1.95413996 0 P 0 ;0
L 0.81818002 -1.95413996 0.8147 -1.95446004 0 P 0 ;0
L 0.8147 -1.95446004 0.81121004 -1.9545 0 P 0 ;0
L 0.77075 -2.02925 0.84511004 -2.02925 0 P 0 ;0
L 0.77076004 -2.02825 0.8452 -2.02825 0 P 0 ;0
L 0.77076998 -2.02725 0.84528996 -2.02725 0 P 0 ;0
L 0.77078002 -2.02625 0.84536998 -2.02625 0 P 0 ;0
L 0.77078996 -2.02525 0.84548996 -2.02525 0 P 0 ;0
L 0.7708 -2.02425 0.84561998 -2.02425 0 P 0 ;0
L 0.77081004 -2.02325 0.84575 -2.02325 0 P 0 ;0
L 0.77081998 -2.02225 0.84588002 -2.02225 0 P 0 ;0
L 0.77083002 -2.02125 0.84601004 -2.02125 0 P 0 ;0
L 0.77083996 -2.02025 0.84613996 -2.02025 0 P 0 ;0
L 0.77085 -2.01925 0.84626004 -2.01925 0 P 0 ;0
L 0.77085 -2.01825 0.84638996 -2.01825 0 P 0 ;0
L 0.77085 -2.01725 0.84651998 -2.01725 0 P 0 ;0
L 0.77086004 -2.01625 0.84663996 -2.01625 0 P 0 ;0
L 0.77086004 -2.01525 0.84676998 -2.01525 0 P 0 ;0
L 0.77086004 -2.01425 0.8469 -2.01425 0 P 0 ;0
L 0.77086004 -2.01325 0.84703002 -2.01325 0 P 0 ;0
L 0.77086004 -2.01225 0.84716004 -2.01225 0 P 0 ;0
L 0.77086004 -2.01125 0.84728996 -2.01125 0 P 0 ;0
L 0.77086004 -2.01025 0.84741004 -2.01025 0 P 0 ;0
L 0.77086998 -2.00925 0.84753996 -2.00925 0 P 0 ;0
L 0.77086998 -2.00825 0.84766998 -2.00825 0 P 0 ;0
L 0.77086998 -2.00725 0.84778996 -2.00725 0 P 0 ;0
L 0.77086998 -2.00625 0.84791998 -2.00625 0 P 0 ;0
L 0.77086998 -2.00525 0.84805 -2.00525 0 P 0 ;0
L 0.77086998 -2.00425 0.84818002 -2.00425 0 P 0 ;0
L 0.77088002 -2.00325 0.84831004 -2.00325 0 P 0 ;0
L 0.77088002 -2.00225 0.84843996 -2.00225 0 P 0 ;0
L 0.77088002 -2.00125 0.84856004 -2.00125 0 P 0 ;0
L 0.77088002 -2.00025 0.84868996 -2.00025 0 P 0 ;0
L 0.77088002 -1.99925 0.84881998 -1.99925 0 P 0 ;0
L 0.77088002 -1.99825 0.84896004 -1.99825 0 P 0 ;0
L 0.77088002 -1.99725 0.84911004 -1.99725 0 P 0 ;0
L 0.77088996 -1.99625 0.84926998 -1.99625 0 P 0 ;0
L 0.77088996 -1.99525 0.84941998 -1.99525 0 P 0 ;0
L 0.77088996 -1.99425 0.84956998 -1.99425 0 P 0 ;0
L 0.77088996 -1.99325 0.84971998 -1.99325 0 P 0 ;0
L 0.77088996 -1.99225 0.84986998 -1.99225 0 P 0 ;0
L 0.77088996 -1.99125 0.85003002 -1.99125 0 P 0 ;0
L 0.7709 -1.99025 0.85018002 -1.99025 0 P 0 ;0
L 0.7709 -1.98925 0.85033002 -1.98925 0 P 0 ;0
L 0.76885 -2.01878002 0.76871998 -2.03201998 0 P 0 ;0
L 0.76871998 -2.03201998 0.7684 -2.04553996 0 P 0 ;0
L 0.7684 -2.04553996 0.76796004 -2.05751004 0 P 0 ;0
L 0.76796004 -2.05751004 0.76741004 -2.06523002 0 P 0 ;0
L 0.76741004 -2.06523002 0.76596004 -2.07933996 0 P 0 ;0
L 0.76596004 -2.07933996 0.7636 -2.09918002 0 P 0 ;0
L 0.7636 -2.09918002 0.76116004 -2.119 0 P 0 ;0
L 0.76116004 -2.119 0.76011998 -2.12526004 0 P 0 ;0
L 0.76011998 -2.12526004 0.75948996 -2.12825 0 P 0 ;0
L 0.75948996 -2.12825 0.84418002 -2.12825 0 P 0 ;0
L 0.84418002 -2.12825 0.84361998 -2.10788002 0 P 0 ;0
L 0.84361998 -2.10788002 0.8436 -2.08276004 0 P 0 ;0
L 0.8436 -2.08276004 0.8449 -2.05491998 0 P 0 ;0
L 0.8449 -2.05491998 0.84736004 -2.02641004 0 P 0 ;0
L 0.84736004 -2.02641004 0.85083996 -1.99923002 0 P 0 ;0
L 0.85083996 -1.99923002 0.85268996 -1.987 0 P 0 ;0
L 0.85268996 -1.987 0.7689 -1.987 0 P 0 ;0
L 0.7689 -1.987 0.76885 -2.01878002 0 P 0 ;0
L 0.76195 -2.12625 0.84211998 -2.12625 0 P 0 ;0
L 0.76213996 -2.12525 0.8421 -2.12525 0 P 0 ;0
L 0.76231004 -2.12425 0.84206998 -2.12425 0 P 0 ;0
L 0.76248002 -2.12325 0.84203996 -2.12325 0 P 0 ;0
L 0.76263996 -2.12225 0.84201004 -2.12225 0 P 0 ;0
L 0.76281004 -2.12125 0.84198996 -2.12125 0 P 0 ;0
L 0.76296998 -2.12025 0.84196004 -2.12025 0 P 0 ;0
L 0.76313996 -2.11925 0.84193002 -2.11925 0 P 0 ;0
L 0.76326998 -2.11825 0.8419 -2.11825 0 P 0 ;0
L 0.76338996 -2.11725 0.84188002 -2.11725 0 P 0 ;0
L 0.76351004 -2.11625 0.84185 -2.11625 0 P 0 ;0
L 0.76363996 -2.11525 0.84181998 -2.11525 0 P 0 ;0
L 0.76376004 -2.11425 0.84178996 -2.11425 0 P 0 ;0
L 0.76388002 -2.11325 0.84176998 -2.11325 0 P 0 ;0
L 0.76401004 -2.11225 0.84173996 -2.11225 0 P 0 ;0
L 0.76413002 -2.11125 0.84171004 -2.11125 0 P 0 ;0
L 0.76425 -2.11025 0.84168002 -2.11025 0 P 0 ;0
L 0.76438002 -2.10925 0.84166004 -2.10925 0 P 0 ;0
L 0.7645 -2.10825 0.84163002 -2.10825 0 P 0 ;0
L 0.76461998 -2.10725 0.84161998 -2.10725 0 P 0 ;0
L 0.76475 -2.10625 0.84161998 -2.10625 0 P 0 ;0
L 0.76486998 -2.10525 0.84161998 -2.10525 0 P 0 ;0
L 0.76498996 -2.10425 0.84161998 -2.10425 0 P 0 ;0
L 0.76511998 -2.10325 0.84161998 -2.10325 0 P 0 ;0
L 0.76523996 -2.10225 0.84161998 -2.10225 0 P 0 ;0
L 0.76536004 -2.10125 0.84161998 -2.10125 0 P 0 ;0
L 0.76548996 -2.10025 0.84161998 -2.10025 0 P 0 ;0
L 0.76561004 -2.09925 0.84161998 -2.09925 0 P 0 ;0
L 0.76573002 -2.09825 0.84161004 -2.09825 0 P 0 ;0
L 0.76583996 -2.09725 0.84161004 -2.09725 0 P 0 ;0
L 0.76596998 -2.09625 0.84161004 -2.09625 0 P 0 ;0
L 0.76608996 -2.09525 0.84161004 -2.09525 0 P 0 ;0
L 0.7662 -2.09425 0.84161004 -2.09425 0 P 0 ;0
L 0.76631998 -2.09325 0.84161004 -2.09325 0 P 0 ;0
L 0.76643996 -2.09225 0.84161004 -2.09225 0 P 0 ;0
L 0.76656004 -2.09125 0.84161004 -2.09125 0 P 0 ;0
L 0.76668002 -2.09025 0.84161004 -2.09025 0 P 0 ;0
L 0.76678996 -2.08925 0.84161004 -2.08925 0 P 0 ;0
L 0.76691998 -2.08825 0.84161004 -2.08825 0 P 0 ;0
L 0.76703002 -2.08725 0.84161004 -2.08725 0 P 0 ;0
L 0.76715 -2.08625 0.8416 -2.08625 0 P 0 ;0
L 0.76726998 -2.08525 0.8416 -2.08525 0 P 0 ;0
L 0.76738996 -2.08425 0.8416 -2.08425 0 P 0 ;0
L 0.76195 -2.12625 0.76208002 -2.12561998 0 P 0 ;0
L 0.76208002 -2.12561998 0.76313996 -2.11928996 0 P 0 ;0
L 0.76313996 -2.11928996 0.76558996 -2.09941998 0 P 0 ;0
L 0.76558996 -2.09941998 0.76558996 -2.09941004 0 P 0 ;0
L 0.76558996 -2.09941004 0.76793996 -2.07956004 0 P 0 ;0
L 0.76793996 -2.07956004 0.7694 -2.0654 0 P 0 ;0
L 0.7694 -2.0654 0.76941004 -2.06536004 0 P 0 ;0
L 0.76941004 -2.06536004 0.76996004 -2.05761998 0 P 0 ;0
L 0.76996004 -2.05761998 0.76996004 -2.05758996 0 P 0 ;0
L 0.76996004 -2.05758996 0.7704 -2.0456 0 P 0 ;0
L 0.7704 -2.0456 0.77071998 -2.03206004 0 P 0 ;0
L 0.77071998 -2.03206004 0.77085 -2.01878002 0 P 0 ;0
L 0.77085 -2.01878002 0.7709 -1.989 0 P 0 ;0
L 0.7709 -1.989 0.85036004 -1.989 0 P 0 ;0
L 0.85036004 -1.989 0.84886004 -1.99895 0 P 0 ;0
L 0.84886004 -1.99895 0.84538002 -2.02618996 0 P 0 ;0
L 0.84538002 -2.02618996 0.8429 -2.05478996 0 P 0 ;0
L 0.8429 -2.05478996 0.8416 -2.08271004 0 P 0 ;0
L 0.8416 -2.08271004 0.84161998 -2.10791004 0 P 0 ;0
L 0.84161998 -2.10791004 0.84211998 -2.12625 0 P 0 ;0
L 0.84211998 -2.12625 0.76195 -2.12625 0 P 0 ;0
L 0.71628996 -1.91261998 0.74938002 -1.91261998 0 P 0 ;0
L 0.71783002 -1.91161998 0.74933002 -1.91161998 0 P 0 ;0
L 0.71953002 -1.91061998 0.74931004 -1.91061998 0 P 0 ;0
L 0.72133002 -1.90961998 0.74928996 -1.90961998 0 P 0 ;0
L 0.72313996 -1.90861998 0.74926998 -1.90861998 0 P 0 ;0
L 0.72493996 -1.90761998 0.74928996 -1.90761998 0 P 0 ;0
L 0.72673996 -1.90661998 0.74931998 -1.90661998 0 P 0 ;0
L 0.72855 -1.90561998 0.74935 -1.90561998 0 P 0 ;0
L 0.73035 -1.90461998 0.74938996 -1.90461998 0 P 0 ;0
L 0.73215 -1.90361998 0.74946998 -1.90361998 0 P 0 ;0
L 0.73396004 -1.90261998 0.74953996 -1.90261998 0 P 0 ;0
L 0.73576004 -1.90161998 0.74961998 -1.90161998 0 P 0 ;0
L 0.73756998 -1.90061998 0.74973996 -1.90061998 0 P 0 ;0
L 0.73943002 -1.89961998 0.74986004 -1.89961998 0 P 0 ;0
L 0.74141998 -1.89861998 0.74998996 -1.89861998 0 P 0 ;0
L 0.74341004 -1.89761998 0.75015 -1.89761998 0 P 0 ;0
L 0.59843002 -2.08361998 0.6754 -2.08361998 0 P 0 ;0
L 0.59846004 -2.08261998 0.67538996 -2.08261998 0 P 0 ;0
L 0.59848002 -2.08161998 0.67538002 -2.08161998 0 P 0 ;0
L 0.59851004 -2.08061998 0.67538002 -2.08061998 0 P 0 ;0
L 0.59853002 -2.07961998 0.67546004 -2.07961998 0 P 0 ;0
L 0.59856004 -2.07861998 0.67553996 -2.07861998 0 P 0 ;0
L 0.59861998 -2.07761998 0.67561004 -2.07761998 0 P 0 ;0
L 0.5987 -2.07661998 0.67568996 -2.07661998 0 P 0 ;0
L 0.59878002 -2.07561998 0.67576004 -2.07561998 0 P 0 ;0
L 0.59885 -2.07461998 0.67583996 -2.07461998 0 P 0 ;0
L 0.59893002 -2.07361998 0.67591998 -2.07361998 0 P 0 ;0
L 0.59901004 -2.07261998 0.67598996 -2.07261998 0 P 0 ;0
L 0.59908002 -2.07161998 0.67606998 -2.07161998 0 P 0 ;0
L 0.59916004 -2.07061998 0.67613996 -2.07061998 0 P 0 ;0
L 0.59923002 -2.06961998 0.67621004 -2.06961998 0 P 0 ;0
L 0.59936004 -2.06861998 0.6763 -2.06861998 0 P 0 ;0
L 0.59948996 -2.06761998 0.67645 -2.06761998 0 P 0 ;0
L 0.59963002 -2.06661998 0.6766 -2.06661998 0 P 0 ;0
L 0.59976998 -2.06561998 0.67676004 -2.06561998 0 P 0 ;0
L 0.5999 -2.06461998 0.67691998 -2.06461998 0 P 0 ;0
L 0.60003002 -2.06361998 0.67706998 -2.06361998 0 P 0 ;0
L 0.60016998 -2.06261998 0.6773 -2.06261998 0 P 0 ;0
L 0.60031004 -2.06161998 0.67753002 -2.06161998 0 P 0 ;0
L 0.60051004 -2.06061998 0.67776004 -2.06061998 0 P 0 ;0
L 0.60071004 -2.05961998 0.67798996 -2.05961998 0 P 0 ;0
L 0.60091998 -2.05861998 0.67823002 -2.05861998 0 P 0 ;0
L 0.60111998 -2.05761998 0.67853002 -2.05761998 0 P 0 ;0
L 0.60133002 -2.05661998 0.67883996 -2.05661998 0 P 0 ;0
L 0.60153996 -2.05561998 0.67913996 -2.05561998 0 P 0 ;0
L 0.60173996 -2.05461998 0.67945 -2.05461998 0 P 0 ;0
L 0.60195 -2.05361998 0.67975 -2.05361998 0 P 0 ;0
L 0.60223002 -2.05261998 0.68006004 -2.05261998 0 P 0 ;0
L 0.60251004 -2.05161998 0.68036004 -2.05161998 0 P 0 ;0
L 0.60278996 -2.05061998 0.68066998 -2.05061998 0 P 0 ;0
L 0.60306004 -2.04961998 0.68096998 -2.04961998 0 P 0 ;0
L 0.60333996 -2.04861998 0.68135 -2.04861998 0 P 0 ;0
L 0.60361998 -2.04761998 0.68173002 -2.04761998 0 P 0 ;0
L 0.6039 -2.04661998 0.68211004 -2.04661998 0 P 0 ;0
L 0.60418002 -2.04561998 0.68248996 -2.04561998 0 P 0 ;0
L 0.60453002 -2.04461998 0.68288002 -2.04461998 0 P 0 ;0
L 0.60488002 -2.04361998 0.68326004 -2.04361998 0 P 0 ;0
L 0.60523002 -2.04261998 0.68363996 -2.04261998 0 P 0 ;0
L 0.60556998 -2.04161998 0.68401998 -2.04161998 0 P 0 ;0
L 0.60591998 -2.04061998 0.6844 -2.04061998 0 P 0 ;0
L 0.60626998 -2.03961998 0.68486004 -2.03961998 0 P 0 ;0
L 0.60661998 -2.03861998 0.68531998 -2.03861998 0 P 0 ;0
L 0.60698996 -2.03761998 0.68578002 -2.03761998 0 P 0 ;0
L 0.60743002 -2.03661998 0.68623996 -2.03661998 0 P 0 ;0
L 0.60786004 -2.03561998 0.6867 -2.03561998 0 P 0 ;0
L 0.60828996 -2.03461998 0.68716004 -2.03461998 0 P 0 ;0
L 0.60873002 -2.03361998 0.68761998 -2.03361998 0 P 0 ;0
L 0.60916004 -2.03261998 0.68808996 -2.03261998 0 P 0 ;0
L 0.60958996 -2.03161998 0.68856998 -2.03161998 0 P 0 ;0
L 0.61003002 -2.03061998 0.68911004 -2.03061998 0 P 0 ;0
L 0.61046004 -2.02961998 0.68965 -2.02961998 0 P 0 ;0
L 0.61088996 -2.02861998 0.69018996 -2.02861998 0 P 0 ;0
L 0.61133002 -2.02761998 0.69073002 -2.02761998 0 P 0 ;0
L 0.61176004 -2.02661998 0.69126998 -2.02661998 0 P 0 ;0
L 0.6122 -2.02561998 0.69181004 -2.02561998 0 P 0 ;0
L 0.61263002 -2.02461998 0.69235 -2.02461998 0 P 0 ;0
L 0.61306004 -2.02361998 0.69288002 -2.02361998 0 P 0 ;0
L 0.61348996 -2.02261998 0.69346998 -2.02261998 0 P 0 ;0
L 0.61393002 -2.02161998 0.69408996 -2.02161998 0 P 0 ;0
L 0.61436004 -2.02061998 0.6947 -2.02061998 0 P 0 ;0
L 0.61478996 -2.01961998 0.69531998 -2.01961998 0 P 0 ;0
L 0.61531004 -2.01861998 0.69593996 -2.01861998 0 P 0 ;0
L 0.61583996 -2.01761998 0.69656004 -2.01761998 0 P 0 ;0
L 0.61636004 -2.01661998 0.69718002 -2.01661998 0 P 0 ;0
L 0.61688002 -2.01561998 0.69778996 -2.01561998 0 P 0 ;0
L 0.6174 -2.01461998 0.69841998 -2.01461998 0 P 0 ;0
L 0.61791998 -2.01361998 0.69911998 -2.01361998 0 P 0 ;0
L 0.61843996 -2.01261998 0.69981998 -2.01261998 0 P 0 ;0
L 0.61896004 -2.01161998 0.70051998 -2.01161998 0 P 0 ;0
L 0.61948002 -2.01061998 0.70123002 -2.01061998 0 P 0 ;0
L 0.62 -2.00961998 0.70193002 -2.00961998 0 P 0 ;0
L 0.62051998 -2.00861998 0.70263002 -2.00861998 0 P 0 ;0
L 0.62103996 -2.00761998 0.70333002 -2.00761998 0 P 0 ;0
L 0.62163996 -2.00661998 0.70403996 -2.00661998 0 P 0 ;0
L 0.62225 -2.00561998 0.70483002 -2.00561998 0 P 0 ;0
L 0.62285 -2.00461998 0.70565 -2.00461998 0 P 0 ;0
L 0.62346004 -2.00361998 0.70646004 -2.00361998 0 P 0 ;0
L 0.62406004 -2.00261998 0.70726998 -2.00261998 0 P 0 ;0
L 0.62466004 -2.00161998 0.70808996 -2.00161998 0 P 0 ;0
L 0.62526998 -2.00061998 0.7089 -2.00061998 0 P 0 ;0
L 0.62586998 -1.99961998 0.70971004 -1.99961998 0 P 0 ;0
L 0.62648002 -1.99861998 0.71053002 -1.99861998 0 P 0 ;0
L 0.62708002 -1.99761998 0.71133996 -1.99761998 0 P 0 ;0
L 0.62768996 -1.99661998 0.71216004 -1.99661998 0 P 0 ;0
L 0.62831998 -1.99561998 0.71296998 -1.99561998 0 P 0 ;0
L 0.62901004 -1.99461998 0.71378996 -1.99461998 0 P 0 ;0
L 0.62971004 -1.99361998 0.71466004 -1.99361998 0 P 0 ;0
L 0.6304 -1.99261998 0.71561004 -1.99261998 0 P 0 ;0
L 0.6311 -1.99161998 0.71656998 -1.99161998 0 P 0 ;0
L 0.63178996 -1.99061998 0.71753002 -1.99061998 0 P 0 ;0
L 0.63248996 -1.98961998 0.71848996 -1.98961998 0 P 0 ;0
L 0.63318002 -1.98861998 0.71945 -1.98861998 0 P 0 ;0
L 0.63388002 -1.98761998 0.72041004 -1.98761998 0 P 0 ;0
L 0.63456998 -1.98661998 0.72136998 -1.98661998 0 P 0 ;0
L 0.63526998 -1.98561998 0.72233002 -1.98561998 0 P 0 ;0
L 0.63598002 -1.98461998 0.72328996 -1.98461998 0 P 0 ;0
L 0.63678996 -1.98361998 0.72425 -1.98361998 0 P 0 ;0
L 0.6376 -1.98261998 0.72521004 -1.98261998 0 P 0 ;0
L 0.63841004 -1.98161998 0.72628002 -1.98161998 0 P 0 ;0
L 0.63921998 -1.98061998 0.72738996 -1.98061998 0 P 0 ;0
L 0.64003002 -1.97961998 0.7285 -1.97961998 0 P 0 ;0
L 0.64083996 -1.97861998 0.72961004 -1.97861998 0 P 0 ;0
L 0.64165 -1.97761998 0.73071004 -1.97761998 0 P 0 ;0
L 0.64246004 -1.97661998 0.73181998 -1.97661998 0 P 0 ;0
L 0.64326998 -1.97561998 0.73293002 -1.97561998 0 P 0 ;0
L 0.64406998 -1.97461998 0.73403996 -1.97461998 0 P 0 ;0
L 0.64488002 -1.97361998 0.73515 -1.97361998 0 P 0 ;0
L 0.64568996 -1.97261998 0.73625 -1.97261998 0 P 0 ;0
L 0.6465 -1.97161998 0.73736004 -1.97161998 0 P 0 ;0
L 0.64731004 -1.97061998 0.73848002 -1.97061998 0 P 0 ;0
L 0.64811998 -1.96961998 0.73973002 -1.96961998 0 P 0 ;0
L 0.64893002 -1.96861998 0.74098996 -1.96861998 0 P 0 ;0
L 0.64981004 -1.96761998 0.74225 -1.96761998 0 P 0 ;0
L 0.65076004 -1.96661998 0.74351004 -1.96661998 0 P 0 ;0
L 0.65171004 -1.96561998 0.74476998 -1.96561998 0 P 0 ;0
L 0.65266998 -1.96461998 0.74603002 -1.96461998 0 P 0 ;0
L 0.65361998 -1.96361998 0.74728996 -1.96361998 0 P 0 ;0
L 0.65458002 -1.96261998 0.74855 -1.96261998 0 P 0 ;0
L 0.65553002 -1.96161998 0.74981004 -1.96161998 0 P 0 ;0
L 0.65648996 -1.96061998 0.75106004 -1.96061998 0 P 0 ;0
L 0.65743996 -1.95961998 0.75233996 -1.95961998 0 P 0 ;0
L 0.6584 -1.95861998 0.7537 -1.95861998 0 P 0 ;0
L 0.65935 -1.95761998 0.75506004 -1.95761998 0 P 0 ;0
L 0.66031004 -1.95661998 0.75641998 -1.95661998 0 P 0 ;0
L 0.66126004 -1.95561998 0.75778996 -1.95561998 0 P 0 ;0
L 0.66221004 -1.95461998 0.75916004 -1.95461998 0 P 0 ;0
L 0.66316998 -1.95361998 0.76053996 -1.95361998 0 P 0 ;0
L 0.66411998 -1.95261998 0.76193996 -1.95261998 0 P 0 ;0
L 0.66523002 -1.95161998 0.76333996 -1.95161998 0 P 0 ;0
L 0.66636004 -1.95061998 0.76406998 -1.95061998 0 P 0 ;0
L 0.66746998 -1.94961998 0.76355 -1.94961998 0 P 0 ;0
L 0.6686 -1.94861998 0.76291998 -1.94861998 0 P 0 ;0
L 0.66971004 -1.94761998 0.76226998 -1.94761998 0 P 0 ;0
L 0.67083996 -1.94661998 0.76161998 -1.94661998 0 P 0 ;0
L 0.67196004 -1.94561998 0.76096998 -1.94561998 0 P 0 ;0
L 0.67306998 -1.94461998 0.76033002 -1.94461998 0 P 0 ;0
L 0.6742 -1.94361998 0.75968996 -1.94361998 0 P 0 ;0
L 0.67531004 -1.94261998 0.75905 -1.94261998 0 P 0 ;0
L 0.67643996 -1.94161998 0.75846004 -1.94161998 0 P 0 ;0
L 0.67755 -1.94061998 0.75788996 -1.94061998 0 P 0 ;0
L 0.67868002 -1.93961998 0.75731998 -1.93961998 0 P 0 ;0
L 0.67978996 -1.93861998 0.75676998 -1.93861998 0 P 0 ;0
L 0.68091998 -1.93761998 0.75626998 -1.93761998 0 P 0 ;0
L 0.68221004 -1.93661998 0.75576998 -1.93661998 0 P 0 ;0
L 0.68353002 -1.93561998 0.75528002 -1.93561998 0 P 0 ;0
L 0.68483996 -1.93461998 0.75483996 -1.93461998 0 P 0 ;0
L 0.68616004 -1.93361998 0.75441004 -1.93361998 0 P 0 ;0
L 0.68746998 -1.93261998 0.75398002 -1.93261998 0 P 0 ;0
L 0.68878002 -1.93161998 0.7536 -1.93161998 0 P 0 ;0
L 0.6901 -1.93061998 0.75323996 -1.93061998 0 P 0 ;0
L 0.69141004 -1.92961998 0.75286998 -1.92961998 0 P 0 ;0
L 0.69271998 -1.92861998 0.75253996 -1.92861998 0 P 0 ;0
L 0.69403002 -1.92761998 0.75223002 -1.92761998 0 P 0 ;0
L 0.69535 -1.92661998 0.75193002 -1.92661998 0 P 0 ;0
L 0.69666004 -1.92561998 0.75163002 -1.92561998 0 P 0 ;0
L 0.69796998 -1.92461998 0.75138002 -1.92461998 0 P 0 ;0
L 0.69936998 -1.92361998 0.75113996 -1.92361998 0 P 0 ;0
L 0.70091004 -1.92261998 0.75088996 -1.92261998 0 P 0 ;0
L 0.70243996 -1.92161998 0.75066004 -1.92161998 0 P 0 ;0
L 0.70398002 -1.92061998 0.75046004 -1.92061998 0 P 0 ;0
L 0.70551998 -1.91961998 0.75026004 -1.91961998 0 P 0 ;0
L 0.70706004 -1.91861998 0.75006998 -1.91861998 0 P 0 ;0
L 0.7086 -1.91761998 0.7499 -1.91761998 0 P 0 ;0
L 0.71013996 -1.91661998 0.74976998 -1.91661998 0 P 0 ;0
L 0.71166998 -1.91561998 0.74961998 -1.91561998 0 P 0 ;0
L 0.71321004 -1.91461998 0.74951998 -1.91461998 0 P 0 ;0
L 0.71475 -1.91361998 0.74945 -1.91361998 0 P 0 ;0
L 0.61556998 -2.15661998 0.70655 -2.15661998 0 P 0 ;0
L 0.61503002 -2.15561998 0.7056 -2.15561998 0 P 0 ;0
L 0.61448996 -2.15461998 0.70465 -2.15461998 0 P 0 ;0
L 0.61395 -2.15361998 0.7037 -2.15361998 0 P 0 ;0
L 0.61341004 -2.15261998 0.70273996 -2.15261998 0 P 0 ;0
L 0.61286998 -2.15161998 0.70178996 -2.15161998 0 P 0 ;0
L 0.61233002 -2.15061998 0.70095 -2.15061998 0 P 0 ;0
L 0.61188002 -2.14961998 0.70015 -2.14961998 0 P 0 ;0
L 0.61143002 -2.14861998 0.69935 -2.14861998 0 P 0 ;0
L 0.61098002 -2.14761998 0.69855 -2.14761998 0 P 0 ;0
L 0.61053002 -2.14661998 0.69775 -2.14661998 0 P 0 ;0
L 0.61008002 -2.14561998 0.69695 -2.14561998 0 P 0 ;0
L 0.60963002 -2.14461998 0.69615 -2.14461998 0 P 0 ;0
L 0.60918002 -2.14361998 0.69535 -2.14361998 0 P 0 ;0
L 0.60873002 -2.14261998 0.69455 -2.14261998 0 P 0 ;0
L 0.60831004 -2.14161998 0.69381998 -2.14161998 0 P 0 ;0
L 0.60793996 -2.14061998 0.69315 -2.14061998 0 P 0 ;0
L 0.60756998 -2.13961998 0.69248002 -2.13961998 0 P 0 ;0
L 0.60721004 -2.13861998 0.69181004 -2.13861998 0 P 0 ;0
L 0.60683996 -2.13761998 0.69115 -2.13761998 0 P 0 ;0
L 0.60646998 -2.13661998 0.69048002 -2.13661998 0 P 0 ;0
L 0.60611004 -2.13561998 0.68981004 -2.13561998 0 P 0 ;0
L 0.60573996 -2.13461998 0.68918002 -2.13461998 0 P 0 ;0
L 0.60538002 -2.13361998 0.68863002 -2.13361998 0 P 0 ;0
L 0.60503996 -2.13261998 0.68808002 -2.13261998 0 P 0 ;0
L 0.60476004 -2.13161998 0.68753002 -2.13161998 0 P 0 ;0
L 0.60446998 -2.13061998 0.68698002 -2.13061998 0 P 0 ;0
L 0.60418002 -2.12961998 0.68643002 -2.12961998 0 P 0 ;0
L 0.6039 -2.12861998 0.68588002 -2.12861998 0 P 0 ;0
L 0.60361004 -2.12761998 0.68533002 -2.12761998 0 P 0 ;0
L 0.60331998 -2.12661998 0.68486004 -2.12661998 0 P 0 ;0
L 0.60303002 -2.12561998 0.68441998 -2.12561998 0 P 0 ;0
L 0.60275 -2.12461998 0.68396998 -2.12461998 0 P 0 ;0
L 0.60246004 -2.12361998 0.68353002 -2.12361998 0 P 0 ;0
L 0.60218002 -2.12261998 0.68308996 -2.12261998 0 P 0 ;0
L 0.60188996 -2.12161998 0.68263996 -2.12161998 0 P 0 ;0
L 0.60166998 -2.12061998 0.6822 -2.12061998 0 P 0 ;0
L 0.60145 -2.11961998 0.68176004 -2.11961998 0 P 0 ;0
L 0.60123002 -2.11861998 0.68138996 -2.11861998 0 P 0 ;0
L 0.60101004 -2.11761998 0.68105 -2.11761998 0 P 0 ;0
L 0.60078002 -2.11661998 0.68071004 -2.11661998 0 P 0 ;0
L 0.6006 -2.11561998 0.68036004 -2.11561998 0 P 0 ;0
L 0.60043002 -2.11461998 0.68001998 -2.11461998 0 P 0 ;0
L 0.60025 -2.11361998 0.67968002 -2.11361998 0 P 0 ;0
L 0.60008002 -2.11261998 0.67933002 -2.11261998 0 P 0 ;0
L 0.59991004 -2.11161998 0.67898996 -2.11161998 0 P 0 ;0
L 0.59976004 -2.11061998 0.6787 -2.11061998 0 P 0 ;0
L 0.59963996 -2.10961998 0.67845 -2.10961998 0 P 0 ;0
L 0.59951004 -2.10861998 0.6782 -2.10861998 0 P 0 ;0
L 0.59938002 -2.10761998 0.67795 -2.10761998 0 P 0 ;0
L 0.59925 -2.10661998 0.6777 -2.10661998 0 P 0 ;0
L 0.59913002 -2.10561998 0.67746004 -2.10561998 0 P 0 ;0
L 0.59905 -2.10461998 0.67721004 -2.10461998 0 P 0 ;0
L 0.59896998 -2.10361998 0.67696004 -2.10361998 0 P 0 ;0
L 0.59888002 -2.10261998 0.67671004 -2.10261998 0 P 0 ;0
L 0.5988 -2.10161998 0.67653996 -2.10161998 0 P 0 ;0
L 0.59871998 -2.10061998 0.67638002 -2.10061998 0 P 0 ;0
L 0.59866998 -2.09961998 0.67621004 -2.09961998 0 P 0 ;0
L 0.59863996 -2.09861998 0.67605 -2.09861998 0 P 0 ;0
L 0.59861004 -2.09761998 0.67588996 -2.09761998 0 P 0 ;0
L 0.59858996 -2.09661998 0.6758 -2.09661998 0 P 0 ;0
L 0.59856004 -2.09561998 0.67571004 -2.09561998 0 P 0 ;0
L 0.59853002 -2.09461998 0.67563002 -2.09461998 0 P 0 ;0
L 0.5985 -2.09361998 0.67553996 -2.09361998 0 P 0 ;0
L 0.59846998 -2.09261998 0.67546004 -2.09261998 0 P 0 ;0
L 0.59843996 -2.09161998 0.67546004 -2.09161998 0 P 0 ;0
L 0.59841998 -2.09061998 0.67545 -2.09061998 0 P 0 ;0
L 0.59838002 -2.08961998 0.67543996 -2.08961998 0 P 0 ;0
L 0.59836004 -2.08861998 0.67543002 -2.08861998 0 P 0 ;0
L 0.59833002 -2.08761998 0.67543002 -2.08761998 0 P 0 ;0
L 0.59835 -2.08661998 0.67541998 -2.08661998 0 P 0 ;0
L 0.59836998 -2.08561998 0.67541004 -2.08561998 0 P 0 ;0
L 0.5984 -2.08461998 0.67541004 -2.08461998 0 P 0 ;0
L 0.80005 -2.25161998 0.85543996 -2.25161998 0 P 0 ;0
L 0.78651998 -2.25061998 0.86596004 -2.25061998 0 P 0 ;0
L 0.77878996 -2.24961998 0.87636004 -2.24961998 0 P 0 ;0
L 0.77106004 -2.24861998 0.88285 -2.24861998 0 P 0 ;0
L 0.76398996 -2.24761998 0.88933996 -2.24761998 0 P 0 ;0
L 0.75891998 -2.24661998 0.89583996 -2.24661998 0 P 0 ;0
L 0.73781004 -1.8982 0.71738996 -1.90951998 0 P 0 ;0
L 0.71738996 -1.90951998 0.69766998 -1.92233996 0 P 0 ;0
L 0.69766998 -1.92233996 0.67971004 -1.93601998 0 P 0 ;0
L 0.67971004 -1.93601998 0.66278996 -1.95113002 0 P 0 ;0
L 0.66278996 -1.95113002 0.64786998 -1.96675 0 P 0 ;0
L 0.64786998 -1.96675 0.63423996 -1.98358996 0 P 0 ;0
L 0.63423996 -1.98358996 0.62643996 -1.99483002 0 P 0 ;0
L 0.62643996 -1.99483002 0.61933996 -2.00655 0 P 0 ;0
L 0.61933996 -2.00655 0.61298996 -2.01873996 0 P 0 ;0
L 0.61298996 -2.01873996 0.60503002 -2.03713002 0 P 0 ;0
L 0.60503002 -2.03713002 0.60225 -2.04506004 0 P 0 ;0
L 0.60225 -2.04506004 0.59998996 -2.05323002 0 P 0 ;0
L 0.59998996 -2.05323002 0.59833996 -2.0612 0 P 0 ;0
L 0.59833996 -2.0612 0.59725 -2.06928996 0 P 0 ;0
L 0.59725 -2.06928996 0.59656998 -2.07833996 0 P 0 ;0
L 0.59656998 -2.07833996 0.59633002 -2.0875 0 P 0 ;0
L 0.59633002 -2.0875 0.59668996 -2.10036998 0 P 0 ;0
L 0.59668996 -2.10036998 0.59715 -2.10596004 0 P 0 ;0
L 0.59715 -2.10596004 0.59786004 -2.11151004 0 P 0 ;0
L 0.59786004 -2.11151004 0.59878996 -2.11686998 0 P 0 ;0
L 0.59878996 -2.11686998 0.59996998 -2.1222 0 P 0 ;0
L 0.59996998 -2.1222 0.60326998 -2.13368996 0 P 0 ;0
L 0.60326998 -2.13368996 0.60656998 -2.1427 0 P 0 ;0
L 0.60656998 -2.1427 0.6105 -2.15143996 0 P 0 ;0
L 0.6105 -2.15143996 0.61505 -2.15988002 0 P 0 ;0
L 0.61505 -2.15988002 0.62023996 -2.16803996 0 P 0 ;0
L 0.62023996 -2.16803996 0.62828996 -2.17873002 0 P 0 ;0
L 0.62828996 -2.17873002 0.63718996 -2.18871004 0 P 0 ;0
L 0.63718996 -2.18871004 0.64693002 -2.19795 0 P 0 ;0
L 0.64693002 -2.19795 0.6582 -2.20701998 0 P 0 ;0
L 0.6582 -2.20701998 0.67011004 -2.21518996 0 P 0 ;0
L 0.67011004 -2.21518996 0.68261004 -2.22243002 0 P 0 ;0
L 0.68261004 -2.22243002 0.69673996 -2.22936004 0 P 0 ;0
L 0.69673996 -2.22936004 0.71123002 -2.23543996 0 P 0 ;0
L 0.71123002 -2.23543996 0.72611998 -2.24066998 0 P 0 ;0
L 0.72611998 -2.24066998 0.74536004 -2.24598996 0 P 0 ;0
L 0.74536004 -2.24598996 0.76493002 -2.24985 0 P 0 ;0
L 0.76493002 -2.24985 0.78671998 -2.25266998 0 P 0 ;0
L 0.78671998 -2.25266998 0.80863002 -2.25425 0 P 0 ;0
L 0.80863002 -2.25425 0.83146004 -2.25463002 0 P 0 ;0
L 0.83146004 -2.25463002 0.85418002 -2.25375 0 P 0 ;0
L 0.85418002 -2.25375 0.87641004 -2.25163996 0 P 0 ;0
L 0.87641004 -2.25163996 0.89853002 -2.24823002 0 P 0 ;0
L 0.89853002 -2.24823002 0.93045 -2.24101998 0 P 0 ;0
L 0.93045 -2.24101998 0.96466004 -2.23063002 0 P 0 ;0
L 0.96466004 -2.23063002 0.99911004 -2.2178 0 P 0 ;0
L 0.99911004 -2.2178 1.03183002 -2.20318002 0 P 0 ;0
L 1.03183002 -2.20318002 1.04391998 -2.19703002 0 P 0 ;0
L 1.04391998 -2.19703002 1.05581004 -2.19048996 0 P 0 ;0
L 1.05581004 -2.19048996 1.06676004 -2.18411998 0 P 0 ;0
L 1.06676004 -2.18411998 1.06681004 -2.18408996 0 P 0 ;0
L 1.06681004 -2.18408996 1.06685 -2.18405 0 P 0 ;0
L 1.06685 -2.18405 1.0669 -2.18401004 0 P 0 ;0
L 1.0669 -2.18401004 1.06693996 -2.18396998 0 P 0 ;0
L 1.06693996 -2.18396998 1.06696998 -2.18391998 0 P 0 ;0
L 1.06696998 -2.18391998 1.06701004 -2.18386998 0 P 0 ;0
L 1.06701004 -2.18386998 1.06703002 -2.18381998 0 P 0 ;0
L 1.06703002 -2.18381998 1.06706004 -2.18376004 0 P 0 ;0
L 1.06706004 -2.18376004 1.06706998 -2.18371004 0 P 0 ;0
L 1.06706998 -2.18371004 1.06708996 -2.18365 0 P 0 ;0
L 1.06708996 -2.18365 1.06708996 -2.18358996 0 P 0 ;0
L 1.06708996 -2.18358996 1.0671 -2.18353002 0 P 0 ;0
L 1.0671 -2.18353002 1.0671 -2.18346998 0 P 0 ;0
L 1.0671 -2.18346998 1.06708996 -2.18341004 0 P 0 ;0
L 1.06708996 -2.18341004 1.06706998 -2.18336004 0 P 0 ;0
L 1.06706998 -2.18336004 1.06706004 -2.1833 0 P 0 ;0
L 1.06706004 -2.1833 1.06703002 -2.18323996 0 P 0 ;0
L 1.06703002 -2.18323996 1.06701004 -2.18318996 0 P 0 ;0
L 1.06701004 -2.18318996 1.06696998 -2.18313996 0 P 0 ;0
L 1.06696998 -2.18313996 1.06693996 -2.18308996 0 P 0 ;0
L 1.06693996 -2.18308996 1.06688002 -2.18303002 0 P 0 ;0
L 1.06688002 -2.18303002 1.06678996 -2.18296998 0 P 0 ;0
L 1.06678996 -2.18296998 1.06673002 -2.18295 0 P 0 ;0
L 1.06673002 -2.18295 1.0667 -2.18295 0 P 0 ;0
L 1.0667 -2.18295 1.06666004 -2.18293996 0 P 0 ;0
L 1.06666004 -2.18293996 1.0666 -2.18293996 0 P 0 ;0
L 1.0666 -2.18293996 1.06656998 -2.18295 0 P 0 ;0
L 1.06656998 -2.18295 1.06653002 -2.18295 0 P 0 ;0
L 1.06653002 -2.18295 1.06153002 -2.1842 0 P 0 ;0
L 1.06153002 -2.1842 1.05583996 -2.18566998 0 P 0 ;0
L 1.05583996 -2.18566998 1.04916998 -2.1875 0 P 0 ;0
L 1.04916998 -2.1875 1.0153 -2.1962 0 P 0 ;0
L 1.0153 -2.1962 0.9814 -2.20333996 0 P 0 ;0
L 0.9814 -2.20333996 0.94881998 -2.2087 0 P 0 ;0
L 0.94881998 -2.2087 0.9189 -2.21198996 0 P 0 ;0
L 0.9189 -2.21198996 0.90113996 -2.21278996 0 P 0 ;0
L 0.90113996 -2.21278996 0.87738002 -2.21265 0 P 0 ;0
L 0.87738002 -2.21265 0.854 -2.21183002 0 P 0 ;0
L 0.854 -2.21183002 0.83788996 -2.21033996 0 P 0 ;0
L 0.83788996 -2.21033996 0.8174 -2.20693002 0 P 0 ;0
L 0.8174 -2.20693002 0.79708996 -2.2023 0 P 0 ;0
L 0.79708996 -2.2023 0.7769 -2.19641004 0 P 0 ;0
L 0.7769 -2.19641004 0.76433002 -2.19183996 0 P 0 ;0
L 0.76433002 -2.19183996 0.75208996 -2.18638002 0 P 0 ;0
L 0.75208996 -2.18638002 0.74026998 -2.18006998 0 P 0 ;0
L 0.74026998 -2.18006998 0.72886998 -2.17291004 0 P 0 ;0
L 0.72886998 -2.17291004 0.71961998 -2.16603002 0 P 0 ;0
L 0.71961998 -2.16603002 0.71098996 -2.15838996 0 P 0 ;0
L 0.71098996 -2.15838996 0.70303002 -2.15003002 0 P 0 ;0
L 0.70303002 -2.15003002 0.6958 -2.14098996 0 P 0 ;0
L 0.6958 -2.14098996 0.69106998 -2.1339 0 P 0 ;0
L 0.69106998 -2.1339 0.68696004 -2.12643002 0 P 0 ;0
L 0.68696004 -2.12643002 0.68351004 -2.11863002 0 P 0 ;0
L 0.68351004 -2.11863002 0.68073996 -2.11056004 0 P 0 ;0
L 0.68073996 -2.11056004 0.67866004 -2.10218996 0 P 0 ;0
L 0.67866004 -2.10218996 0.67788002 -2.09741998 0 P 0 ;0
L 0.67788002 -2.09741998 0.67746004 -2.0926 0 P 0 ;0
L 0.67746004 -2.0926 0.67738002 -2.08076004 0 P 0 ;0
L 0.67738002 -2.08076004 0.67828002 -2.06891004 0 P 0 ;0
L 0.67828002 -2.06891004 0.67903002 -2.06403996 0 P 0 ;0
L 0.67903002 -2.06403996 0.68013002 -2.05923996 0 P 0 ;0
L 0.68013002 -2.05923996 0.68288002 -2.05021998 0 P 0 ;0
L 0.68288002 -2.05021998 0.68623996 -2.04141004 0 P 0 ;0
L 0.68623996 -2.04141004 0.69018002 -2.03286004 0 P 0 ;0
L 0.69018002 -2.03286004 0.69486004 -2.02418002 0 P 0 ;0
L 0.69486004 -2.02418002 0.70003996 -2.0158 0 P 0 ;0
L 0.70003996 -2.0158 0.70573002 -2.00768996 0 P 0 ;0
L 0.70573002 -2.00768996 0.7158 -1.99531998 0 P 0 ;0
L 0.7158 -1.99531998 0.72681004 -1.98385 0 P 0 ;0
L 0.72681004 -1.98385 0.73971004 -1.9722 0 P 0 ;0
L 0.73971004 -1.9722 0.7533 -1.9614 0 P 0 ;0
L 0.7533 -1.9614 0.75753996 -1.95828002 0 P 0 ;0
L 0.75753996 -1.95828002 0.76138002 -1.95548002 0 P 0 ;0
L 0.76138002 -1.95548002 0.76463002 -1.95316004 0 P 0 ;0
L 0.76463002 -1.95316004 0.76516004 -1.95281004 0 P 0 ;0
L 0.76516004 -1.95281004 0.7657 -1.95248996 0 P 0 ;0
L 0.7657 -1.95248996 0.76578002 -1.95243996 0 P 0 ;0
L 0.76578002 -1.95243996 0.76586004 -1.95238002 0 P 0 ;0
L 0.76586004 -1.95238002 0.76593002 -1.95231998 0 P 0 ;0
L 0.76593002 -1.95231998 0.766 -1.95223996 0 P 0 ;0
L 0.766 -1.95223996 0.76606004 -1.95216998 0 P 0 ;0
L 0.76606004 -1.95216998 0.76616004 -1.95201004 0 P 0 ;0
L 0.76616004 -1.95201004 0.7662 -1.95191998 0 P 0 ;0
L 0.7662 -1.95191998 0.76626004 -1.95173996 0 P 0 ;0
L 0.76626004 -1.95173996 0.76628002 -1.95163996 0 P 0 ;0
L 0.76628002 -1.95163996 0.7663 -1.95143002 0 P 0 ;0
L 0.7663 -1.95143002 0.7663 -1.95121004 0 P 0 ;0
L 0.7663 -1.95121004 0.76628996 -1.951 0 P 0 ;0
L 0.76628996 -1.951 0.76625 -1.95078996 0 P 0 ;0
L 0.76625 -1.95078996 0.7662 -1.95058002 0 P 0 ;0
L 0.7662 -1.95058002 0.76613002 -1.95036998 0 P 0 ;0
L 0.76613002 -1.95036998 0.76583002 -1.94966998 0 P 0 ;0
L 0.76583002 -1.94966998 0.76548996 -1.94896998 0 P 0 ;0
L 0.76548996 -1.94896998 0.76508996 -1.9483 0 P 0 ;0
L 0.76508996 -1.9483 0.76253002 -1.94436004 0 P 0 ;0
L 0.76253002 -1.94436004 0.76056998 -1.94126998 0 P 0 ;0
L 0.76056998 -1.94126998 0.75871998 -1.93806004 0 P 0 ;0
L 0.75871998 -1.93806004 0.75716998 -1.93496998 0 P 0 ;0
L 0.75716998 -1.93496998 0.7558 -1.93178002 0 P 0 ;0
L 0.7558 -1.93178002 0.7546 -1.92853996 0 P 0 ;0
L 0.7546 -1.92853996 0.75358996 -1.92521004 0 P 0 ;0
L 0.75358996 -1.92521004 0.7527 -1.92161998 0 P 0 ;0
L 0.7527 -1.92161998 0.75196998 -1.91796004 0 P 0 ;0
L 0.75196998 -1.91796004 0.75155 -1.91496004 0 P 0 ;0
L 0.75155 -1.91496004 0.75133002 -1.91193002 0 P 0 ;0
L 0.75133002 -1.91193002 0.75126998 -1.9085 0 P 0 ;0
L 0.75126998 -1.9085 0.75136004 -1.90506004 0 P 0 ;0
L 0.75136004 -1.90506004 0.75161004 -1.90181998 0 P 0 ;0
L 0.75161004 -1.90181998 0.752 -1.8986 0 P 0 ;0
L 0.752 -1.8986 0.75228996 -1.89701998 0 P 0 ;0
L 0.75228996 -1.89701998 0.75268996 -1.89546998 0 P 0 ;0
L 0.75268996 -1.89546998 0.7532 -1.89395 0 P 0 ;0
L 0.7532 -1.89395 0.75358996 -1.89281998 0 P 0 ;0
L 0.75358996 -1.89281998 0.75373002 -1.89231998 0 P 0 ;0
L 0.75373002 -1.89231998 0.75383996 -1.8918 0 P 0 ;0
L 0.75383996 -1.8918 0.75391998 -1.89138996 0 P 0 ;0
L 0.75391998 -1.89138996 0.75396998 -1.89098996 0 P 0 ;0
L 0.75396998 -1.89098996 0.75396998 -1.89086004 0 P 0 ;0
L 0.75396998 -1.89086004 0.75393996 -1.89076998 0 P 0 ;0
L 0.75393996 -1.89076998 0.7539 -1.89071004 0 P 0 ;0
L 0.7539 -1.89071004 0.75386004 -1.89066998 0 P 0 ;0
L 0.75386004 -1.89066998 0.75381004 -1.89063002 0 P 0 ;0
L 0.75381004 -1.89063002 0.75378996 -1.89061004 0 P 0 ;0
L 0.75378996 -1.89061004 0.75373002 -1.89058996 0 P 0 ;0
L 0.75373002 -1.89058996 0.75368002 -1.89056998 0 P 0 ;0
L 0.75368002 -1.89056998 0.75356004 -1.89056998 0 P 0 ;0
L 0.75356004 -1.89056998 0.75346998 -1.8906 0 P 0 ;0
L 0.75346998 -1.8906 0.74898002 -1.8927 0 P 0 ;0
L 0.74898002 -1.8927 0.74383002 -1.89518002 0 P 0 ;0
L 0.74383002 -1.89518002 0.73781004 -1.8982 0 P 0 ;0
L 0.69776998 -2.22761998 0.96701004 -2.22761998 0 P 0 ;0
L 0.6957 -2.22661998 0.96968996 -2.22661998 0 P 0 ;0
L 0.69366998 -2.22561998 0.97238002 -2.22561998 0 P 0 ;0
L 0.69163002 -2.22461998 0.97506004 -2.22461998 0 P 0 ;0
L 0.68958996 -2.22361998 0.97775 -2.22361998 0 P 0 ;0
L 0.68756004 -2.22261998 0.98043002 -2.22261998 0 P 0 ;0
L 0.68551998 -2.22161998 0.98311004 -2.22161998 0 P 0 ;0
L 0.68348996 -2.22061998 0.9858 -2.22061998 0 P 0 ;0
L 0.68176998 -2.21961998 0.98848002 -2.21961998 0 P 0 ;0
L 0.68003996 -2.21861998 0.99116998 -2.21861998 0 P 0 ;0
L 0.67831004 -2.21761998 0.99385 -2.21761998 0 P 0 ;0
L 0.67658002 -2.21661998 0.99653996 -2.21661998 0 P 0 ;0
L 0.67485 -2.21561998 0.99908002 -2.21561998 0 P 0 ;0
L 0.67311998 -2.21461998 0.87665 -2.21461998 0 P 0 ;0
L 0.6714 -2.21361998 0.85166004 -2.21361998 0 P 0 ;0
L 0.6699 -2.21261998 0.84083002 -2.21261998 0 P 0 ;0
L 0.66845 -2.21161998 0.8334 -2.21161998 0 P 0 ;0
L 0.66698996 -2.21061998 0.8274 -2.21061998 0 P 0 ;0
L 0.66553002 -2.20961998 0.82138996 -2.20961998 0 P 0 ;0
L 0.66406998 -2.20861998 0.81583002 -2.20861998 0 P 0 ;0
L 0.66261998 -2.20761998 0.81143996 -2.20761998 0 P 0 ;0
L 0.66116004 -2.20661998 0.80706004 -2.20661998 0 P 0 ;0
L 0.6597 -2.20561998 0.80266998 -2.20561998 0 P 0 ;0
L 0.65841004 -2.20461998 0.79828996 -2.20461998 0 P 0 ;0
L 0.65716998 -2.20361998 0.79448996 -2.20361998 0 P 0 ;0
L 0.65593002 -2.20261998 0.79106004 -2.20261998 0 P 0 ;0
L 0.65468996 -2.20161998 0.78763996 -2.20161998 0 P 0 ;0
L 0.83143002 -2.25261998 0.80871998 -2.25225 0 P 0 ;0
L 0.80871998 -2.25225 0.78691998 -2.25066998 0 P 0 ;0
L 0.78691998 -2.25066998 0.76525 -2.24786998 0 P 0 ;0
L 0.76525 -2.24786998 0.74581998 -2.24403996 0 P 0 ;0
L 0.74581998 -2.24403996 0.72671004 -2.23876004 0 P 0 ;0
L 0.72671004 -2.23876004 0.71196004 -2.23356998 0 P 0 ;0
L 0.71196004 -2.23356998 0.69756998 -2.22753996 0 P 0 ;0
L 0.69756998 -2.22753996 0.68355 -2.22066004 0 P 0 ;0
L 0.68355 -2.22066004 0.67118002 -2.2135 0 P 0 ;0
L 0.67118002 -2.2135 0.65938996 -2.20541004 0 P 0 ;0
L 0.65938996 -2.20541004 0.64825 -2.19643996 0 P 0 ;0
L 0.64825 -2.19643996 0.63861998 -2.18731998 0 P 0 ;0
L 0.63861998 -2.18731998 0.62983002 -2.17746998 0 P 0 ;0
L 0.62983002 -2.17746998 0.62188996 -2.1669 0 P 0 ;0
L 0.62188996 -2.1669 0.61678002 -2.15886998 0 P 0 ;0
L 0.61678002 -2.15886998 0.6123 -2.15056004 0 P 0 ;0
L 0.6123 -2.15056004 0.60841998 -2.14193996 0 P 0 ;0
L 0.60841998 -2.14193996 0.60516998 -2.13306998 0 P 0 ;0
L 0.60516998 -2.13306998 0.60191004 -2.12171004 0 P 0 ;0
L 0.60191004 -2.12171004 0.60075 -2.11648002 0 P 0 ;0
L 0.60075 -2.11648002 0.59983996 -2.11121004 0 P 0 ;0
L 0.59983996 -2.11121004 0.59913996 -2.10576004 0 P 0 ;0
L 0.59913996 -2.10576004 0.59868996 -2.10026004 0 P 0 ;0
L 0.59868996 -2.10026004 0.59833002 -2.0875 0 P 0 ;0
L 0.59833002 -2.0875 0.59856998 -2.07843996 0 P 0 ;0
L 0.59856998 -2.07843996 0.59923996 -2.0695 0 P 0 ;0
L 0.59923996 -2.0695 0.60031998 -2.06153996 0 P 0 ;0
L 0.60031998 -2.06153996 0.60193002 -2.05368996 0 P 0 ;0
L 0.60193002 -2.05368996 0.60416004 -2.04566004 0 P 0 ;0
L 0.60416004 -2.04566004 0.60688996 -2.03786004 0 P 0 ;0
L 0.60688996 -2.03786004 0.6148 -2.01961004 0 P 0 ;0
L 0.6148 -2.01961004 0.62108996 -2.00753002 0 P 0 ;0
L 0.62108996 -2.00753002 0.62811998 -1.99591998 0 P 0 ;0
L 0.62811998 -1.99591998 0.63583996 -1.98478996 0 P 0 ;0
L 0.63583996 -1.98478996 0.64936998 -1.96808002 0 P 0 ;0
L 0.64936998 -1.96808002 0.66418002 -1.95256998 0 P 0 ;0
L 0.66418002 -1.95256998 0.68098002 -1.93756004 0 P 0 ;0
L 0.68098002 -1.93756004 0.69881998 -1.92398002 0 P 0 ;0
L 0.69881998 -1.92398002 0.71841998 -1.91123996 0 P 0 ;0
L 0.71841998 -1.91123996 0.73875 -1.89996998 0 P 0 ;0
L 0.73875 -1.89996998 0.74471004 -1.89696998 0 P 0 ;0
L 0.74471004 -1.89696998 0.74983002 -1.89451004 0 P 0 ;0
L 0.74983002 -1.89451004 0.7511 -1.89391004 0 P 0 ;0
L 0.7511 -1.89391004 0.75076998 -1.89488996 0 P 0 ;0
L 0.75076998 -1.89488996 0.75033996 -1.89658996 0 P 0 ;0
L 0.75033996 -1.89658996 0.75003002 -1.8983 0 P 0 ;0
L 0.75003002 -1.8983 0.74961998 -1.90161998 0 P 0 ;0
L 0.74961998 -1.90161998 0.74936004 -1.90496004 0 P 0 ;0
L 0.74936004 -1.90496004 0.74926998 -1.9085 0 P 0 ;0
L 0.74926998 -1.9085 0.74933002 -1.91201998 0 P 0 ;0
L 0.74933002 -1.91201998 0.74956004 -1.91516998 0 P 0 ;0
L 0.74956004 -1.91516998 0.75 -1.91828996 0 P 0 ;0
L 0.75 -1.91828996 0.75075 -1.92205 0 P 0 ;0
L 0.75075 -1.92205 0.75166004 -1.92573996 0 P 0 ;0
L 0.75166004 -1.92573996 0.7527 -1.92916998 0 P 0 ;0
L 0.7527 -1.92916998 0.75393996 -1.93253002 0 P 0 ;0
L 0.75393996 -1.93253002 0.75536004 -1.93581998 0 P 0 ;0
L 0.75536004 -1.93581998 0.75696004 -1.939 0 P 0 ;0
L 0.75696004 -1.939 0.75885 -1.94231004 0 P 0 ;0
L 0.75885 -1.94231004 0.76083996 -1.94543996 0 P 0 ;0
L 0.76083996 -1.94543996 0.76338996 -1.94933996 0 P 0 ;0
L 0.76338996 -1.94933996 0.76371998 -1.94991998 0 P 0 ;0
L 0.76371998 -1.94991998 0.76401004 -1.9505 0 P 0 ;0
L 0.76401004 -1.9505 0.76423996 -1.95103002 0 P 0 ;0
L 0.76423996 -1.95103002 0.76408996 -1.95111004 0 P 0 ;0
L 0.76408996 -1.95111004 0.76348996 -1.95151004 0 P 0 ;0
L 0.76348996 -1.95151004 0.76021004 -1.95386004 0 P 0 ;0
L 0.76021004 -1.95386004 0.7602 -1.95386998 0 P 0 ;0
L 0.7602 -1.95386998 0.75636998 -1.95666004 0 P 0 ;0
L 0.75636998 -1.95666004 0.75636004 -1.95666998 0 P 0 ;0
L 0.75636004 -1.95666998 0.75635 -1.95666998 0 P 0 ;0
L 0.75635 -1.95666998 0.75208996 -1.95981004 0 P 0 ;0
L 0.75208996 -1.95981004 0.73841004 -1.97066998 0 P 0 ;0
L 0.73841004 -1.97066998 0.72541004 -1.98241004 0 P 0 ;0
L 0.72541004 -1.98241004 0.7143 -1.994 0 P 0 ;0
L 0.7143 -1.994 0.71425 -1.99406004 0 P 0 ;0
L 0.71425 -1.99406004 0.70413996 -2.00648002 0 P 0 ;0
L 0.70413996 -2.00648002 0.69836998 -2.01468996 0 P 0 ;0
L 0.69836998 -2.01468996 0.69313002 -2.02318002 0 P 0 ;0
L 0.69313002 -2.02318002 0.68838996 -2.03196004 0 P 0 ;0
L 0.68838996 -2.03196004 0.68438996 -2.04063996 0 P 0 ;0
L 0.68438996 -2.04063996 0.68098996 -2.04958002 0 P 0 ;0
L 0.68098996 -2.04958002 0.6782 -2.05873002 0 P 0 ;0
L 0.6782 -2.05873002 0.67706004 -2.06366004 0 P 0 ;0
L 0.67706004 -2.06366004 0.67628996 -2.06866998 0 P 0 ;0
L 0.67628996 -2.06866998 0.67538002 -2.08068996 0 P 0 ;0
L 0.67538002 -2.08068996 0.67546004 -2.09268996 0 P 0 ;0
L 0.67546004 -2.09268996 0.67588996 -2.09766998 0 P 0 ;0
L 0.67588996 -2.09766998 0.6767 -2.10258996 0 P 0 ;0
L 0.6767 -2.10258996 0.67881998 -2.11111998 0 P 0 ;0
L 0.67881998 -2.11111998 0.68163996 -2.11936004 0 P 0 ;0
L 0.68163996 -2.11936004 0.68516004 -2.12731998 0 P 0 ;0
L 0.68516004 -2.12731998 0.68935 -2.13493996 0 P 0 ;0
L 0.68935 -2.13493996 0.69418002 -2.14216998 0 P 0 ;0
L 0.69418002 -2.14216998 0.70153002 -2.15135 0 P 0 ;0
L 0.70153002 -2.15135 0.7096 -2.15983002 0 P 0 ;0
L 0.7096 -2.15983002 0.71836004 -2.16758996 0 P 0 ;0
L 0.71836004 -2.16758996 0.71843002 -2.16763996 0 P 0 ;0
L 0.71843002 -2.16763996 0.72773996 -2.17456004 0 P 0 ;0
L 0.72773996 -2.17456004 0.73926998 -2.1818 0 P 0 ;0
L 0.73926998 -2.1818 0.75121004 -2.18818002 0 P 0 ;0
L 0.75121004 -2.18818002 0.75128002 -2.18821004 0 P 0 ;0
L 0.75128002 -2.18821004 0.76358002 -2.19368996 0 P 0 ;0
L 0.76358002 -2.19368996 0.77628002 -2.19831004 0 P 0 ;0
L 0.77628002 -2.19831004 0.79658996 -2.20423996 0 P 0 ;0
L 0.79658996 -2.20423996 0.81701004 -2.20888996 0 P 0 ;0
L 0.81701004 -2.20888996 0.83763996 -2.21233002 0 P 0 ;0
L 0.83763996 -2.21233002 0.85388002 -2.21383002 0 P 0 ;0
L 0.85388002 -2.21383002 0.87733996 -2.21465 0 P 0 ;0
L 0.87733996 -2.21465 0.90118002 -2.21478996 0 P 0 ;0
L 0.90118002 -2.21478996 0.91906004 -2.21398996 0 P 0 ;0
L 0.91906004 -2.21398996 0.94908996 -2.21068002 0 P 0 ;0
L 0.94908996 -2.21068002 0.98176998 -2.2053 0 P 0 ;0
L 0.98176998 -2.2053 1.01575 -2.19815 0 P 0 ;0
L 1.01575 -2.19815 1.04968002 -2.18943002 0 P 0 ;0
L 1.04968002 -2.18943002 1.05633996 -2.18761004 0 P 0 ;0
L 1.05633996 -2.18761004 1.05713996 -2.1874 0 P 0 ;0
L 1.05713996 -2.1874 1.05483002 -2.18875 0 P 0 ;0
L 1.05483002 -2.18875 1.04298996 -2.19526004 0 P 0 ;0
L 1.04298996 -2.19526004 1.03096998 -2.20136998 0 P 0 ;0
L 1.03096998 -2.20136998 0.99835 -2.21595 0 P 0 ;0
L 0.99835 -2.21595 0.96401998 -2.22873996 0 P 0 ;0
L 0.96401998 -2.22873996 0.92993996 -2.23908002 0 P 0 ;0
L 0.92993996 -2.23908002 0.89816004 -2.24626004 0 P 0 ;0
L 0.89816004 -2.24626004 0.87616004 -2.24965 0 P 0 ;0
L 0.87616004 -2.24965 0.85405 -2.25176004 0 P 0 ;0
L 0.85405 -2.25176004 0.83143002 -2.25261998 0 P 0 ;0
L 0.65345 -2.20061998 0.78421004 -2.20061998 0 P 0 ;0
L 0.65221004 -2.19961998 0.78078002 -2.19961998 0 P 0 ;0
L 0.65096004 -2.19861998 0.77735 -2.19861998 0 P 0 ;0
L 0.64971998 -2.19761998 0.77438996 -2.19761998 0 P 0 ;0
L 0.64848002 -2.19661998 0.77163996 -2.19661998 0 P 0 ;0
L 0.64738996 -2.19561998 0.76888996 -2.19561998 0 P 0 ;0
L 0.64633996 -2.19461998 0.76613996 -2.19461998 0 P 0 ;0
L 0.64528002 -2.19361998 0.76343002 -2.19361998 0 P 0 ;0
L 0.64421998 -2.19261998 0.76118996 -2.19261998 0 P 0 ;0
L 0.64316998 -2.19161998 0.75893996 -2.19161998 0 P 0 ;0
L 0.64211004 -2.19061998 0.7567 -2.19061998 0 P 0 ;0
L 0.64106004 -2.18961998 0.75446004 -2.18961998 0 P 0 ;0
L 0.64 -2.18861998 0.75221004 -2.18861998 0 P 0 ;0
L 0.63895 -2.18761998 0.75018002 -2.18761998 0 P 0 ;0
L 0.63801004 -2.18661998 0.74831004 -2.18661998 0 P 0 ;0
L 0.63711004 -2.18561998 0.74643002 -2.18561998 0 P 0 ;0
L 0.63621998 -2.18461998 0.74456004 -2.18461998 0 P 0 ;0
L 0.63533002 -2.18361998 0.74268002 -2.18361998 0 P 0 ;0
L 0.63443996 -2.18261998 0.74081004 -2.18261998 0 P 0 ;0
L 0.63353996 -2.18161998 0.73898996 -2.18161998 0 P 0 ;0
L 0.63265 -2.18061998 0.73738996 -2.18061998 0 P 0 ;0
L 0.63176004 -2.17961998 0.7358 -2.17961998 0 P 0 ;0
L 0.63086998 -2.17861998 0.73421004 -2.17861998 0 P 0 ;0
L 0.62996998 -2.17761998 0.73261998 -2.17761998 0 P 0 ;0
L 0.6292 -2.17661998 0.73103002 -2.17661998 0 P 0 ;0
L 0.62845 -2.17561998 0.72943996 -2.17561998 0 P 0 ;0
L 0.6277 -2.17461998 0.72783996 -2.17461998 0 P 0 ;0
L 0.62693996 -2.17361998 0.72648002 -2.17361998 0 P 0 ;0
L 0.62618996 -2.17261998 0.72513996 -2.17261998 0 P 0 ;0
L 0.62543996 -2.17161998 0.72378996 -2.17161998 0 P 0 ;0
L 0.62468996 -2.17061998 0.72245 -2.17061998 0 P 0 ;0
L 0.62393996 -2.16961998 0.7211 -2.16961998 0 P 0 ;0
L 0.62318002 -2.16861998 0.71976004 -2.16861998 0 P 0 ;0
L 0.62243996 -2.16761998 0.71841004 -2.16761998 0 P 0 ;0
L 0.62171004 -2.16661998 0.71726998 -2.16661998 0 P 0 ;0
L 0.62108002 -2.16561998 0.71613996 -2.16561998 0 P 0 ;0
L 0.62043996 -2.16461998 0.71501004 -2.16461998 0 P 0 ;0
L 0.61981004 -2.16361998 0.71388002 -2.16361998 0 P 0 ;0
L 0.61916998 -2.16261998 0.71276004 -2.16261998 0 P 0 ;0
L 0.61853002 -2.16161998 0.71163002 -2.16161998 0 P 0 ;0
L 0.6179 -2.16061998 0.7105 -2.16061998 0 P 0 ;0
L 0.61726004 -2.15961998 0.7094 -2.15961998 0 P 0 ;0
L 0.61665 -2.15861998 0.70845 -2.15861998 0 P 0 ;0
L 0.61611004 -2.15761998 0.7075 -2.15761998 0 P 0 ;0
L 0.75383996 -2.24561998 0.901 -2.24561998 0 P 0 ;0
L 0.74876998 -2.24461998 0.90541998 -2.24461998 0 P 0 ;0
L 0.74431004 -2.24361998 0.90985 -2.24361998 0 P 0 ;0
L 0.7407 -2.24261998 0.91426998 -2.24261998 0 P 0 ;0
L 0.73708002 -2.24161998 0.9187 -2.24161998 0 P 0 ;0
L 0.73346998 -2.24061998 0.92311998 -2.24061998 0 P 0 ;0
L 0.72986004 -2.23961998 0.92753996 -2.23961998 0 P 0 ;0
L 0.72633996 -2.23861998 0.93145 -2.23861998 0 P 0 ;0
L 0.72348996 -2.23761998 0.93473996 -2.23761998 0 P 0 ;0
L 0.72063996 -2.23661998 0.93803996 -2.23661998 0 P 0 ;0
L 0.7178 -2.23561998 0.94133002 -2.23561998 0 P 0 ;0
L 0.71495 -2.23461998 0.94461998 -2.23461998 0 P 0 ;0
L 0.7121 -2.23361998 0.94791998 -2.23361998 0 P 0 ;0
L 0.70968996 -2.23261998 0.95121004 -2.23261998 0 P 0 ;0
L 0.70731004 -2.23161998 0.95451004 -2.23161998 0 P 0 ;0
L 0.70491998 -2.23061998 0.9578 -2.23061998 0 P 0 ;0
L 0.70253996 -2.22961998 0.9611 -2.22961998 0 P 0 ;0
L 0.70015 -2.22861998 0.96431998 -2.22861998 0 P 0 ;0
L 8.45 3.66615 8.45 3.71615 6 P 0 
L 8.5 3.76615 8.5 3.81615 6 P 0 
L 8.45 3.81615 8.45 3.86615 6 P 0 
L 8.5 3.46615 8.5 3.51615 6 P 0 
L 8.45 3.41615 8.45 3.46615 6 P 0 
L 8.5 3.61615 8.5 3.66615 6 P 0 
L 8.45 3.26615 8.45 3.31615 6 P 0 
L 8.5 3.31615 8.5 3.36615 6 P 0 
L 8.2 3.66615 8.2 3.71615 6 P 0 
L 8.35 3.66615 8.35 3.71615 6 P 0 
L 8.4 3.76615 8.4 3.81615 6 P 0 
L 8.35 3.81615 8.35 3.86615 6 P 0 
L 8.2 3.81615 8.2 3.86615 6 P 0 
L 8.4 3.46615 8.4 3.51615 6 P 0 
L 8.35 3.41615 8.35 3.46615 6 P 0 
L 8.2 3.41615 8.2 3.46615 6 P 0 
L 8.4 3.61615 8.4 3.66615 6 P 0 
L 8.35 3.26615 8.35 3.31615 6 P 0 
L 8.4 3.31615 8.4 3.36615 6 P 0 
L 8.2 3.26615 8.2 3.31615 6 P 0 
L 8.25 2.86615 8.3 2.86615 6 P 0 
L 8.1 3.66615 8.1 3.71615 6 P 0 
L 8.15 3.76615 8.15 3.81615 6 P 0 
L 8.1 3.81615 8.1 3.86615 6 P 0 
L 8.05 3.76615 8.05 3.81615 6 P 0 
L 8.1 3.41615 8.1 3.46615 6 P 0 
L 8.15 3.46615 8.15 3.51615 6 P 0 
L 8 3.46615 8 3.51615 6 P 0 
L 8.05 3.61615 8.05 3.66615 6 P 0 
L 8.15 3.61615 8.15 3.66615 6 P 0 
L 8.1 3.26615 8.1 3.31615 6 P 0 
L 8.15 3.31615 8.15 3.36615 6 P 0 
L 8.05 3.31615 8.05 3.36615 6 P 0 
L 5.42048002 1.91835 5.42048002 1.87835 6 P 0 
L 5.57531004 1.8508 5.57531004 1.8108 6 P 0 
L 2.34606004 3.26615 2.34606004 3.31615 6 P 0 
L 2.39606004 3.31615 2.39606004 3.36615 6 P 0 
L 2.44606004 3.26615 2.44606004 3.31615 6 P 0 
L 2.49606004 3.31615 2.49606004 3.36615 6 P 0 
L 2.49606004 3.46615 2.49606004 3.51615 6 P 0 
L 2.44606004 3.41615 2.44606004 3.46615 6 P 0 
L 2.39606004 3.46615 2.39606004 3.51615 6 P 0 
L 2.34606004 3.41615 2.34606004 3.46615 6 P 0 
L 2.19606004 3.26615 2.19606004 3.31615 6 P 0 
L 2.09606004 3.26615 2.09606004 3.31615 6 P 0 
L 2.14606004 3.31615 2.14606004 3.36615 6 P 0 
L 2.19606004 3.41615 2.19606004 3.46615 6 P 0 
L 2.09606004 3.41615 2.09606004 3.46615 6 P 0 
L 2.04606004 3.31615 2.04606004 3.36615 6 P 0 
L 2.14606004 3.46615 2.14606004 3.51615 6 P 0 
L 1.99606004 3.46615 1.99606004 3.51615 6 P 0 
L 2.04606004 3.61615 2.04606004 3.66615 6 P 0 
L 2.09606004 3.66615 2.09606004 3.71615 6 P 0 
L 2.14606004 3.61615 2.14606004 3.66615 6 P 0 
L 2.19606004 3.66615 2.19606004 3.71615 6 P 0 
L 2.49606004 3.61615 2.49606004 3.66615 6 P 0 
L 2.34606004 3.66615 2.34606004 3.71615 6 P 0 
L 2.39606004 3.61615 2.39606004 3.66615 6 P 0 
L 2.44606004 3.66615 2.44606004 3.71615 6 P 0 
L 2.49606004 3.76615 2.49606004 3.81615 6 P 0 
L 2.44606004 3.81615 2.44606004 3.86615 6 P 0 
L 2.39606004 3.76615 2.39606004 3.81615 6 P 0 
L 2.34606004 3.81615 2.34606004 3.86615 6 P 0 
L 2.14606004 3.76615 2.14606004 3.81615 6 P 0 
L 2.19606004 3.81615 2.19606004 3.86615 6 P 0 
L 2.09606004 3.81615 2.09606004 3.86615 6 P 0 
L 2.04606004 3.76615 2.04606004 3.81615 6 P 0 
L 2.24606004 2.86615 2.29606004 2.86615 6 P 0 
L 5.42048002 1.6433 5.42048002 1.6033 6 P 0 
L 5.57531004 1.7118 5.57531004 1.6718 6 P 0 
L 5.42048002 1.7796 5.42048002 1.7396 6 P 0 
L 5.57531004 1.9869 5.57531004 1.9469 6 P 0 
L 5.42048002 2.0547 5.42048002 2.0147 6 P 0 
L 5.57531004 2.1278 5.57531004 2.0878 6 P 0 
L 5.42048002 2.1954 5.42048002 2.1554 6 P 0 
L 5.57531004 2.2632 5.57531004 2.2232 6 P 0 
L 5.42048002 2.3308 5.42048002 2.2908 6 P 0 
L 5.57531004 2.3986 5.57531004 2.3586 6 P 0 
L 5.42048002 2.4662 5.42048002 2.4262 6 P 0 
L 5.57531004 2.5378 5.57531004 2.4978 6 P 0 
L 5.57531004 2.673 5.57531004 2.633 6 P 0 
L 5.42048002 2.6054 5.42048002 2.5654 6 P 0 
L 10.09 2.73655 10.09 2.69655 6 P 0 
L 9.975 2.66445 9.975 2.62445 6 P 0 
L 9.975 2.5109 9.975 2.4709 6 P 0 
L 10.09 2.57845 10.09 2.53845 6 P 0 
L 10.09 2.44335 10.09 2.40335 6 P 0 
L 9.975 2.3758 9.975 2.3358 6 P 0 
L 10.09 2.30825 10.09 2.26825 6 P 0 
L 9.975 2.23955 9.975 2.19955 6 P 0 
L 10.09 2.17095 10.09 2.13095 6 P 0 
L 10.09 2.05655 10.09 2.01655 6 P 0 
L 10.225 1.96645 10.225 1.92645 6 P 0 
L 10.26025 1.86845 10.26025 1.82845 6 P 0 
L 10.26 1.70445 10.26 1.66445 6 P 0 
L 10.35543996 1.52156004 10.38371998 1.49328002 7 P 0 
L 10.46445 1.395 10.42445 1.395 6 P 0 
L 10.395 1.28555 10.395 1.32555 6 P 0 
L 11.53316004 1.412 11.53316004 1.452 6 P 0 
L 11.73316004 1.492 11.73316004 1.532 6 P 0 
L 11.53316004 1.572 11.53316004 1.612 6 P 0 
L 11.78316004 1.652 11.78316004 1.692 6 P 0 
L 11.53316004 1.732 11.53316004 1.772 6 P 0 
L 11.73316004 1.812 11.73316004 1.852 6 P 0 
L 11.53316004 1.892 11.53316004 1.932 6 P 0 
L 11.53316004 2.052 11.53316004 2.092 6 P 0 
L 11.73316004 1.972 11.73316004 2.012 6 P 0 
L 11.73316004 2.132 11.73316004 2.172 6 P 0 
L 11.83316004 2.212 11.83316004 2.252 6 P 0 
L 11.73316004 2.292 11.73316004 2.332 6 P 0 
L 11.53316004 2.372 11.53316004 2.412 6 P 0 
L 11.53316004 2.532 11.53316004 2.572 6 P 0 
L 11.73316004 2.452 11.73316004 2.492 6 P 0 
L 11.73316004 2.612 11.73316004 2.652 6 P 0 
L 8.98115 2.825 8.98115 2.865 6 P 0 
L 2.97721004 2.825 2.97721004 2.865 6 P 0 
L 11.03661004 2.46615 11.03661004 2.51615 6 P 0 
L 11.08661004 2.21615 11.08661004 2.26615 6 P 0 
L 10.98661004 2.21615 10.98661004 2.26615 6 P 0 
L 11.03661004 2.26615 11.03661004 2.31615 6 P 0 
L 10.93661004 2.26615 10.93661004 2.31615 6 P 0 
L 10.98661004 2.36615 10.98661004 2.41615 6 P 0 
L 10.93661004 2.41615 10.93661004 2.46615 6 P 0 
L 11.08661004 2.36615 11.08661004 2.41615 6 P 0 
L 10.93661004 2.01615 10.93661004 2.06615 6 P 0 
L 10.98661004 2.06615 10.98661004 2.11615 6 P 0 
L 11.03661004 2.01615 11.03661004 2.06615 6 P 0 
L 11.08661004 2.06615 11.08661004 2.11615 6 P 0 
L 10.93661004 1.86615 10.93661004 1.91615 6 P 0 
L 11.03661004 1.86615 11.03661004 1.91615 6 P 0 
L 10.98661004 1.91615 10.98661004 1.96615 6 P 0 
L 11.08661004 1.91615 11.08661004 1.96615 6 P 0 
L 10.73661004 2.46615 10.73661004 2.41615 6 P 0 
L 10.68661004 2.41615 10.68661004 2.36615 6 P 0 
L 10.68661004 2.26615 10.68661004 2.21615 6 P 0 
L 10.73661004 2.31615 10.73661004 2.26615 6 P 0 
L 10.68661004 2.11615 10.68661004 2.06615 6 P 0 
L 10.83661004 2.16615 10.88661004 2.16615 6 P 0 
L 10.73661004 2.01615 10.73661004 2.06615 6 P 0 
L 10.68661004 1.91615 10.68661004 1.96615 6 P 0 
L 10.73661004 1.86615 10.73661004 1.91615 6 P 0 
L 10.63661004 2.46615 10.63661004 2.41615 6 P 0 
L 10.58661004 2.41615 10.58661004 2.36615 6 P 0 
L 10.63661004 2.31615 10.63661004 2.26615 6 P 0 
L 10.58661004 2.26615 10.58661004 2.21615 6 P 0 
L 10.58661004 2.11615 10.58661004 2.06615 6 P 0 
L 10.63661004 2.01615 10.63661004 2.06615 6 P 0 
L 10.58661004 1.91615 10.58661004 1.96615 6 P 0 
L 10.63661004 1.86615 10.63661004 1.91615 6 P 0 
L 0.69348996 1.86611998 0.69348996 1.90611998 6 P 0 
L 5.03268002 2.46615 5.03268002 2.51615 6 P 0 
L 5.08268002 2.36615 5.08268002 2.41615 6 P 0 
L 4.93268002 2.41615 4.93268002 2.46615 6 P 0 
L 4.98268002 2.36615 4.98268002 2.41615 6 P 0 
L 4.93268002 2.26615 4.93268002 2.31615 6 P 0 
L 5.03268002 2.26615 5.03268002 2.31615 6 P 0 
L 4.98268002 2.21615 4.98268002 2.26615 6 P 0 
L 5.08268002 2.21615 5.08268002 2.26615 6 P 0 
L 5.08268002 2.06615 5.08268002 2.11615 6 P 0 
L 5.03268002 2.01615 5.03268002 2.06615 6 P 0 
L 4.98268002 2.06615 4.98268002 2.11615 6 P 0 
L 4.93268002 2.01615 4.93268002 2.06615 6 P 0 
L 5.08268002 1.91615 5.08268002 1.96615 6 P 0 
L 4.98268002 1.91615 4.98268002 1.96615 6 P 0 
L 5.03268002 1.86615 5.03268002 1.91615 6 P 0 
L 4.93268002 1.86615 4.93268002 1.91615 6 P 0 
L 4.73268002 1.86615 4.73268002 1.91615 6 P 0 
L 4.63268002 1.86615 4.63268002 1.91615 6 P 0 
L 4.68268002 1.91615 4.68268002 1.96615 6 P 0 
L 4.58268002 1.91615 4.58268002 1.96615 6 P 0 
L 4.63268002 2.01615 4.63268002 2.06615 6 P 0 
L 4.73268002 2.01615 4.73268002 2.06615 6 P 0 
L 4.83268002 2.16615 4.88268002 2.16615 6 P 0 
L 4.58268002 2.11615 4.58268002 2.06615 6 P 0 
L 4.68268002 2.11615 4.68268002 2.06615 6 P 0 
L 4.73268002 2.31615 4.73268002 2.26615 6 P 0 
L 4.68268002 2.26615 4.68268002 2.21615 6 P 0 
L 4.58268002 2.26615 4.58268002 2.21615 6 P 0 
L 4.63268002 2.31615 4.63268002 2.26615 6 P 0 
L 4.58268002 2.41615 4.58268002 2.36615 6 P 0 
L 4.68268002 2.41615 4.68268002 2.36615 6 P 0 
L 4.63268002 2.46615 4.63268002 2.41615 6 P 0 
L 4.73268002 2.46615 4.73268002 2.41615 6 P 0 
A 12.75476004 4.52361998 12.75476004 4.52361998 12.73621004 4.52361998 3 P 0 N
A 12.8335 4.48425 12.8335 4.48425 12.81495 4.48425 3 P 0 N
L 12.73621004 4.52361998 12.81495 4.48425 9 P 0 
L 12.73621004 4.36613996 12.81495 4.32676998 9 P 0 
A 12.8335 4.32676998 12.8335 4.32676998 12.81495 4.32676998 3 P 0 N
A 12.75476004 4.36613996 12.75476004 4.36613996 12.73621004 4.36613996 3 P 0 N
L 12.73621004 4.20866004 12.81495 4.16928996 9 P 0 
A 12.8335 4.16928996 12.8335 4.16928996 12.81495 4.16928996 3 P 0 N
A 12.75476004 4.20866004 12.75476004 4.20866004 12.73621004 4.20866004 3 P 0 N
L 12.73621004 4.05118002 12.81495 4.01181004 9 P 0 
A 12.8335 4.01181004 12.8335 4.01181004 12.81495 4.01181004 3 P 0 N
A 12.75476004 4.05118002 12.75476004 4.05118002 12.73621004 4.05118002 3 P 0 N
L 12.73621004 3.8937 12.81495 3.85433002 9 P 0 
A 12.8335 3.85433002 12.8335 3.85433002 12.81495 3.85433002 3 P 0 N
A 12.75476004 3.8937 12.75476004 3.8937 12.73621004 3.8937 3 P 0 N
A 12.75476004 3.73621998 12.75476004 3.73621998 12.73621004 3.73621998 3 P 0 N
L 12.73621004 3.73621998 12.81495 3.69685 9 P 0 
A 12.8335 3.69685 12.8335 3.69685 12.81495 3.69685 3 P 0 N
L 12.73621004 3.57873996 12.81495 3.53936998 9 P 0 
A 12.8335 3.53936998 12.8335 3.53936998 12.81495 3.53936998 3 P 0 N
A 12.75476004 3.57873996 12.75476004 3.57873996 12.73621004 3.57873996 3 P 0 N
L 12.73621004 3.42126004 12.81495 3.38188996 9 P 0 
A 12.8335 3.38188996 12.8335 3.38188996 12.81495 3.38188996 3 P 0 N
A 12.75476004 3.42126004 12.75476004 3.42126004 12.73621004 3.42126004 3 P 0 N
A 12.8335 3.22441004 12.8335 3.22441004 12.81495 3.22441004 3 P 0 N
L 12.73621004 3.02756004 12.81495 3.06693002 9 P 0 
A 12.8335 3.06693002 12.8335 3.06693002 12.81495 3.06693002 3 P 0 N
A 12.75476004 3.02756004 12.75476004 3.02756004 12.73621004 3.02756004 3 P 0 N
L 12.73621004 3.18503996 12.81495 3.22441004 9 P 0 
A 12.75476004 3.18503996 12.75476004 3.18503996 12.73621004 3.18503996 3 P 0 N
A 12.8335 2.75196998 12.8335 2.75196998 12.81495 2.75196998 3 P 0 N
L 12.73621004 2.87008002 12.81495 2.90945 9 P 0 
A 12.8335 2.90945 12.8335 2.90945 12.81495 2.90945 3 P 0 N
A 12.75476004 2.87008002 12.75476004 2.87008002 12.73621004 2.87008002 3 P 0 N
A 12.8335 2.51575 12.8335 2.51575 12.81495 2.51575 3 P 0 N
A 12.75476004 2.47638002 12.75476004 2.47638002 12.73621004 2.47638002 3 P 0 N
L 12.73621004 2.7126 12.81495 2.75196998 9 P 0 
A 12.75476004 2.7126 12.75476004 2.7126 12.73621004 2.7126 3 P 0 N
L 12.73621004 2.3189 12.81495 2.35826998 9 P 0 
A 12.8335 2.35826998 12.8335 2.35826998 12.81495 2.35826998 3 P 0 N
A 12.75476004 2.3189 12.75476004 2.3189 12.73621004 2.3189 3 P 0 N
L 12.73621004 2.47638002 12.81495 2.51575 9 P 0 
A 12.75476004 2.00393996 12.75476004 2.00393996 12.73621004 2.00393996 3 P 0 N
L 12.73621004 2.16141998 12.81495 2.20078996 9 P 0 
A 12.8335 2.20078996 12.8335 2.20078996 12.81495 2.20078996 3 P 0 N
A 12.75476004 2.16141998 12.75476004 2.16141998 12.73621004 2.16141998 3 P 0 N
L 12.73621004 2.00393996 12.81495 1.96456998 9 P 0 
A 12.8335 1.96456998 12.8335 1.96456998 12.81495 1.96456998 3 P 0 N
L 12.55905 4.563 12.63778996 4.60236998 9 P 0 
A 12.65633996 4.60236998 12.65633996 4.60236998 12.63778996 4.60236998 3 P 0 N
A 12.5776 4.563 12.5776 4.563 12.55905 4.563 3 P 0 N
L 12.55905 4.24803002 12.63778996 4.2874 9 P 0 
A 12.65633996 4.2874 12.65633996 4.2874 12.63778996 4.2874 3 P 0 N
A 12.5776 4.24803002 12.5776 4.24803002 12.55905 4.24803002 3 P 0 N
L 12.55905 4.40551004 12.63778996 4.44488002 9 P 0 
A 12.65633996 4.44488002 12.65633996 4.44488002 12.63778996 4.44488002 3 P 0 N
A 12.5776 4.40551004 12.5776 4.40551004 12.55905 4.40551004 3 P 0 N
A 12.65633996 3.97243996 12.65633996 3.97243996 12.63778996 3.97243996 3 P 0 N
L 12.55905 4.09055 12.63778996 4.12991998 9 P 0 
A 12.65633996 4.12991998 12.65633996 4.12991998 12.63778996 4.12991998 3 P 0 N
A 12.5776 4.09055 12.5776 4.09055 12.55905 4.09055 3 P 0 N
L 12.55905 3.77558996 12.63778996 3.81496004 9 P 0 
A 12.65633996 3.81496004 12.65633996 3.81496004 12.63778996 3.81496004 3 P 0 N
A 12.5776 3.77558996 12.5776 3.77558996 12.55905 3.77558996 3 P 0 N
L 12.55905 3.93306998 12.63778996 3.97243996 9 P 0 
A 12.5776 3.93306998 12.5776 3.93306998 12.55905 3.93306998 3 P 0 N
A 12.65633996 3.5 12.65633996 3.5 12.63778996 3.5 3 P 0 N
L 12.55905 3.61811004 12.63778996 3.65748002 9 P 0 
A 12.65633996 3.65748002 12.65633996 3.65748002 12.63778996 3.65748002 3 P 0 N
A 12.5776 3.61811004 12.5776 3.61811004 12.55905 3.61811004 3 P 0 N
L 12.55905 3.30315 12.63778996 3.26378002 9 P 0 
A 12.65633996 3.26378002 12.65633996 3.26378002 12.63778996 3.26378002 3 P 0 N
A 12.5776 3.30315 12.5776 3.30315 12.55905 3.30315 3 P 0 N
L 12.55905 3.46063002 12.63778996 3.5 9 P 0 
A 12.5776 3.46063002 12.5776 3.46063002 12.55905 3.46063002 3 P 0 N
L 12.55905 3.14566998 12.63778996 3.1063 9 P 0 
A 12.65633996 3.1063 12.65633996 3.1063 12.63778996 3.1063 3 P 0 N
A 12.5776 3.14566998 12.5776 3.14566998 12.55905 3.14566998 3 P 0 N
A 12.5776 2.98818996 12.5776 2.98818996 12.55905 2.98818996 3 P 0 N
L 12.55905 2.98818996 12.63778996 2.94881998 9 P 0 
A 12.65633996 2.94881998 12.65633996 2.94881998 12.63778996 2.94881998 3 P 0 N
L 12.55905 2.83071004 12.63778996 2.79133996 9 P 0 
A 12.65633996 2.79133996 12.65633996 2.79133996 12.63778996 2.79133996 3 P 0 N
A 12.5776 2.83071004 12.5776 2.83071004 12.55905 2.83071004 3 P 0 N
L 12.55905 2.59448996 12.63778996 2.55511998 9 P 0 
A 12.65633996 2.55511998 12.65633996 2.55511998 12.63778996 2.55511998 3 P 0 N
A 12.5776 2.59448996 12.5776 2.59448996 12.55905 2.59448996 3 P 0 N
L 12.55905 2.43701004 12.63778996 2.39763996 9 P 0 
A 12.65633996 2.39763996 12.65633996 2.39763996 12.63778996 2.39763996 3 P 0 N
A 12.5776 2.43701004 12.5776 2.43701004 12.55905 2.43701004 3 P 0 N
L 12.55905 2.27953002 12.63778996 2.24016004 9 P 0 
A 12.65633996 2.24016004 12.65633996 2.24016004 12.63778996 2.24016004 3 P 0 N
A 12.5776 2.27953002 12.5776 2.27953002 12.55905 2.27953002 3 P 0 N
A 12.5776 2.04331004 12.5776 2.04331004 12.55905 2.04331004 3 P 0 N
A 12.65633996 2.08268002 12.65633996 2.08268002 12.63778996 2.08268002 3 P 0 N
L 12.55905 2.04331004 12.63778996 2.08268002 9 P 0 
L 12.55905 1.96456998 12.63778996 1.9252 9 P 0 
A 12.65633996 1.9252 12.65633996 1.9252 12.63778996 1.9252 3 P 0 N
A 12.5776 1.96456998 12.5776 1.96456998 12.55905 1.96456998 3 P 0 N
A 0.11303996 4.52363002 0.11303996 4.52363002 0.09448996 4.52363002 3 P 0 N
A 0.19178002 4.563 0.19178002 4.563 0.17323002 4.563 3 P 0 N
L 0.09448996 4.52363002 0.17323002 4.563 9 P 0 
A 0.11303996 4.36613996 0.11303996 4.36613996 0.09448996 4.36613996 3 P 0 N
A 0.19178002 4.40551004 0.19178002 4.40551004 0.17323002 4.40551004 3 P 0 N
L 0.09448996 4.36613996 0.17323002 4.40551004 9 P 0 
A 0.11303996 4.20866004 0.11303996 4.20866004 0.09448996 4.20866004 3 P 0 N
A 0.19178002 4.24803002 0.19178002 4.24803002 0.17323002 4.24803002 3 P 0 N
L 0.09448996 4.20866004 0.17323002 4.24803002 9 P 0 
A 0.11303996 4.05118002 0.11303996 4.05118002 0.09448996 4.05118002 3 P 0 N
A 0.19178002 4.09055 0.19178002 4.09055 0.17323002 4.09055 3 P 0 N
L 0.09448996 4.05118002 0.17323002 4.09055 9 P 0 
A 0.11303996 3.8937 0.11303996 3.8937 0.09448996 3.8937 3 P 0 N
A 0.19178002 3.93306998 0.19178002 3.93306998 0.17323002 3.93306998 3 P 0 N
L 0.09448996 3.8937 0.17323002 3.93306998 9 P 0 
A 0.11303996 3.73621998 0.11303996 3.73621998 0.09448996 3.73621998 3 P 0 N
A 0.19178002 3.77558996 0.19178002 3.77558996 0.17323002 3.77558996 3 P 0 N
L 0.09448996 3.73621998 0.17323002 3.77558996 9 P 0 
A 0.11303996 3.57873996 0.11303996 3.57873996 0.09448996 3.57873996 3 P 0 N
A 0.19178002 3.61811004 0.19178002 3.61811004 0.17323002 3.61811004 3 P 0 N
L 0.09448996 3.57873996 0.17323002 3.61811004 9 P 0 
A 0.11303996 3.42126004 0.11303996 3.42126004 0.09448996 3.42126004 3 P 0 N
A 0.19178002 3.46063002 0.19178002 3.46063002 0.17323002 3.46063002 3 P 0 N
L 0.09448996 3.42126004 0.17323002 3.46063002 9 P 0 
A 0.2902 3.14566998 0.2902 3.14566998 0.27165 3.14566998 3 P 0 N
A 0.36893996 3.18503996 0.36893996 3.18503996 0.35038996 3.18503996 3 P 0 N
L 0.27165 3.14566998 0.35038996 3.18503996 9 P 0 
A 0.2902 2.98818996 0.2902 2.98818996 0.27165 2.98818996 3 P 0 N
A 0.36893996 3.02756004 0.36893996 3.02756004 0.35038996 3.02756004 3 P 0 N
L 0.27165 2.98818996 0.35038996 3.02756004 9 P 0 
A 0.2902 2.83071004 0.2902 2.83071004 0.27165 2.83071004 3 P 0 N
A 0.36893996 2.87008002 0.36893996 2.87008002 0.35038996 2.87008002 3 P 0 N
L 0.27165 2.83071004 0.35038996 2.87008002 9 P 0 
A 0.2902 2.67323002 0.2902 2.67323002 0.27165 2.67323002 3 P 0 N
A 0.36893996 2.7126 0.36893996 2.7126 0.35038996 2.7126 3 P 0 N
L 0.27165 2.67323002 0.35038996 2.7126 9 P 0 
A 0.2902 2.43701004 0.2902 2.43701004 0.27165 2.43701004 3 P 0 N
A 0.36893996 2.47638002 0.36893996 2.47638002 0.35038996 2.47638002 3 P 0 N
L 0.27165 2.43701004 0.35038996 2.47638002 9 P 0 
A 0.2902 2.27953002 0.2902 2.27953002 0.27165 2.27953002 3 P 0 N
A 0.36893996 2.3189 0.36893996 2.3189 0.35038996 2.3189 3 P 0 N
L 0.27165 2.27953002 0.35038996 2.3189 9 P 0 
A 0.2902 2.12205 0.2902 2.12205 0.27165 2.12205 3 P 0 N
A 0.36893996 2.16141998 0.36893996 2.16141998 0.35038996 2.16141998 3 P 0 N
L 0.27165 2.12205 0.35038996 2.16141998 9 P 0 
L 0.09448996 2.00393996 0.17323002 2.04331004 9 P 0 
A 0.19178002 2.04331004 0.19178002 2.04331004 0.17323002 2.04331004 3 P 0 N
A 0.11303996 2.00393996 0.11303996 2.00393996 0.09448996 2.00393996 3 P 0 N
A 0.2902 1.96456998 0.2902 1.96456998 0.27165 1.96456998 3 P 0 N
A 0.36893996 1.9252 0.36893996 1.9252 0.35038996 1.9252 3 P 0 N
L 0.27165 1.96456998 0.35038996 1.9252 8 P 0 
A 0.11303996 1.9252 0.11303996 1.9252 0.09448996 1.9252 3 P 0 N
A 0.19178002 1.88583002 0.19178002 1.88583002 0.17323002 1.88583002 3 P 0 N
L 0.09448996 1.9252 0.17323002 1.88583002 9 P 0 
A 0.11303996 2.24016004 0.11303996 2.24016004 0.09448996 2.24016004 3 P 0 N
A 0.19178002 2.20078996 0.19178002 2.20078996 0.17323002 2.20078996 3 P 0 N
L 0.09448996 2.24016004 0.17323002 2.20078996 9 P 0 
A 0.11303996 2.39763996 0.11303996 2.39763996 0.09448996 2.39763996 3 P 0 N
A 0.19178002 2.35826998 0.19178002 2.35826998 0.17323002 2.35826998 3 P 0 N
L 0.09448996 2.39763996 0.17323002 2.35826998 9 P 0 
A 0.11303996 2.55511998 0.11303996 2.55511998 0.09448996 2.55511998 3 P 0 N
A 0.19178002 2.51575 0.19178002 2.51575 0.17323002 2.51575 3 P 0 N
L 0.09448996 2.55511998 0.17323002 2.51575 9 P 0 
A 0.11303996 2.79133996 0.11303996 2.79133996 0.09448996 2.79133996 3 P 0 N
A 0.19178002 2.75196998 0.19178002 2.75196998 0.17323002 2.75196998 3 P 0 N
L 0.09448996 2.79133996 0.17323002 2.75196998 9 P 0 
A 0.11303996 2.94881998 0.11303996 2.94881998 0.09448996 2.94881998 3 P 0 N
A 0.19178002 2.90945 0.19178002 2.90945 0.17323002 2.90945 3 P 0 N
L 0.09448996 2.94881998 0.17323002 2.90945 9 P 0 
A 0.11303996 3.1063 0.11303996 3.1063 0.09448996 3.1063 3 P 0 N
A 0.19178002 3.06693002 0.19178002 3.06693002 0.17323002 3.06693002 3 P 0 N
L 0.09448996 3.1063 0.17323002 3.06693002 9 P 0 
A 0.11303996 3.26378002 0.11303996 3.26378002 0.09448996 3.26378002 3 P 0 N
A 0.19178002 3.22441004 0.19178002 3.22441004 0.17323002 3.22441004 3 P 0 N
L 0.09448996 3.26378002 0.17323002 3.22441004 9 P 0 
A 0.2902 3.38188996 0.2902 3.38188996 0.27165 3.38188996 3 P 0 N
A 0.36893996 3.34251998 0.36893996 3.34251998 0.35038996 3.34251998 3 P 0 N
L 0.27165 3.38188996 0.35038996 3.34251998 9 P 0 
A 0.2902 3.53936998 0.2902 3.53936998 0.27165 3.53936998 3 P 0 N
A 0.36893996 3.5 0.36893996 3.5 0.35038996 3.5 3 P 0 N
L 0.27165 3.53936998 0.35038996 3.5 9 P 0 
A 0.2902 3.69685 0.2902 3.69685 0.27165 3.69685 3 P 0 N
A 0.36893996 3.65748002 0.36893996 3.65748002 0.35038996 3.65748002 3 P 0 N
L 0.27165 3.69685 0.35038996 3.65748002 9 P 0 
A 0.2902 3.85433002 0.2902 3.85433002 0.27165 3.85433002 3 P 0 N
A 0.36893996 3.81496004 0.36893996 3.81496004 0.35038996 3.81496004 3 P 0 N
L 0.27165 3.85433002 0.35038996 3.81496004 9 P 0 
A 0.2902 4.01181004 0.2902 4.01181004 0.27165 4.01181004 3 P 0 N
A 0.36893996 3.97243996 0.36893996 3.97243996 0.35038996 3.97243996 3 P 0 N
L 0.27165 4.01181004 0.35038996 3.97243996 9 P 0 
A 0.2902 4.16928996 0.2902 4.16928996 0.27165 4.16928996 3 P 0 N
A 0.36893996 4.12991998 0.36893996 4.12991998 0.35038996 4.12991998 3 P 0 N
L 0.27165 4.16928996 0.35038996 4.12991998 9 P 0 
A 0.2902 4.32676998 0.2902 4.32676998 0.27165 4.32676998 3 P 0 N
A 0.36893996 4.2874 0.36893996 4.2874 0.35038996 4.2874 3 P 0 N
L 0.27165 4.32676998 0.35038996 4.2874 9 P 0 
L 0.27165 4.48425 0.35038996 4.44488002 9 P 0 
A 0.36893996 4.44488002 0.36893996 4.44488002 0.35038996 4.44488002 3 P 0 N
A 0.2902 4.48425 0.2902 4.48425 0.27165 4.48425 3 P 0 N
L 10.173 4.503 10.155 4.485 3 P 0 
L 10.155 4.485 10.173 4.467 3 P 0 
L 5.49 4.88 5.49 4.96 3 P 0 
L 5.49 4.96 5.535 5.005 3 P 0 
L 5.535 5.005 6.15 5.005 3 P 0 
L 6.15 5.005 6.205 4.95 3 P 0 
L 6.205 4.95 6.34 4.95 3 P 0 
L 6.34 4.95 6.435 4.855 3 P 0 
L 6.435 4.855 6.435 4.675 3 P 0 
L 6.435 4.675 6.625 4.485 3 P 0 
L 6.625 4.485 10.165 4.485 3 P 0 
L 4.53 4.88 4.23 4.88 3 P 0 
L 4.23 4.88 4.17 4.82 3 P 0 
L 4.17 4.82 4.17 2.98606004 3 P 0 
L 4.17 2.98606004 4.26606004 2.89 3 P 0 
L 4.26606004 2.89 5.10606004 2.89 3 P 0 
L 5.10606004 2.89 5.13106004 2.915 3 P 0 
L 5.13106004 2.915 5.13106004 3.26106004 3 P 0 
L 5.13106004 3.26106004 5.49 3.62 3 P 0 
L 5.49 3.62 5.49 4.88 3 P 0 
L 5.49 4.88 4.53 4.88 3 P 0 
L 5.49 4.9 5.47 4.88 3 P 0 
L 5.47 4.88 5.489 4.861 3 P 0 
L 4.80606004 2.89 4.82606004 2.87 3 P 0 
L 4.82606004 2.87 4.84606004 2.89 3 P 0 
L 11.495 3.355 11.475 3.335 3 P 0 
L 11.475 3.335 11.495 3.315 3 P 0 
L 11.495 3.335 11.495 2.905 3 P 0 
L 11.495 2.905 11.445 2.855 3 P 0 
L 11.445 2.855 11.385 2.855 3 P 0 
L 11.385 2.855 11.345 2.815 3 P 0 
L 11.345 2.815 11.345 1.795 3 P 0 
L 11.345 1.795 11.28 1.73 3 P 0 
L 11.28 1.73 10.68 1.73 3 P 0 
L 10.68 1.73 10.52 1.57 3 P 0 
L 10.52 1.57 8.56 1.57 3 P 0 
L 8.56 1.57 8.375 1.755 3 P 0 
L 8.375 1.755 6.01 1.755 3 P 0 
L 6.01 1.755 5.765 1.51 3 P 0 
L 5.765 1.51 5.165 1.51 3 P 0 
L 5.165 1.51 4.83 1.845 3 P 0 
L 4.83 1.845 4.83 2.12 3 P 0 
L 4.83 2.12 4.805 2.145 3 P 0 
L 4.805 2.145 4.805 2.19 3 P 0 
L 4.805 2.19 4.82606004 2.21106004 3 P 0 
L 4.82606004 2.21106004 4.82606004 2.87 3 P 0 
L 10.53393996 4.88 11.43393996 4.88 3 P 0 
L 11.43393996 4.88 11.495 4.82 3 P 0 
L 11.495 4.82 11.495 3.335 3 P 0 
L 11.495 3.335 11.21 3.335 3 P 0 
L 11.21 3.335 11.135 3.26 3 P 0 
L 11.135 3.26 11.135 2.915 3 P 0 
L 11.135 2.915 11.11 2.89 3 P 0 
L 11.11 2.89 10.27 2.89 3 P 0 
L 10.27 2.89 10.17393996 2.98606004 3 P 0 
L 10.17393996 2.98606004 10.17393996 4.82 3 P 0 
L 10.17393996 4.82 10.23393996 4.88 3 P 0 
L 10.23393996 4.88 10.53393996 4.88 3 P 0 
L 4.87 0.025 6.565 0.025 15 P 0 
L 4.885 0.085 6.53 0.085 15 P 0 
L 4.895 0.15 6.54 0.15 15 P 0 
L 4.89 0.215 6.555 0.215 15 P 0 
L 4.89 0.3 6.535 0.3 15 P 0 
L 4.895 0.37 6.54 0.37 15 P 0 
A 12.84646004 6.02361998 12.9252 5.94488002 12.84646004 5.94488002 9 P 0 Y
A 12.9252 0.07873996 12.84646004 0 12.84646004 0.07873996 9 P 0 Y
L 12.9252 5.94488002 12.9252 0.07873996 9 P 0 
L 12.84646004 0 6.66536004 0 9 P 0 
A 6.58661998 0.35433002 6.50788002 0.43306998 6.50788002 0.35433002 9 P 0 N
A 6.66536004 0 6.58661998 0.07873996 6.66535994 0.07873996 9 P 0 Y
L 6.58661998 0.07873996 6.58661998 0.35433002 9 P 0 
A 4.93308002 0.43306998 4.85433996 0.35433002 4.93307992 0.35433002 9 P 0 N
L 6.50788002 0.43306998 4.93308002 0.43306998 9 P 0 
L 4.85433996 0.35433002 4.85433996 0.07873996 9 P 0 
A 4.85433996 0.07873996 4.77558996 0 4.7755999 0.07873996 9 P 0 Y
A 0.07873996 0 0 0.07873996 0.07873996 0.07873996 9 P 0 Y
L 4.77558996 0 0.07873996 0 9 P 0 
L 0.07873996 6.02361998 12.84646004 6.02361998 9 P 0 
A 0 5.94488002 0.07873996 6.02361998 0.07873996 5.94488002 9 P 0 Y
L 0 0.07873996 0 5.94488002 9 P 0 
L 0 6.07011998 12.89 6.07011998 15 P 0 
L 0 -0.0465 12.89 -0.0465 15 P 0 
L 0.005 6.16 0.035 6.13 3 P 0 
L 12.91 6.15 12.88 6.12 3 P 0 
L 12.91 -0.13 12.88 -0.1 3 P 0 
L 0.005 -0.135 0.035 -0.105 3 P 0 
L 0 -0.41426004 0 -0.093 9 P 0 
A 0.07873996 -0.493 0 -0.41426004 0.07873996 -0.41426004 9 P 0 Y
L 12.84646004 -0.493 0.07873996 -0.493 9 P 0 
A 12.9252 -0.41426004 12.84646004 -0.493 12.84646004 -0.41426004 9 P 0 Y
L 12.9252 -0.093 12.9252 -0.41426004 9 P 0 
L 0 -0.093 12.9252 -0.093 9 P 0 
L 0 6.11661998 12.9252 6.11661998 9 P 0 
L 0 6.43788002 0 6.11661998 9 P 0 
A 0.07873996 6.51661998 0 6.43788002 0.07873996 6.43788002 9 P 0 N
L 12.84646004 6.51661998 0.07873996 6.51661998 9 P 0 
A 12.9252 6.43788002 12.84646004 6.51661998 12.84646004 6.43788002 9 P 0 N
L 12.9252 6.11661998 12.9252 6.43788002 9 P 0 
A 12.84646004 6.02361998 12.9252 5.94488002 12.84646004 5.94488002 18 P 0 Y
L 12.9252 5.94488002 12.9252 0.07873996 18 P 0 
A 12.9252 0.07873996 12.84646004 0 12.84646004 0.07873996 18 P 0 Y
A 6.58661998 0.35433002 6.50788002 0.43306998 6.50788002 0.35433002 18 P 0 N
L 6.58661998 0.07873996 6.58661998 0.35433002 18 P 0 
A 6.66536004 0 6.58661998 0.07873996 6.66535994 0.07873996 18 P 0 Y
L 12.84646004 0 6.66536004 0 18 P 0 
L 6.50788002 0.43306998 4.93308002 0.43306998 18 P 0 
A 4.93308002 0.43306998 4.85433996 0.35433002 4.93307992 0.35433002 18 P 0 N
L 4.85433996 0.35433002 4.85433996 0.07873996 18 P 0 
A 4.85433996 0.07873996 4.77558996 0 4.7755999 0.07873996 18 P 0 Y
A 0 5.94488002 0.07873996 6.02361998 0.07873996 5.94488002 18 P 0 Y
L 0.07873996 6.02361998 12.84646004 6.02361998 18 P 0 
L 0 0.07873996 0 5.94488002 18 P 0 
A 0.07873996 0 0 0.07873996 0.07873996 0.07873996 18 P 0 Y
L 4.77558996 0 0.07873996 0 18 P 0 
L 0.0349 -2.3038 0.0349 -1.0038 2 P 0 ;0
L 0.0349 -1.0038 4.5349 -1.0038 2 P 0 ;0
L 4.5349 -1.0038 4.5349 -2.3038 2 P 0 ;0
L 4.5349 -2.3038 0.0349 -2.3038 2 P 0 ;0
L 0.0349 -1.6038 4.5349 -1.6038 2 P 0 ;0
L 0.0349 -1.8038 4.5349 -1.8038 2 P 0 ;0
L 2.4349 -2.1038 4.0349 -2.1038 2 P 0 ;0
L 2.4349 -2.3038 2.4349 -1.8038 2 P 0 ;0
L 3.2349 -2.1038 3.2349 -1.8038 2 P 0 ;0
L 4.0349 -2.3038 4.0349 -1.8038 2 P 0 ;0
L 0.0723999 -1.6844687 0.07906663 -1.69030079 1 P 0 ;0
L 0.07906663 -1.69030079 0.08656654 -1.6938 1 P 0 ;0
L 0.08656654 -1.6938 0.09323337 -1.6938 1 P 0 ;0
L 0.09323337 -1.6938 0.0999001 -1.69030079 1 P 0 ;0
L 0.0999001 -1.69030079 0.10490059 -1.6844687 1 P 0 ;0
L 0.10490059 -1.6844687 0.1074 -1.67629951 1 P 0 ;0
L 0.1074 -1.67629951 0.10573376 -1.66813455 1 P 0 ;0
L 0.10573376 -1.66813455 0.10156644 -1.66113396 1 P 0 ;0
L 0.10156644 -1.66113396 0.09406654 -1.65646614 1 P 0 ;0
L 0.09406654 -1.65646614 0.08406713 -1.65413327 1 P 0 ;0
L 0.08406713 -1.65413327 0.07823346 -1.64946762 1 P 0 ;0
L 0.07823346 -1.64946762 0.07573248 -1.64130059 1 P 0 ;0
L 0.07573248 -1.64130059 0.0774003 -1.63313356 1 P 0 ;0
L 0.0774003 -1.63313356 0.08156614 -1.62730148 1 P 0 ;0
L 0.08156614 -1.62730148 0.0873997 -1.6238 1 P 0 ;0
L 0.0873997 -1.6238 0.09323337 -1.6238 1 P 8191 ;0
L 0.09323337 -1.6238 0.09906693 -1.62613287 1 P 0 ;0
L 0.09906693 -1.62613287 0.10406742 -1.63196713 1 P 0 ;0
L 0.1383999 -1.6938 0.1383999 -1.6238 1 P 0 ;0
L 0.1734 -1.6238 0.1734 -1.6938 1 P 0 ;0
L 0.1734 -1.65880108 0.1383999 -1.65880108 1 P 0 ;0
L 0.23856683 -1.6938 0.20523307 -1.6938 1 P 0 ;0
L 0.20523307 -1.6938 0.20523307 -1.6238 1 P 0 ;0
L 0.20523307 -1.6238 0.23856683 -1.6238 1 P 0 ;0
L 0.22523337 -1.65763258 0.20523307 -1.65763258 1 P 0 ;0
L 0.30456683 -1.6938 0.27123307 -1.6938 1 P 0 ;0
L 0.27123307 -1.6938 0.27123307 -1.6238 1 P 0 ;0
L 0.27123307 -1.6238 0.30456683 -1.6238 1 P 0 ;0
L 0.29123337 -1.65763258 0.27123307 -1.65763258 1 P 0 ;0
L 0.35389921 -1.6238 0.35389921 -1.6938 1 P 0 ;0
L 0.33473356 -1.6238 0.37306634 -1.6238 1 P 0 ;0
L 0.09489921 -1.7188 0.09489921 -1.7888 1 P 0 ;0
L 0.07573356 -1.7188 0.11406634 -1.7188 1 P 0 ;0
L 0.1508998 -1.7188 0.17089862 -1.7188 1 P 0 ;0
L 0.16089921 -1.7188 0.16089921 -1.7888 1 P 0 ;0
L 0.1508998 -1.7888 0.17089862 -1.7888 1 P 0 ;0
L 0.22689921 -1.7188 0.22689921 -1.7888 1 P 0 ;0
L 0.20773356 -1.7188 0.24606634 -1.7188 1 P 0 ;0
L 0.27623307 -1.7188 0.27623307 -1.7888 1 P 0 ;0
L 0.27623307 -1.7888 0.30956683 -1.7888 1 P 0 ;0
L 0.37556683 -1.7888 0.34223307 -1.7888 1 P 0 ;0
L 0.34223307 -1.7888 0.34223307 -1.7188 1 P 0 ;0
L 0.34223307 -1.7188 0.37556683 -1.7188 1 P 0 ;0
L 0.36223337 -1.75263258 0.34223307 -1.75263258 1 P 0 ;0
L 2.5438999 -1.96813563 2.5519 -1.97480089 1 P 0 ;0
L 2.5519 -1.97480089 2.5608999 -1.9788 1 P 0 ;0
L 2.5608999 -1.9788 2.5689 -1.9788 1 P 0 ;0
L 2.5689 -1.9788 2.5769001 -1.97480089 1 P 0 ;0
L 2.5769001 -1.97480089 2.58290069 -1.96813563 1 P 0 ;0
L 2.58290069 -1.96813563 2.5859 -1.95879941 1 P 0 ;0
L 2.5859 -1.95879941 2.58390049 -1.94946811 1 P 0 ;0
L 2.58390049 -1.94946811 2.5788997 -1.94146732 1 P 0 ;0
L 2.5788997 -1.94146732 2.5698998 -1.93613278 1 P 0 ;0
L 2.5698998 -1.93613278 2.55790049 -1.93346663 1 P 0 ;0
L 2.55790049 -1.93346663 2.5509002 -1.92813445 1 P 0 ;0
L 2.5509002 -1.92813445 2.54789902 -1.91880069 1 P 0 ;0
L 2.54789902 -1.91880069 2.54990039 -1.90946683 1 P 0 ;0
L 2.54990039 -1.90946683 2.55489931 -1.90280167 1 P 0 ;0
L 2.55489931 -1.90280167 2.5618997 -1.8988 1 P 0 ;0
L 2.5618997 -1.8988 2.5689 -1.8988 1 P 0 ;0
L 2.5689 -1.8988 2.57590039 -1.90146614 1 P 0 ;0
L 2.57590039 -1.90146614 2.58190089 -1.90813386 1 P 0 ;0
L 2.6648998 -1.90546772 2.65889931 -1.90146614 1 P 0 ;0
L 2.65889931 -1.90146614 2.65190079 -1.8988 1 P 0 ;0
L 2.65190079 -1.8988 2.64390069 -1.8988 1 P 0 ;0
L 2.64390069 -1.8988 2.63489892 -1.90280167 1 P 0 ;0
L 2.63489892 -1.90280167 2.62790039 -1.90946683 1 P 0 ;0
L 2.62790039 -1.90946683 2.62289961 -1.91746762 1 P 0 ;0
L 2.62289961 -1.91746762 2.61889862 -1.93080049 1 P 0 ;0
L 2.61889862 -1.93080049 2.61789892 -1.94280039 1 P 0 ;0
L 2.61789892 -1.94280039 2.6199003 -1.9548003 1 P 0 ;0
L 2.6199003 -1.9548003 2.62289961 -1.96280098 1 P 0 ;0
L 2.62289961 -1.96280098 2.6289002 -1.97080177 1 P 0 ;0
L 2.6289002 -1.97080177 2.63590049 -1.97613396 1 P 0 ;0
L 2.63590049 -1.97613396 2.64289902 -1.9788 1 P 0 ;0
L 2.64289902 -1.9788 2.64989941 -1.9788 1 P 0 ;0
L 2.64989941 -1.9788 2.6568997 -1.97613396 1 P 0 ;0
L 2.6568997 -1.97613396 2.6629003 -1.97213484 1 P 0 ;0
L 2.6629003 -1.97213484 2.66790098 -1.96680266 1 P 0 ;0
L 2.69589892 -1.9788 2.72089902 -1.8988 1 P 0 ;0
L 2.72089902 -1.8988 2.74590098 -1.9788 1 P 0 ;0
L 2.73689931 -1.95080118 2.70489882 -1.95080118 1 P 0 ;0
L 2.77889961 -1.8988 2.77889961 -1.9788 1 P 0 ;0
L 2.77889961 -1.9788 2.8189003 -1.9788 1 P 0 ;0
L 2.8969003 -1.9788 2.85689961 -1.9788 1 P 0 ;0
L 2.85689961 -1.9788 2.85689961 -1.8988 1 P 0 ;0
L 2.85689961 -1.8988 2.8969003 -1.8988 1 P 0 ;0
L 2.8809 -1.93746575 2.85689961 -1.93746575 1 P 0 ;0
L 3.03289902 -1.9788 3.03289902 -1.8988 1 P 0 ;0
L 3.03289902 -1.8988 3.0208998 -1.91479911 1 P 0 ;0
L 3.0208998 -1.9788 3.04489833 -1.9788 1 P 0 ;0
L 3.11089902 -1.98146604 3.10889951 -1.98013297 1 P 8191 ;0
L 3.10889951 -1.98013297 3.10889951 -1.97746703 1 P 8191 ;0
L 3.10889951 -1.97746703 3.11089902 -1.97613396 1 P 8191 ;0
L 3.11089902 -1.97613396 3.11290039 -1.97746703 1 P 8191 ;0
L 3.11290039 -1.97746703 3.11290039 -1.98013297 1 P 8191 ;0
L 3.11290039 -1.98013297 3.11089902 -1.98146604 1 P 8191 ;0
L 3.11089902 -1.945469 3.10889951 -1.94413346 1 P 8191 ;0
L 3.10889951 -1.94413346 3.10889951 -1.94146732 1 P 8191 ;0
L 3.10889951 -1.94146732 3.11089902 -1.94013435 1 P 8191 ;0
L 3.11089902 -1.94013435 3.11290039 -1.94146732 1 P 8191 ;0
L 3.11290039 -1.94146732 3.11290039 -1.94413346 1 P 8191 ;0
L 3.11290039 -1.94413346 3.11089902 -1.945469 1 P 8191 ;0
L 3.18889902 -1.9788 3.18889902 -1.8988 1 P 0 ;0
L 3.18889902 -1.8988 3.1768998 -1.91479911 1 P 0 ;0
L 3.1768998 -1.9788 3.20089833 -1.9788 1 P 0 ;0
L 2.5138999 -2.23313563 2.5219 -2.23980089 1 P 0 ;0
L 2.5219 -2.23980089 2.5308999 -2.2438 1 P 0 ;0
L 2.5308999 -2.2438 2.5389 -2.2438 1 P 0 ;0
L 2.5389 -2.2438 2.5469001 -2.23980089 1 P 0 ;0
L 2.5469001 -2.23980089 2.55290069 -2.23313563 1 P 0 ;0
L 2.55290069 -2.23313563 2.5559 -2.22379941 1 P 0 ;0
L 2.5559 -2.22379941 2.55390049 -2.21446811 1 P 0 ;0
L 2.55390049 -2.21446811 2.5488997 -2.20646732 1 P 0 ;0
L 2.5488997 -2.20646732 2.5398998 -2.20113278 1 P 0 ;0
L 2.5398998 -2.20113278 2.52790049 -2.19846663 1 P 0 ;0
L 2.52790049 -2.19846663 2.5209002 -2.19313445 1 P 0 ;0
L 2.5209002 -2.19313445 2.51789902 -2.18380069 1 P 0 ;0
L 2.51789902 -2.18380069 2.51990039 -2.17446683 1 P 0 ;0
L 2.51990039 -2.17446683 2.52489931 -2.16780167 1 P 0 ;0
L 2.52489931 -2.16780167 2.5318997 -2.1638 1 P 0 ;0
L 2.5318997 -2.1638 2.5389 -2.1638 1 P 0 ;0
L 2.5389 -2.1638 2.54590039 -2.16646614 1 P 0 ;0
L 2.54590039 -2.16646614 2.55190089 -2.17313386 1 P 0 ;0
L 2.5918999 -2.2438 2.5918999 -2.1638 1 P 0 ;0
L 2.6339 -2.1638 2.6339 -2.2438 1 P 0 ;0
L 2.6339 -2.20380128 2.5918999 -2.20380128 1 P 0 ;0
L 2.7109003 -2.2438 2.67089961 -2.2438 1 P 0 ;0
L 2.67089961 -2.2438 2.67089961 -2.1638 1 P 0 ;0
L 2.67089961 -2.1638 2.7109003 -2.1638 1 P 0 ;0
L 2.6949 -2.20246575 2.67089961 -2.20246575 1 P 0 ;0
L 2.7889003 -2.2438 2.74889961 -2.2438 1 P 0 ;0
L 2.74889961 -2.2438 2.74889961 -2.1638 1 P 0 ;0
L 2.74889961 -2.1638 2.7889003 -2.1638 1 P 0 ;0
L 2.7729 -2.20246575 2.74889961 -2.20246575 1 P 0 ;0
L 2.84689902 -2.1638 2.84689902 -2.2438 1 P 0 ;0
L 2.8239003 -2.1638 2.86989961 -2.1638 1 P 0 ;0
L 3.29489961 -1.9238 3.29489961 -2.0038 1 P 0 ;0
L 3.29489961 -2.0038 3.3349003 -2.0038 1 P 0 ;0
L 3.36789892 -2.0038 3.39289902 -1.9238 1 P 0 ;0
L 3.39289902 -1.9238 3.41790098 -2.0038 1 P 0 ;0
L 3.40889931 -1.97580118 3.37689882 -1.97580118 1 P 0 ;0
L 3.47089902 -2.0038 3.47089902 -1.96780039 1 P 0 ;0
L 3.47089902 -1.96780039 3.45089961 -1.9238 1 P 0 ;0
L 3.4909003 -1.9238 3.47089902 -1.96780039 1 P 0 ;0
L 3.5689003 -2.0038 3.52889961 -2.0038 1 P 0 ;0
L 3.52889961 -2.0038 3.52889961 -1.9238 1 P 0 ;0
L 3.52889961 -1.9238 3.5689003 -1.9238 1 P 0 ;0
L 3.5529 -1.96246575 3.52889961 -1.96246575 1 P 0 ;0
L 3.60689961 -2.0038 3.60689961 -1.9238 1 P 0 ;0
L 3.60689961 -1.9238 3.6318998 -1.9238 1 P 0 ;0
L 3.6318998 -1.9238 3.6398999 -1.92780167 1 P 0 ;0
L 3.6398999 -1.92780167 3.64490069 -1.93313386 1 P 0 ;0
L 3.64490069 -1.93313386 3.6469003 -1.94380069 1 P 0 ;0
L 3.6469003 -1.94380069 3.64490069 -1.95446752 1 P 0 ;0
L 3.64490069 -1.95446752 3.6389001 -1.96113278 1 P 0 ;0
L 3.6389001 -1.96113278 3.6318998 -1.96513435 1 P 0 ;0
L 3.6318998 -1.96513435 3.60689961 -1.96513435 1 P 0 ;0
L 3.6318998 -1.96513435 3.6469003 -2.0038 1 P 0 ;0
L 3.33989902 -2.2538 3.33189892 -2.25246703 1 P 0 ;0
L 3.33189892 -2.25246703 3.32490039 -2.24713484 1 P 0 ;0
L 3.32490039 -2.24713484 3.3188999 -2.23913406 1 P 0 ;0
L 3.3188999 -2.23913406 3.31489892 -2.2298003 1 P 0 ;0
L 3.31489892 -2.2298003 3.31289931 -2.21913346 1 P 0 ;0
L 3.31289931 -2.21913346 3.31289931 -2.20846663 1 P 0 ;0
L 3.31289931 -2.20846663 3.31489892 -2.1977998 1 P 0 ;0
L 3.31489892 -2.1977998 3.3188999 -2.18846604 1 P 0 ;0
L 3.3188999 -2.18846604 3.32490039 -2.18046772 1 P 0 ;0
L 3.32490039 -2.18046772 3.33189892 -2.17513307 1 P 0 ;0
L 3.33189892 -2.17513307 3.33989902 -2.1738 1 P 0 ;0
L 3.33989902 -2.1738 3.34789911 -2.17513307 1 P 0 ;0
L 3.34789911 -2.17513307 3.35489951 -2.18046772 1 P 0 ;0
L 3.35489951 -2.18046772 3.3609 -2.18846604 1 P 0 ;0
L 3.3609 -2.18846604 3.36490098 -2.1977998 1 P 0 ;0
L 3.36490098 -2.1977998 3.36690059 -2.20846663 1 P 0 ;0
L 3.36690059 -2.20846663 3.36690059 -2.21913346 1 P 0 ;0
L 3.36690059 -2.21913346 3.36490098 -2.2298003 1 P 0 ;0
L 3.36490098 -2.2298003 3.3609 -2.23913406 1 P 0 ;0
L 3.3609 -2.23913406 3.35489951 -2.24713484 1 P 0 ;0
L 3.35489951 -2.24713484 3.34789911 -2.25246703 1 P 0 ;0
L 3.34789911 -2.25246703 3.33989902 -2.2538 1 P 0 ;0
L 3.39889941 -2.2538 3.39889941 -2.1738 1 P 0 ;0
L 3.39889941 -2.1738 3.43690049 -2.1738 1 P 0 ;0
L 3.4228998 -2.21246575 3.39889941 -2.21246575 1 P 0 ;0
L 0.16489872 -1.0538 0.16489872 -1.1538 1 P 0 ;0
L 0.13423376 -1.0538 0.19556614 -1.0538 1 P 0 ;0
L 0.2588997 -1.0538 0.29089774 -1.0538 1 P 0 ;0
L 0.27489872 -1.0538 0.27489872 -1.1538 1 P 0 ;0
L 0.2588997 -1.1538 0.29089774 -1.1538 1 P 0 ;0
L 0.38489872 -1.0538 0.38489872 -1.1538 1 P 0 ;0
L 0.35423376 -1.0538 0.41556614 -1.0538 1 P 0 ;0
L 0.46823287 -1.0538 0.46823287 -1.1538 1 P 0 ;0
L 0.46823287 -1.1538 0.52156703 -1.1538 1 P 0 ;0
L 0.63156703 -1.1538 0.57823287 -1.1538 1 P 0 ;0
L 0.57823287 -1.1538 0.57823287 -1.0538 1 P 0 ;0
L 0.57823287 -1.0538 0.63156703 -1.0538 1 P 0 ;0
L 0.61023337 -1.10213219 0.57823287 -1.10213219 1 P 0 ;0
L 4.18989892 -1.9538 4.21489902 -1.8738 1 P 0 ;0
L 4.21489902 -1.8738 4.23990098 -1.9538 1 P 0 ;0
L 4.23089931 -1.92580118 4.19889882 -1.92580118 1 P 0 ;0
L 4.27289961 -1.9538 4.27289961 -1.8738 1 P 0 ;0
L 4.27289961 -1.8738 4.2978998 -1.8738 1 P 0 ;0
L 4.2978998 -1.8738 4.3058999 -1.87780167 1 P 0 ;0
L 4.3058999 -1.87780167 4.31090069 -1.88313386 1 P 0 ;0
L 4.31090069 -1.88313386 4.3129003 -1.89380069 1 P 0 ;0
L 4.3129003 -1.89380069 4.31090069 -1.90446752 1 P 0 ;0
L 4.31090069 -1.90446752 4.3049001 -1.91113278 1 P 0 ;0
L 4.3049001 -1.91113278 4.2978998 -1.91513435 1 P 0 ;0
L 4.2978998 -1.91513435 4.27289961 -1.91513435 1 P 0 ;0
L 4.2978998 -1.91513435 4.3129003 -1.9538 1 P 0 ;0
L 4.37089902 -1.8738 4.37089902 -1.9538 1 P 0 ;0
L 4.3479003 -1.8738 4.39389961 -1.8738 1 P 0 ;0
L 3.61989892 -2.2538 3.61989892 -2.1638 1 P 0 ;0
L 3.61989892 -2.1638 3.6058997 -2.18179892 1 P 0 ;0
L 3.6058997 -2.2538 3.63389803 -2.2538 1 P 0 ;0
L 3.68773268 -2.17879961 3.69473337 -2.16980148 1 P 0 ;0
L 3.69473337 -2.16980148 3.70290039 -2.1652997 1 P 0 ;0
L 3.70290039 -2.1652997 3.71223386 -2.1638 1 P 0 ;0
L 3.71223386 -2.1638 3.7239002 -2.16679941 1 P 0 ;0
L 3.7239002 -2.16679941 3.73206722 -2.17430059 1 P 0 ;0
L 3.73206722 -2.17430059 3.7344001 -2.18329862 1 P 0 ;0
L 3.7344001 -2.18329862 3.73323366 -2.19230217 1 P 0 ;0
L 3.73323366 -2.19230217 3.72856585 -2.19980059 1 P 0 ;0
L 3.72856585 -2.19980059 3.70523317 -2.2148001 1 P 0 ;0
L 3.70523317 -2.2148001 3.69473337 -2.22530069 1 P 0 ;0
L 3.69473337 -2.22530069 3.68773268 -2.24030295 1 P 0 ;0
L 3.68773268 -2.24030295 3.6853998 -2.2538 1 P 0 ;0
L 3.6853998 -2.2538 3.7344001 -2.2538 1 P 0 ;0
L 1.9639003 -1.6638 1.93590197 -1.6638 1 P 0 ;0
L 1.94990108 -1.6638 1.94990108 -1.7538 1 P 0 ;0
L 1.9639003 -1.7538 1.93590197 -1.7538 1 P 0 ;0
L 1.88673297 -1.7538 1.88673297 -1.6638 1 P 0 ;0
L 1.88673297 -1.6638 1.83306713 -1.7538 1 P 0 ;0
L 1.83306713 -1.7538 1.83306713 -1.6638 1 P 0 ;0
L 1.76990108 -1.6638 1.76990108 -1.7538 1 P 0 ;0
L 1.79673297 -1.6638 1.74306713 -1.6638 1 P 0 ;0
L 1.65656634 -1.7538 1.70323376 -1.7538 1 P 0 ;0
L 1.70323376 -1.7538 1.70323376 -1.6638 1 P 0 ;0
L 1.70323376 -1.6638 1.65656634 -1.6638 1 P 0 ;0
L 1.67523327 -1.70729902 1.70323376 -1.70729902 1 P 0 ;0
L 1.61323376 -1.7538 1.61323376 -1.6638 1 P 0 ;0
L 1.61323376 -1.6638 1.58406693 -1.6638 1 P 0 ;0
L 1.58406693 -1.6638 1.57473346 -1.66830187 1 P 0 ;0
L 1.57473346 -1.66830187 1.56889921 -1.67430059 1 P 0 ;0
L 1.56889921 -1.67430059 1.56656634 -1.68630069 1 P 0 ;0
L 1.56656634 -1.68630069 1.56889921 -1.69830089 1 P 0 ;0
L 1.56889921 -1.69830089 1.5758998 -1.70579931 1 P 0 ;0
L 1.5758998 -1.70579931 1.58406693 -1.71030108 1 P 0 ;0
L 1.58406693 -1.71030108 1.61323376 -1.71030108 1 P 0 ;0
L 1.58406693 -1.71030108 1.56656634 -1.7538 1 P 0 ;0
L 1.52673297 -1.7538 1.52673297 -1.6638 1 P 0 ;0
L 1.52673297 -1.6638 1.47306713 -1.7538 1 P 0 ;0
L 1.47306713 -1.7538 1.47306713 -1.6638 1 P 0 ;0
L 1.43906791 -1.7538 1.40990108 -1.6638 1 P 0 ;0
L 1.40990108 -1.6638 1.38073219 -1.7538 1 P 0 ;0
L 1.39123415 -1.72230128 1.42856811 -1.72230128 1 P 0 ;0
L 1.34323376 -1.6638 1.34323376 -1.7538 1 P 0 ;0
L 1.34323376 -1.7538 1.29656634 -1.7538 1 P 0 ;0
L 1.16323376 -1.6638 1.16323376 -1.7538 1 P 0 ;0
L 1.16323376 -1.7538 1.11656634 -1.7538 1 P 0 ;0
L 1.07906791 -1.7538 1.04990108 -1.6638 1 P 0 ;0
L 1.04990108 -1.6638 1.02073219 -1.7538 1 P 0 ;0
L 1.03123415 -1.72230128 1.06856811 -1.72230128 1 P 0 ;0
L 0.95990108 -1.7538 0.95990108 -1.71330049 1 P 0 ;0
L 0.95990108 -1.71330049 0.98323376 -1.6638 1 P 0 ;0
L 0.93656634 -1.6638 0.95990108 -1.71330049 1 P 0 ;0
L 0.84656634 -1.7538 0.89323376 -1.7538 1 P 0 ;0
L 0.89323376 -1.7538 0.89323376 -1.6638 1 P 0 ;0
L 0.89323376 -1.6638 0.84656634 -1.6638 1 P 0 ;0
L 0.86523327 -1.70729902 0.89323376 -1.70729902 1 P 0 ;0
L 0.80323376 -1.7538 0.80323376 -1.6638 1 P 0 ;0
L 0.80323376 -1.6638 0.77406693 -1.6638 1 P 0 ;0
L 0.77406693 -1.6638 0.76473346 -1.66830187 1 P 0 ;0
L 0.76473346 -1.66830187 0.75889921 -1.67430059 1 P 0 ;0
L 0.75889921 -1.67430059 0.75656634 -1.68630069 1 P 0 ;0
L 0.75656634 -1.68630069 0.75889921 -1.69830089 1 P 0 ;0
L 0.75889921 -1.69830089 0.7658998 -1.70579931 1 P 0 ;0
L 0.7658998 -1.70579931 0.77406693 -1.71030108 1 P 0 ;0
L 0.77406693 -1.71030108 0.80323376 -1.71030108 1 P 0 ;0
L 0.77406693 -1.71030108 0.75656634 -1.7538 1 P 0 ;0
L 0.60223396 -1.7538 0.59990108 -1.73430148 1 P 0 ;0
L 0.59990108 -1.73430148 0.5963997 -1.71780226 1 P 0 ;0
L 0.5963997 -1.71780226 0.59173406 -1.7028 1 P 0 ;0
L 0.59173406 -1.7028 0.5858998 -1.68630069 1 P 0 ;0
L 0.5858998 -1.68630069 0.57656634 -1.6638 1 P 0 ;0
L 0.57656634 -1.6638 0.62323376 -1.6638 1 P 0 ;0
L 3.81756604 -2.0038 3.81989892 -1.98430148 1 P 0 ;0
L 3.81989892 -1.98430148 3.8234003 -1.96780226 1 P 0 ;0
L 3.8234003 -1.96780226 3.82806594 -1.9528 1 P 0 ;0
L 3.82806594 -1.9528 3.8339002 -1.93630069 1 P 0 ;0
L 3.8339002 -1.93630069 3.84323366 -1.9138 1 P 0 ;0
L 3.84323366 -1.9138 3.79656624 -1.9138 1 P 0 ;0
L 3.06756604 -2.2538 3.06989892 -2.23430148 1 P 0 ;0
L 3.06989892 -2.23430148 3.0734003 -2.21780226 1 P 0 ;0
L 3.0734003 -2.21780226 3.07806594 -2.2028 1 P 0 ;0
L 3.07806594 -2.2028 3.0839002 -2.18630069 1 P 0 ;0
L 3.0839002 -2.18630069 3.09323366 -2.1638 1 P 0 ;0
L 3.09323366 -2.1638 3.04656624 -2.1638 1 P 0 ;0
L 0.59099833 -1.36499882 0.5990003 -1.35750039 1 P 0 ;0
L 0.5990003 -1.35750039 0.60499902 -1.34500315 1 P 0 ;0
L 0.60499902 -1.34500315 0.60900187 -1.32749764 1 P 0 ;0
L 0.60900187 -1.32749764 0.60499902 -1.31250089 1 P 0 ;0
L 0.60499902 -1.31250089 0.59700079 -1.30250305 1 P 0 ;0
L 0.59700079 -1.30250305 0.5830001 -1.295 1 P 0 ;0
L 0.5830001 -1.295 0.52900059 -1.295 1 P 0 ;0
L 0.52900059 -1.295 0.52900059 -1.445 1 P 0 ;0
L 0.52900059 -1.445 0.59500118 -1.445 1 P 0 ;0
L 0.59500118 -1.445 0.60900187 -1.43500217 1 P 0 ;0
L 0.60900187 -1.43500217 0.6170001 -1.42000079 1 P 0 ;0
L 0.6170001 -1.42000079 0.62099931 -1.4025 1 P 0 ;0
L 0.62099931 -1.4025 0.6170001 -1.38500374 1 P 0 ;0
L 0.6170001 -1.38500374 0.60499902 -1.37000236 1 P 0 ;0
L 0.60499902 -1.37000236 0.59099833 -1.36499882 1 P 0 ;0
L 0.59099833 -1.36499882 0.52900059 -1.36499882 1 P 0 ;0
L 0.77100138 -1.445 0.77100138 -1.34500315 1 P 0 ;0
L 0.77100138 -1.36249941 0.76299951 -1.35250148 1 P 0 ;0
L 0.76299951 -1.35250148 0.75099833 -1.34750256 1 P 0 ;0
L 0.75099833 -1.34750256 0.73700138 -1.34500315 1 P 0 ;0
L 0.73700138 -1.34500315 0.72300069 -1.35000207 1 P 0 ;0
L 0.72300069 -1.35000207 0.71099961 -1.3599999 1 P 0 ;0
L 0.71099961 -1.3599999 0.70299764 -1.37500128 1 P 0 ;0
L 0.70299764 -1.37500128 0.69899852 -1.39500157 1 P 0 ;0
L 0.69899852 -1.39500157 0.70299764 -1.41500187 1 P 0 ;0
L 0.70299764 -1.41500187 0.71099961 -1.43000325 1 P 0 ;0
L 0.71099961 -1.43000325 0.72300069 -1.44000108 1 P 0 ;0
L 0.72300069 -1.44000108 0.73700138 -1.445 1 P 0 ;0
L 0.73700138 -1.445 0.75099833 -1.44250059 1 P 0 ;0
L 0.75099833 -1.44250059 0.76299951 -1.43500217 1 P 0 ;0
L 0.76299951 -1.43500217 0.77100138 -1.42500433 1 P 0 ;0
L 0.86700039 -1.445 0.86700039 -1.34500315 1 P 0 ;0
L 0.86700039 -1.36499882 0.87699833 -1.35500098 1 P 0 ;0
L 0.87699833 -1.35500098 0.8869998 -1.34750256 1 P 0 ;0
L 0.8869998 -1.34750256 0.90100049 -1.34500315 1 P 0 ;0
L 0.90100049 -1.34500315 0.91099833 -1.34750256 1 P 0 ;0
L 0.91099833 -1.34750256 0.92299951 -1.35500098 1 P 0 ;0
L 1.02700039 -1.445 1.02700039 -1.34500315 1 P 0 ;0
L 1.02700039 -1.36499882 1.03699833 -1.35500098 1 P 0 ;0
L 1.03699833 -1.35500098 1.0469998 -1.34750256 1 P 0 ;0
L 1.0469998 -1.34750256 1.06100049 -1.34500315 1 P 0 ;0
L 1.06100049 -1.34500315 1.07099833 -1.34750256 1 P 0 ;0
L 1.07099833 -1.34750256 1.08299951 -1.35500098 1 P 0 ;0
L 1.18500089 -1.37750069 1.24900187 -1.37750069 1 P 0 ;0
L 1.24900187 -1.37750069 1.24299951 -1.3599999 1 P 0 ;0
L 1.24299951 -1.3599999 1.23300157 -1.35000207 1 P 0 ;0
L 1.23300157 -1.35000207 1.21900089 -1.34500315 1 P 0 ;0
L 1.21900089 -1.34500315 1.2050003 -1.34750256 1 P 0 ;0
L 1.2050003 -1.34750256 1.19299911 -1.35500098 1 P 0 ;0
L 1.19299911 -1.35500098 1.18500089 -1.37250177 1 P 0 ;0
L 1.18500089 -1.37250177 1.18099803 -1.38750315 1 P 0 ;0
L 1.18099803 -1.38750315 1.18099803 -1.4025 1 P 0 ;0
L 1.18099803 -1.4025 1.18500089 -1.41750138 1 P 0 ;0
L 1.18500089 -1.41750138 1.19499872 -1.43250276 1 P 0 ;0
L 1.19499872 -1.43250276 1.2069998 -1.44250059 1 P 0 ;0
L 1.2069998 -1.44250059 1.22100049 -1.445 1 P 0 ;0
L 1.22100049 -1.445 1.23500118 -1.44000108 1 P 0 ;0
L 1.23500118 -1.44000108 1.24900187 -1.42500433 1 P 0 ;0
L 1.37499813 -1.445 1.37499813 -1.295 1 P 0 ;0
L 1.50500089 -1.37750069 1.56900187 -1.37750069 1 P 0 ;0
L 1.56900187 -1.37750069 1.56299951 -1.3599999 1 P 0 ;0
L 1.56299951 -1.3599999 1.55300157 -1.35000207 1 P 0 ;0
L 1.55300157 -1.35000207 1.53900089 -1.34500315 1 P 0 ;0
L 1.53900089 -1.34500315 1.5250003 -1.34750256 1 P 0 ;0
L 1.5250003 -1.34750256 1.51299911 -1.35500098 1 P 0 ;0
L 1.51299911 -1.35500098 1.50500089 -1.37250177 1 P 0 ;0
L 1.50500089 -1.37250177 1.50099803 -1.38750315 1 P 0 ;0
L 1.50099803 -1.38750315 1.50099803 -1.4025 1 P 0 ;0
L 1.50099803 -1.4025 1.50500089 -1.41750138 1 P 0 ;0
L 1.50500089 -1.41750138 1.51499872 -1.43250276 1 P 0 ;0
L 1.51499872 -1.43250276 1.5269998 -1.44250059 1 P 0 ;0
L 1.5269998 -1.44250059 1.54100049 -1.445 1 P 0 ;0
L 1.54100049 -1.445 1.55500118 -1.44000108 1 P 0 ;0
L 1.55500118 -1.44000108 1.56900187 -1.42500433 1 P 0 ;0
L 1.6529998 -1.48999951 1.66500089 -1.49499843 1 P 0 ;0
L 1.66500089 -1.49499843 1.68100108 -1.48999951 1 P 0 ;0
L 1.68100108 -1.48999951 1.69099902 -1.48000167 1 P 0 ;0
L 1.69099902 -1.48000167 1.69900089 -1.4674997 1 P 0 ;0
L 1.69900089 -1.4674997 1.71099833 -1.42750374 1 P 0 ;0
L 1.71099833 -1.42750374 1.7370001 -1.34500315 1 P 0 ;0
L 1.67299911 -1.34500315 1.71099833 -1.42750374 1 P 0 ;0
L 1.82500089 -1.37750069 1.88900187 -1.37750069 1 P 0 ;0
L 1.88900187 -1.37750069 1.88299951 -1.3599999 1 P 0 ;0
L 1.88299951 -1.3599999 1.87300157 -1.35000207 1 P 0 ;0
L 1.87300157 -1.35000207 1.85900089 -1.34500315 1 P 0 ;0
L 1.85900089 -1.34500315 1.8450003 -1.34750256 1 P 0 ;0
L 1.8450003 -1.34750256 1.83299911 -1.35500098 1 P 0 ;0
L 1.83299911 -1.35500098 1.82500089 -1.37250177 1 P 0 ;0
L 1.82500089 -1.37250177 1.82099803 -1.38750315 1 P 0 ;0
L 1.82099803 -1.38750315 1.82099803 -1.4025 1 P 0 ;0
L 1.82099803 -1.4025 1.82500089 -1.41750138 1 P 0 ;0
L 1.82500089 -1.41750138 1.83499872 -1.43250276 1 P 0 ;0
L 1.83499872 -1.43250276 1.8469998 -1.44250059 1 P 0 ;0
L 1.8469998 -1.44250059 1.86100049 -1.445 1 P 0 ;0
L 1.86100049 -1.445 1.87500118 -1.44000108 1 P 0 ;0
L 1.87500118 -1.44000108 1.88900187 -1.42500433 1 P 0 ;0
L 2.18699921 -1.37000236 2.22700167 -1.37000236 1 P 0 ;0
L 2.22700167 -1.37000236 2.22700167 -1.41500187 1 P 0 ;0
L 2.22700167 -1.41500187 2.21500059 -1.43000325 1 P 0 ;0
L 2.21500059 -1.43000325 2.2009999 -1.44000108 1 P 0 ;0
L 2.2009999 -1.44000108 2.18100049 -1.445 1 P 0 ;0
L 2.18100049 -1.445 2.16100108 -1.44000108 1 P 0 ;0
L 2.16100108 -1.44000108 2.14700039 -1.43000325 1 P 0 ;0
L 2.14700039 -1.43000325 2.13499931 -1.41500187 1 P 0 ;0
L 2.13499931 -1.41500187 2.12699734 -1.39750108 1 P 0 ;0
L 2.12699734 -1.39750108 2.12299823 -1.37750069 1 P 0 ;0
L 2.12299823 -1.37750069 2.12299823 -1.3599999 1 P 0 ;0
L 2.12299823 -1.3599999 2.12699734 -1.34500315 1 P 0 ;0
L 2.12699734 -1.34500315 2.13499931 -1.32749764 1 P 0 ;0
L 2.13499931 -1.32749764 2.14700039 -1.31250089 1 P 0 ;0
L 2.14700039 -1.31250089 2.15899783 -1.30250305 1 P 0 ;0
L 2.15899783 -1.30250305 2.17499813 -1.295 1 P 0 ;0
L 2.17499813 -1.295 2.18899882 -1.295 1 P 0 ;0
L 2.18899882 -1.295 2.20499902 -1.29999902 1 P 0 ;0
L 2.20499902 -1.29999902 2.2170001 -1.31000138 1 P 0 ;0
L 2.29699892 -1.31999931 2.309 -1.30500246 1 P 0 ;0
L 2.309 -1.30500246 2.32300069 -1.29749951 1 P 0 ;0
L 2.32300069 -1.29749951 2.33900089 -1.295 1 P 0 ;0
L 2.33900089 -1.295 2.3590003 -1.29999902 1 P 0 ;0
L 2.3590003 -1.29999902 2.37300098 -1.31250089 1 P 0 ;0
L 2.37300098 -1.31250089 2.3770001 -1.32749764 1 P 0 ;0
L 2.3770001 -1.32749764 2.37500059 -1.34250364 1 P 0 ;0
L 2.37500059 -1.34250364 2.36699862 -1.35500098 1 P 0 ;0
L 2.36699862 -1.35500098 2.3269998 -1.3800002 1 P 0 ;0
L 2.3269998 -1.3800002 2.309 -1.39750108 1 P 0 ;0
L 2.309 -1.39750108 2.29699892 -1.42250482 1 P 0 ;0
L 2.29699892 -1.42250482 2.2929998 -1.445 1 P 0 ;0
L 2.2929998 -1.445 2.3770001 -1.445 1 P 0 ;0
L 2.6129998 -1.42500433 2.629 -1.43750167 1 P 0 ;0
L 2.629 -1.43750167 2.6469998 -1.445 1 P 0 ;0
L 2.6469998 -1.445 2.6630001 -1.445 1 P 0 ;0
L 2.6630001 -1.445 2.6790003 -1.43750167 1 P 0 ;0
L 2.6790003 -1.43750167 2.69100138 -1.42500433 1 P 0 ;0
L 2.69100138 -1.42500433 2.6970001 -1.40749892 1 P 0 ;0
L 2.6970001 -1.40749892 2.69300098 -1.39000266 1 P 0 ;0
L 2.69300098 -1.39000266 2.68299951 -1.37500128 1 P 0 ;0
L 2.68299951 -1.37500128 2.66499961 -1.36499882 1 P 0 ;0
L 2.66499961 -1.36499882 2.64100108 -1.3599999 1 P 0 ;0
L 2.64100108 -1.3599999 2.62700039 -1.35000207 1 P 0 ;0
L 2.62700039 -1.35000207 2.62099803 -1.33250118 1 P 0 ;0
L 2.62099803 -1.33250118 2.62500089 -1.31500039 1 P 0 ;0
L 2.62500089 -1.31500039 2.63499872 -1.30250305 1 P 0 ;0
L 2.63499872 -1.30250305 2.64899941 -1.295 1 P 0 ;0
L 2.64899941 -1.295 2.6630001 -1.295 1 P 0 ;0
L 2.6630001 -1.295 2.67700079 -1.29999902 1 P 0 ;0
L 2.67700079 -1.29999902 2.68900187 -1.31250089 1 P 0 ;0
L 2.7729998 -1.445 2.8570001 -1.295 1 P 0 ;0
L 2.7729998 -1.295 2.8570001 -1.445 1 P 0 ;0
L 2.92299823 -1.445 2.92299823 -1.295 1 P 0 ;0
L 2.92299823 -1.295 2.97499813 -1.42000079 1 P 0 ;0
L 2.97499813 -1.42000079 3.02700167 -1.295 1 P 0 ;0
L 3.02700167 -1.295 3.02700167 -1.445 1 P 0 ;0
L 3.09699892 -1.31999931 3.109 -1.30500246 1 P 0 ;0
L 3.109 -1.30500246 3.12300069 -1.29749951 1 P 0 ;0
L 3.12300069 -1.29749951 3.13900089 -1.295 1 P 0 ;0
L 3.13900089 -1.295 3.1590003 -1.29999902 1 P 0 ;0
L 3.1590003 -1.29999902 3.17300098 -1.31250089 1 P 0 ;0
L 3.17300098 -1.31250089 3.1770001 -1.32749764 1 P 0 ;0
L 3.1770001 -1.32749764 3.17500059 -1.34250364 1 P 0 ;0
L 3.17500059 -1.34250364 3.16699862 -1.35500098 1 P 0 ;0
L 3.16699862 -1.35500098 3.1269998 -1.3800002 1 P 0 ;0
L 3.1269998 -1.3800002 3.109 -1.39750108 1 P 0 ;0
L 3.109 -1.39750108 3.09699892 -1.42250482 1 P 0 ;0
L 3.09699892 -1.42250482 3.0929998 -1.445 1 P 0 ;0
L 3.0929998 -1.445 3.1770001 -1.445 1 P 0 ;0
L 3.269 -1.39500157 3.3209999 -1.39500157 1 P 0 ;0
L 3.41499931 -1.445 3.41499931 -1.295 1 P 0 ;0
L 3.41499931 -1.295 3.46499961 -1.295 1 P 0 ;0
L 3.46499961 -1.295 3.4809999 -1.30250305 1 P 0 ;0
L 3.4809999 -1.30250305 3.49100138 -1.31250089 1 P 0 ;0
L 3.49100138 -1.31250089 3.49500059 -1.33250118 1 P 0 ;0
L 3.49500059 -1.33250118 3.49100138 -1.35250148 1 P 0 ;0
L 3.49100138 -1.35250148 3.4790003 -1.36499882 1 P 0 ;0
L 3.4790003 -1.36499882 3.46499961 -1.37250177 1 P 0 ;0
L 3.46499961 -1.37250177 3.41499931 -1.37250177 1 P 0 ;0
L 3.46499961 -1.37250177 3.49500059 -1.445 1 P 0 ;0
L 3.61499813 -1.34500315 3.61499813 -1.445 1 P 0 ;0
L 3.61499813 -1.30500246 3.61099902 -1.30250305 1 P 8191 ;0
L 3.61099902 -1.30250305 3.61099902 -1.29749951 1 P 8191 ;0
L 3.61099902 -1.29749951 3.61499813 -1.295 1 P 8191 ;0
L 3.61499813 -1.295 3.61900089 -1.29749951 1 P 8191 ;0
L 3.61900089 -1.29749951 3.61900089 -1.30250305 1 P 8191 ;0
L 3.61900089 -1.30250305 3.61499813 -1.30500246 1 P 8191 ;0
L 3.74500089 -1.42750374 3.75499872 -1.43750167 1 P 0 ;0
L 3.75499872 -1.43750167 3.76899941 -1.445 1 P 0 ;0
L 3.76899941 -1.445 3.78100049 -1.445 1 P 0 ;0
L 3.78100049 -1.445 3.79300157 -1.44000108 1 P 0 ;0
L 3.79300157 -1.44000108 3.8009999 -1.43250276 1 P 0 ;0
L 3.8009999 -1.43250276 3.80499902 -1.42250482 1 P 0 ;0
L 3.80499902 -1.42250482 3.80299951 -1.40749892 1 P 0 ;0
L 3.80299951 -1.40749892 3.79500118 -1.40000049 1 P 0 ;0
L 3.79500118 -1.40000049 3.75899783 -1.38500374 1 P 0 ;0
L 3.75899783 -1.38500374 3.75099961 -1.36749833 1 P 0 ;0
L 3.75099961 -1.36749833 3.75499872 -1.35500098 1 P 0 ;0
L 3.75499872 -1.35500098 3.76300069 -1.34750256 1 P 0 ;0
L 3.76300069 -1.34750256 3.77499813 -1.34500315 1 P 0 ;0
L 3.77499813 -1.34500315 3.78699921 -1.34750256 1 P 0 ;0
L 3.78699921 -1.34750256 3.7990003 -1.35500098 1 P 0 ;0
L 3.90500089 -1.37750069 3.96900187 -1.37750069 1 P 0 ;0
L 3.96900187 -1.37750069 3.96299951 -1.3599999 1 P 0 ;0
L 3.96299951 -1.3599999 3.95300157 -1.35000207 1 P 0 ;0
L 3.95300157 -1.35000207 3.93900089 -1.34500315 1 P 0 ;0
L 3.93900089 -1.34500315 3.9250003 -1.34750256 1 P 0 ;0
L 3.9250003 -1.34750256 3.91299911 -1.35500098 1 P 0 ;0
L 3.91299911 -1.35500098 3.90500089 -1.37250177 1 P 0 ;0
L 3.90500089 -1.37250177 3.90099803 -1.38750315 1 P 0 ;0
L 3.90099803 -1.38750315 3.90099803 -1.4025 1 P 0 ;0
L 3.90099803 -1.4025 3.90500089 -1.41750138 1 P 0 ;0
L 3.90500089 -1.41750138 3.91499872 -1.43250276 1 P 0 ;0
L 3.91499872 -1.43250276 3.9269998 -1.44250059 1 P 0 ;0
L 3.9269998 -1.44250059 3.94100049 -1.445 1 P 0 ;0
L 3.94100049 -1.445 3.95500118 -1.44000108 1 P 0 ;0
L 3.95500118 -1.44000108 3.96900187 -1.42500433 1 P 0 ;0
L 4.06700039 -1.445 4.06700039 -1.34500315 1 P 0 ;0
L 4.06700039 -1.36499882 4.07699833 -1.35500098 1 P 0 ;0
L 4.07699833 -1.35500098 4.0869998 -1.34750256 1 P 0 ;0
L 4.0869998 -1.34750256 4.10100049 -1.34500315 1 P 0 ;0
L 4.10100049 -1.34500315 4.11099833 -1.34750256 1 P 0 ;0
L 4.11099833 -1.34750256 4.12299951 -1.35500098 1 P 0 ;0
L 4.16964783 -2.2038 4.21839813 -2.0478 1 P 0 ;0
L 4.21839813 -2.0478 4.26715207 -2.2038 1 P 0 ;0
L 4.24959862 -2.14920217 4.18719774 -2.14920217 1 P 0 ;0
L 4.37939813 -2.2038 4.37939813 -2.0478 1 P 0 ;0
L 4.37939813 -2.0478 4.35599961 -2.07899813 1 P 0 ;0
L 4.35599961 -2.2038 4.40279675 -2.2038 1 P 0 ;0
L 2.0009002 -0.9538 2.0009002 -0.8038 1 P 0 ;0
L 2.0009002 -0.8038 2.04089902 -0.8038 1 P 0 ;0
L 2.04089902 -0.8038 2.05689921 -0.81130305 1 P 0 ;0
L 2.05689921 -0.81130305 2.0689003 -0.82130089 1 P 0 ;0
L 2.0689003 -0.82130089 2.07890187 -0.83629764 1 P 0 ;0
L 2.07890187 -0.83629764 2.0869001 -0.85380315 1 P 0 ;0
L 2.0869001 -0.85380315 2.0888997 -0.87880236 1 P 0 ;0
L 2.0888997 -0.87880236 2.0869001 -0.90380157 1 P 0 ;0
L 2.0869001 -0.90380157 2.07890187 -0.92130246 1 P 0 ;0
L 2.07890187 -0.92130246 2.0689003 -0.93630374 1 P 0 ;0
L 2.0689003 -0.93630374 2.05689921 -0.94630167 1 P 0 ;0
L 2.05689921 -0.94630167 2.04089902 -0.9538 1 P 0 ;0
L 2.04089902 -0.9538 2.0009002 -0.9538 1 P 0 ;0
L 2.15489783 -0.9538 2.20489813 -0.8038 1 P 0 ;0
L 2.20489813 -0.8038 2.25490207 -0.9538 1 P 0 ;0
L 2.23689862 -0.90130207 2.17289764 -0.90130207 1 P 0 ;0
L 2.36489813 -0.8038 2.36489813 -0.9538 1 P 0 ;0
L 2.31890059 -0.8038 2.41089931 -0.8038 1 P 0 ;0
L 2.56490059 -0.9538 2.48489931 -0.9538 1 P 0 ;0
L 2.48489931 -0.9538 2.48489931 -0.8038 1 P 0 ;0
L 2.48489931 -0.8038 2.56490059 -0.8038 1 P 0 ;0
L 2.5329001 -0.87629833 2.48489931 -0.87629833 1 P 0 ;0
L 2.84489813 -0.9538 2.82889783 -0.95130059 1 P 0 ;0
L 2.82889783 -0.95130059 2.81490089 -0.94130276 1 P 0 ;0
L 2.81490089 -0.94130276 2.8028998 -0.92630138 1 P 0 ;0
L 2.8028998 -0.92630138 2.79489783 -0.90880049 1 P 0 ;0
L 2.79489783 -0.90880049 2.79089862 -0.8888002 1 P 0 ;0
L 2.79089862 -0.8888002 2.79089862 -0.8687999 1 P 0 ;0
L 2.79089862 -0.8687999 2.79489783 -0.84879961 1 P 0 ;0
L 2.79489783 -0.84879961 2.8028998 -0.83129872 1 P 0 ;0
L 2.8028998 -0.83129872 2.81490089 -0.81630197 1 P 0 ;0
L 2.81490089 -0.81630197 2.82889783 -0.80629951 1 P 0 ;0
L 2.82889783 -0.80629951 2.84489813 -0.8038 1 P 0 ;0
L 2.84489813 -0.8038 2.86089833 -0.80629951 1 P 0 ;0
L 2.86089833 -0.80629951 2.87489902 -0.81630197 1 P 0 ;0
L 2.87489902 -0.81630197 2.8869001 -0.83129872 1 P 0 ;0
L 2.8869001 -0.83129872 2.89490207 -0.84879961 1 P 0 ;0
L 2.89490207 -0.84879961 2.89890128 -0.8687999 1 P 0 ;0
L 2.89890128 -0.8687999 2.89890128 -0.8888002 1 P 0 ;0
L 2.89890128 -0.8888002 2.89490207 -0.90880049 1 P 0 ;0
L 2.89490207 -0.90880049 2.8869001 -0.92630138 1 P 0 ;0
L 2.8869001 -0.92630138 2.87489902 -0.94130276 1 P 0 ;0
L 2.87489902 -0.94130276 2.86089833 -0.95130059 1 P 0 ;0
L 2.86089833 -0.95130059 2.84489813 -0.9538 1 P 0 ;0
L 3.0488997 -0.81630197 3.03689862 -0.80879902 1 P 0 ;0
L 3.03689862 -0.80879902 3.02290157 -0.8038 1 P 0 ;0
L 3.02290157 -0.8038 3.00690138 -0.8038 1 P 0 ;0
L 3.00690138 -0.8038 2.98889783 -0.81130305 1 P 0 ;0
L 2.98889783 -0.81130305 2.97490089 -0.82380039 1 P 0 ;0
L 2.97490089 -0.82380039 2.96489931 -0.83880177 1 P 0 ;0
L 2.96489931 -0.83880177 2.95689734 -0.86380098 1 P 0 ;0
L 2.95689734 -0.86380098 2.95489783 -0.88630069 1 P 0 ;0
L 2.95489783 -0.88630069 2.95890059 -0.90880049 1 P 0 ;0
L 2.95890059 -0.90880049 2.96489931 -0.92380187 1 P 0 ;0
L 2.96489931 -0.92380187 2.97690039 -0.93880325 1 P 0 ;0
L 2.97690039 -0.93880325 2.99090108 -0.94880108 1 P 0 ;0
L 2.99090108 -0.94880108 3.00489813 -0.9538 1 P 0 ;0
L 3.00489813 -0.9538 3.01889882 -0.9538 1 P 0 ;0
L 3.01889882 -0.9538 3.03289951 -0.94880108 1 P 0 ;0
L 3.03289951 -0.94880108 3.04490059 -0.94130276 1 P 0 ;0
L 3.04490059 -0.94130276 3.05490207 -0.93130482 1 P 0 ;0
L 3.16489813 -0.8038 3.16489813 -0.9538 1 P 0 ;0
L 3.11890059 -0.8038 3.21089931 -0.8038 1 P 0 ;0
L 3.28889852 -0.95879892 3.36090138 -0.8038 1 P 0 ;0
L 3.44689892 -0.82879931 3.4589 -0.81380246 1 P 0 ;0
L 3.4589 -0.81380246 3.47290069 -0.80629951 1 P 0 ;0
L 3.47290069 -0.80629951 3.48890089 -0.8038 1 P 0 ;0
L 3.48890089 -0.8038 3.5089003 -0.80879902 1 P 0 ;0
L 3.5089003 -0.80879902 3.52290098 -0.82130089 1 P 0 ;0
L 3.52290098 -0.82130089 3.5269001 -0.83629764 1 P 0 ;0
L 3.5269001 -0.83629764 3.52490059 -0.85130364 1 P 0 ;0
L 3.52490059 -0.85130364 3.51689862 -0.86380098 1 P 0 ;0
L 3.51689862 -0.86380098 3.4768998 -0.8888002 1 P 0 ;0
L 3.4768998 -0.8888002 3.4589 -0.90630108 1 P 0 ;0
L 3.4589 -0.90630108 3.44689892 -0.93130482 1 P 0 ;0
L 3.44689892 -0.93130482 3.4428998 -0.9538 1 P 0 ;0
L 3.4428998 -0.9538 3.5269001 -0.9538 1 P 0 ;0
L 3.64089902 -0.9538 3.64489813 -0.92130246 1 P 0 ;0
L 3.64489813 -0.92130246 3.65090049 -0.89380374 1 P 0 ;0
L 3.65090049 -0.89380374 3.65889882 -0.8687999 1 P 0 ;0
L 3.65889882 -0.8687999 3.6689003 -0.84130118 1 P 0 ;0
L 3.6689003 -0.84130118 3.68490059 -0.8038 1 P 0 ;0
L 3.68490059 -0.8038 3.60489931 -0.8038 1 P 0 ;0
L 3.76889852 -0.95879892 3.84090138 -0.8038 1 P 0 ;0
L 3.92689892 -0.82879931 3.9389 -0.81380246 1 P 0 ;0
L 3.9389 -0.81380246 3.95290069 -0.80629951 1 P 0 ;0
L 3.95290069 -0.80629951 3.96890089 -0.8038 1 P 0 ;0
L 3.96890089 -0.8038 3.9889003 -0.80879902 1 P 0 ;0
L 3.9889003 -0.80879902 4.00290098 -0.82130089 1 P 0 ;0
L 4.00290098 -0.82130089 4.0069001 -0.83629764 1 P 0 ;0
L 4.0069001 -0.83629764 4.00490059 -0.85130364 1 P 0 ;0
L 4.00490059 -0.85130364 3.99689862 -0.86380098 1 P 0 ;0
L 3.99689862 -0.86380098 3.9568998 -0.8888002 1 P 0 ;0
L 3.9568998 -0.8888002 3.9389 -0.90630108 1 P 0 ;0
L 3.9389 -0.90630108 3.92689892 -0.93130482 1 P 0 ;0
L 3.92689892 -0.93130482 3.9228998 -0.9538 1 P 0 ;0
L 3.9228998 -0.9538 4.0069001 -0.9538 1 P 0 ;0
L 4.12489813 -0.8038 4.10889783 -0.80879902 1 P 0 ;0
L 4.10889783 -0.80879902 4.09690039 -0.82130089 1 P 0 ;0
L 4.09690039 -0.82130089 4.08889852 -0.83629764 1 P 0 ;0
L 4.08889852 -0.83629764 4.0828998 -0.85630256 1 P 0 ;0
L 4.0828998 -0.85630256 4.0809002 -0.87880236 1 P 0 ;0
L 4.0809002 -0.87880236 4.0828998 -0.90130207 1 P 0 ;0
L 4.0828998 -0.90130207 4.08889852 -0.92130246 1 P 0 ;0
L 4.08889852 -0.92130246 4.09690039 -0.93630374 1 P 0 ;0
L 4.09690039 -0.93630374 4.10889783 -0.94880108 1 P 0 ;0
L 4.10889783 -0.94880108 4.12489813 -0.9538 1 P 0 ;0
L 4.12489813 -0.9538 4.14089833 -0.94880108 1 P 0 ;0
L 4.14089833 -0.94880108 4.15289951 -0.93630374 1 P 0 ;0
L 4.15289951 -0.93630374 4.16090138 -0.92130246 1 P 0 ;0
L 4.16090138 -0.92130246 4.1669001 -0.90130207 1 P 0 ;0
L 4.1669001 -0.90130207 4.1688997 -0.87880236 1 P 0 ;0
L 4.1688997 -0.87880236 4.1669001 -0.85630256 1 P 0 ;0
L 4.1669001 -0.85630256 4.16090138 -0.83629764 1 P 0 ;0
L 4.16090138 -0.83629764 4.15289951 -0.82130089 1 P 0 ;0
L 4.15289951 -0.82130089 4.14089833 -0.80879902 1 P 0 ;0
L 4.14089833 -0.80879902 4.12489813 -0.8038 1 P 0 ;0
L 4.28489813 -0.9538 4.28489813 -0.8038 1 P 0 ;0
L 4.28489813 -0.8038 4.26089961 -0.83379823 1 P 0 ;0
L 4.26089961 -0.9538 4.30889665 -0.9538 1 P 0 ;0
L 4.44089902 -0.9538 4.44489813 -0.92130246 1 P 0 ;0
L 4.44489813 -0.92130246 4.45090049 -0.89380374 1 P 0 ;0
L 4.45090049 -0.89380374 4.45889882 -0.8687999 1 P 0 ;0
L 4.45889882 -0.8687999 4.4689003 -0.84130118 1 P 0 ;0
L 4.4689003 -0.84130118 4.48490059 -0.8038 1 P 0 ;0
L 4.48490059 -0.8038 4.40489931 -0.8038 1 P 0 ;0

### steps/drc/layers/l8/features
#
#Feature symbol names
#
$0 r2
$1 r6
$2 r15
$3 r20
$4 r28
$5 r30
$6 r32
$7 r33
$8 r40
$9 r50
$10 r57.09
$11 r59.45
$12 r78.74
$13 r86.61
$14 r90.55
$15 r100
$16 r131.89
$17 r137.8
$18 r150
$19 r161.42
$20 r168.31
$21 r173.23
$22 r181.1
$23 r204.72
$24 r224.41
$25 r393.7
$26 r433.07
$27 r440.94
$28 null
$29 oval236.22x177.17
$30 thr61.02x49.21x45x4x15.75
$31 thr96.46x76.77x45x4x19.69

#
#Feature attribute names
#
@0 .nomenclature
@1 .geometry

#
#Feature attribute text strings
#
&0 TPB30V20D10AT28BPM
&1 C1_11P0_7
&2 C1_11P0_7TP
&3 V17D8AT30SM11
&4 V20D10AT28SM14
&5 C2_5N
&6 S1_11P0_7TP
&7 S1_11P0_7
&8 V20D10AT28PG
&9 C1_17P0_76TPM
&10 C1_9P1_4
&11 S1_9P1_4
&12 SP-8C5_2P0_254
&13 SP-9C5_7P0_254
&14 C3_175N-A
&15 C10N
&16 C3_3N
&17 C4_5N-B
&18 C4N-B
&19 C3_5N
&20 O5X3_5N
&21 C3N
&22 C1_3N
&23 C2_35N
&24 C1N

#
#Layer features
#
P 7.785 4.45 4 P 0 0;1=0
P 7.835 4.45 4 P 0 0;1=0
P 1.8 4.485 4 P 0 0;1=0
P 1.86 4.485 4 P 0 0;1=0
P 0.27165 1.72835 10 P 0 0;1=1
P 0.17323002 2.12205 10 P 0 0;1=1
P 12.73621004 1.76771998 10 P 0 0;1=1
P 12.81495 2.59448996 10 P 0 0;1=1
P 12.63778996 2.16141998 10 P 0 0;1=1
P 0.725 -0.25 10 P 0 0;1=2
P 0.875 -0.25 10 P 0 0;1=2
P 1.065 6.26 10 P 0 0;1=2
P 1.065 6.36 10 P 0 0;1=2
P 1.29 6.26 10 P 0 0;1=2
P 1.29 6.36 10 P 0 0;1=2
P 1.515 6.26 10 P 0 0;1=2
P 1.515 6.36 10 P 0 0;1=2
P 0.84 6.26 10 P 0 0;1=2
P 0.84 6.36 10 P 0 0;1=2
P 1.74 6.26 10 P 0 0;1=2
P 1.74 6.36 10 P 0 0;1=2
P 2.09606004 3.56615 5 P 0 0;1=3
P 8.1 3.56615 5 P 0 0;1=3
P 12.55905 3.38188996 10 P 0 0;1=1
P 12.81495 4.64173996 10 P 0 0;1=1
P 12.81495 1.88583002 10 P 0 0;1=1
P 0.35038996 4.60236998 10 P 0 0;1=1
P 0.35038996 2.55511998 10 P 0 0;1=1
P 0.35038996 1.84646004 10 P 0 0;1=1
P 0.09448996 3.34251998 10 P 0 0;1=1
P 6.385 5.03 4 P 0 0;1=4
P 12.68701998 0.97243996 17 P 0 0;1=5
P 0.22245 0.93306998 17 P 0 0;1=5
P 12.68701004 4.91338002 17 P 0 0;1=5
P 3.94 4.545 4 P 0 0;1=0
P 4.91 5.375 4 P 0 0;1=4
P 1.08 5.85 4 P 0 0;1=0
P 3.6817 5.74 4 P 0 0;1=4
P 10.07 2.928 4 P 0 0;1=4
P 4.105 4.985 4 P 0 0;1=0
P 4.125 2.725 4 P 0 0;1=4
P 4.02 4.355 4 P 0 0;1=0
P 1.16 5.85 4 P 0 0;1=0
P 3.815 5.815 4 P 0 0;1=4
P 1.19 6.36 30 P 0 3;1=6
P 1.19 6.26 30 P 0 3;1=6
P 1.415 6.36 30 P 0 3;1=6
P 1.415 6.26 30 P 0 3;1=6
P 1.64 6.36 30 P 0 3;1=6
P 1.64 6.26 30 P 0 3;1=6
P 0.965 6.26 30 P 0 3;1=6
P 0.965 6.36 30 P 0 3;1=6
P 0.74 6.26 30 P 0 3;1=6
P 0.74 6.36 30 P 0 3;1=6
P 12.63778996 1.37401998 10 P 0 0;1=7
P 0.17323002 1.33465 10 P 0 0;1=7
P 6.501 5.017 4 P 0 0;1=0
P 7.425 3.43 4 P 0 0;1=0
P 7.445 1.705 4 P 0 0;1=4
P 11.03661004 3.81615 5 P 0 0;1=3
P 11.135 2.845 4 P 0 0;1=4
P 11.03661004 2.16615 5 P 0 0;1=3
P 3.8899 4.765 4 P 0 0;1=0
P 4.93268002 2.41615 5 P 0 0;1=3
P 4.93268002 2.46615 5 P 0 0;1=3
P 7.2926 5.04351004 4 P 0 0;1=0
P 7.2426 5.04351004 4 P 0 0;1=0
P 3.45646004 5.3 4 P 0 0;1=0
P 1.28906004 5.04351004 4 P 0 0;1=0
P 1.23906004 5.04351004 4 P 0 0;1=0
P 9.46 5.3 4 P 0 0;1=0
P 4.68268002 2.36615 5 P 0 0;1=3
P 0.27165 4.01181004 10 P 0 0;1=1
P 4.58268002 2.36615 5 P 0 0;1=3
P 0.27165 4.16928996 10 P 0 0;1=1
P 4.63268002 2.41615 5 P 0 0;1=3
P 0.27165 4.32676998 10 P 0 0;1=1
P 4.73268002 2.26615 5 P 0 0;1=3
P 0.27165 3.38188996 10 P 0 0;1=1
P 4.73268002 2.41615 5 P 0 0;1=3
P 0.27165 4.48425 10 P 0 0;1=1
P 4.68268002 2.21615 5 P 0 0;1=3
P 0.27165 3.53936998 10 P 0 0;1=1
P 4.63268002 2.26615 5 P 0 0;1=3
P 0.27165 3.85433002 10 P 0 0;1=1
P 4.58268002 2.06615 5 P 0 0;1=3
P 0.35038996 3.02756004 10 P 0 0;1=1
P 4.58268002 2.11615 5 P 0 0;1=3
P 0.27165 2.98818996 10 P 0 0;1=1
P 4.63268002 1.86615 5 P 0 0;1=3
P 0.35038996 2.3189 10 P 0 0;1=1
P 4.58268002 1.96615 5 P 0 0;1=3
P 0.27165 2.43701004 10 P 0 0;1=1
P 4.68268002 2.06615 5 P 0 0;1=3
P 0.35038996 3.18503996 10 P 0 0;1=1
P 4.58268002 1.91615 5 P 0 0;1=3
P 0.35038996 2.47638002 10 P 0 0;1=1
P 0.27165 2.27953002 10 P 0 0;1=1
P 4.63268002 1.91615 5 P 0 0;1=3
P 5.42048002 1.7396 5 P 0 0;1=3
P 0.09448996 2.55511998 10 P 0 0;1=1
P 4.68268002 2.11615 5 P 0 0;1=3
P 0.27165 3.14566998 10 P 0 0;1=1
P 5.42048002 1.7796 5 P 0 0;1=3
P 0.17323002 2.51575 10 P 0 0;1=1
P 4.68268002 1.91615 5 P 0 0;1=3
P 0.35038996 2.16141998 10 P 0 0;1=1
P 4.68268002 1.96615 5 P 0 0;1=3
P 0.27165 2.12205 10 P 0 0;1=1
P 5.57531004 2.0878 5 P 0 0;1=3
P 0.09448996 3.1063 10 P 0 0;1=1
P 5.57531004 2.1278 5 P 0 0;1=3
P 0.17323002 3.06693002 10 P 0 0;1=1
P 5.57531004 2.2232 5 P 0 0;1=3
P 0.17323002 3.46063002 10 P 0 0;1=1
P 5.57531004 2.2632 5 P 0 0;1=3
P 0.09448996 3.42126004 10 P 0 0;1=1
P 5.42048002 2.4662 5 P 0 0;1=3
P 0.09448996 4.05118002 10 P 0 0;1=1
P 5.57531004 2.3986 5 P 0 0;1=3
P 0.09448996 3.8937 10 P 0 0;1=1
P 5.57531004 2.673 5 P 0 0;1=3
P 0.09448996 4.36613996 10 P 0 0;1=1
P 5.57531004 1.9869 5 P 0 0;1=3
P 0.17323002 2.75196998 10 P 0 0;1=1
P 5.57531004 2.4978 5 P 0 0;1=3
P 0.17323002 4.24803002 10 P 0 0;1=1
P 5.57531004 1.6718 5 P 0 0;1=3
P 0.17323002 2.20078996 10 P 0 0;1=1
P 5.57531004 2.633 5 P 0 0;1=3
P 0.17323002 4.40551004 10 P 0 0;1=1
P 5.57531004 1.7118 5 P 0 0;1=3
P 0.09448996 2.24016004 10 P 0 0;1=1
P 5.57531004 2.5378 5 P 0 0;1=3
P 0.09448996 4.20866004 10 P 0 0;1=1
P 5.42048002 1.6433 5 P 0 0;1=3
P 0.09448996 2.39763996 10 P 0 0;1=1
P 5.42048002 2.6054 5 P 0 0;1=3
P 0.09448996 4.52361998 10 P 0 0;1=1
P 5.42048002 1.87835 5 P 0 0;1=3
P 0.09448996 2.94881998 10 P 0 0;1=1
P 5.57531004 2.3586 5 P 0 0;1=3
P 0.17323002 3.93306998 10 P 0 0;1=1
P 5.42048002 1.6033 5 P 0 0;1=3
P 0.17323002 2.35826998 10 P 0 0;1=1
P 5.42048002 2.4262 5 P 0 0;1=3
P 0.17323002 4.09055 10 P 0 0;1=1
P 5.42048002 1.91835 5 P 0 0;1=3
P 0.17323002 2.90945 10 P 0 0;1=1
P 5.42048002 2.0547 5 P 0 0;1=3
P 0.17323002 3.22441004 10 P 0 0;1=1
P 5.57531004 1.9469 5 P 0 0;1=3
P 0.09448996 2.79133996 10 P 0 0;1=1
P 5.42048002 2.0147 5 P 0 0;1=3
P 0.09448996 3.26378002 10 P 0 0;1=1
P 5.57531004 1.8508 5 P 0 0;1=3
P 0.09448996 2.00393996 10 P 0 0;1=1
P 5.57531004 1.8108 5 P 0 0;1=3
P 0.17323002 2.04331004 10 P 0 0;1=1
P 0.35038996 3.97243996 10 P 0 0;1=1
P 4.68268002 2.41615 5 P 0 0;1=3
P 4.73268002 2.46615 5 P 0 0;1=3
P 0.35038996 4.44488002 10 P 0 0;1=1
P 4.63268002 2.46615 5 P 0 0;1=3
P 0.35038996 4.2874 10 P 0 0;1=1
P 0.35038996 4.12991998 10 P 0 0;1=1
P 4.58268002 2.41615 5 P 0 0;1=3
P 4.68268002 2.26615 5 P 0 0;1=3
P 0.35038996 3.5 10 P 0 0;1=1
P 5.42048002 2.1554 5 P 0 0;1=3
P 0.17323002 3.77558996 10 P 0 0;1=1
P 4.73268002 2.31615 5 P 0 0;1=3
P 0.35038996 3.34251998 10 P 0 0;1=1
P 4.63268002 2.31615 5 P 0 0;1=3
P 0.35038996 3.81496004 10 P 0 0;1=1
P 4.58268002 2.26615 5 P 0 0;1=3
P 0.35038996 3.65748002 10 P 0 0;1=1
P 5.42048002 2.5654 5 P 0 0;1=3
P 0.17323002 4.563 10 P 0 0;1=1
P 5.42048002 2.1954 5 P 0 0;1=3
P 0.09448996 3.73621998 10 P 0 0;1=1
P 0.09448996 3.57873996 10 P 0 0;1=1
P 5.42048002 2.3308 5 P 0 0;1=3
P 0.17323002 3.61811004 10 P 0 0;1=1
P 5.42048002 2.2908 5 P 0 0;1=3
P 0.35038996 1.9252 10 P 0 0;1=1
P 4.73268002 1.91615 5 P 0 0;1=3
P 4.73268002 1.86615 5 P 0 0;1=3
P 0.27165 1.96456998 10 P 0 0;1=1
P 4.58268002 2.21615 5 P 0 0;1=3
P 0.27165 3.69685 10 P 0 0;1=1
P 4.73268002 2.06615 5 P 0 0;1=3
P 0.27165 2.67323002 10 P 0 0;1=1
P 4.73268002 2.01615 5 P 0 0;1=3
P 0.35038996 2.7126 10 P 0 0;1=1
P 4.63268002 2.01615 5 P 0 0;1=3
P 0.35038996 2.87008002 10 P 0 0;1=1
P 4.63268002 2.06615 5 P 0 0;1=3
P 0.27165 2.83071004 10 P 0 0;1=1
P 6.785 4.725 4 P 0 0;1=4
P 6.785 4.685 4 P 0 0;1=4
P 6.74018996 4.765 4 P 0 0;1=4
P 6.74 4.805 4 P 0 0;1=0
P 6.785 4.845 4 P 0 0;1=4
P 6.785 4.805 4 P 0 0;1=4
P 6.785 4.765 4 P 0 0;1=4
P 6.74 4.845 4 P 0 0;1=4
P 6.65 5.055 4 P 0 0;1=0
P 6.49205 5.09705 4 P 0 0;1=0
P 6.495 4.9328 4 P 0 0;1=0
P 6.55118996 5.04705 4 P 0 0;1=0
P 6.78 4.94705 4 P 0 0;1=0
P 6.755 4.89705 4 P 0 0;1=0
P 6.74 4.987 4 P 0 0;1=0
P 12.73621004 2.08268002 10 P 0 0;1=1
P 12.73621004 2.63386004 10 P 0 0;1=1
P 12.81495 3.30315 10 P 0 0;1=1
P 12.73621004 4.60236998 10 P 0 0;1=1
P 12.55905 1.96456998 10 P 0 0;1=1
P 12.63778996 1.9252 10 P 0 0;1=1
P 0.09448996 1.9252 10 P 0 0;1=1
P 0.17323002 1.88583002 10 P 0 0;1=1
P 0.27165 2.04331004 10 P 0 0;1=1
P 0.27165 4.563 10 P 0 0;1=1
P 0.35038996 3.26378002 10 P 0 0;1=1
P 0.27165 2.59448996 10 P 0 0;1=1
P 0.17323002 1.72835 10 P 0 0;1=1
P 5.03268002 1.91615 5 P 0 0;1=3
P 1.025 -0.25 10 P 0 0;1=2
P 1.175 -0.25 10 P 0 0;1=2
P 1.325 -0.25 10 P 0 0;1=2
P 5.03268002 2.06615 5 P 0 0;1=3
P 12.63778996 4.12991998 10 P 0 0;1=1
P 11.53316004 2.372 5 P 0 0;1=3
P 5.08268002 2.26615 5 P 0 0;1=3
P 11.53316004 1.892 5 P 0 0;1=3
P 12.55905 3.30315 10 P 0 0;1=1
P 12.81495 2.51575 10 P 0 0;1=1
P 10.58661004 1.91615 5 P 0 0;1=3
P 10.26 1.66445 5 P 0 0;1=3
P 11.03998996 4.8431 4 P 0 0;1=4
P 11.08498996 4.8431 4 P 0 0;1=4
P 11.13498996 4.8431 4 P 0 0;1=4
P 11.17998996 4.8431 4 P 0 0;1=4
P 11.17998996 4.8031 4 P 0 0;1=4
P 11.17998996 4.7581 4 P 0 0;1=4
P 11.17998996 4.7131 4 P 0 0;1=4
P 11.17998996 4.6731 4 P 0 0;1=4
P 11.03998996 4.6731 4 P 0 0;1=4
P 11.08498996 4.6731 4 P 0 0;1=4
P 11.13498996 4.6731 4 P 0 0;1=4
P 11.03998996 4.7131 4 P 0 0;1=4
P 11.03998996 4.8031 4 P 0 0;1=4
P 11.03998996 4.7581 4 P 0 0;1=4
P 10.81998996 4.6631 4 P 0 0;1=4
P 10.85998996 4.6631 4 P 0 0;1=4
P 10.65998996 4.6631 4 P 0 0;1=4
P 10.69998996 4.6631 4 P 0 0;1=4
P 10.81998996 4.7031 4 P 0 0;1=4
P 10.81998996 4.8381 4 P 0 0;1=4
P 10.81998996 4.7931 4 P 0 0;1=4
P 10.81998996 4.7481 4 P 0 0;1=4
P 10.85998996 4.7031 4 P 0 0;1=4
P 10.85998996 4.8381 4 P 0 0;1=4
P 10.85998996 4.7931 4 P 0 0;1=4
P 10.85998996 4.7481 4 P 0 0;1=4
P 10.65998996 4.7031 4 P 0 0;1=4
P 10.65998996 4.8381 4 P 0 0;1=4
P 10.65998996 4.7931 4 P 0 0;1=4
P 10.65998996 4.7481 4 P 0 0;1=4
P 10.69998996 4.7031 4 P 0 0;1=4
P 10.69998996 4.8381 4 P 0 0;1=4
P 10.69998996 4.7931 4 P 0 0;1=4
P 10.69998996 4.7481 4 P 0 0;1=4
P 10.77998996 4.6431 4 P 0 0;1=4
P 10.73498996 4.6431 4 P 0 0;1=4
P 10.73998996 4.8381 4 P 0 0;1=4
P 10.77998996 4.8381 4 P 0 0;1=4
P 10.30998996 4.6631 4 P 0 0;1=4
P 10.26998996 4.6631 4 P 0 0;1=4
P 10.34498996 4.6431 4 P 0 0;1=4
P 10.38998996 4.6431 4 P 0 0;1=4
P 10.42998996 4.6631 4 P 0 0;1=4
P 10.46998996 4.6631 4 P 0 0;1=4
P 10.30998996 4.7481 4 P 0 0;1=4
P 10.30998996 4.7931 4 P 0 0;1=4
P 10.30998996 4.7031 4 P 0 0;1=4
P 10.26998996 4.7481 4 P 0 0;1=4
P 10.26998996 4.7931 4 P 0 0;1=4
P 10.26998996 4.7031 4 P 0 0;1=4
P 10.26998996 4.8381 4 P 0 0;1=4
P 10.30998996 4.8381 4 P 0 0;1=4
P 10.38998996 4.8381 4 P 0 0;1=4
P 10.34998996 4.8381 4 P 0 0;1=4
P 10.46998996 4.8381 4 P 0 0;1=4
P 10.42998996 4.8381 4 P 0 0;1=4
P 10.42998996 4.7031 4 P 0 0;1=4
P 10.42998996 4.7931 4 P 0 0;1=4
P 10.42998996 4.7481 4 P 0 0;1=4
P 10.46998996 4.7031 4 P 0 0;1=4
P 10.46998996 4.7931 4 P 0 0;1=4
P 10.46998996 4.7481 4 P 0 0;1=4
P 10.58661004 3.16615 5 P 0 0;1=3
P 10.63661004 3.01615 5 P 0 0;1=3
P 10.58661004 3.11615 5 P 0 0;1=3
P 10.58661004 3.01615 5 P 0 0;1=3
P 10.63661004 3.11615 5 P 0 0;1=3
P 10.63661004 2.96615 5 P 0 0;1=3
P 10.58661004 2.96615 5 P 0 0;1=3
P 10.58661004 3.41615 5 P 0 0;1=3
P 10.63661004 3.16615 5 P 0 0;1=3
P 10.63661004 3.26615 5 P 0 0;1=3
P 10.58661004 3.31615 5 P 0 0;1=3
P 10.58661004 3.26615 5 P 0 0;1=3
P 10.63661004 3.31615 5 P 0 0;1=3
P 10.63661004 3.56615 5 P 0 0;1=3
P 10.63661004 3.61615 5 P 0 0;1=3
P 10.58661004 3.56615 5 P 0 0;1=3
P 10.58661004 3.61615 5 P 0 0;1=3
P 10.63661004 3.46615 5 P 0 0;1=3
P 10.63661004 3.41615 5 P 0 0;1=3
P 10.58661004 3.46615 5 P 0 0;1=3
P 10.63661004 3.86615 5 P 0 0;1=3
P 10.63661004 3.76615 5 P 0 0;1=3
P 10.58661004 3.86615 5 P 0 0;1=3
P 10.58661004 3.76615 5 P 0 0;1=3
P 10.63661004 3.71615 5 P 0 0;1=3
P 10.58661004 3.71615 5 P 0 0;1=3
P 10.88661004 2.96615 5 P 0 0;1=3
P 10.83661004 2.96615 5 P 0 0;1=3
P 10.88661004 3.01615 5 P 0 0;1=3
P 10.83661004 3.01615 5 P 0 0;1=3
P 10.88661004 3.11615 5 P 0 0;1=3
P 10.83661004 3.11615 5 P 0 0;1=3
P 10.83661004 3.16615 5 P 0 0;1=3
P 10.78661004 3.16615 5 P 0 0;1=3
P 10.68661004 3.16615 5 P 0 0;1=3
P 10.73661004 3.16615 5 P 0 0;1=3
P 10.78661004 3.01615 5 P 0 0;1=3
P 10.78661004 3.11615 5 P 0 0;1=3
P 10.73661004 3.01615 5 P 0 0;1=3
P 10.73661004 3.11615 5 P 0 0;1=3
P 10.68661004 3.01615 5 P 0 0;1=3
P 10.68661004 3.11615 5 P 0 0;1=3
P 10.78661004 2.96615 5 P 0 0;1=3
P 10.73661004 2.96615 5 P 0 0;1=3
P 10.68661004 2.96615 5 P 0 0;1=3
P 10.88661004 3.16615 5 P 0 0;1=3
P 10.88661004 3.26615 5 P 0 0;1=3
P 10.83661004 3.26615 5 P 0 0;1=3
P 10.83661004 3.31615 5 P 0 0;1=3
P 10.88661004 3.31615 5 P 0 0;1=3
P 10.83661004 3.41615 5 P 0 0;1=3
P 10.78661004 3.41615 5 P 0 0;1=3
P 10.68661004 3.41615 5 P 0 0;1=3
P 10.73661004 3.41615 5 P 0 0;1=3
P 10.78661004 3.31615 5 P 0 0;1=3
P 10.78661004 3.26615 5 P 0 0;1=3
P 10.68661004 3.31615 5 P 0 0;1=3
P 10.68661004 3.26615 5 P 0 0;1=3
P 10.73661004 3.26615 5 P 0 0;1=3
P 10.73661004 3.31615 5 P 0 0;1=3
P 10.88661004 3.41615 5 P 0 0;1=3
P 10.83661004 3.46615 5 P 0 0;1=3
P 10.88661004 3.46615 5 P 0 0;1=3
P 10.83661004 3.56615 5 P 0 0;1=3
P 10.88661004 3.56615 5 P 0 0;1=3
P 10.83661004 3.61615 5 P 0 0;1=3
P 10.88661004 3.61615 5 P 0 0;1=3
P 10.78661004 3.56615 5 P 0 0;1=3
P 10.78661004 3.61615 5 P 0 0;1=3
P 10.68661004 3.61615 5 P 0 0;1=3
P 10.68661004 3.56615 5 P 0 0;1=3
P 10.73661004 3.61615 5 P 0 0;1=3
P 10.73661004 3.56615 5 P 0 0;1=3
P 10.78661004 3.46615 5 P 0 0;1=3
P 10.73661004 3.46615 5 P 0 0;1=3
P 10.68661004 3.46615 5 P 0 0;1=3
P 10.83661004 3.71615 5 P 0 0;1=3
P 10.88661004 3.71615 5 P 0 0;1=3
P 10.83661004 3.76615 5 P 0 0;1=3
P 10.88661004 3.76615 5 P 0 0;1=3
P 10.83661004 3.86615 5 P 0 0;1=3
P 10.88661004 3.86615 5 P 0 0;1=3
P 10.78661004 3.86615 5 P 0 0;1=3
P 10.78661004 3.76615 5 P 0 0;1=3
P 10.68661004 3.86615 5 P 0 0;1=3
P 10.68661004 3.76615 5 P 0 0;1=3
P 10.73661004 3.86615 5 P 0 0;1=3
P 10.73661004 3.76615 5 P 0 0;1=3
P 10.78661004 3.71615 5 P 0 0;1=3
P 10.68661004 3.71615 5 P 0 0;1=3
P 10.73661004 3.71615 5 P 0 0;1=3
P 11.03661004 2.96615 5 P 0 0;1=3
P 10.93661004 2.96615 5 P 0 0;1=3
P 10.98661004 2.96615 5 P 0 0;1=3
P 11.03661004 3.01615 5 P 0 0;1=3
P 10.93661004 3.01615 5 P 0 0;1=3
P 10.98661004 3.01615 5 P 0 0;1=3
P 11.03661004 3.11615 5 P 0 0;1=3
P 10.93661004 3.11615 5 P 0 0;1=3
P 10.98661004 3.11615 5 P 0 0;1=3
P 11.03661004 3.16615 5 P 0 0;1=3
P 10.93661004 3.16615 5 P 0 0;1=3
P 10.98661004 3.16615 5 P 0 0;1=3
P 11.03661004 3.26615 5 P 0 0;1=3
P 10.93661004 3.26615 5 P 0 0;1=3
P 10.98661004 3.26615 5 P 0 0;1=3
P 10.98661004 3.31615 5 P 0 0;1=3
P 10.93661004 3.31615 5 P 0 0;1=3
P 11.03661004 3.31615 5 P 0 0;1=3
P 10.98661004 3.41615 5 P 0 0;1=3
P 10.93661004 3.41615 5 P 0 0;1=3
P 11.03661004 3.41615 5 P 0 0;1=3
P 10.98661004 3.46615 5 P 0 0;1=3
P 10.93661004 3.46615 5 P 0 0;1=3
P 11.03661004 3.46615 5 P 0 0;1=3
P 10.98661004 3.56615 5 P 0 0;1=3
P 10.93661004 3.56615 5 P 0 0;1=3
P 11.03661004 3.56615 5 P 0 0;1=3
P 10.98661004 3.61615 5 P 0 0;1=3
P 10.93661004 3.61615 5 P 0 0;1=3
P 11.03661004 3.61615 5 P 0 0;1=3
P 10.98661004 3.71615 5 P 0 0;1=3
P 10.93661004 3.71615 5 P 0 0;1=3
P 11.03661004 3.71615 5 P 0 0;1=3
P 10.98661004 3.76615 5 P 0 0;1=3
P 10.93661004 3.76615 5 P 0 0;1=3
P 11.03661004 3.76615 5 P 0 0;1=3
P 10.98661004 3.86615 5 P 0 0;1=3
P 10.93661004 3.86615 5 P 0 0;1=3
P 11.03661004 3.86615 5 P 0 0;1=3
P 5.08268002 2.06615 5 P 0 0;1=3
P 10.58661004 2.36615 5 P 0 0;1=3
P 9.975 2.4709 5 P 0 0;1=3
P 12.73621004 4.20866004 10 P 0 0;1=1
P 11.08661004 2.36615 5 P 0 0;1=3
P 5.08268002 2.11615 5 P 0 0;1=3
P 11.08661004 2.41615 5 P 0 0;1=3
P 12.73621004 2.47638002 10 P 0 0;1=1
P 10.58661004 1.96615 5 P 0 0;1=3
P 10.26 1.70445 5 P 0 0;1=3
P 10.98661004 2.41615 5 P 0 0;1=3
P 8.5 3.76615 5 P 0 0;1=3
P 9.35271004 5.1035 5 P 0 0;1=3
P 4.98268002 2.06615 5 P 0 0;1=3
P 8.5 3.81615 5 P 0 0;1=3
P 9.31271004 5.1035 5 P 0 0;1=3
P 12.55905 2.59448996 10 P 0 0;1=1
P 11.53316004 1.572 5 P 0 0;1=3
P 4.98268002 2.11615 5 P 0 0;1=3
P 10.98661004 2.36615 5 P 0 0;1=3
P 8.5 3.61615 5 P 0 0;1=3
P 9.56531004 5.14 5 P 0 0;1=3
P 4.93268002 2.01615 5 P 0 0;1=3
P 11.53316004 1.412 5 P 0 0;1=3
P 12.63778996 2.39763996 10 P 0 0;1=1
P 8.5 3.66615 5 P 0 0;1=3
P 9.52531004 5.14 5 P 0 0;1=3
P 12.73621004 2.87008002 10 P 0 0;1=1
P 10.63661004 2.06615 5 P 0 0;1=3
P 10.225 1.96645 5 P 0 0;1=3
P 11.53316004 1.452 5 P 0 0;1=3
P 12.55905 2.43701004 10 P 0 0;1=1
P 8.35 3.66615 5 P 0 0;1=3
P 9.56531004 4.71973002 5 P 0 0;1=3
P 4.93268002 2.06615 5 P 0 0;1=3
P 8.35 3.71615 5 P 0 0;1=3
P 9.52531004 4.71973002 5 P 0 0;1=3
P 11.83316004 2.212 5 P 0 0;1=3
P 12.63778996 3.65748002 10 P 0 0;1=1
P 12.73621004 3.02756004 10 P 0 0;1=1
P 10.58661004 2.11615 5 P 0 0;1=3
P 10.09 2.05655 5 P 0 0;1=3
P 11.53316004 1.932 5 P 0 0;1=3
P 12.63778996 3.26378002 10 P 0 0;1=1
P 8.74578996 5.14 5 P 0 0;1=3
P 8.05 3.61615 5 P 0 0;1=3
P 12.81495 4.01181004 10 P 0 0;1=1
P 10.09 2.57845 5 P 0 0;1=3
P 10.68661004 2.41615 5 P 0 0;1=3
P 11.73316004 1.492 5 P 0 0;1=3
P 12.63778996 2.24016004 10 P 0 0;1=1
P 8.78578996 5.14 5 P 0 0;1=3
P 8.05 3.66615 5 P 0 0;1=3
P 12.73621004 2.7126 10 P 0 0;1=1
P 10.73661004 2.06615 5 P 0 0;1=3
P 10.26025 1.86845 5 P 0 0;1=3
P 11.03661004 2.46615 5 P 0 0;1=3
P 8.15 3.61615 5 P 0 0;1=3
P 8.88441004 5.17001998 5 P 0 0;1=3
P 12.55905 4.09055 10 P 0 0;1=1
P 11.53316004 2.412 5 P 0 0;1=3
P 11.03661004 2.51615 5 P 0 0;1=3
P 8.15 3.66615 5 P 0 0;1=3
P 8.92441004 5.17001998 5 P 0 0;1=3
P 1.057 5.027 4 P 0 0;1=0
P 12.73621004 3.18503996 10 P 0 0;1=1
P 10.68661004 2.11615 5 P 0 0;1=3
P 10.09 2.17095 5 P 0 0;1=3
P 11.78316004 1.692 5 P 0 0;1=3
P 12.55905 2.04331004 10 P 0 0;1=1
P 12.81495 2.90945 10 P 0 0;1=1
P 10.63661004 2.01615 5 P 0 0;1=3
P 10.225 1.92645 5 P 0 0;1=3
P 11.78316004 1.652 5 P 0 0;1=3
P 12.63778996 2.08268002 10 P 0 0;1=1
P 1.122 5.417 4 P 0 0;1=4
P 5.855 0.925 4 P 0 0;1=4
P 3.88 4.545 4 P 0 0;1=0
P 0.96555 5.78055 4 P 0 0;1=0
P 4.07 4.625 4 P 0 0;1=4
P 10.58661004 2.71615 5 P 0 0;1=3
P 9.91 4.433 4 P 0 0;1=0
P 9.995 2.936 4 P 0 0;1=4
P 11.83316004 2.252 5 P 0 0;1=3
P 12.55905 3.61811004 10 P 0 0;1=1
P 12.81495 3.06693002 10 P 0 0;1=1
P 10.58661004 2.06615 5 P 0 0;1=3
P 10.09 2.01655 5 P 0 0;1=3
P 8.1 3.81615 5 P 0 0;1=3
P 9.10011004 5.0535 5 P 0 0;1=3
P 8.1 3.86615 5 P 0 0;1=3
P 9.14011004 5.0535 5 P 0 0;1=3
P 3.9599 5.395 4 P 0 0;1=0
P 0.88681004 5.78181004 4 P 0 0;1=4
P 12.73621004 2.3189 10 P 0 0;1=1
P 10.63661004 1.91615 5 P 0 0;1=3
P 10.38371998 1.49328002 5 P 0 0;1=3
P 8.35 3.81615 5 P 0 0;1=3
P 9.28185 5.22001998 5 P 0 0;1=3
P 0.72933002 5.463 4 P 0 0;1=0
P 11.53316004 2.572 5 P 0 0;1=3
P 12.55905 4.56298996 10 P 0 0;1=1
P 8.35 3.86615 5 P 0 0;1=3
P 9.24185 5.22001998 5 P 0 0;1=3
P 4.125 2.682 4 P 0 0;1=4
P 3.94 4.42 4 P 0 0;1=0
P 5.03 5.4 4 P 0 0;1=4
P 4.58268002 2.71615 5 P 0 0;1=3
P 8.45 3.81615 5 P 0 0;1=3
P 9.21098002 4.78291998 5 P 0 0;1=3
P 8.45 3.86615 5 P 0 0;1=3
P 9.17098002 4.78291998 5 P 0 0;1=3
P 3.75998996 0.24001004 4 P 0 0;1=0
P 9.55795 0.26133996 4 P 0 0;1=0
P 3.71203002 0.77535 4 P 0 0;1=4
P 3.70998996 0.7 4 P 0 0;1=4
P 9.50795 0.72133002 4 P 0 0;1=4
P 9.46795 0.82631998 4 P 0 0;1=4
P 4.02893002 2.59336998 4 P 0 0;1=4
P 11.395 2.725 4 P 0 0;1=0
P 11.395 2.8 4 P 0 0;1=4
P 11.58613002 2.905 4 P 0 0;1=4
P 11.58613002 2.785 4 P 0 0;1=4
P 1.33906004 4.60351004 4 P 0 0;1=0
P 3.67 4.45 4 P 0 0;1=4
P 3.72 4.545 4 P 0 0;1=4
P 5.37968996 2.8 4 P 0 0;1=4
P 5.387 2.725 4 P 0 0;1=0
P 5.5822 2.785 4 P 0 0;1=4
P 5.5822 2.905 4 P 0 0;1=4
P 7.2426 4.69351004 4 P 0 0;1=4
P 7.2926 4.60351004 4 P 0 0;1=4
P 9.98 4.51 4 P 0 0;1=4
P 10.07286004 2.82336998 4 P 0 0;1=4
P 10.03 4.61 4 P 0 0;1=4
P 1.23906004 4.69351004 4 P 0 0;1=4
P 3.89 4.655 4 P 0 0;1=4
P 3.9899 4.765 4 P 0 0;1=4
P 4.1049 4.86 4 P 0 0;1=4
P 4.0599 5.395 4 P 0 0;1=4
P 3.91 5.51 4 P 0 0;1=4
P 5.125 5.4 4 P 0 0;1=4
P 1.37925 5.78 4 P 0 0;1=4
P 1.45798996 5.78 4 P 0 0;1=4
P 1.42 5.78 4 P 0 0;1=4
P 1.335 5.78 4 P 0 0;1=4
P 12.63778996 2.55511998 10 P 0 0;1=1
P 11.53316004 1.612 5 P 0 0;1=3
P 8.4 3.76615 5 P 0 0;1=3
P 9.28185 4.642 5 P 0 0;1=3
P 12.73621004 4.36613996 10 P 0 0;1=1
P 10.63661004 2.41615 5 P 0 0;1=3
P 9.975 2.66445 5 P 0 0;1=3
P 8.4 3.81615 5 P 0 0;1=3
P 9.24185 4.642 5 P 0 0;1=3
P 11.53316004 2.532 5 P 0 0;1=3
P 12.63778996 4.60236998 10 P 0 0;1=1
P 8.45 3.66615 5 P 0 0;1=3
P 9.42358002 4.78291998 5 P 0 0;1=3
P 0.95951004 5.4595 4 P 0 0;1=0
P 8.45 3.71615 5 P 0 0;1=3
P 9.38358002 4.78291998 5 P 0 0;1=3
P 8.4 3.61615 5 P 0 0;1=3
P 9.49445 4.587 5 P 0 0;1=3
P 8.4 3.66615 5 P 0 0;1=3
P 9.45445 4.587 5 P 0 0;1=3
P 9.07353996 4.42 4 P 0 0;1=4
P 7.1926 5.15351004 4 P 0 0;1=0
P 8.1 3.66615 5 P 0 0;1=3
P 8.74578996 4.667 5 P 0 0;1=3
P 8.1 3.71615 5 P 0 0;1=3
P 8.78578996 4.667 5 P 0 0;1=3
P 8.2 3.66615 5 P 0 0;1=3
P 8.81665 4.78291998 5 P 0 0;1=3
P 8.2 3.71615 5 P 0 0;1=3
P 8.85665 4.78291998 5 P 0 0;1=3
P 8.05 3.76615 5 P 0 0;1=3
P 8.89061998 4.667 5 P 0 0;1=3
P 8.05 3.81615 5 P 0 0;1=3
P 8.93061998 4.667 5 P 0 0;1=3
P 9.02925 4.667 5 P 0 0;1=3
P 8.2 3.81615 5 P 0 0;1=3
P 9.06925 4.667 5 P 0 0;1=3
P 8.2 3.86615 5 P 0 0;1=3
P 4.68268002 2.71615 5 P 0 0;1=3
P 4.98268002 2.71615 5 P 0 0;1=3
P 2.14606004 2.51615 5 P 0 0;1=3
P 8.45 3.41615 5 P 0 0;1=3
P 8.18811004 5.0535 5 P 0 0;1=3
P 5.03268002 3.81615 5 P 0 0;1=3
P 4.07408002 4.01978996 4 P 0 0;1=0
P 8.45 3.46615 5 P 0 0;1=3
P 8.14811004 5.0535 5 P 0 0;1=3
P 5.03268002 2.16615 5 P 0 0;1=3
P 3.9099 5.395 4 P 0 0;1=0
P 8.45 3.26615 5 P 0 0;1=3
P 8.40071004 5.115 5 P 0 0;1=3
P 8.45 3.31615 5 P 0 0;1=3
P 8.36071004 5.115 5 P 0 0;1=3
P 8.35 3.26615 5 P 0 0;1=3
P 8.40071004 4.742 5 P 0 0;1=3
P 8.35 3.31615 5 P 0 0;1=3
P 8.36071004 4.742 5 P 0 0;1=3
P 8.3 3.56615 5 P 0 0;1=3
P 8.05 3.31615 5 P 0 0;1=3
P 7.58118996 5.169 5 P 0 0;1=3
P 8.25 3.56615 5 P 0 0;1=3
P 8.05 3.36615 5 P 0 0;1=3
P 7.62118996 5.169 5 P 0 0;1=3
P 2.24606004 2.86615 5 P 0 0;1=3
P 8.05 2.61615 5 P 0 0;1=3
P 8.05 2.66615 5 P 0 0;1=3
P 8.1 2.46615 5 P 0 0;1=3
P 8.1 2.41615 5 P 0 0;1=3
P 8.2 2.46615 5 P 0 0;1=3
P 8.2 2.41615 5 P 0 0;1=3
P 8.15 2.41615 5 P 0 0;1=3
P 8.15 2.36615 5 P 0 0;1=3
P 8.05 2.41615 5 P 0 0;1=3
P 8.05 2.36615 5 P 0 0;1=3
P 8.2 2.31615 5 P 0 0;1=3
P 8.2 2.26615 5 P 0 0;1=3
P 8.15 2.26615 5 P 0 0;1=3
P 8.15 2.21615 5 P 0 0;1=3
P 8.1 2.31615 5 P 0 0;1=3
P 8.1 2.26615 5 P 0 0;1=3
P 8.05 2.26615 5 P 0 0;1=3
P 8.05 2.21615 5 P 0 0;1=3
P 8.1 2.11615 5 P 0 0;1=3
P 8.1 2.06615 5 P 0 0;1=3
P 8.2 2.11615 5 P 0 0;1=3
P 8.2 2.06615 5 P 0 0;1=3
P 8.15 2.06615 5 P 0 0;1=3
P 8.15 2.01615 5 P 0 0;1=3
P 8.05 2.06615 5 P 0 0;1=3
P 8.05 2.01615 5 P 0 0;1=3
P 8.2 1.96615 5 P 0 0;1=3
P 8.2 1.91615 5 P 0 0;1=3
P 8.15 1.91615 5 P 0 0;1=3
P 8.15 1.86615 5 P 0 0;1=3
P 8.1 1.96615 5 P 0 0;1=3
P 8.1 1.91615 5 P 0 0;1=3
P 8.05 1.91615 5 P 0 0;1=3
P 8.05 1.86615 5 P 0 0;1=3
P 8.1 3.16615 5 P 0 0;1=3
P 8.1 3.11615 5 P 0 0;1=3
P 8.2 3.16615 5 P 0 0;1=3
P 8.2 3.11615 5 P 0 0;1=3
P 8.15 3.11615 5 P 0 0;1=3
P 8.15 3.06615 5 P 0 0;1=3
P 8.05 3.11615 5 P 0 0;1=3
P 8.05 3.06615 5 P 0 0;1=3
P 8.2 3.01615 5 P 0 0;1=3
P 8.2 2.96615 5 P 0 0;1=3
P 8.15 2.96615 5 P 0 0;1=3
P 8.15 2.91615 5 P 0 0;1=3
P 8.1 3.01615 5 P 0 0;1=3
P 8.1 2.96615 5 P 0 0;1=3
P 8.05 2.96615 5 P 0 0;1=3
P 8.05 2.91615 5 P 0 0;1=3
P 8 2.81615 5 P 0 0;1=3
P 8 2.76615 5 P 0 0;1=3
P 8.15 2.81615 5 P 0 0;1=3
P 8.15 2.76615 5 P 0 0;1=3
P 8.2 2.76615 5 P 0 0;1=3
P 8.2 2.71615 5 P 0 0;1=3
P 8.1 2.76615 5 P 0 0;1=3
P 8.1 2.71615 5 P 0 0;1=3
P 8.15 2.66615 5 P 0 0;1=3
P 8.15 2.61615 5 P 0 0;1=3
P 8.2 2.61615 5 P 0 0;1=3
P 8.2 2.56615 5 P 0 0;1=3
P 8.1 2.61615 5 P 0 0;1=3
P 8.1 2.56615 5 P 0 0;1=3
P 8.35 2.56615 5 P 0 0;1=3
P 8.35 2.61615 5 P 0 0;1=3
P 8.35 2.46615 5 P 0 0;1=3
P 8.35 2.41615 5 P 0 0;1=3
P 8.45 2.46615 5 P 0 0;1=3
P 8.45 2.41615 5 P 0 0;1=3
P 8.5 2.41615 5 P 0 0;1=3
P 8.5 2.36615 5 P 0 0;1=3
P 8.4 2.41615 5 P 0 0;1=3
P 8.4 2.36615 5 P 0 0;1=3
P 8.45 2.31615 5 P 0 0;1=3
P 8.45 2.26615 5 P 0 0;1=3
P 8.5 2.26615 5 P 0 0;1=3
P 8.5 2.21615 5 P 0 0;1=3
P 8.4 2.26615 5 P 0 0;1=3
P 8.4 2.21615 5 P 0 0;1=3
P 8.35 2.31615 5 P 0 0;1=3
P 8.35 2.26615 5 P 0 0;1=3
P 8.35 2.11615 5 P 0 0;1=3
P 8.35 2.06615 5 P 0 0;1=3
P 8.45 2.11615 5 P 0 0;1=3
P 8.45 2.06615 5 P 0 0;1=3
P 8.5 2.06615 5 P 0 0;1=3
P 8.5 2.01615 5 P 0 0;1=3
P 8.4 2.06615 5 P 0 0;1=3
P 8.4 2.01615 5 P 0 0;1=3
P 8.45 1.96615 5 P 0 0;1=3
P 8.45 1.91615 5 P 0 0;1=3
P 8.5 1.91615 5 P 0 0;1=3
P 8.5 1.86615 5 P 0 0;1=3
P 8.4 1.91615 5 P 0 0;1=3
P 8.4 1.86615 5 P 0 0;1=3
P 8.35 1.96615 5 P 0 0;1=3
P 8.35 1.91615 5 P 0 0;1=3
P 8.35 3.16615 5 P 0 0;1=3
P 8.35 3.11615 5 P 0 0;1=3
P 8.45 3.16615 5 P 0 0;1=3
P 8.45 3.11615 5 P 0 0;1=3
P 8.5 3.11615 5 P 0 0;1=3
P 8.5 3.06615 5 P 0 0;1=3
P 8.4 3.11615 5 P 0 0;1=3
P 8.4 3.06615 5 P 0 0;1=3
P 8.45 3.01615 5 P 0 0;1=3
P 8.45 2.96615 5 P 0 0;1=3
P 8.5 2.96615 5 P 0 0;1=3
P 8.5 2.91615 5 P 0 0;1=3
P 8.4 2.96615 5 P 0 0;1=3
P 8.4 2.91615 5 P 0 0;1=3
P 8.35 3.01615 5 P 0 0;1=3
P 8.35 2.96615 5 P 0 0;1=3
P 8.4 2.81615 5 P 0 0;1=3
P 8.4 2.76615 5 P 0 0;1=3
P 8.5 2.81615 5 P 0 0;1=3
P 8.5 2.76615 5 P 0 0;1=3
P 8.45 2.76615 5 P 0 0;1=3
P 8.45 2.71615 5 P 0 0;1=3
P 8.35 2.76615 5 P 0 0;1=3
P 8.35 2.71615 5 P 0 0;1=3
P 8.5 2.66615 5 P 0 0;1=3
P 8.5 2.61615 5 P 0 0;1=3
P 8.45 2.61615 5 P 0 0;1=3
P 8.45 2.56615 5 P 0 0;1=3
P 8.4 2.66615 5 P 0 0;1=3
P 8.4 2.61615 5 P 0 0;1=3
P 2.04606004 2.61615 5 P 0 0;1=3
P 2.04606004 2.66615 5 P 0 0;1=3
P 2.09606004 2.46615 5 P 0 0;1=3
P 2.09606004 2.41615 5 P 0 0;1=3
P 2.19606004 2.46615 5 P 0 0;1=3
P 2.19606004 2.41615 5 P 0 0;1=3
P 2.14606004 2.41615 5 P 0 0;1=3
P 2.14606004 2.36615 5 P 0 0;1=3
P 2.04606004 2.41615 5 P 0 0;1=3
P 2.04606004 2.36615 5 P 0 0;1=3
P 2.19606004 2.31615 5 P 0 0;1=3
P 2.19606004 2.26615 5 P 0 0;1=3
P 2.14606004 2.26615 5 P 0 0;1=3
P 2.14606004 2.21615 5 P 0 0;1=3
P 2.09606004 2.31615 5 P 0 0;1=3
P 2.09606004 2.26615 5 P 0 0;1=3
P 2.04606004 2.26615 5 P 0 0;1=3
P 2.04606004 2.21615 5 P 0 0;1=3
P 2.09606004 2.11615 5 P 0 0;1=3
P 2.09606004 2.06615 5 P 0 0;1=3
P 2.19606004 2.11615 5 P 0 0;1=3
P 2.19606004 2.06615 5 P 0 0;1=3
P 2.14606004 2.06615 5 P 0 0;1=3
P 2.14606004 2.01615 5 P 0 0;1=3
P 2.04606004 2.06615 5 P 0 0;1=3
P 2.04606004 2.01615 5 P 0 0;1=3
P 2.19606004 1.96615 5 P 0 0;1=3
P 2.19606004 1.91615 5 P 0 0;1=3
P 2.14606004 1.91615 5 P 0 0;1=3
P 2.14606004 1.86615 5 P 0 0;1=3
P 2.09606004 1.96615 5 P 0 0;1=3
P 2.09606004 1.91615 5 P 0 0;1=3
P 2.04606004 1.91615 5 P 0 0;1=3
P 2.04606004 1.86615 5 P 0 0;1=3
P 2.09606004 3.16615 5 P 0 0;1=3
P 2.09606004 3.11615 5 P 0 0;1=3
P 2.19606004 3.16615 5 P 0 0;1=3
P 2.19606004 3.11615 5 P 0 0;1=3
P 2.14606004 3.11615 5 P 0 0;1=3
P 2.14606004 3.06615 5 P 0 0;1=3
P 2.04606004 3.11615 5 P 0 0;1=3
P 2.04606004 3.06615 5 P 0 0;1=3
P 2.19606004 3.01615 5 P 0 0;1=3
P 2.19606004 2.96615 5 P 0 0;1=3
P 2.14606004 2.96615 5 P 0 0;1=3
P 2.14606004 2.91615 5 P 0 0;1=3
P 2.09606004 3.01615 5 P 0 0;1=3
P 2.09606004 2.96615 5 P 0 0;1=3
P 2.04606004 2.96615 5 P 0 0;1=3
P 2.04606004 2.91615 5 P 0 0;1=3
P 1.99606004 2.81615 5 P 0 0;1=3
P 1.99606004 2.76615 5 P 0 0;1=3
P 2.14606004 2.81615 5 P 0 0;1=3
P 2.14606004 2.76615 5 P 0 0;1=3
P 2.19606004 2.76615 5 P 0 0;1=3
P 2.19606004 2.71615 5 P 0 0;1=3
P 2.09606004 2.76615 5 P 0 0;1=3
P 2.09606004 2.71615 5 P 0 0;1=3
P 2.14606004 2.66615 5 P 0 0;1=3
P 2.14606004 2.61615 5 P 0 0;1=3
P 2.19606004 2.61615 5 P 0 0;1=3
P 2.19606004 2.56615 5 P 0 0;1=3
P 2.09606004 2.61615 5 P 0 0;1=3
P 2.09606004 2.56615 5 P 0 0;1=3
P 2.34606004 2.56615 5 P 0 0;1=3
P 2.34606004 2.61615 5 P 0 0;1=3
P 2.34606004 2.46615 5 P 0 0;1=3
P 2.34606004 2.41615 5 P 0 0;1=3
P 2.44606004 2.46615 5 P 0 0;1=3
P 2.44606004 2.41615 5 P 0 0;1=3
P 2.49606004 2.41615 5 P 0 0;1=3
P 2.49606004 2.36615 5 P 0 0;1=3
P 2.39606004 2.41615 5 P 0 0;1=3
P 2.39606004 2.36615 5 P 0 0;1=3
P 2.44606004 2.31615 5 P 0 0;1=3
P 2.44606004 2.26615 5 P 0 0;1=3
P 2.49606004 2.26615 5 P 0 0;1=3
P 2.49606004 2.21615 5 P 0 0;1=3
P 2.39606004 2.26615 5 P 0 0;1=3
P 2.39606004 2.21615 5 P 0 0;1=3
P 2.34606004 2.31615 5 P 0 0;1=3
P 2.34606004 2.26615 5 P 0 0;1=3
P 2.34606004 2.11615 5 P 0 0;1=3
P 2.34606004 2.06615 5 P 0 0;1=3
P 2.44606004 2.11615 5 P 0 0;1=3
P 2.44606004 2.06615 5 P 0 0;1=3
P 2.49606004 2.06615 5 P 0 0;1=3
P 2.49606004 2.01615 5 P 0 0;1=3
P 2.39606004 2.06615 5 P 0 0;1=3
P 2.39606004 2.01615 5 P 0 0;1=3
P 2.44606004 1.96615 5 P 0 0;1=3
P 2.44606004 1.91615 5 P 0 0;1=3
P 2.49606004 1.91615 5 P 0 0;1=3
P 2.49606004 1.86615 5 P 0 0;1=3
P 2.39606004 1.91615 5 P 0 0;1=3
P 2.39606004 1.86615 5 P 0 0;1=3
P 2.34606004 1.96615 5 P 0 0;1=3
P 2.34606004 1.91615 5 P 0 0;1=3
P 2.34606004 3.16615 5 P 0 0;1=3
P 2.34606004 3.11615 5 P 0 0;1=3
P 2.44606004 3.16615 5 P 0 0;1=3
P 2.44606004 3.11615 5 P 0 0;1=3
P 2.49606004 3.11615 5 P 0 0;1=3
P 2.49606004 3.06615 5 P 0 0;1=3
P 2.39606004 3.11615 5 P 0 0;1=3
P 2.39606004 3.06615 5 P 0 0;1=3
P 2.44606004 3.01615 5 P 0 0;1=3
P 2.44606004 2.96615 5 P 0 0;1=3
P 2.49606004 2.96615 5 P 0 0;1=3
P 2.49606004 2.91615 5 P 0 0;1=3
P 2.39606004 2.96615 5 P 0 0;1=3
P 2.39606004 2.91615 5 P 0 0;1=3
P 2.34606004 3.01615 5 P 0 0;1=3
P 2.34606004 2.96615 5 P 0 0;1=3
P 2.39606004 2.81615 5 P 0 0;1=3
P 2.39606004 2.76615 5 P 0 0;1=3
P 2.49606004 2.81615 5 P 0 0;1=3
P 2.49606004 2.76615 5 P 0 0;1=3
P 2.44606004 2.76615 5 P 0 0;1=3
P 2.44606004 2.71615 5 P 0 0;1=3
P 2.34606004 2.76615 5 P 0 0;1=3
P 2.34606004 2.71615 5 P 0 0;1=3
P 2.49606004 2.66615 5 P 0 0;1=3
P 2.49606004 2.61615 5 P 0 0;1=3
P 2.44606004 2.61615 5 P 0 0;1=3
P 2.44606004 2.56615 5 P 0 0;1=3
P 2.39606004 2.66615 5 P 0 0;1=3
P 2.39606004 2.61615 5 P 0 0;1=3
P 8.94061998 4.70573996 4 P 0 0;1=4
P 9.01925 4.70573996 4 P 0 0;1=4
P 9.07925 4.70573996 4 P 0 0;1=4
P 8.73578996 4.70573996 4 P 0 0;1=4
P 8.79578996 4.70573996 4 P 0 0;1=4
P 8.86665 4.74418002 4 P 0 0;1=4
P 8.80665 4.74418002 4 P 0 0;1=4
P 9.43358002 4.74418002 4 P 0 0;1=4
P 9.51531004 4.68098996 4 P 0 0;1=4
P 9.57531004 4.68098996 4 P 0 0;1=4
P 9.44445 4.62573996 4 P 0 0;1=4
P 9.50445 4.62573996 4 P 0 0;1=4
P 9.23185 4.68073996 4 P 0 0;1=4
P 9.29185 4.68073996 4 P 0 0;1=4
P 9.16098002 4.74418002 4 P 0 0;1=4
P 9.37358002 4.74418002 4 P 0 0;1=4
P 9.22098002 4.74418002 4 P 0 0;1=4
P 9.51531004 5.17873996 4 P 0 0;1=4
P 9.57531004 5.17873996 4 P 0 0;1=4
P 9.43358002 5.18128002 4 P 0 0;1=4
P 9.23185 5.18128002 4 P 0 0;1=4
P 9.29185 5.18128002 4 P 0 0;1=4
P 9.37358002 5.18128002 4 P 0 0;1=4
P 9.36271004 5.14223996 4 P 0 0;1=4
P 9.30271004 5.14223996 4 P 0 0;1=4
P 9.15011004 5.09223996 4 P 0 0;1=4
P 9.09011004 5.09223996 4 P 0 0;1=4
P 9.07925 5.20373996 4 P 0 0;1=4
P 9.01925 5.20373996 4 P 0 0;1=4
P 8.93441004 5.20876004 4 P 0 0;1=4
P 8.73578996 5.17873996 4 P 0 0;1=4
P 8.79578996 5.17873996 4 P 0 0;1=4
P 8.87441004 5.20876004 4 P 0 0;1=4
P 7.64205 4.74418002 4 P 0 0;1=4
P 7.70205 4.74418002 4 P 0 0;1=4
P 7.63118996 4.66826004 4 P 0 0;1=4
P 7.57118996 4.66826004 4 P 0 0;1=4
P 7.91465 4.61826004 4 P 0 0;1=4
P 7.78378996 4.74418002 4 P 0 0;1=4
P 7.84378996 4.74418002 4 P 0 0;1=4
P 7.85465 4.61826004 4 P 0 0;1=4
P 8.06725 4.74418002 4 P 0 0;1=4
P 8.12725 4.74418002 4 P 0 0;1=4
P 8.02206998 4.62815 4 P 0 0;1=4
P 8.08206998 4.62815 4 P 0 0;1=4
P 8.41071004 4.70326004 4 P 0 0;1=4
P 8.35071004 4.70326004 4 P 0 0;1=4
P 8.20898002 4.74418002 4 P 0 0;1=4
P 8.26898002 4.74418002 4 P 0 0;1=4
P 8.21208996 4.62826004 4 P 0 0;1=4
P 8.27208996 4.62826004 4 P 0 0;1=4
P 8.19811004 5.09223996 4 P 0 0;1=4
P 8.12725 5.13026004 4 P 0 0;1=4
P 8.06725 5.13026004 4 P 0 0;1=4
P 7.91465 5.13026004 4 P 0 0;1=4
P 7.92551004 5.09223996 4 P 0 0;1=4
P 7.98551004 5.09223996 4 P 0 0;1=4
P 7.85465 5.13026004 4 P 0 0;1=4
P 7.64203996 5.09223996 4 P 0 0;1=4
P 7.70203996 5.09223996 4 P 0 0;1=4
P 7.57118996 5.13026004 4 P 0 0;1=4
P 7.63118996 5.13026004 4 P 0 0;1=4
P 2.73225 4.70573996 4 P 0 0;1=4
P 2.79225 4.70573996 4 P 0 0;1=4
P 3.22831004 5.18128002 4 P 0 0;1=4
P 3.28831004 5.18128002 4 P 0 0;1=4
P 3.01571004 5.20373996 4 P 0 0;1=4
P 3.07571004 5.20373996 4 P 0 0;1=4
P 2.73225 5.17873996 4 P 0 0;1=4
P 2.79225 5.17873996 4 P 0 0;1=4
P 1.56765 4.66826004 4 P 0 0;1=4
P 1.62765 4.66826004 4 P 0 0;1=4
P 1.56765 5.13026004 4 P 0 0;1=4
P 1.62765 5.13026004 4 P 0 0;1=4
P 1.91111004 5.13026004 4 P 0 0;1=4
P 1.85111004 5.13026004 4 P 0 0;1=4
P 5.08268002 2.76615 5 P 0 0;1=3
P 5.03268002 2.76615 5 P 0 0;1=3
P 5.03268002 2.71615 5 P 0 0;1=3
P 4.93268002 2.76615 5 P 0 0;1=3
P 4.98268002 2.76615 5 P 0 0;1=3
P 4.93268002 2.71615 5 P 0 0;1=3
P 5.08268002 2.66615 5 P 0 0;1=3
P 4.98268002 2.66615 5 P 0 0;1=3
P 5.03268002 2.56615 5 P 0 0;1=3
P 4.93268002 2.56615 5 P 0 0;1=3
P 4.98268002 2.46615 5 P 0 0;1=3
P 4.98268002 2.51615 5 P 0 0;1=3
P 4.93268002 2.51615 5 P 0 0;1=3
P 5.08268002 2.51615 5 P 0 0;1=3
P 5.08268002 2.46615 5 P 0 0;1=3
P 5.03268002 2.21615 5 P 0 0;1=3
P 4.93268002 2.21615 5 P 0 0;1=3
P 4.98268002 2.31615 5 P 0 0;1=3
P 4.93268002 2.36615 5 P 0 0;1=3
P 5.08268002 2.31615 5 P 0 0;1=3
P 5.08268002 2.16615 5 P 0 0;1=3
P 4.93268002 2.16615 5 P 0 0;1=3
P 4.98268002 2.16615 5 P 0 0;1=3
P 4.93268002 1.96615 5 P 0 0;1=3
P 5.03268002 1.96615 5 P 0 0;1=3
P 5.03268002 2.11615 5 P 0 0;1=3
P 4.93268002 2.11615 5 P 0 0;1=3
P 4.98268002 2.01615 5 P 0 0;1=3
P 5.08268002 2.01615 5 P 0 0;1=3
P 4.98268002 1.86615 5 P 0 0;1=3
P 5.08268002 1.86615 5 P 0 0;1=3
P 4.78268002 3.81615 5 P 0 0;1=3
P 4.78268002 3.66615 5 P 0 0;1=3
P 4.73268002 3.81615 5 P 0 0;1=3
P 4.73268002 3.66615 5 P 0 0;1=3
P 4.68268002 3.81615 5 P 0 0;1=3
P 4.68268002 3.66615 5 P 0 0;1=3
P 4.78268002 3.51615 5 P 0 0;1=3
P 4.73268002 3.51615 5 P 0 0;1=3
P 4.68268002 3.51615 5 P 0 0;1=3
P 4.78268002 3.36615 5 P 0 0;1=3
P 4.73268002 3.36615 5 P 0 0;1=3
P 4.78268002 3.21615 5 P 0 0;1=3
P 4.73268002 3.21615 5 P 0 0;1=3
P 4.68268002 3.36615 5 P 0 0;1=3
P 4.68268002 3.21615 5 P 0 0;1=3
P 4.78268002 3.06615 5 P 0 0;1=3
P 4.73268002 3.06615 5 P 0 0;1=3
P 4.68268002 3.06615 5 P 0 0;1=3
P 4.78268002 2.91615 5 P 0 0;1=3
P 4.73268002 2.91615 5 P 0 0;1=3
P 4.68268002 2.91615 5 P 0 0;1=3
P 4.88268002 2.76615 5 P 0 0;1=3
P 4.88268002 2.66615 5 P 0 0;1=3
P 4.78268002 2.46615 5 P 0 0;1=3
P 4.88268002 2.56615 5 P 0 0;1=3
P 4.88268002 2.61615 5 P 0 0;1=3
P 4.68268002 2.46615 5 P 0 0;1=3
P 4.88268002 2.46615 5 P 0 0;1=3
P 4.88268002 2.51615 5 P 0 0;1=3
P 4.78268002 2.41615 5 P 0 0;1=3
P 4.88268002 2.41615 5 P 0 0;1=3
P 4.78268002 2.36615 5 P 0 0;1=3
P 4.78268002 2.31615 5 P 0 0;1=3
P 4.78268002 2.26615 5 P 0 0;1=3
P 4.78268002 2.21615 5 P 0 0;1=3
P 4.73268002 2.36615 5 P 0 0;1=3
P 4.68268002 2.31615 5 P 0 0;1=3
P 4.73268002 2.21615 5 P 0 0;1=3
P 4.88268002 2.21615 5 P 0 0;1=3
P 4.88268002 2.26615 5 P 0 0;1=3
P 4.88268002 2.31615 5 P 0 0;1=3
P 4.88268002 2.36615 5 P 0 0;1=3
P 4.73268002 2.16615 5 P 0 0;1=3
P 4.68268002 2.16615 5 P 0 0;1=3
P 4.78268002 1.96615 5 P 0 0;1=3
P 4.78268002 2.06615 5 P 0 0;1=3
P 4.78268002 2.01615 5 P 0 0;1=3
P 4.88268002 1.96615 5 P 0 0;1=3
P 4.88268002 2.06615 5 P 0 0;1=3
P 4.88268002 2.01615 5 P 0 0;1=3
P 4.78268002 2.11615 5 P 0 0;1=3
P 4.88268002 2.11615 5 P 0 0;1=3
P 4.73268002 2.11615 5 P 0 0;1=3
P 4.68268002 2.01615 5 P 0 0;1=3
P 4.73268002 1.96615 5 P 0 0;1=3
P 4.78268002 1.86615 5 P 0 0;1=3
P 4.88268002 1.86615 5 P 0 0;1=3
P 4.68268002 1.86615 5 P 0 0;1=3
P 4.63268002 3.81615 5 P 0 0;1=3
P 4.63268002 3.66615 5 P 0 0;1=3
P 4.58268002 3.81615 5 P 0 0;1=3
P 4.58268002 3.66615 5 P 0 0;1=3
P 4.63268002 3.51615 5 P 0 0;1=3
P 4.58268002 3.51615 5 P 0 0;1=3
P 4.63268002 3.36615 5 P 0 0;1=3
P 4.58268002 3.36615 5 P 0 0;1=3
P 4.63268002 3.21615 5 P 0 0;1=3
P 4.58268002 3.21615 5 P 0 0;1=3
P 4.63268002 3.06615 5 P 0 0;1=3
P 4.58268002 3.06615 5 P 0 0;1=3
P 4.63268002 2.91615 5 P 0 0;1=3
P 4.58268002 2.91615 5 P 0 0;1=3
P 4.58268002 2.46615 5 P 0 0;1=3
P 4.63268002 2.21615 5 P 0 0;1=3
P 4.58268002 2.31615 5 P 0 0;1=3
P 4.63268002 2.36615 5 P 0 0;1=3
P 4.58268002 2.01615 5 P 0 0;1=3
P 4.63268002 2.11615 5 P 0 0;1=3
P 4.63268002 1.96615 5 P 0 0;1=3
P 4.58268002 1.86615 5 P 0 0;1=3
P 2.04606004 3.41615 5 P 0 0;1=3
P 2.09606004 3.51615 5 P 0 0;1=3
P 3.37003996 5.18128002 4 P 0 0;1=4
P 3.43003996 5.18128002 4 P 0 0;1=4
P 3.29916998 5.14223996 4 P 0 0;1=4
P 3.35916998 5.14223996 4 P 0 0;1=4
P 2.93708002 4.70573996 4 P 0 0;1=4
P 3.07571004 4.70573996 4 P 0 0;1=4
P 3.01571004 4.70573996 4 P 0 0;1=4
P 2.87708002 4.70573996 4 P 0 0;1=4
P 2.93086998 5.20876004 4 P 0 0;1=4
P 2.87086998 5.20876004 4 P 0 0;1=4
P 2.80311004 4.74418002 4 P 0 0;1=4
P 2.86311004 4.74418002 4 P 0 0;1=4
P 3.08656998 5.09223996 4 P 0 0;1=4
P 3.14656998 5.09223996 4 P 0 0;1=4
P 2.26855 4.62826004 4 P 0 0;1=4
P 2.20855 4.62826004 4 P 0 0;1=4
P 2.26543996 4.74418002 4 P 0 0;1=4
P 2.20543996 4.74418002 4 P 0 0;1=4
P 2.34716998 4.70326004 4 P 0 0;1=4
P 2.07853002 4.62815 4 P 0 0;1=4
P 2.01853002 4.62815 4 P 0 0;1=4
P 2.12371004 4.74418002 4 P 0 0;1=4
P 2.06371004 4.74418002 4 P 0 0;1=4
P 2.19456998 5.09223996 4 P 0 0;1=4
P 2.13456998 5.09223996 4 P 0 0;1=4
P 2.12371004 5.13026004 4 P 0 0;1=4
P 2.06371004 5.13026004 4 P 0 0;1=4
P 1.6985 5.09223996 4 P 0 0;1=4
P 1.6385 5.09223996 4 P 0 0;1=4
P 1.85111004 4.61826004 4 P 0 0;1=4
P 1.63851004 4.74418002 4 P 0 0;1=4
P 1.69851004 4.74418002 4 P 0 0;1=4
P 1.98196998 5.09223996 4 P 0 0;1=4
P 1.92196998 5.09223996 4 P 0 0;1=4
P 1.84025 4.74418002 4 P 0 0;1=4
P 1.78025 4.74418002 4 P 0 0;1=4
P 11.03661004 2.71615 5 P 0 0;1=3
P 10.93661004 2.71615 5 P 0 0;1=3
P 11.03661004 2.76615 5 P 0 0;1=3
P 10.98661004 2.76615 5 P 0 0;1=3
P 10.93661004 2.76615 5 P 0 0;1=3
P 11.08661004 2.76615 5 P 0 0;1=3
P 11.03661004 2.56615 5 P 0 0;1=3
P 10.93661004 2.56615 5 P 0 0;1=3
P 10.98661004 2.66615 5 P 0 0;1=3
P 10.98661004 2.51615 5 P 0 0;1=3
P 10.93661004 2.51615 5 P 0 0;1=3
P 11.08661004 2.66615 5 P 0 0;1=3
P 11.08661004 2.51615 5 P 0 0;1=3
P 11.08661004 2.46615 5 P 0 0;1=3
P 10.98661004 2.46615 5 P 0 0;1=3
P 11.08661004 2.31615 5 P 0 0;1=3
P 10.93661004 2.36615 5 P 0 0;1=3
P 10.98661004 2.31615 5 P 0 0;1=3
P 10.93661004 2.21615 5 P 0 0;1=3
P 11.03661004 2.21615 5 P 0 0;1=3
P 11.03661004 2.11615 5 P 0 0;1=3
P 10.93661004 2.11615 5 P 0 0;1=3
P 10.98661004 2.01615 5 P 0 0;1=3
P 10.93661004 1.96615 5 P 0 0;1=3
P 11.03661004 1.96615 5 P 0 0;1=3
P 11.08661004 2.01615 5 P 0 0;1=3
P 10.98661004 2.16615 5 P 0 0;1=3
P 10.93661004 2.16615 5 P 0 0;1=3
P 11.08661004 2.16615 5 P 0 0;1=3
P 10.98661004 1.86615 5 P 0 0;1=3
P 11.08661004 1.86615 5 P 0 0;1=3
P 10.73661004 2.71615 5 P 0 0;1=3
P 10.73661004 2.76615 5 P 0 0;1=3
P 10.88661004 2.76615 5 P 0 0;1=3
P 10.78661004 2.76615 5 P 0 0;1=3
P 10.73661004 2.56615 5 P 0 0;1=3
P 10.68661004 2.66615 5 P 0 0;1=3
P 10.73661004 2.51615 5 P 0 0;1=3
P 10.68661004 2.51615 5 P 0 0;1=3
P 10.88661004 2.61615 5 P 0 0;1=3
P 10.88661004 2.56615 5 P 0 0;1=3
P 10.88661004 2.51615 5 P 0 0;1=3
P 10.78661004 2.56615 5 P 0 0;1=3
P 10.78661004 2.61615 5 P 0 0;1=3
P 10.78661004 2.66615 5 P 0 0;1=3
P 10.78661004 2.51615 5 P 0 0;1=3
P 10.78661004 2.46615 5 P 0 0;1=3
P 10.68661004 2.46615 5 P 0 0;1=3
P 10.88661004 2.46615 5 P 0 0;1=3
P 10.78661004 2.21615 5 P 0 0;1=3
P 10.78661004 2.26615 5 P 0 0;1=3
P 10.78661004 2.31615 5 P 0 0;1=3
P 10.78661004 2.36615 5 P 0 0;1=3
P 10.68661004 2.31615 5 P 0 0;1=3
P 10.73661004 2.36615 5 P 0 0;1=3
P 10.73661004 2.21615 5 P 0 0;1=3
P 10.78661004 2.41615 5 P 0 0;1=3
P 10.88661004 2.36615 5 P 0 0;1=3
P 10.88661004 2.31615 5 P 0 0;1=3
P 10.88661004 2.26615 5 P 0 0;1=3
P 10.88661004 2.21615 5 P 0 0;1=3
P 10.73661004 1.96615 5 P 0 0;1=3
P 10.68661004 2.01615 5 P 0 0;1=3
P 10.73661004 2.11615 5 P 0 0;1=3
P 10.78661004 2.11615 5 P 0 0;1=3
P 10.78661004 2.01615 5 P 0 0;1=3
P 10.78661004 1.96615 5 P 0 0;1=3
P 10.78661004 2.06615 5 P 0 0;1=3
P 10.68661004 2.16615 5 P 0 0;1=3
P 10.73661004 2.16615 5 P 0 0;1=3
P 10.88661004 2.01615 5 P 0 0;1=3
P 10.88661004 2.06615 5 P 0 0;1=3
P 10.88661004 2.11615 5 P 0 0;1=3
P 10.88661004 1.96615 5 P 0 0;1=3
P 10.78661004 1.91615 5 P 0 0;1=3
P 10.68661004 1.86615 5 P 0 0;1=3
P 10.78661004 1.86615 5 P 0 0;1=3
P 10.88661004 1.86615 5 P 0 0;1=3
P 10.63661004 2.71615 5 P 0 0;1=3
P 10.63661004 2.76615 5 P 0 0;1=3
P 10.63661004 2.56615 5 P 0 0;1=3
P 10.58661004 2.66615 5 P 0 0;1=3
P 10.63661004 2.51615 5 P 0 0;1=3
P 10.58661004 2.51615 5 P 0 0;1=3
P 10.58661004 2.46615 5 P 0 0;1=3
P 10.63661004 2.36615 5 P 0 0;1=3
P 10.58661004 2.31615 5 P 0 0;1=3
P 10.58661004 2.01615 5 P 0 0;1=3
P 10.63661004 1.96615 5 P 0 0;1=3
P 10.63661004 2.11615 5 P 0 0;1=3
P 10.58661004 1.86615 5 P 0 0;1=3
P 1.92346004 5.377 4 P 0 0;1=4
P 2.14346004 5.377 4 P 0 0;1=4
P 7.927 5.377 4 P 0 0;1=4
P 8.147 5.377 4 P 0 0;1=4
P 3.43003996 4.74418002 4 P 0 0;1=4
P 3.51176998 4.68098996 4 P 0 0;1=4
P 3.57176998 4.68098996 4 P 0 0;1=4
P 3.21743996 4.74418002 4 P 0 0;1=4
P 3.37003996 4.74418002 4 P 0 0;1=4
P 3.41 5.332 4 P 0 0;1=4
P 5.38048002 1.5957 4 P 0 0;1=4
P 5.38048002 1.7891 4 P 0 0;1=4
P 5.38048002 1.732 4 P 0 0;1=4
P 5.38048002 1.6528 4 P 0 0;1=4
P 5.53531004 1.8603 4 P 0 0;1=4
P 5.53531004 1.8032 4 P 0 0;1=4
P 5.53531004 2.2727 4 P 0 0;1=4
P 5.53531004 2.1373 4 P 0 0;1=4
P 5.53531004 1.9964 4 P 0 0;1=4
P 5.38048002 2.3403 4 P 0 0;1=4
P 5.38048002 2.2832 4 P 0 0;1=4
P 5.38048002 2.2049 4 P 0 0;1=4
P 5.38048002 2.1478 4 P 0 0;1=4
P 5.38048002 2.0642 4 P 0 0;1=4
P 5.38048002 2.0071 4 P 0 0;1=4
P 5.38048002 1.9288 4 P 0 0;1=4
P 5.38048002 1.8717 4 P 0 0;1=4
P 5.53531004 2.351 4 P 0 0;1=4
P 5.38048002 2.4757 4 P 0 0;1=4
P 5.38048002 2.4186 4 P 0 0;1=4
P 5.53531004 2.4902 4 P 0 0;1=4
P 5.53531004 2.6825 4 P 0 0;1=4
P 5.53531004 2.6254 4 P 0 0;1=4
P 5.38048002 2.5578 4 P 0 0;1=4
P 5.38048002 2.6149 4 P 0 0;1=4
P 10.43 1.3341 4 P 0 0;1=4
P 10.43 1.277 4 P 0 0;1=4
P 10.4159 1.43 4 P 0 0;1=4
P 10.473 1.43 4 P 0 0;1=4
P 10.37313996 1.55336004 4 P 0 0;1=4
P 10.41451004 1.51198002 4 P 0 0;1=4
P 10.295 1.713 4 P 0 0;1=4
P 10.295 1.6559 4 P 0 0;1=4
P 10.26 1.9179 4 P 0 0;1=4
P 10.29525 1.877 4 P 0 0;1=4
P 10.29525 1.8199 4 P 0 0;1=4
P 10.26 1.975 4 P 0 0;1=4
P 10.125 2.0651 4 P 0 0;1=4
P 10.125 2.1224 4 P 0 0;1=4
P 10.125 2.1795 4 P 0 0;1=4
P 10.01 2.2481 4 P 0 0;1=4
P 10.01 2.191 4 P 0 0;1=4
P 10.01 2.38435 4 P 0 0;1=4
P 10.01 2.32725 4 P 0 0;1=4
P 10.125 2.3168 4 P 0 0;1=4
P 10.125 2.2597 4 P 0 0;1=4
P 10.125 2.4519 4 P 0 0;1=4
P 10.125 2.3948 4 P 0 0;1=4
P 10.01 2.51945 4 P 0 0;1=4
P 10.01 2.46235 4 P 0 0;1=4
P 10.125 2.587 4 P 0 0;1=4
P 10.125 2.5299 4 P 0 0;1=4
P 10.01 2.673 4 P 0 0;1=4
P 10.01 2.6159 4 P 0 0;1=4
P 11.74316004 1.7035 4 P 0 0;1=4
P 11.74316004 1.6405 4 P 0 0;1=4
P 11.69316004 1.4805 4 P 0 0;1=4
P 11.69316004 1.5435 4 P 0 0;1=4
P 11.49316004 1.5605 4 P 0 0;1=4
P 11.49316004 1.6235 4 P 0 0;1=4
P 11.49316004 1.4635 4 P 0 0;1=4
P 11.49366004 1.401 4 P 0 0;1=4
P 11.69316004 2.6005 4 P 0 0;1=4
P 11.69316004 2.5035 4 P 0 0;1=4
P 11.69316004 2.4405 4 P 0 0;1=4
P 11.69316004 2.3435 4 P 0 0;1=4
P 11.69316004 2.2805 4 P 0 0;1=4
P 11.69316004 2.1835 4 P 0 0;1=4
P 11.69316004 1.9605 4 P 0 0;1=4
P 11.69316004 2.0235 4 P 0 0;1=4
P 11.69316004 2.1205 4 P 0 0;1=4
P 11.69316004 1.8005 4 P 0 0;1=4
P 11.69316004 1.8635 4 P 0 0;1=4
P 11.49316004 2.5205 4 P 0 0;1=4
P 11.49316004 2.5835 4 P 0 0;1=4
P 11.49316004 2.4235 4 P 0 0;1=4
P 11.49316004 2.3605 4 P 0 0;1=4
P 11.79316004 2.2635 4 P 0 0;1=4
P 11.79316004 2.2005 4 P 0 0;1=4
P 11.49316004 1.9435 4 P 0 0;1=4
P 11.49316004 2.1035 4 P 0 0;1=4
P 11.49316004 2.0405 4 P 0 0;1=4
P 11.49316004 1.8805 4 P 0 0;1=4
P 11.49366004 1.721 4 P 0 0;1=4
P 11.49316004 1.7835 4 P 0 0;1=4
P 10.125 2.7451 4 P 0 0;1=4
P 10.125 2.688 4 P 0 0;1=4
P 12.34 2.19 4 P 0 0;1=4
P 9.415 5.332 4 P 0 0;1=4
P 9.265 5.332 4 P 0 0;1=4
P 9.07 5.332 4 P 0 0;1=4
P 4.7 5.54928996 4 P 0 0;1=4
P 4.81 5.375 4 P 0 0;1=4
P 4.96 5.375 4 P 0 0;1=4
P 5.16 5.645 4 P 0 0;1=4
P 5.04441004 5.605 4 P 0 0;1=4
P 4.92 5.7 4 P 0 0;1=4
P 9.91 4.7 4 P 0 0;1=4
P 3.57 4.45 4 P 0 0;1=4
P 10.465 5.195 4 P 0 0;1=4
P 10.515 5.32 4 P 0 0;1=4
P 10.465 5.275 4 P 0 0;1=4
P 12.025 4.915 4 P 0 0;1=4
P 12.12 4.965 4 P 0 0;1=4
P 12.185 4.915 4 P 0 0;1=4
P 3.72 4.45 4 P 0 0;1=4
P 3.66 4.63 4 P 0 0;1=4
P 3.77 4.86 4 P 0 0;1=4
P 9.96 4.69 4 P 0 0;1=4
P 10.03 4.51 4 P 0 0;1=4
P 3.835 4.6 4 P 0 0;1=4
P 3.9865 4.635 4 P 0 0;1=4
P 4.14 4.655 4 P 0 0;1=4
P 4.1049 4.7649 4 P 0 0;1=4
P 1.28051004 5.78 4 P 0 0;1=4
P 3.87 5.125 4 P 0 0;1=4
P 0.4826 5.8976 4 P 0 0;1=4
P 0.84953002 5.17 4 P 0 0;1=4
P 0.955 5.325 4 P 0 0;1=4
P 1.31 5.355 4 P 0 0;1=4
P 1.20176998 5.78 4 P 0 0;1=4
P 6.31295 4.99705 4 P 0 0;1=4
P 6.87 5 4 P 0 0;1=4
P 9.64796004 0.79643002 4 P 0 0;1=4
P 9.40795 0.26133002 4 P 0 0;1=4
P 3.60998996 0.24 4 P 0 0;1=4
P 3.65998996 0.345 4 P 0 0;1=4
P 3.86 0.7751 4 P 0 0;1=0
P 6.905 4.94705 4 P 0 0;1=4
P 6.905 4.88705 4 P 0 0;1=4
P 6.955 4.8 4 P 0 0;1=4
P 6.955 4.84 4 P 0 0;1=4
P 6.955 4.72 4 P 0 0;1=4
P 6.955 4.76 4 P 0 0;1=4
P 6.59708996 5.0502 4 P 0 0;1=4
P 6.65218996 4.77 4 P 0 0;1=4
P 6.62118996 4.95641998 4 P 0 0;1=8
P 6.6015 4.93673996 4 P 0 0;1=8
P 6.64088002 4.93673996 4 P 0 0;1=8
P 6.62118996 4.91705 4 P 0 0;1=8
P 6.62118996 4.87768002 4 P 0 0;1=8
P 6.6015 4.89736004 4 P 0 0;1=8
P 6.64088002 4.89736004 4 P 0 0;1=8
P 6.62 4.69 4 P 0 0;1=4
P 6.62 4.725 4 P 0 0;1=4
P 6.385 5.07 4 P 0 0;1=4
P 5.53593996 4.55505 4 P 0 0;1=4
P 6.05708996 4.5102 4 P 0 0;1=4
P 6.01708996 4.5102 4 P 0 0;1=4
P 5.97708996 4.5102 4 P 0 0;1=4
P 5.93708996 4.5102 4 P 0 0;1=4
P 5.89708996 4.5102 4 P 0 0;1=4
P 6.09708996 4.5102 4 P 0 0;1=4
P 5.61708996 4.5102 4 P 0 0;1=4
P 5.65708996 4.5102 4 P 0 0;1=4
P 5.85708996 4.5102 4 P 0 0;1=4
P 5.81708996 4.5102 4 P 0 0;1=4
P 5.77708996 4.5102 4 P 0 0;1=4
P 5.73708996 4.5102 4 P 0 0;1=4
P 5.69708996 4.5102 4 P 0 0;1=4
P 5.57708996 4.5102 4 P 0 0;1=4
P 0.036 0.10868002 4 P 0 0;1=4
P 0.036 0.15868002 4 P 0 0;1=4
P 0.036 0.20868002 4 P 0 0;1=4
P 0.22873996 0.036 4 P 0 0;1=4
P 0.17873996 0.036 4 P 0 0;1=4
P 0.12873996 0.036 4 P 0 0;1=4
P 0.07873996 0.036 4 P 0 0;1=4
P 0.47873996 0.036 4 P 0 0;1=4
P 0.42873996 0.036 4 P 0 0;1=4
P 0.37873996 0.036 4 P 0 0;1=4
P 0.32873996 0.036 4 P 0 0;1=4
P 0.27873996 0.036 4 P 0 0;1=4
P 0.77873996 0.036 4 P 0 0;1=4
P 0.72873996 0.036 4 P 0 0;1=4
P 0.67873996 0.036 4 P 0 0;1=4
P 0.62873996 0.036 4 P 0 0;1=4
P 0.57873996 0.036 4 P 0 0;1=4
P 0.52873996 0.036 4 P 0 0;1=4
P 1.02873996 0.036 4 P 0 0;1=4
P 0.97873996 0.036 4 P 0 0;1=4
P 0.92873996 0.036 4 P 0 0;1=4
P 0.87873996 0.036 4 P 0 0;1=4
P 0.82873996 0.036 4 P 0 0;1=4
P 1.27873996 0.036 4 P 0 0;1=4
P 1.22873996 0.036 4 P 0 0;1=4
P 1.17873996 0.036 4 P 0 0;1=4
P 1.12873996 0.036 4 P 0 0;1=4
P 1.07873996 0.036 4 P 0 0;1=4
P 1.52873996 0.036 4 P 0 0;1=4
P 1.47873996 0.036 4 P 0 0;1=4
P 1.42873996 0.036 4 P 0 0;1=4
P 1.37873996 0.036 4 P 0 0;1=4
P 1.32873996 0.036 4 P 0 0;1=4
P 1.82873996 0.036 4 P 0 0;1=4
P 1.77873996 0.036 4 P 0 0;1=4
P 1.72873996 0.036 4 P 0 0;1=4
P 1.67873996 0.036 4 P 0 0;1=4
P 1.62873996 0.036 4 P 0 0;1=4
P 1.57873996 0.036 4 P 0 0;1=4
P 2.07873996 0.036 4 P 0 0;1=4
P 2.02873996 0.036 4 P 0 0;1=4
P 1.97873996 0.036 4 P 0 0;1=4
P 1.92873996 0.036 4 P 0 0;1=4
P 1.87873996 0.036 4 P 0 0;1=4
P 2.32873996 0.036 4 P 0 0;1=4
P 2.27873996 0.036 4 P 0 0;1=4
P 2.22873996 0.036 4 P 0 0;1=4
P 2.17873996 0.036 4 P 0 0;1=4
P 2.12873996 0.036 4 P 0 0;1=4
P 2.62873996 0.036 4 P 0 0;1=4
P 2.57873996 0.036 4 P 0 0;1=4
P 2.52873996 0.036 4 P 0 0;1=4
P 2.47873996 0.036 4 P 0 0;1=4
P 2.42873996 0.036 4 P 0 0;1=4
P 2.37873996 0.036 4 P 0 0;1=4
P 2.87873996 0.036 4 P 0 0;1=4
P 2.82873996 0.036 4 P 0 0;1=4
P 2.77873996 0.036 4 P 0 0;1=4
P 2.72873996 0.036 4 P 0 0;1=4
P 2.67873996 0.036 4 P 0 0;1=4
P 3.12873996 0.036 4 P 0 0;1=4
P 3.07873996 0.036 4 P 0 0;1=4
P 3.02873996 0.036 4 P 0 0;1=4
P 2.97873996 0.036 4 P 0 0;1=4
P 2.92873996 0.036 4 P 0 0;1=4
P 3.37873996 0.036 4 P 0 0;1=4
P 3.32873996 0.036 4 P 0 0;1=4
P 3.27873996 0.036 4 P 0 0;1=4
P 3.22873996 0.036 4 P 0 0;1=4
P 3.17873996 0.036 4 P 0 0;1=4
P 3.67873996 0.036 4 P 0 0;1=4
P 3.62873996 0.036 4 P 0 0;1=4
P 3.57873996 0.036 4 P 0 0;1=4
P 3.52873996 0.036 4 P 0 0;1=4
P 3.47873996 0.036 4 P 0 0;1=4
P 3.42873996 0.036 4 P 0 0;1=4
P 3.92873996 0.036 4 P 0 0;1=4
P 3.87873996 0.036 4 P 0 0;1=4
P 3.82873996 0.036 4 P 0 0;1=4
P 3.77873996 0.036 4 P 0 0;1=4
P 3.72873996 0.036 4 P 0 0;1=4
P 4.17873996 0.036 4 P 0 0;1=4
P 4.12873996 0.036 4 P 0 0;1=4
P 4.07873996 0.036 4 P 0 0;1=4
P 4.02873996 0.036 4 P 0 0;1=4
P 3.97873996 0.036 4 P 0 0;1=4
P 4.42873996 0.036 4 P 0 0;1=4
P 4.37873996 0.036 4 P 0 0;1=4
P 4.32873996 0.036 4 P 0 0;1=4
P 4.27873996 0.036 4 P 0 0;1=4
P 4.22873996 0.036 4 P 0 0;1=4
P 4.72873996 0.036 4 P 0 0;1=4
P 4.67873996 0.036 4 P 0 0;1=4
P 4.62873996 0.036 4 P 0 0;1=4
P 4.57873996 0.036 4 P 0 0;1=4
P 4.52873996 0.036 4 P 0 0;1=4
P 4.47873996 0.036 4 P 0 0;1=4
P 4.81833996 0.21825 4 P 0 0;1=4
P 4.81833996 0.16825 4 P 0 0;1=4
P 4.81833996 0.11825 4 P 0 0;1=4
P 4.81703996 0.06826004 4 P 0 0;1=4
P 4.77873996 0.03611998 4 P 0 0;1=4
P 6.80731004 0.036 4 P 0 0;1=4
P 6.75731004 0.036 4 P 0 0;1=4
P 6.70731004 0.036 4 P 0 0;1=4
P 6.65731004 0.03676004 4 P 0 0;1=4
P 6.62298996 0.07311998 4 P 0 0;1=4
P 6.62261998 0.12311998 4 P 0 0;1=4
P 6.62261998 0.17311998 4 P 0 0;1=4
P 6.62261998 0.22311998 4 P 0 0;1=4
P 7.00731004 0.036 4 P 0 0;1=4
P 6.95731004 0.036 4 P 0 0;1=4
P 6.90731004 0.036 4 P 0 0;1=4
P 6.85731004 0.036 4 P 0 0;1=4
P 0.036 0.25868002 4 P 0 0;1=4
P 0.036 0.30868002 4 P 0 0;1=4
P 0.036 0.35868002 4 P 0 0;1=4
P 0.036 0.40868002 4 P 0 0;1=4
P 0.036 0.45868002 4 P 0 0;1=4
P 4.96803996 0.46906998 4 P 0 0;1=4
P 4.91805 0.46808002 4 P 0 0;1=4
P 4.87108996 0.45088996 4 P 0 0;1=4
P 4.83591004 0.41536004 4 P 0 0;1=4
P 4.81918996 0.36823996 4 P 0 0;1=4
P 4.81833996 0.31825 4 P 0 0;1=4
P 4.81833996 0.26825 4 P 0 0;1=4
P 5.21803996 0.46906998 4 P 0 0;1=4
P 5.16803996 0.46906998 4 P 0 0;1=4
P 5.11803996 0.46906998 4 P 0 0;1=4
P 5.06803996 0.46906998 4 P 0 0;1=4
P 5.01803996 0.46906998 4 P 0 0;1=4
P 5.51803996 0.46906998 4 P 0 0;1=4
P 5.46803996 0.46906998 4 P 0 0;1=4
P 5.41803996 0.46906998 4 P 0 0;1=4
P 5.36803996 0.46906998 4 P 0 0;1=4
P 5.31803996 0.46906998 4 P 0 0;1=4
P 5.26803996 0.46906998 4 P 0 0;1=4
P 5.76803996 0.46906998 4 P 0 0;1=4
P 5.71803996 0.46906998 4 P 0 0;1=4
P 5.66803996 0.46906998 4 P 0 0;1=4
P 5.61803996 0.46906998 4 P 0 0;1=4
P 5.56803996 0.46906998 4 P 0 0;1=4
P 6.01803996 0.46906998 4 P 0 0;1=4
P 5.96803996 0.46906998 4 P 0 0;1=4
P 5.91803996 0.46906998 4 P 0 0;1=4
P 5.86803996 0.46906998 4 P 0 0;1=4
P 5.81803996 0.46906998 4 P 0 0;1=4
P 6.31803996 0.46906998 4 P 0 0;1=4
P 6.26803996 0.46906998 4 P 0 0;1=4
P 6.21803996 0.46906998 4 P 0 0;1=4
P 6.16803996 0.46906998 4 P 0 0;1=4
P 6.11803996 0.46906998 4 P 0 0;1=4
P 6.06803996 0.46906998 4 P 0 0;1=4
P 6.56568002 0.45345 4 P 0 0;1=4
P 6.51803002 0.46861998 4 P 0 0;1=4
P 6.46803996 0.46906998 4 P 0 0;1=4
P 6.41803996 0.46906998 4 P 0 0;1=4
P 6.36803996 0.46906998 4 P 0 0;1=4
P 6.62261998 0.27311998 4 P 0 0;1=4
P 6.62261998 0.32311998 4 P 0 0;1=4
P 6.62106998 0.3731 4 P 0 0;1=4
P 6.60233996 0.41946004 4 P 0 0;1=4
P 0.036 0.50868002 4 P 0 0;1=4
P 0.036 0.55868002 4 P 0 0;1=4
P 11.845 2.85 4 P 0 0;1=4
P 8.98115 2.7861 4 P 0 0;1=4
P 8.98115 2.8989 4 P 0 0;1=4
P 11.58613002 2.855 4 P 0 0;1=4
P 11.50361998 2.8 4 P 0 0;1=4
P 11.50361998 2.73 4 P 0 0;1=4
P 5.5722 3 4 P 0 0;1=4
P 5.75778996 3.02558996 4 P 0 0;1=4
P 5.9192 2.943 4 P 0 0;1=4
P 4.07386004 2.55 4 P 0 0;1=4
P 3.86826998 2.64558996 4 P 0 0;1=4
P 9.995 2.87558996 4 P 0 0;1=4
P 10.11778996 2.78 4 P 0 0;1=4
P 7.2426 4.60351004 4 P 0 0;1=4
P 7.3401 4.85601004 4 P 0 0;1=4
P 7.1926 5.04351004 4 P 0 0;1=4
P 0.66 2.045 4 P 0 0;1=0
P 1.792 2.4781 4 P 0 0;1=4
P 2.97721004 2.8989 4 P 0 0;1=4
P 2.97721004 2.7861 4 P 0 0;1=4
P 2.9422 2.925 4 P 0 0;1=4
P 8.94278996 2.925 4 P 0 0;1=4
P 5.5822 2.855 4 P 0 0;1=4
P 5.84968996 2.85 4 P 0 0;1=4
P 0.65348996 1.85608996 4 P 0 0;1=4
P 0.65348996 1.91628996 4 P 0 0;1=4
P 0.09448996 4.60236998 10 P 0 0;1=1
P 0.35038996 4.20866004 10 P 0 0;1=1
P 0.09448996 4.2874 10 P 0 0;1=1
P 0.09448996 4.12991998 10 P 0 0;1=1
P 0.17323002 4.16928996 10 P 0 0;1=1
P 0.27165 4.09055 10 P 0 0;1=1
P 0.27165 3.93306998 10 P 0 0;1=1
P 0.35038996 4.05118002 10 P 0 0;1=1
P 0.35038996 3.8937 10 P 0 0;1=1
P 0.09448996 3.97243996 10 P 0 0;1=1
P 0.09448996 3.81496004 10 P 0 0;1=1
P 0.17323002 4.01181004 10 P 0 0;1=1
P 0.17323002 3.85433002 10 P 0 0;1=1
P 0.27165 3.77558996 10 P 0 0;1=1
P 0.27165 3.61811004 10 P 0 0;1=1
P 0.35038996 3.73621998 10 P 0 0;1=1
P 0.35038996 3.57873996 10 P 0 0;1=1
P 0.09448996 3.65748002 10 P 0 0;1=1
P 0.09448996 3.5 10 P 0 0;1=1
P 0.17323002 3.69685 10 P 0 0;1=1
P 0.17323002 3.53936998 10 P 0 0;1=1
P 0.27165 3.46063002 10 P 0 0;1=1
P 0.35038996 3.42126004 10 P 0 0;1=1
P 0.27165 3.30315 10 P 0 0;1=1
P 0.27165 3.22441004 10 P 0 0;1=1
P 0.17323002 3.38188996 10 P 0 0;1=1
P 0.17323002 3.30315 10 P 0 0;1=1
P 0.35038996 3.1063 10 P 0 0;1=1
P 0.35038996 2.94881998 10 P 0 0;1=1
P 0.27165 3.06693002 10 P 0 0;1=1
P 0.27165 2.90945 10 P 0 0;1=1
P 0.17323002 3.14566998 10 P 0 0;1=1
P 0.17323002 2.98818996 10 P 0 0;1=1
P 0.09448996 3.18503996 10 P 0 0;1=1
P 0.09448996 3.02756004 10 P 0 0;1=1
P 0.35038996 2.79133996 10 P 0 0;1=1
P 0.27165 2.75196998 10 P 0 0;1=1
P 0.35038996 2.63386004 10 P 0 0;1=1
P 0.17323002 2.83071004 10 P 0 0;1=1
P 0.09448996 2.87008002 10 P 0 0;1=1
P 0.09448996 2.7126 10 P 0 0;1=1
P 0.35038996 2.39763996 10 P 0 0;1=1
P 0.27165 2.51575 10 P 0 0;1=1
P 0.27165 2.35826998 10 P 0 0;1=1
P 0.17323002 2.59448996 10 P 0 0;1=1
P 0.17323002 2.43701004 10 P 0 0;1=1
P 0.09448996 2.47638002 10 P 0 0;1=1
P 0.09448996 2.3189 10 P 0 0;1=1
P 0.35038996 2.24016004 10 P 0 0;1=1
P 0.35038996 2.08268002 10 P 0 0;1=1
P 0.35038996 2.00393996 10 P 0 0;1=1
P 0.27165 2.20078996 10 P 0 0;1=1
P 0.17323002 2.27953002 10 P 0 0;1=1
P 0.09448996 2.16141998 10 P 0 0;1=1
P 0.09448996 2.08268002 10 P 0 0;1=1
P 0.17323002 1.96456998 10 P 0 0;1=1
P 0.09448996 1.84646004 10 P 0 0;1=1
P 0.09448996 4.44488002 10 P 0 0;1=1
P 12.63778996 2.00393996 10 P 0 0;1=1
P 12.55905 2.12205 10 P 0 0;1=1
P 12.55905 1.88583002 10 P 0 0;1=1
P 12.81495 2.12205 10 P 0 0;1=1
P 12.81495 2.04331004 10 P 0 0;1=1
P 12.73621004 2.39763996 10 P 0 0;1=1
P 12.73621004 2.24016004 10 P 0 0;1=1
P 12.63778996 2.3189 10 P 0 0;1=1
P 12.55905 2.35826998 10 P 0 0;1=1
P 12.55905 2.20078996 10 P 0 0;1=1
P 12.81495 2.43701004 10 P 0 0;1=1
P 12.81495 2.27953002 10 P 0 0;1=1
P 12.73621004 2.55511998 10 P 0 0;1=1
P 12.63778996 2.63386004 10 P 0 0;1=1
P 12.63778996 2.47638002 10 P 0 0;1=1
P 12.55905 2.51575 10 P 0 0;1=1
P 12.81495 2.67323002 10 P 0 0;1=1
P 12.73621004 2.94881998 10 P 0 0;1=1
P 12.73621004 2.79133996 10 P 0 0;1=1
P 12.63778996 3.02756004 10 P 0 0;1=1
P 12.63778996 2.87008002 10 P 0 0;1=1
P 12.55905 2.90945 10 P 0 0;1=1
P 12.55905 2.75196998 10 P 0 0;1=1
P 12.81495 2.98818996 10 P 0 0;1=1
P 12.81495 2.83071004 10 P 0 0;1=1
P 12.73621004 3.26378002 10 P 0 0;1=1
P 12.73621004 3.1063 10 P 0 0;1=1
P 12.63778996 3.18503996 10 P 0 0;1=1
P 12.55905 3.22441004 10 P 0 0;1=1
P 12.55905 3.06693002 10 P 0 0;1=1
P 12.81495 3.14566998 10 P 0 0;1=1
P 12.55905 3.53936998 10 P 0 0;1=1
P 12.63778996 3.57873996 10 P 0 0;1=1
P 12.63778996 3.42126004 10 P 0 0;1=1
P 12.73621004 3.5 10 P 0 0;1=1
P 12.73621004 3.34251998 10 P 0 0;1=1
P 12.63778996 3.34251998 10 P 0 0;1=1
P 12.81495 3.61811004 10 P 0 0;1=1
P 12.81495 3.46063002 10 P 0 0;1=1
P 12.55905 3.85433002 10 P 0 0;1=1
P 12.55905 3.69685 10 P 0 0;1=1
P 12.63778996 3.8937 10 P 0 0;1=1
P 12.63778996 3.73621998 10 P 0 0;1=1
P 12.73621004 3.81496004 10 P 0 0;1=1
P 12.73621004 3.65748002 10 P 0 0;1=1
P 12.81495 3.93306998 10 P 0 0;1=1
P 12.81495 3.77558996 10 P 0 0;1=1
P 12.55905 4.16928996 10 P 0 0;1=1
P 12.55905 4.01181004 10 P 0 0;1=1
P 12.63778996 4.20866004 10 P 0 0;1=1
P 12.63778996 4.05118002 10 P 0 0;1=1
P 12.73621004 4.12991998 10 P 0 0;1=1
P 12.73621004 3.97243996 10 P 0 0;1=1
P 12.81495 4.09055 10 P 0 0;1=1
P 12.55905 4.48425 10 P 0 0;1=1
P 12.55905 4.32676998 10 P 0 0;1=1
P 12.63778996 4.52361998 10 P 0 0;1=1
P 12.63778996 4.36613996 10 P 0 0;1=1
P 12.73621004 4.44488002 10 P 0 0;1=1
P 12.73621004 4.2874 10 P 0 0;1=1
P 12.81495 4.40551004 10 P 0 0;1=1
P 12.81495 4.24803002 10 P 0 0;1=1
P 12.55905 4.64173996 10 P 0 0;1=1
P 12.81495 4.56298996 10 P 0 0;1=1
P 0.27165 4.40551004 10 P 0 0;1=1
P 0.35038996 4.52361998 10 P 0 0;1=1
P 0.17323002 4.48425 10 P 0 0;1=1
P 0.27165 4.24803002 10 P 0 0;1=1
P 0.35038996 4.36613996 10 P 0 0;1=1
P 0.17323002 4.32676998 10 P 0 0;1=1
P 5.49221004 2.73 4 P 0 0;1=4
P 5.44886004 2.9414 4 P 0 0;1=4
P 5.44886004 3.0214 4 P 0 0;1=4
P 5.44886004 3.0564 4 P 0 0;1=4
P 5.44886004 3.1014 4 P 0 0;1=4
P 5.44886004 3.1364 4 P 0 0;1=4
P 5.44886004 3.2164 4 P 0 0;1=4
P 5.44886004 3.1814 4 P 0 0;1=4
P 5.44886004 2.9764 4 P 0 0;1=4
P 5.44886004 3.2614 4 P 0 0;1=4
P 5.44886004 3.2964 4 P 0 0;1=4
P 10.33998996 4.9231 4 P 0 0;1=4
P 10.38498996 4.9231 4 P 0 0;1=0
P 10.77498996 4.9231 4 P 0 0;1=4
P 10.72998996 4.9231 4 P 0 0;1=4
P 10.30498996 4.9431 4 P 0 0;1=4
P 10.26498996 4.9431 4 P 0 0;1=4
P 10.30498996 5.0281 4 P 0 0;1=4
P 10.30498996 5.0731 4 P 0 0;1=4
P 10.30498996 4.9831 4 P 0 0;1=4
P 10.26498996 5.0281 4 P 0 0;1=4
P 10.26498996 5.0731 4 P 0 0;1=4
P 10.26498996 4.9831 4 P 0 0;1=4
P 10.26498996 5.1181 4 P 0 0;1=4
P 10.30498996 5.1181 4 P 0 0;1=4
P 10.34498996 5.1181 4 P 0 0;1=4
P 10.42498996 4.9431 4 P 0 0;1=4
P 10.46498996 4.9431 4 P 0 0;1=4
P 10.38498996 5.1181 4 P 0 0;1=4
P 10.46498996 5.1181 4 P 0 0;1=4
P 10.42498996 5.1181 4 P 0 0;1=4
P 10.42498996 4.9831 4 P 0 0;1=4
P 10.42498996 5.0731 4 P 0 0;1=4
P 10.42498996 5.0281 4 P 0 0;1=4
P 10.46498996 4.9831 4 P 0 0;1=4
P 10.46498996 5.0731 4 P 0 0;1=4
P 10.46498996 5.0281 4 P 0 0;1=4
P 10.85498996 4.9431 4 P 0 0;1=4
P 10.81498996 4.9431 4 P 0 0;1=4
P 10.65498996 4.9431 4 P 0 0;1=4
P 10.69498996 4.9431 4 P 0 0;1=4
P 10.85498996 5.0281 4 P 0 0;1=4
P 10.85498996 5.0731 4 P 0 0;1=4
P 10.85498996 4.9831 4 P 0 0;1=4
P 10.81498996 5.0281 4 P 0 0;1=4
P 10.81498996 5.0731 4 P 0 0;1=4
P 10.81498996 4.9831 4 P 0 0;1=4
P 10.81498996 5.1181 4 P 0 0;1=4
P 10.85498996 5.1181 4 P 0 0;1=4
P 10.73498996 5.1181 4 P 0 0;1=4
P 10.69498996 5.1181 4 P 0 0;1=4
P 10.65498996 5.1181 4 P 0 0;1=4
P 10.77498996 5.1181 4 P 0 0;1=4
P 10.65498996 4.9831 4 P 0 0;1=4
P 10.65498996 5.0731 4 P 0 0;1=4
P 10.65498996 5.0281 4 P 0 0;1=4
P 10.69498996 4.9831 4 P 0 0;1=4
P 10.69498996 5.0731 4 P 0 0;1=4
P 10.69498996 5.0281 4 P 0 0;1=4
P 1.23906004 4.60351004 4 P 0 0;1=4
P 1.18906004 5.04351004 4 P 0 0;1=4
P 1.33656004 4.85601004 4 P 0 0;1=4
P 10.16606998 2.81 4 P 0 0;1=4
P 4.15221004 2.9281 4 P 0 0;1=4
P 11.45278996 2.9414 4 P 0 0;1=4
P 11.45278996 3.0214 4 P 0 0;1=4
P 11.45278996 3.0564 4 P 0 0;1=4
P 11.45278996 3.1014 4 P 0 0;1=4
P 11.45278996 3.1364 4 P 0 0;1=4
P 11.45278996 3.2164 4 P 0 0;1=4
P 11.45278996 3.1814 4 P 0 0;1=4
P 11.45278996 2.9764 4 P 0 0;1=4
P 11.45278996 3.2614 4 P 0 0;1=4
P 11.45278996 3.2964 4 P 0 0;1=4
P 0.09448996 1.45276004 10 P 0 0;1=1
P 0.27165 1.57086998 10 P 0 0;1=1
P 0.35038996 1.45276004 10 P 0 0;1=1
P 12.81495 1.49213002 10 P 0 0;1=1
P 12.73621004 1.61023996 10 P 0 0;1=1
P 12.55905 1.49213002 10 P 0 0;1=1
P 0.27165 1.88583002 10 P 0 0;1=1
P 12.73621004 1.9252 10 P 0 0;1=1
P 7.35731004 0.036 4 P 0 0;1=4
P 7.60731004 0.036 4 P 0 0;1=4
P 7.55731004 0.036 4 P 0 0;1=4
P 7.50731004 0.036 4 P 0 0;1=4
P 7.45731004 0.036 4 P 0 0;1=4
P 7.40731004 0.036 4 P 0 0;1=4
P 7.85731004 0.036 4 P 0 0;1=4
P 7.80731004 0.036 4 P 0 0;1=4
P 7.75731004 0.036 4 P 0 0;1=4
P 7.70731004 0.036 4 P 0 0;1=4
P 7.65731004 0.036 4 P 0 0;1=4
P 8.15731004 0.036 4 P 0 0;1=4
P 8.10731004 0.036 4 P 0 0;1=4
P 8.05731004 0.036 4 P 0 0;1=4
P 8.00731004 0.036 4 P 0 0;1=4
P 7.95731004 0.036 4 P 0 0;1=4
P 7.90731004 0.036 4 P 0 0;1=4
P 8.40731004 0.036 4 P 0 0;1=4
P 8.35731004 0.036 4 P 0 0;1=4
P 8.30731004 0.036 4 P 0 0;1=4
P 8.25731004 0.036 4 P 0 0;1=4
P 8.20731004 0.036 4 P 0 0;1=4
P 8.65731004 0.036 4 P 0 0;1=4
P 8.60731004 0.036 4 P 0 0;1=4
P 8.55731004 0.036 4 P 0 0;1=4
P 8.50731004 0.036 4 P 0 0;1=4
P 8.45731004 0.036 4 P 0 0;1=4
P 8.90731004 0.036 4 P 0 0;1=4
P 8.85731004 0.036 4 P 0 0;1=4
P 8.80731004 0.036 4 P 0 0;1=4
P 8.75731004 0.036 4 P 0 0;1=4
P 8.70731004 0.036 4 P 0 0;1=4
P 9.20731004 0.036 4 P 0 0;1=4
P 9.15731004 0.036 4 P 0 0;1=4
P 9.10731004 0.036 4 P 0 0;1=4
P 9.05731004 0.036 4 P 0 0;1=4
P 9.00731004 0.036 4 P 0 0;1=4
P 8.95731004 0.036 4 P 0 0;1=4
P 9.45731004 0.036 4 P 0 0;1=4
P 9.40731004 0.036 4 P 0 0;1=4
P 9.35731004 0.036 4 P 0 0;1=4
P 9.30731004 0.036 4 P 0 0;1=4
P 9.25731004 0.036 4 P 0 0;1=4
P 9.70731004 0.036 4 P 0 0;1=4
P 9.65731004 0.036 4 P 0 0;1=4
P 9.60731004 0.036 4 P 0 0;1=4
P 9.55731004 0.036 4 P 0 0;1=4
P 9.50731004 0.036 4 P 0 0;1=4
P 10.00731004 0.036 4 P 0 0;1=4
P 9.95731004 0.036 4 P 0 0;1=4
P 9.90731004 0.036 4 P 0 0;1=4
P 9.85731004 0.036 4 P 0 0;1=4
P 9.80731004 0.036 4 P 0 0;1=4
P 9.75731004 0.036 4 P 0 0;1=4
P 10.25731004 0.036 4 P 0 0;1=4
P 10.20731004 0.036 4 P 0 0;1=4
P 10.15731004 0.036 4 P 0 0;1=4
P 10.10731004 0.036 4 P 0 0;1=4
P 10.05731004 0.036 4 P 0 0;1=4
P 10.50731004 0.036 4 P 0 0;1=4
P 10.45731004 0.036 4 P 0 0;1=4
P 10.40731004 0.036 4 P 0 0;1=4
P 10.35731004 0.036 4 P 0 0;1=4
P 10.30731004 0.036 4 P 0 0;1=4
P 10.75731004 0.036 4 P 0 0;1=4
P 10.70731004 0.036 4 P 0 0;1=4
P 10.65731004 0.036 4 P 0 0;1=4
P 10.60731004 0.036 4 P 0 0;1=4
P 10.55731004 0.036 4 P 0 0;1=4
P 11.05731004 0.036 4 P 0 0;1=4
P 11.00731004 0.036 4 P 0 0;1=4
P 10.95731004 0.036 4 P 0 0;1=4
P 10.90731004 0.036 4 P 0 0;1=4
P 10.85731004 0.036 4 P 0 0;1=4
P 10.80731004 0.036 4 P 0 0;1=4
P 11.30731004 0.036 4 P 0 0;1=4
P 11.25731004 0.036 4 P 0 0;1=4
P 11.20731004 0.036 4 P 0 0;1=4
P 11.15731004 0.036 4 P 0 0;1=4
P 11.10731004 0.036 4 P 0 0;1=4
P 11.55731004 0.036 4 P 0 0;1=4
P 11.50731004 0.036 4 P 0 0;1=4
P 11.45731004 0.036 4 P 0 0;1=4
P 11.40731004 0.036 4 P 0 0;1=4
P 11.35731004 0.036 4 P 0 0;1=4
P 11.80731004 0.036 4 P 0 0;1=4
P 11.75731004 0.036 4 P 0 0;1=4
P 11.70731004 0.036 4 P 0 0;1=4
P 11.65731004 0.036 4 P 0 0;1=4
P 11.60731004 0.036 4 P 0 0;1=4
P 12.10731004 0.036 4 P 0 0;1=4
P 12.05731004 0.036 4 P 0 0;1=4
P 12.00731004 0.036 4 P 0 0;1=4
P 11.95731004 0.036 4 P 0 0;1=4
P 11.90731004 0.036 4 P 0 0;1=4
P 11.85731004 0.036 4 P 0 0;1=4
P 12.35731004 0.036 4 P 0 0;1=4
P 12.30731004 0.036 4 P 0 0;1=4
P 12.25731004 0.036 4 P 0 0;1=4
P 12.20731004 0.036 4 P 0 0;1=4
P 12.15731004 0.036 4 P 0 0;1=4
P 12.60731004 0.036 4 P 0 0;1=4
P 12.55731004 0.036 4 P 0 0;1=4
P 12.50731004 0.036 4 P 0 0;1=4
P 12.45731004 0.036 4 P 0 0;1=4
P 12.40731004 0.036 4 P 0 0;1=4
P 12.8892 0.22596004 4 P 0 0;1=4
P 12.8892 0.17596004 4 P 0 0;1=4
P 12.8892 0.12596004 4 P 0 0;1=4
P 12.88911004 0.07596004 4 P 0 0;1=4
P 12.85728996 0.03738996 4 P 0 0;1=4
P 12.80731004 0.036 4 P 0 0;1=4
P 12.75731004 0.036 4 P 0 0;1=4
P 12.70731004 0.036 4 P 0 0;1=4
P 12.65731004 0.036 4 P 0 0;1=4
P 12.8892 0.47596004 4 P 0 0;1=4
P 12.8892 0.42596004 4 P 0 0;1=4
P 12.8892 0.37596004 4 P 0 0;1=4
P 12.8892 0.32596004 4 P 0 0;1=4
P 12.8892 0.27596004 4 P 0 0;1=4
P 12.8892 0.62596004 4 P 0 0;1=4
P 12.8892 0.57596004 4 P 0 0;1=4
P 12.8892 0.52596004 4 P 0 0;1=4
P 0.036 1.00868002 4 P 0 0;1=4
P 0.036 1.05868002 4 P 0 0;1=4
P 0.036 1.10868002 4 P 0 0;1=4
P 0.036 1.15868002 4 P 0 0;1=4
P 0.036 1.20868002 4 P 0 0;1=4
P 0.036 1.25868002 4 P 0 0;1=4
P 0.036 1.30868002 4 P 0 0;1=4
P 0.036 1.35868002 4 P 0 0;1=4
P 0.036 1.40868002 4 P 0 0;1=4
P 0.036 1.45868002 4 P 0 0;1=4
P 0.036 1.50868002 4 P 0 0;1=4
P 0.036 1.55868002 4 P 0 0;1=4
P 0.036 1.60868002 4 P 0 0;1=4
P 0.036 1.65868002 4 P 0 0;1=4
P 0.036 1.70868002 4 P 0 0;1=4
P 0.036 1.75868002 4 P 0 0;1=4
P 0.036 1.80868002 4 P 0 0;1=4
P 0.036 1.85868002 4 P 0 0;1=4
P 0.036 1.90868002 4 P 0 0;1=4
P 0.036 1.95868002 4 P 0 0;1=4
P 0.036 2.00868002 4 P 0 0;1=4
P 0.036 2.05868002 4 P 0 0;1=4
P 0.036 2.10868002 4 P 0 0;1=4
P 0.036 2.15868002 4 P 0 0;1=4
P 0.036 2.20868002 4 P 0 0;1=4
P 0.036 2.25868002 4 P 0 0;1=4
P 0.036 2.30868002 4 P 0 0;1=4
P 0.036 2.35868002 4 P 0 0;1=4
P 0.036 2.40868002 4 P 0 0;1=4
P 0.036 2.45868002 4 P 0 0;1=4
P 0.036 2.50868002 4 P 0 0;1=4
P 0.036 2.55868002 4 P 0 0;1=4
P 0.036 2.60868002 4 P 0 0;1=4
P 0.036 2.65868002 4 P 0 0;1=4
P 0.036 2.70868002 4 P 0 0;1=4
P 0.036 2.75868002 4 P 0 0;1=4
P 0.036 2.80868002 4 P 0 0;1=4
P 0.036 2.85868002 4 P 0 0;1=4
P 0.036 2.90868002 4 P 0 0;1=4
P 0.036 2.95868002 4 P 0 0;1=4
P 0.036 3.00868002 4 P 0 0;1=4
P 0.036 3.05868002 4 P 0 0;1=4
P 0.036 3.10868002 4 P 0 0;1=4
P 0.036 3.15868002 4 P 0 0;1=4
P 0.036 3.20868002 4 P 0 0;1=4
P 0.036 3.25868002 4 P 0 0;1=4
P 0.036 3.30868002 4 P 0 0;1=4
P 0.036 3.35868002 4 P 0 0;1=4
P 0.036 3.40868002 4 P 0 0;1=4
P 0.036 3.45868002 4 P 0 0;1=4
P 0.036 3.50868002 4 P 0 0;1=4
P 0.036 3.55868002 4 P 0 0;1=4
P 0.036 3.60868002 4 P 0 0;1=4
P 0.036 3.65868002 4 P 0 0;1=4
P 0.036 3.70868002 4 P 0 0;1=4
P 0.036 3.75868002 4 P 0 0;1=4
P 0.036 3.80868002 4 P 0 0;1=4
P 0.036 3.85868002 4 P 0 0;1=4
P 0.036 3.90868002 4 P 0 0;1=4
P 0.036 3.95868002 4 P 0 0;1=4
P 0.036 4.00868002 4 P 0 0;1=4
P 0.036 4.05868002 4 P 0 0;1=4
P 0.036 4.10868002 4 P 0 0;1=4
P 0.036 4.15868002 4 P 0 0;1=4
P 0.036 4.20868002 4 P 0 0;1=4
P 0.036 4.25868002 4 P 0 0;1=4
P 0.036 4.30868002 4 P 0 0;1=4
P 0.036 4.35868002 4 P 0 0;1=4
P 0.036 4.40868002 4 P 0 0;1=4
P 0.036 4.45868002 4 P 0 0;1=4
P 0.036 4.50868002 4 P 0 0;1=4
P 0.036 4.55868002 4 P 0 0;1=4
P 0.036 4.60868002 4 P 0 0;1=4
P 0.036 4.65868002 4 P 0 0;1=4
P 0.036 4.70868002 4 P 0 0;1=4
P 0.036 4.75868002 4 P 0 0;1=4
P 12.8892 1.02596004 4 P 0 0;1=4
P 12.8892 1.27596004 4 P 0 0;1=4
P 12.8892 1.22596004 4 P 0 0;1=4
P 12.8892 1.17596004 4 P 0 0;1=4
P 12.8892 1.12596004 4 P 0 0;1=4
P 12.8892 1.07596004 4 P 0 0;1=4
P 12.8892 1.52596004 4 P 0 0;1=4
P 12.8892 1.47596004 4 P 0 0;1=4
P 12.8892 1.42596004 4 P 0 0;1=4
P 12.8892 1.37596004 4 P 0 0;1=4
P 12.8892 1.32596004 4 P 0 0;1=4
P 12.8892 1.77596004 4 P 0 0;1=4
P 12.8892 1.72596004 4 P 0 0;1=4
P 12.8892 1.67596004 4 P 0 0;1=4
P 12.8892 1.62596004 4 P 0 0;1=4
P 12.8892 1.57596004 4 P 0 0;1=4
P 12.8892 2.07596004 4 P 0 0;1=4
P 12.8892 2.02596004 4 P 0 0;1=4
P 12.8892 1.97596004 4 P 0 0;1=4
P 12.8892 1.92596004 4 P 0 0;1=4
P 12.8892 1.87596004 4 P 0 0;1=4
P 12.8892 1.82596004 4 P 0 0;1=4
P 12.8892 2.32596004 4 P 0 0;1=4
P 12.8892 2.27596004 4 P 0 0;1=4
P 12.8892 2.22596004 4 P 0 0;1=4
P 12.8892 2.17596004 4 P 0 0;1=4
P 12.8892 2.57596004 4 P 0 0;1=4
P 12.8892 2.52596004 4 P 0 0;1=4
P 12.8892 2.47596004 4 P 0 0;1=4
P 12.8892 2.42596004 4 P 0 0;1=4
P 12.8892 2.37596004 4 P 0 0;1=4
P 12.8892 2.82596004 4 P 0 0;1=4
P 12.8892 2.77596004 4 P 0 0;1=4
P 12.8892 2.72596004 4 P 0 0;1=4
P 12.8892 2.67596004 4 P 0 0;1=4
P 12.8892 2.62596004 4 P 0 0;1=4
P 12.8892 3.12596004 4 P 0 0;1=4
P 12.8892 3.07596004 4 P 0 0;1=4
P 12.8892 3.02596004 4 P 0 0;1=4
P 12.8892 2.97596004 4 P 0 0;1=4
P 12.8892 2.92596004 4 P 0 0;1=4
P 12.8892 2.87596004 4 P 0 0;1=4
P 12.8892 3.37596004 4 P 0 0;1=4
P 12.8892 3.32596004 4 P 0 0;1=4
P 12.8892 3.27596004 4 P 0 0;1=4
P 12.8892 3.22596004 4 P 0 0;1=4
P 12.8892 3.17596004 4 P 0 0;1=4
P 12.8892 3.62596004 4 P 0 0;1=4
P 12.8892 3.57596004 4 P 0 0;1=4
P 12.8892 3.52596004 4 P 0 0;1=4
P 12.8892 3.47596004 4 P 0 0;1=4
P 12.8892 3.42596004 4 P 0 0;1=4
P 12.8892 3.92596004 4 P 0 0;1=4
P 12.8892 3.87596004 4 P 0 0;1=4
P 12.8892 3.82596004 4 P 0 0;1=4
P 12.8892 3.77596004 4 P 0 0;1=4
P 12.8892 3.72596004 4 P 0 0;1=4
P 12.8892 3.67596004 4 P 0 0;1=4
P 12.8892 4.17596004 4 P 0 0;1=4
P 12.8892 4.12596004 4 P 0 0;1=4
P 12.8892 4.07596004 4 P 0 0;1=4
P 12.8892 4.02596004 4 P 0 0;1=4
P 12.8892 3.97596004 4 P 0 0;1=4
P 12.8892 4.42596004 4 P 0 0;1=4
P 12.8892 4.37596004 4 P 0 0;1=4
P 12.8892 4.32596004 4 P 0 0;1=4
P 12.8892 4.27596004 4 P 0 0;1=4
P 12.8892 4.22596004 4 P 0 0;1=4
P 12.8892 4.67596004 4 P 0 0;1=4
P 12.8892 4.62596004 4 P 0 0;1=4
P 12.8892 4.57596004 4 P 0 0;1=4
P 12.8892 4.52596004 4 P 0 0;1=4
P 12.8892 4.47596004 4 P 0 0;1=4
P 12.8892 4.82596004 4 P 0 0;1=4
P 12.8892 4.77596004 4 P 0 0;1=4
P 12.8892 4.72596004 4 P 0 0;1=4
P 0.036 5.25868002 4 P 0 0;1=4
P 0.036 5.30868002 4 P 0 0;1=4
P 0.036 5.35868002 4 P 0 0;1=4
P 0.036 5.40868002 4 P 0 0;1=4
P 0.036 5.45868002 4 P 0 0;1=4
P 0.036 5.50868002 4 P 0 0;1=4
P 0.036 5.55868002 4 P 0 0;1=4
P 0.036 5.60868002 4 P 0 0;1=4
P 0.036 5.65868002 4 P 0 0;1=4
P 0.036 5.70868002 4 P 0 0;1=4
P 0.036 5.75868002 4 P 0 0;1=4
P 0.036 5.80868002 4 P 0 0;1=4
P 0.036 5.85868002 4 P 0 0;1=4
P 0.036 5.90868002 4 P 0 0;1=4
P 0.03826998 5.95863002 4 P 0 0;1=4
P 0.07901004 5.98761998 4 P 0 0;1=4
P 0.12901004 5.98761998 4 P 0 0;1=4
P 0.17901004 5.98761998 4 P 0 0;1=4
P 0.22901004 5.98761998 4 P 0 0;1=4
P 0.27901004 5.98761998 4 P 0 0;1=4
P 0.32901004 5.98761998 4 P 0 0;1=4
P 0.37901004 5.98761998 4 P 0 0;1=4
P 0.42901004 5.98761998 4 P 0 0;1=4
P 0.47901004 5.98761998 4 P 0 0;1=4
P 0.52901004 5.98761998 4 P 0 0;1=4
P 0.57901004 5.98761998 4 P 0 0;1=4
P 0.62901004 5.98761998 4 P 0 0;1=4
P 0.67901004 5.98761998 4 P 0 0;1=4
P 0.72901004 5.98761998 4 P 0 0;1=4
P 0.77901004 5.98761998 4 P 0 0;1=4
P 0.82901004 5.98761998 4 P 0 0;1=4
P 0.87901004 5.98761998 4 P 0 0;1=4
P 0.92901004 5.98761998 4 P 0 0;1=4
P 0.97901004 5.98761998 4 P 0 0;1=4
P 1.02901004 5.98761998 4 P 0 0;1=4
P 1.07901004 5.98761998 4 P 0 0;1=4
P 1.12901004 5.98761998 4 P 0 0;1=4
P 1.17901004 5.98761998 4 P 0 0;1=4
P 1.22901004 5.98761998 4 P 0 0;1=4
P 1.27901004 5.98761998 4 P 0 0;1=4
P 1.32901004 5.98761998 4 P 0 0;1=4
P 1.37901004 5.98761998 4 P 0 0;1=4
P 1.42901004 5.98761998 4 P 0 0;1=4
P 1.47901004 5.98761998 4 P 0 0;1=4
P 1.52901004 5.98761998 4 P 0 0;1=4
P 1.57901004 5.98761998 4 P 0 0;1=4
P 1.62901004 5.98761998 4 P 0 0;1=4
P 1.67901004 5.98761998 4 P 0 0;1=4
P 1.72901004 5.98761998 4 P 0 0;1=4
P 1.77901004 5.98761998 4 P 0 0;1=4
P 1.82901004 5.98761998 4 P 0 0;1=4
P 1.87901004 5.98761998 4 P 0 0;1=4
P 1.92901004 5.98761998 4 P 0 0;1=4
P 1.97901004 5.98761998 4 P 0 0;1=4
P 2.02901004 5.98761998 4 P 0 0;1=4
P 2.07901004 5.98761998 4 P 0 0;1=4
P 2.12901004 5.98761998 4 P 0 0;1=4
P 2.17901004 5.98761998 4 P 0 0;1=4
P 2.22901004 5.98761998 4 P 0 0;1=4
P 2.27901004 5.98761998 4 P 0 0;1=4
P 2.32901004 5.98761998 4 P 0 0;1=4
P 2.37901004 5.98761998 4 P 0 0;1=4
P 2.42901004 5.98761998 4 P 0 0;1=4
P 2.47901004 5.98761998 4 P 0 0;1=4
P 2.52901004 5.98761998 4 P 0 0;1=4
P 2.57901004 5.98761998 4 P 0 0;1=4
P 2.62901004 5.98761998 4 P 0 0;1=4
P 2.67901004 5.98761998 4 P 0 0;1=4
P 2.72901004 5.98761998 4 P 0 0;1=4
P 2.77901004 5.98761998 4 P 0 0;1=4
P 2.82901004 5.98761998 4 P 0 0;1=4
P 2.87901004 5.98761998 4 P 0 0;1=4
P 2.92901004 5.98761998 4 P 0 0;1=4
P 2.97901004 5.98761998 4 P 0 0;1=4
P 3.02901004 5.98761998 4 P 0 0;1=4
P 3.07901004 5.98761998 4 P 0 0;1=4
P 3.12901004 5.98761998 4 P 0 0;1=4
P 3.17901004 5.98761998 4 P 0 0;1=4
P 3.22901004 5.98761998 4 P 0 0;1=4
P 3.27901004 5.98761998 4 P 0 0;1=4
P 3.32901004 5.98761998 4 P 0 0;1=4
P 3.37901004 5.98761998 4 P 0 0;1=4
P 3.42901004 5.98761998 4 P 0 0;1=4
P 3.47901004 5.98761998 4 P 0 0;1=4
P 3.52901004 5.98761998 4 P 0 0;1=4
P 3.57901004 5.98761998 4 P 0 0;1=4
P 3.62901004 5.98761998 4 P 0 0;1=4
P 3.67901004 5.98761998 4 P 0 0;1=4
P 3.72901004 5.98761998 4 P 0 0;1=4
P 3.77901004 5.98761998 4 P 0 0;1=4
P 3.82901004 5.98761998 4 P 0 0;1=4
P 3.87901004 5.98761998 4 P 0 0;1=4
P 3.92901004 5.98761998 4 P 0 0;1=4
P 3.97901004 5.98761998 4 P 0 0;1=4
P 4.02901004 5.98761998 4 P 0 0;1=4
P 4.07901004 5.98761998 4 P 0 0;1=4
P 4.12901004 5.98761998 4 P 0 0;1=4
P 4.17901004 5.98761998 4 P 0 0;1=4
P 4.22901004 5.98761998 4 P 0 0;1=4
P 4.27901004 5.98761998 4 P 0 0;1=4
P 4.32901004 5.98761998 4 P 0 0;1=4
P 4.37901004 5.98761998 4 P 0 0;1=4
P 4.42901004 5.98761998 4 P 0 0;1=4
P 4.47901004 5.98761998 4 P 0 0;1=4
P 4.52901004 5.98761998 4 P 0 0;1=4
P 4.57901004 5.98761998 4 P 0 0;1=4
P 4.62901004 5.98761998 4 P 0 0;1=4
P 4.67901004 5.98761998 4 P 0 0;1=4
P 4.72901004 5.98761998 4 P 0 0;1=4
P 4.77901004 5.98761998 4 P 0 0;1=4
P 4.82901004 5.98761998 4 P 0 0;1=4
P 4.87901004 5.98761998 4 P 0 0;1=4
P 4.92901004 5.98761998 4 P 0 0;1=4
P 4.97901004 5.98761998 4 P 0 0;1=4
P 5.02901004 5.98761998 4 P 0 0;1=4
P 5.07901004 5.98761998 4 P 0 0;1=4
P 5.12901004 5.98761998 4 P 0 0;1=4
P 5.17901004 5.98761998 4 P 0 0;1=4
P 5.22901004 5.98761998 4 P 0 0;1=4
P 5.27901004 5.98761998 4 P 0 0;1=4
P 5.32901004 5.98761998 4 P 0 0;1=4
P 5.37901004 5.98761998 4 P 0 0;1=4
P 5.42901004 5.98761998 4 P 0 0;1=4
P 5.47901004 5.98761998 4 P 0 0;1=4
P 5.52901004 5.98761998 4 P 0 0;1=4
P 5.57901004 5.98761998 4 P 0 0;1=4
P 5.62901004 5.98761998 4 P 0 0;1=4
P 5.67901004 5.98761998 4 P 0 0;1=4
P 5.72901004 5.98761998 4 P 0 0;1=4
P 5.77901004 5.98761998 4 P 0 0;1=4
P 5.82901004 5.98761998 4 P 0 0;1=4
P 5.87901004 5.98761998 4 P 0 0;1=4
P 5.92901004 5.98761998 4 P 0 0;1=4
P 5.97901004 5.98761998 4 P 0 0;1=4
P 6.02901004 5.98761998 4 P 0 0;1=4
P 6.07901004 5.98761998 4 P 0 0;1=4
P 6.12901004 5.98761998 4 P 0 0;1=4
P 6.17901004 5.98761998 4 P 0 0;1=4
P 6.22901004 5.98761998 4 P 0 0;1=4
P 6.27901004 5.98761998 4 P 0 0;1=4
P 6.32901004 5.98761998 4 P 0 0;1=4
P 6.37901004 5.98761998 4 P 0 0;1=4
P 6.42901004 5.98761998 4 P 0 0;1=4
P 6.47901004 5.98761998 4 P 0 0;1=4
P 6.52901004 5.98761998 4 P 0 0;1=4
P 6.57901004 5.98761998 4 P 0 0;1=4
P 6.62901004 5.98761998 4 P 0 0;1=4
P 6.67901004 5.98761998 4 P 0 0;1=4
P 6.72901004 5.98761998 4 P 0 0;1=4
P 6.77901004 5.98761998 4 P 0 0;1=4
P 6.82901004 5.98761998 4 P 0 0;1=4
P 6.87901004 5.98761998 4 P 0 0;1=4
P 6.92901004 5.98761998 4 P 0 0;1=4
P 6.97901004 5.98761998 4 P 0 0;1=4
P 12.8892 5.47596004 4 P 0 0;1=4
P 12.8892 5.42596004 4 P 0 0;1=4
P 12.8892 5.37596004 4 P 0 0;1=4
P 12.8892 5.32596004 4 P 0 0;1=4
P 12.8892 5.27596004 4 P 0 0;1=4
P 12.8892 5.72596004 4 P 0 0;1=4
P 12.8892 5.67596004 4 P 0 0;1=4
P 12.8892 5.62596004 4 P 0 0;1=4
P 12.8892 5.57596004 4 P 0 0;1=4
P 12.8892 5.52596004 4 P 0 0;1=4
P 7.37901004 5.98761998 4 P 0 0;1=4
P 7.42901004 5.98761998 4 P 0 0;1=4
P 7.47901004 5.98761998 4 P 0 0;1=4
P 7.52901004 5.98761998 4 P 0 0;1=4
P 7.57901004 5.98761998 4 P 0 0;1=4
P 7.62901004 5.98761998 4 P 0 0;1=4
P 7.67901004 5.98761998 4 P 0 0;1=4
P 7.72901004 5.98761998 4 P 0 0;1=4
P 7.77901004 5.98761998 4 P 0 0;1=4
P 7.82901004 5.98761998 4 P 0 0;1=4
P 7.87901004 5.98761998 4 P 0 0;1=4
P 7.92901004 5.98761998 4 P 0 0;1=4
P 7.97901004 5.98761998 4 P 0 0;1=4
P 8.02901004 5.98761998 4 P 0 0;1=4
P 8.07901004 5.98761998 4 P 0 0;1=4
P 8.12901004 5.98761998 4 P 0 0;1=4
P 8.17901004 5.98761998 4 P 0 0;1=4
P 8.22901004 5.98761998 4 P 0 0;1=4
P 8.27901004 5.98761998 4 P 0 0;1=4
P 8.32901004 5.98761998 4 P 0 0;1=4
P 8.37901004 5.98761998 4 P 0 0;1=4
P 8.42901004 5.98761998 4 P 0 0;1=4
P 8.47901004 5.98761998 4 P 0 0;1=4
P 8.52901004 5.98761998 4 P 0 0;1=4
P 8.57901004 5.98761998 4 P 0 0;1=4
P 8.62901004 5.98761998 4 P 0 0;1=4
P 8.67901004 5.98761998 4 P 0 0;1=4
P 8.72901004 5.98761998 4 P 0 0;1=4
P 8.77901004 5.98761998 4 P 0 0;1=4
P 8.82901004 5.98761998 4 P 0 0;1=4
P 8.87901004 5.98761998 4 P 0 0;1=4
P 8.92901004 5.98761998 4 P 0 0;1=4
P 8.97901004 5.98761998 4 P 0 0;1=4
P 9.02901004 5.98761998 4 P 0 0;1=4
P 9.07901004 5.98761998 4 P 0 0;1=4
P 9.12901004 5.98761998 4 P 0 0;1=4
P 9.17901004 5.98761998 4 P 0 0;1=4
P 9.22901004 5.98761998 4 P 0 0;1=4
P 9.27901004 5.98761998 4 P 0 0;1=4
P 9.32901004 5.98761998 4 P 0 0;1=4
P 9.37901004 5.98761998 4 P 0 0;1=4
P 9.42901004 5.98761998 4 P 0 0;1=4
P 9.47901004 5.98761998 4 P 0 0;1=4
P 9.52901004 5.98761998 4 P 0 0;1=4
P 9.57901004 5.98761998 4 P 0 0;1=4
P 9.62901004 5.98761998 4 P 0 0;1=4
P 9.67901004 5.98761998 4 P 0 0;1=4
P 9.72901004 5.98761998 4 P 0 0;1=4
P 9.77901004 5.98761998 4 P 0 0;1=4
P 9.82901004 5.98761998 4 P 0 0;1=4
P 9.87901004 5.98761998 4 P 0 0;1=4
P 9.92901004 5.98761998 4 P 0 0;1=4
P 9.97901004 5.98761998 4 P 0 0;1=4
P 10.02901004 5.98761998 4 P 0 0;1=4
P 10.07901004 5.98761998 4 P 0 0;1=4
P 10.12901004 5.98761998 4 P 0 0;1=4
P 10.17901004 5.98761998 4 P 0 0;1=4
P 10.22901004 5.98761998 4 P 0 0;1=4
P 10.27901004 5.98761998 4 P 0 0;1=4
P 10.32901004 5.98761998 4 P 0 0;1=4
P 10.37901004 5.98761998 4 P 0 0;1=4
P 10.42901004 5.98761998 4 P 0 0;1=4
P 10.47901004 5.98761998 4 P 0 0;1=4
P 10.52901004 5.98761998 4 P 0 0;1=4
P 10.57901004 5.98761998 4 P 0 0;1=4
P 10.62901004 5.98761998 4 P 0 0;1=4
P 10.67901004 5.98761998 4 P 0 0;1=4
P 10.72901004 5.98761998 4 P 0 0;1=4
P 10.77901004 5.98761998 4 P 0 0;1=4
P 10.82901004 5.98761998 4 P 0 0;1=4
P 10.87901004 5.98761998 4 P 0 0;1=4
P 10.92901004 5.98761998 4 P 0 0;1=4
P 10.97901004 5.98761998 4 P 0 0;1=4
P 11.02901004 5.98761998 4 P 0 0;1=4
P 11.07901004 5.98761998 4 P 0 0;1=4
P 11.12901004 5.98761998 4 P 0 0;1=4
P 11.17901004 5.98761998 4 P 0 0;1=4
P 11.22901004 5.98761998 4 P 0 0;1=4
P 11.27901004 5.98761998 4 P 0 0;1=4
P 11.32901004 5.98761998 4 P 0 0;1=4
P 11.37901004 5.98761998 4 P 0 0;1=4
P 11.42901004 5.98761998 4 P 0 0;1=4
P 11.47901004 5.98761998 4 P 0 0;1=4
P 11.52901004 5.98761998 4 P 0 0;1=4
P 11.57901004 5.98761998 4 P 0 0;1=4
P 11.62901004 5.98761998 4 P 0 0;1=4
P 11.67901004 5.98761998 4 P 0 0;1=4
P 11.72901004 5.98761998 4 P 0 0;1=4
P 11.77901004 5.98761998 4 P 0 0;1=4
P 11.82901004 5.98761998 4 P 0 0;1=4
P 11.87901004 5.98761998 4 P 0 0;1=4
P 11.92901004 5.98761998 4 P 0 0;1=4
P 11.97901004 5.98761998 4 P 0 0;1=4
P 12.02901004 5.98761998 4 P 0 0;1=4
P 12.07901004 5.98761998 4 P 0 0;1=4
P 12.12901004 5.98761998 4 P 0 0;1=4
P 12.17901004 5.98761998 4 P 0 0;1=4
P 12.22901004 5.98761998 4 P 0 0;1=4
P 12.27901004 5.98761998 4 P 0 0;1=4
P 12.32901004 5.98761998 4 P 0 0;1=4
P 12.37901004 5.98761998 4 P 0 0;1=4
P 12.42901004 5.98761998 4 P 0 0;1=4
P 12.47901004 5.98761998 4 P 0 0;1=4
P 12.52901004 5.98761998 4 P 0 0;1=4
P 12.57901004 5.98761998 4 P 0 0;1=4
P 12.62901004 5.98761998 4 P 0 0;1=4
P 12.67901004 5.98761998 4 P 0 0;1=4
P 12.72901004 5.98761998 4 P 0 0;1=4
P 12.77901004 5.98761998 4 P 0 0;1=4
P 12.82901004 5.98761998 4 P 0 0;1=4
P 12.87726004 5.97451004 4 P 0 0;1=4
P 12.8892 5.92596004 4 P 0 0;1=4
P 12.8892 5.87596004 4 P 0 0;1=4
P 12.8892 5.82596004 4 P 0 0;1=4
P 12.8892 5.77596004 4 P 0 0;1=4
P 4.33605 4.9231 4 P 0 0;1=4
P 4.38105 4.9231 4 P 0 0;1=4
P 4.30105 4.9431 4 P 0 0;1=4
P 4.42105 4.9431 4 P 0 0;1=4
P 4.46105 4.9431 4 P 0 0;1=4
P 4.26105 4.9431 4 P 0 0;1=4
P 4.72605 4.9231 4 P 0 0;1=4
P 4.65105 4.9431 4 P 0 0;1=4
P 4.69105 4.9431 4 P 0 0;1=4
P 4.85105 4.9431 4 P 0 0;1=4
P 4.81105 4.9431 4 P 0 0;1=4
P 4.77105 4.9231 4 P 0 0;1=4
P 4.30105 5.0281 4 P 0 0;1=4
P 4.30105 5.0731 4 P 0 0;1=4
P 4.30105 4.9831 4 P 0 0;1=4
P 4.34105 5.1181 4 P 0 0;1=4
P 4.38105 5.1181 4 P 0 0;1=4
P 4.46105 5.1181 4 P 0 0;1=4
P 4.42105 5.1181 4 P 0 0;1=4
P 4.42105 4.9831 4 P 0 0;1=4
P 4.42105 5.0731 4 P 0 0;1=4
P 4.42105 5.0281 4 P 0 0;1=4
P 4.46105 4.9831 4 P 0 0;1=4
P 4.46105 5.0731 4 P 0 0;1=4
P 4.46105 5.0281 4 P 0 0;1=4
P 4.26105 5.0281 4 P 0 0;1=4
P 4.26105 5.0731 4 P 0 0;1=4
P 4.26105 4.9831 4 P 0 0;1=4
P 4.73105 5.1181 4 P 0 0;1=4
P 4.69105 5.1181 4 P 0 0;1=4
P 4.65105 5.1181 4 P 0 0;1=4
P 4.65105 4.9831 4 P 0 0;1=4
P 4.65105 5.0731 4 P 0 0;1=4
P 4.65105 5.0281 4 P 0 0;1=4
P 4.69105 4.9831 4 P 0 0;1=4
P 4.69105 5.0731 4 P 0 0;1=4
P 4.69105 5.0281 4 P 0 0;1=4
P 4.85105 5.0281 4 P 0 0;1=4
P 4.85105 5.0731 4 P 0 0;1=4
P 4.85105 4.9831 4 P 0 0;1=4
P 4.81105 5.0281 4 P 0 0;1=4
P 4.81105 5.0731 4 P 0 0;1=4
P 4.81105 4.9831 4 P 0 0;1=4
P 4.81105 5.1181 4 P 0 0;1=4
P 4.85105 5.1181 4 P 0 0;1=4
P 4.77105 5.1181 4 P 0 0;1=4
P 4.30105 5.1181 4 P 0 0;1=4
P 4.26105 5.1181 4 P 0 0;1=4
P 9.45795 0.36633002 4 P 0 0;1=4
P 6.62 4.645 4 P 0 0;1=4
P 6.62 4.61 4 P 0 0;1=4
P 6.605 4.77 4 P 0 0;1=4
P 6.315 4.9 4 P 0 0;1=4
P 6.315 4.865 4 P 0 0;1=4
P 6.315 4.82 4 P 0 0;1=4
P 6.315 4.785 4 P 0 0;1=4
P 6.315 4.705 4 P 0 0;1=4
P 6.315 4.74 4 P 0 0;1=4
P 6.315 4.66 4 P 0 0;1=4
P 6.315 4.625 4 P 0 0;1=4
P 1.51673002 5.78 4 P 0 0;1=4
P 1.12303002 5.46016004 4 P 0 0;1=4
P 1.20176998 5.46016004 4 P 0 0;1=4
P 1.51673002 5.46016004 4 P 0 0;1=4
P 1.36 5.355 4 P 0 0;1=4
P 1.41 5.355 4 P 0 0;1=4
P 1.46 5.355 4 P 0 0;1=4
P 1.305 5.885 4 P 0 0;1=4
P 1.355 5.885 4 P 0 0;1=4
P 1.405 5.885 4 P 0 0;1=4
P 1.455 5.885 4 P 0 0;1=4
P 0.705 5.355 4 P 0 0;1=4
P 0.7 5.267 4 P 0 0;1=0
P 0.73 5.175 4 P 0 0;1=4
P 1.03 5.065 4 P 0 0;1=4
P 1.28051004 5.46016004 4 P 0 0;1=4
P 12.215 4.915 4 P 0 0;1=4
P 12.055 4.915 4 P 0 0;1=4
P 10.465 5.245 4 P 0 0;1=4
P 10.465 5.165 4 P 0 0;1=4
P 11.7719 4.80998996 4 P 0 0;1=4
P 11.7719 4.85498996 4 P 0 0;1=4
P 11.7719 4.90498996 4 P 0 0;1=4
P 11.7719 4.94998996 4 P 0 0;1=4
P 11.9719 4.94998996 4 P 0 0;1=4
P 11.9719 4.80998996 4 P 0 0;1=4
P 11.9719 4.85498996 4 P 0 0;1=4
P 11.9719 4.90498996 4 P 0 0;1=4
P 11.9219 4.94998996 4 P 0 0;1=4
P 11.9219 4.80998996 4 P 0 0;1=4
P 11.8719 4.94998996 4 P 0 0;1=4
P 11.8719 4.80998996 4 P 0 0;1=4
P 11.8219 4.80998996 4 P 0 0;1=4
P 11.8219 4.94998996 4 P 0 0;1=4
P 11.69316004 2.6635 4 P 0 0;1=4
P 10.125 2.008 4 P 0 0;1=4
P 5.53531004 1.6642 4 P 0 0;1=4
P 5.53531004 1.7213 4 P 0 0;1=4
P 5.53531004 2.0802 4 P 0 0;1=4
P 5.53531004 1.9393 4 P 0 0;1=4
P 5.53531004 2.2156 4 P 0 0;1=4
P 5.53531004 2.4081 4 P 0 0;1=4
P 5.53531004 2.5473 4 P 0 0;1=4
P 2.86855 4.92 4 P 0 0;1=4
P 2.79768002 4.92 4 P 0 0;1=4
P 3.08113996 4.92 4 P 0 0;1=4
P 3.36461004 4.926 4 P 0 0;1=4
P 3.22288002 4.92 4 P 0 0;1=4
P 3.50633996 4.92 4 P 0 0;1=4
P 3.43546998 4.928 4 P 0 0;1=4
P 3.15398002 4.81401998 4 P 0 0;1=4
P 3.22288002 4.81401998 4 P 0 0;1=4
P 3.36461004 4.81401998 4 P 0 0;1=4
P 3.43546998 4.81401998 4 P 0 0;1=4
P 3.50633996 4.81401998 4 P 0 0;1=4
P 3.22288002 5.023 4 P 0 0;1=4
P 3.50633996 5.023 4 P 0 0;1=4
P 3.43546998 5.023 4 P 0 0;1=4
P 3.14 4.92 4 P 0 0;1=4
P 3.275 4.92 4 P 0 0;1=4
P 3.26 5.332 4 P 0 0;1=4
P 3.06791998 5.332 4 P 0 0;1=4
P 3.51176998 5.17873996 4 P 0 0;1=4
P 3.57176998 5.17873996 4 P 0 0;1=4
P 3.15743996 4.74418002 4 P 0 0;1=4
P 1.63308002 4.92 4 P 0 0;1=4
P 1.84568002 4.92 4 P 0 0;1=4
P 1.77481004 4.92 4 P 0 0;1=4
P 1.70395 4.92 4 P 0 0;1=4
P 2.12913996 4.92 4 P 0 0;1=4
P 2.05828002 4.92 4 P 0 0;1=4
P 1.98741004 4.92 4 P 0 0;1=4
P 1.91653996 4.92 4 P 0 0;1=4
P 2.34173996 4.92 4 P 0 0;1=4
P 2.27086998 4.92 4 P 0 0;1=4
P 2.20001004 4.926 4 P 0 0;1=4
P 2.34173996 4.81 4 P 0 0;1=4
P 2.27086998 4.81 4 P 0 0;1=4
P 2.20001004 4.81 4 P 0 0;1=4
P 1.63173002 4.81526998 4 P 0 0;1=4
P 1.7 4.812 4 P 0 0;1=4
P 1.84568002 4.81 4 P 0 0;1=4
P 1.776 4.812 4 P 0 0;1=4
P 2.12913996 4.81 4 P 0 0;1=4
P 1.99 4.81 4 P 0 0;1=4
P 1.92 4.81 4 P 0 0;1=4
P 2.40716998 5.15373996 4 P 0 0;1=4
P 2.34716998 5.15373996 4 P 0 0;1=4
P 10.58661004 2.16615 5 P 0 0;1=3
P 10.63661004 2.16615 5 P 0 0;1=3
P 10.63661004 2.21615 5 P 0 0;1=3
P 10.88661004 1.91615 5 P 0 0;1=3
P 10.88661004 2.41615 5 P 0 0;1=3
P 10.88661004 2.66615 5 P 0 0;1=3
P 11.03661004 2.41615 5 P 0 0;1=3
P 11.03661004 2.36615 5 P 0 0;1=3
P 1.91111004 4.61826004 4 P 0 0;1=4
P 2.40716998 4.70326004 4 P 0 0;1=4
P 2.945 4.92 4 P 0 0;1=4
P 3.01028002 4.92 4 P 0 0;1=4
P 7.78 2.4781 4 P 0 0;1=0
P 2.24606004 3.86615 5 P 0 0;1=3
P 2.49606004 3.86615 5 P 0 0;1=3
P 2.24606004 3.81615 5 P 0 0;1=3
P 2.19606004 3.76615 5 P 0 0;1=3
P 2.24606004 3.76615 5 P 0 0;1=3
P 2.29606004 3.76615 5 P 0 0;1=3
P 2.49606004 3.71615 5 P 0 0;1=3
P 2.49606004 3.56615 5 P 0 0;1=3
P 2.44606004 3.56615 5 P 0 0;1=3
P 2.39606004 3.56615 5 P 0 0;1=3
P 2.29606004 3.61615 5 P 0 0;1=3
P 2.24606004 3.71615 5 P 0 0;1=3
P 2.24606004 3.66615 5 P 0 0;1=3
P 2.24606004 3.61615 5 P 0 0;1=3
P 2.19606004 3.61615 5 P 0 0;1=3
P 2.19606004 3.56615 5 P 0 0;1=3
P 2.14606004 3.56615 5 P 0 0;1=3
P 2.04606004 3.56615 5 P 0 0;1=3
P 1.99606004 3.56615 5 P 0 0;1=3
P 2.04606004 3.51615 5 P 0 0;1=3
P 2.04606004 3.46615 5 P 0 0;1=3
P 2.19606004 3.51615 5 P 0 0;1=3
P 2.24606004 3.51615 5 P 0 0;1=3
P 2.29606004 3.51615 5 P 0 0;1=3
P 2.49606004 3.41615 5 P 0 0;1=3
P 2.44606004 3.36615 5 P 0 0;1=3
P 2.24606004 3.46615 5 P 0 0;1=3
P 2.24606004 3.41615 5 P 0 0;1=3
P 2.29606004 3.36615 5 P 0 0;1=3
P 2.24606004 3.36615 5 P 0 0;1=3
P 2.19606004 3.36615 5 P 0 0;1=3
P 1.99606004 3.41615 5 P 0 0;1=3
P 2.09606004 3.36615 5 P 0 0;1=3
P 2.24606004 3.31615 5 P 0 0;1=3
P 2.24606004 3.26615 5 P 0 0;1=3
P 2.29606004 3.21615 5 P 0 0;1=3
P 2.24606004 3.21615 5 P 0 0;1=3
P 2.19606004 3.21615 5 P 0 0;1=3
P 2.09606004 3.21615 5 P 0 0;1=3
P 2.14606004 3.16615 5 P 0 0;1=3
P 2.04606004 3.16615 5 P 0 0;1=3
P 2.24606004 3.16615 5 P 0 0;1=3
P 2.29606004 3.16615 5 P 0 0;1=3
P 2.34606004 3.21615 5 P 0 0;1=3
P 2.44606004 3.21615 5 P 0 0;1=3
P 2.49606004 3.21615 5 P 0 0;1=3
P 2.49606004 3.26615 5 P 0 0;1=3
P 2.49606004 3.16615 5 P 0 0;1=3
P 2.39606004 3.16615 5 P 0 0;1=3
P 2.29606004 3.06615 5 P 0 0;1=3
P 2.29606004 3.11615 5 P 0 0;1=3
P 2.29606004 2.96615 5 P 0 0;1=3
P 2.29606004 3.01615 5 P 0 0;1=3
P 2.24606004 3.06615 5 P 0 0;1=3
P 2.24606004 3.11615 5 P 0 0;1=3
P 2.24606004 2.96615 5 P 0 0;1=3
P 2.24606004 3.01615 5 P 0 0;1=3
P 2.34606004 2.86615 5 P 0 0;1=3
P 2.34606004 2.91615 5 P 0 0;1=3
P 2.29606004 2.76615 5 P 0 0;1=3
P 2.29606004 2.81615 5 P 0 0;1=3
P 2.24606004 2.76615 5 P 0 0;1=3
P 2.24606004 2.81615 5 P 0 0;1=3
P 2.19606004 2.81615 5 P 0 0;1=3
P 2.09606004 2.81615 5 P 0 0;1=3
P 2.09606004 2.86615 5 P 0 0;1=3
P 2.19606004 3.06615 5 P 0 0;1=3
P 2.14606004 3.01615 5 P 0 0;1=3
P 2.09606004 3.06615 5 P 0 0;1=3
P 2.04606004 3.01615 5 P 0 0;1=3
P 2.09606004 2.91615 5 P 0 0;1=3
P 2.14606004 2.86615 5 P 0 0;1=3
P 2.04606004 2.86615 5 P 0 0;1=3
P 2.19606004 2.91615 5 P 0 0;1=3
P 2.24606004 2.91615 5 P 0 0;1=3
P 2.29606004 2.91615 5 P 0 0;1=3
P 2.39606004 3.01615 5 P 0 0;1=3
P 2.34606004 3.06615 5 P 0 0;1=3
P 2.44606004 3.06615 5 P 0 0;1=3
P 2.49606004 3.01615 5 P 0 0;1=3
P 2.44606004 2.91615 5 P 0 0;1=3
P 2.44606004 2.86615 5 P 0 0;1=3
P 2.39606004 2.86615 5 P 0 0;1=3
P 2.34606004 2.81615 5 P 0 0;1=3
P 2.44606004 2.81615 5 P 0 0;1=3
P 2.49606004 2.86615 5 P 0 0;1=3
P 2.49606004 2.71615 5 P 0 0;1=3
P 2.44606004 2.66615 5 P 0 0;1=3
P 2.39606004 2.71615 5 P 0 0;1=3
P 2.34606004 2.66615 5 P 0 0;1=3
P 2.29606004 2.71615 5 P 0 0;1=3
P 2.29606004 2.66615 5 P 0 0;1=3
P 2.24606004 2.71615 5 P 0 0;1=3
P 2.24606004 2.66615 5 P 0 0;1=3
P 2.19606004 2.66615 5 P 0 0;1=3
P 2.14606004 2.71615 5 P 0 0;1=3
P 2.09606004 2.66615 5 P 0 0;1=3
P 2.04606004 2.71615 5 P 0 0;1=3
P 2.04606004 2.56615 5 P 0 0;1=3
P 2.04606004 2.51615 5 P 0 0;1=3
P 2.04606004 2.46615 5 P 0 0;1=3
P 2.09606004 2.51615 5 P 0 0;1=3
P 2.14606004 2.56615 5 P 0 0;1=3
P 2.24606004 2.61615 5 P 0 0;1=3
P 2.24606004 2.56615 5 P 0 0;1=3
P 2.29606004 2.61615 5 P 0 0;1=3
P 2.29606004 2.56615 5 P 0 0;1=3
P 2.34606004 2.51615 5 P 0 0;1=3
P 2.29606004 2.51615 5 P 0 0;1=3
P 2.24606004 2.51615 5 P 0 0;1=3
P 2.19606004 2.51615 5 P 0 0;1=3
P 2.14606004 2.46615 5 P 0 0;1=3
P 2.24606004 2.46615 5 P 0 0;1=3
P 2.29606004 2.46615 5 P 0 0;1=3
P 2.29606004 2.41615 5 P 0 0;1=3
P 2.24606004 2.41615 5 P 0 0;1=3
P 2.24606004 2.36615 5 P 0 0;1=3
P 2.19606004 2.36615 5 P 0 0;1=3
P 2.29606004 2.36615 5 P 0 0;1=3
P 2.39606004 2.46615 5 P 0 0;1=3
P 2.39606004 2.51615 5 P 0 0;1=3
P 2.39606004 2.56615 5 P 0 0;1=3
P 2.44606004 2.51615 5 P 0 0;1=3
P 2.49606004 2.56615 5 P 0 0;1=3
P 2.49606004 2.51615 5 P 0 0;1=3
P 2.49606004 2.46615 5 P 0 0;1=3
P 2.44606004 2.36615 5 P 0 0;1=3
P 2.49606004 2.31615 5 P 0 0;1=3
P 2.39606004 2.31615 5 P 0 0;1=3
P 2.34606004 2.36615 5 P 0 0;1=3
P 2.29606004 2.31615 5 P 0 0;1=3
P 2.24606004 2.31615 5 P 0 0;1=3
P 2.04606004 2.31615 5 P 0 0;1=3
P 2.04606004 2.16615 5 P 0 0;1=3
P 2.04606004 2.11615 5 P 0 0;1=3
P 2.04606004 1.96615 5 P 0 0;1=3
P 2.09606004 2.01615 5 P 0 0;1=3
P 2.14606004 1.96615 5 P 0 0;1=3
P 2.09606004 1.86615 5 P 0 0;1=3
P 2.19606004 1.86615 5 P 0 0;1=3
P 2.24606004 1.86615 5 P 0 0;1=3
P 2.29606004 1.86615 5 P 0 0;1=3
P 2.34606004 1.86615 5 P 0 0;1=3
P 2.24606004 1.91615 5 P 0 0;1=3
P 2.29606004 1.91615 5 P 0 0;1=3
P 2.24606004 1.96615 5 P 0 0;1=3
P 2.29606004 1.96615 5 P 0 0;1=3
P 2.19606004 2.01615 5 P 0 0;1=3
P 2.24606004 2.01615 5 P 0 0;1=3
P 2.29606004 2.01615 5 P 0 0;1=3
P 2.34606004 2.01615 5 P 0 0;1=3
P 2.39606004 1.96615 5 P 0 0;1=3
P 2.44606004 2.01615 5 P 0 0;1=3
P 2.49606004 1.96615 5 P 0 0;1=3
P 2.44606004 1.86615 5 P 0 0;1=3
P 2.49606004 2.11615 5 P 0 0;1=3
P 2.44606004 2.16615 5 P 0 0;1=3
P 2.49606004 2.16615 5 P 0 0;1=3
P 2.44606004 2.21615 5 P 0 0;1=3
P 2.39606004 2.16615 5 P 0 0;1=3
P 2.39606004 2.11615 5 P 0 0;1=3
P 2.34606004 2.16615 5 P 0 0;1=3
P 2.34606004 2.21615 5 P 0 0;1=3
P 2.29606004 2.21615 5 P 0 0;1=3
P 2.29606004 2.16615 5 P 0 0;1=3
P 2.29606004 2.06615 5 P 0 0;1=3
P 2.29606004 2.11615 5 P 0 0;1=3
P 2.24606004 2.11615 5 P 0 0;1=3
P 2.24606004 2.16615 5 P 0 0;1=3
P 2.24606004 2.06615 5 P 0 0;1=3
P 2.24606004 2.21615 5 P 0 0;1=3
P 2.29606004 2.26615 5 P 0 0;1=3
P 2.24606004 2.26615 5 P 0 0;1=3
P 2.19606004 2.21615 5 P 0 0;1=3
P 2.19606004 2.16615 5 P 0 0;1=3
P 2.14606004 2.11615 5 P 0 0;1=3
P 2.14606004 2.16615 5 P 0 0;1=3
P 2.09606004 2.21615 5 P 0 0;1=3
P 2.09606004 2.16615 5 P 0 0;1=3
P 2.09606004 2.36615 5 P 0 0;1=3
P 2.14606004 2.31615 5 P 0 0;1=3
P 1.99606004 2.71615 5 P 0 0;1=3
P 1.99606004 2.86615 5 P 0 0;1=3
P 2.04606004 2.81615 5 P 0 0;1=3
P 2.04606004 2.76615 5 P 0 0;1=3
P 3.29373996 5.023 4 P 0 0;1=4
P 2.14606004 3.26615 5 P 0 0;1=3
P 2.04606004 3.26615 5 P 0 0;1=3
P 2.04606004 3.21615 5 P 0 0;1=3
P 2.14606004 3.21615 5 P 0 0;1=3
P 2.39606004 3.21615 5 P 0 0;1=3
P 2.39606004 3.26615 5 P 0 0;1=3
P 2.29606004 3.26615 5 P 0 0;1=3
P 2.29606004 3.31615 5 P 0 0;1=3
P 2.34606004 3.36615 5 P 0 0;1=3
P 2.14606004 3.41615 5 P 0 0;1=3
P 2.09606004 3.61615 5 P 0 0;1=3
P 2.29606004 3.46615 5 P 0 0;1=3
P 2.29606004 3.41615 5 P 0 0;1=3
P 2.39606004 3.41615 5 P 0 0;1=3
P 2.34606004 3.51615 5 P 0 0;1=3
P 2.34606004 3.61615 5 P 0 0;1=3
P 2.34606004 3.56615 5 P 0 0;1=3
P 2.44606004 3.51615 5 P 0 0;1=3
P 2.44606004 3.61615 5 P 0 0;1=3
P 2.14606004 3.71615 5 P 0 0;1=3
P 2.04606004 3.71615 5 P 0 0;1=3
P 2.09606004 3.76615 5 P 0 0;1=3
P 2.14606004 3.86615 5 P 0 0;1=3
P 2.04606004 3.86615 5 P 0 0;1=3
P 2.29606004 3.71615 5 P 0 0;1=3
P 2.29606004 3.66615 5 P 0 0;1=3
P 2.39606004 3.71615 5 P 0 0;1=3
P 2.34606004 3.76615 5 P 0 0;1=3
P 2.29606004 3.81615 5 P 0 0;1=3
P 2.39606004 3.86615 5 P 0 0;1=3
P 2.29606004 3.86615 5 P 0 0;1=3
P 2.44606004 3.76615 5 P 0 0;1=3
P 2.19606004 2.86615 5 P 0 0;1=3
P 3.36461004 5.023 4 P 0 0;1=4
P 3.29373996 4.81401998 4 P 0 0;1=4
P 3.01028002 4.81401998 4 P 0 0;1=4
P 2.94141004 4.81401998 4 P 0 0;1=4
P 2.86555 4.81401998 4 P 0 0;1=4
P 2.79768002 4.81401998 4 P 0 0;1=4
P 3.15201004 5.023 4 P 0 0;1=4
P 3.08113996 5.023 4 P 0 0;1=4
P 3.01028002 5.023 4 P 0 0;1=4
P 2.93941004 5.023 4 P 0 0;1=4
P 2.86855 5.023 4 P 0 0;1=4
P 2.79768002 5.023 4 P 0 0;1=4
P 1.70395 5.023 4 P 0 0;1=4
P 1.63308002 5.023 4 P 0 0;1=4
P 1.77481004 5.023 4 P 0 0;1=4
P 1.91653996 5.023 4 P 0 0;1=4
P 1.84568002 5.023 4 P 0 0;1=4
P 1.98741004 5.023 4 P 0 0;1=4
P 2.05828002 5.023 4 P 0 0;1=4
P 2.12913996 5.023 4 P 0 0;1=4
P 2.20001004 5.023 4 P 0 0;1=4
P 2.27086998 5.023 4 P 0 0;1=4
P 2.34173996 5.023 4 P 0 0;1=4
P 1.56221004 5.023 4 P 0 0;1=4
P 1.56221004 4.81401998 4 P 0 0;1=4
P 2.06086998 4.81 4 P 0 0;1=4
P 2.41261004 5.023 4 P 0 0;1=4
P 2.41261004 4.81401998 4 P 0 0;1=4
P 2.72681004 5.023 4 P 0 0;1=4
P 2.72681004 4.81401998 4 P 0 0;1=4
P 3.57721004 4.81401998 4 P 0 0;1=4
P 3.57721004 5.023 4 P 0 0;1=4
P 4.88268002 1.91615 5 P 0 0;1=3
P 4.78268002 1.91615 5 P 0 0;1=3
P 5.03268002 2.36615 5 P 0 0;1=3
P 5.03268002 2.41615 5 P 0 0;1=3
P 4.88268002 3.66615 5 P 0 0;1=3
P 4.83268002 3.66615 5 P 0 0;1=3
P 5.03268002 3.66615 5 P 0 0;1=3
P 4.93268002 3.66615 5 P 0 0;1=3
P 4.98268002 3.66615 5 P 0 0;1=3
P 4.88268002 3.51615 5 P 0 0;1=3
P 4.83268002 3.51615 5 P 0 0;1=3
P 5.03268002 3.51615 5 P 0 0;1=3
P 4.93268002 3.51615 5 P 0 0;1=3
P 4.98268002 3.51615 5 P 0 0;1=3
P 4.88268002 3.81615 5 P 0 0;1=3
P 4.83268002 3.81615 5 P 0 0;1=3
P 4.93268002 3.81615 5 P 0 0;1=3
P 4.98268002 3.81615 5 P 0 0;1=3
P 4.88268002 3.36615 5 P 0 0;1=3
P 4.83268002 3.36615 5 P 0 0;1=3
P 5.03268002 3.36615 5 P 0 0;1=3
P 4.93268002 3.36615 5 P 0 0;1=3
P 4.98268002 3.36615 5 P 0 0;1=3
P 4.83268002 3.21615 5 P 0 0;1=3
P 4.88268002 3.21615 5 P 0 0;1=3
P 4.98268002 3.21615 5 P 0 0;1=3
P 4.93268002 3.21615 5 P 0 0;1=3
P 5.03268002 3.21615 5 P 0 0;1=3
P 4.83268002 3.06615 5 P 0 0;1=3
P 4.88268002 3.06615 5 P 0 0;1=3
P 4.98268002 3.06615 5 P 0 0;1=3
P 4.93268002 3.06615 5 P 0 0;1=3
P 5.03268002 3.06615 5 P 0 0;1=3
P 4.83268002 2.91615 5 P 0 0;1=3
P 4.88268002 2.91615 5 P 0 0;1=3
P 4.98268002 2.91615 5 P 0 0;1=3
P 4.93268002 2.91615 5 P 0 0;1=3
P 5.03268002 2.91615 5 P 0 0;1=3
P 4.78268002 2.51615 5 P 0 0;1=3
P 4.73268002 2.51615 5 P 0 0;1=3
P 4.68268002 2.51615 5 P 0 0;1=3
P 4.63268002 2.51615 5 P 0 0;1=3
P 4.58268002 2.51615 5 P 0 0;1=3
P 4.63268002 2.56615 5 P 0 0;1=3
P 4.73268002 2.56615 5 P 0 0;1=3
P 4.78268002 2.56615 5 P 0 0;1=3
P 4.78268002 2.61615 5 P 0 0;1=3
P 4.78268002 2.66615 5 P 0 0;1=3
P 4.68268002 2.66615 5 P 0 0;1=3
P 4.58268002 2.66615 5 P 0 0;1=3
P 4.73268002 2.71615 5 P 0 0;1=3
P 4.63268002 2.71615 5 P 0 0;1=3
P 4.63268002 2.76615 5 P 0 0;1=3
P 4.73268002 2.76615 5 P 0 0;1=3
P 4.78268002 2.76615 5 P 0 0;1=3
P 4.63268002 2.16615 5 P 0 0;1=3
P 4.78268002 2.16615 5 P 0 0;1=3
P 10.63661004 2.91615 5 P 0 0;1=3
P 10.58661004 2.91615 5 P 0 0;1=3
P 10.63661004 3.06615 5 P 0 0;1=3
P 10.58661004 3.06615 5 P 0 0;1=3
P 10.63661004 3.36615 5 P 0 0;1=3
P 10.58661004 3.36615 5 P 0 0;1=3
P 10.63661004 3.21615 5 P 0 0;1=3
P 10.58661004 3.21615 5 P 0 0;1=3
P 10.58661004 3.66615 5 P 0 0;1=3
P 10.63661004 3.51615 5 P 0 0;1=3
P 10.58661004 3.51615 5 P 0 0;1=3
P 10.63661004 3.81615 5 P 0 0;1=3
P 10.63661004 3.66615 5 P 0 0;1=3
P 10.58661004 3.81615 5 P 0 0;1=3
P 10.83661004 2.91615 5 P 0 0;1=3
P 10.78661004 2.91615 5 P 0 0;1=3
P 10.73661004 2.91615 5 P 0 0;1=3
P 10.68661004 2.91615 5 P 0 0;1=3
P 10.88661004 2.91615 5 P 0 0;1=3
P 10.88661004 3.06615 5 P 0 0;1=3
P 10.83661004 3.06615 5 P 0 0;1=3
P 10.78661004 3.06615 5 P 0 0;1=3
P 10.73661004 3.06615 5 P 0 0;1=3
P 10.68661004 3.06615 5 P 0 0;1=3
P 10.88661004 3.21615 5 P 0 0;1=3
P 10.83661004 3.21615 5 P 0 0;1=3
P 10.83661004 3.36615 5 P 0 0;1=3
P 10.88661004 3.36615 5 P 0 0;1=3
P 10.78661004 3.36615 5 P 0 0;1=3
P 10.73661004 3.36615 5 P 0 0;1=3
P 10.78661004 3.21615 5 P 0 0;1=3
P 10.73661004 3.21615 5 P 0 0;1=3
P 10.68661004 3.36615 5 P 0 0;1=3
P 10.68661004 3.21615 5 P 0 0;1=3
P 10.83661004 3.51615 5 P 0 0;1=3
P 10.88661004 3.51615 5 P 0 0;1=3
P 10.83661004 3.66615 5 P 0 0;1=3
P 10.78661004 3.66615 5 P 0 0;1=3
P 10.73661004 3.66615 5 P 0 0;1=3
P 10.68661004 3.66615 5 P 0 0;1=3
P 10.78661004 3.51615 5 P 0 0;1=3
P 10.73661004 3.51615 5 P 0 0;1=3
P 10.68661004 3.51615 5 P 0 0;1=3
P 10.83661004 3.81615 5 P 0 0;1=3
P 10.88661004 3.81615 5 P 0 0;1=3
P 10.88661004 3.66615 5 P 0 0;1=3
P 10.78661004 3.81615 5 P 0 0;1=3
P 10.73661004 3.81615 5 P 0 0;1=3
P 10.68661004 3.81615 5 P 0 0;1=3
P 11.03661004 2.91615 5 P 0 0;1=3
P 10.93661004 2.91615 5 P 0 0;1=3
P 10.98661004 2.91615 5 P 0 0;1=3
P 11.03661004 3.06615 5 P 0 0;1=3
P 10.93661004 3.06615 5 P 0 0;1=3
P 10.98661004 3.06615 5 P 0 0;1=3
P 11.03661004 3.21615 5 P 0 0;1=3
P 10.93661004 3.21615 5 P 0 0;1=3
P 10.98661004 3.21615 5 P 0 0;1=3
P 10.98661004 3.36615 5 P 0 0;1=3
P 10.93661004 3.36615 5 P 0 0;1=3
P 11.03661004 3.36615 5 P 0 0;1=3
P 10.98661004 3.51615 5 P 0 0;1=3
P 10.93661004 3.51615 5 P 0 0;1=3
P 11.03661004 3.51615 5 P 0 0;1=3
P 10.98661004 3.66615 5 P 0 0;1=3
P 10.93661004 3.66615 5 P 0 0;1=3
P 11.03661004 3.66615 5 P 0 0;1=3
P 10.98661004 3.81615 5 P 0 0;1=3
P 10.93661004 3.81615 5 P 0 0;1=3
P 3.07691004 4.81401998 4 P 0 0;1=4
P 8.1 1.86615 5 P 0 0;1=3
P 8.15 2.16615 5 P 0 0;1=3
P 8.15 2.11615 5 P 0 0;1=3
P 8.15 1.96615 5 P 0 0;1=3
P 8.1 2.01615 5 P 0 0;1=3
P 8.05 1.96615 5 P 0 0;1=3
P 8.05 2.11615 5 P 0 0;1=3
P 8.05 2.16615 5 P 0 0;1=3
P 8.15 2.31615 5 P 0 0;1=3
P 8.1 2.36615 5 P 0 0;1=3
P 8.1 2.16615 5 P 0 0;1=3
P 8.1 2.21615 5 P 0 0;1=3
P 8.05 2.31615 5 P 0 0;1=3
P 8.15 2.46615 5 P 0 0;1=3
P 8.15 2.56615 5 P 0 0;1=3
P 8.1 2.51615 5 P 0 0;1=3
P 8.05 2.46615 5 P 0 0;1=3
P 8.05 2.51615 5 P 0 0;1=3
P 8.05 2.56615 5 P 0 0;1=3
P 8.1 2.66615 5 P 0 0;1=3
P 8.05 2.76615 5 P 0 0;1=3
P 8.05 2.81615 5 P 0 0;1=3
P 8 2.86615 5 P 0 0;1=3
P 8 2.71615 5 P 0 0;1=3
P 8.05 2.71615 5 P 0 0;1=3
P 8.15 2.71615 5 P 0 0;1=3
P 8.05 2.86615 5 P 0 0;1=3
P 8.15 2.86615 5 P 0 0;1=3
P 8.1 2.91615 5 P 0 0;1=3
P 8.1 2.86615 5 P 0 0;1=3
P 8.1 2.81615 5 P 0 0;1=3
P 8.05 3.01615 5 P 0 0;1=3
P 8.1 3.06615 5 P 0 0;1=3
P 8.15 3.01615 5 P 0 0;1=3
P 8.15 3.16615 5 P 0 0;1=3
P 8.05 3.16615 5 P 0 0;1=3
P 8 3.41615 5 P 0 0;1=3
P 8.05 3.41615 5 P 0 0;1=3
P 8.1 3.36615 5 P 0 0;1=3
P 8.1 3.21615 5 P 0 0;1=3
P 8.15 3.56615 5 P 0 0;1=3
P 8.05 3.56615 5 P 0 0;1=3
P 8 3.56615 5 P 0 0;1=3
P 8.05 3.51615 5 P 0 0;1=3
P 8.05 3.46615 5 P 0 0;1=3
P 8.1 3.51615 5 P 0 0;1=3
P 8.35 1.86615 5 P 0 0;1=3
P 8.3 1.86615 5 P 0 0;1=3
P 8.25 1.86615 5 P 0 0;1=3
P 8.2 1.86615 5 P 0 0;1=3
P 8.25 2.06615 5 P 0 0;1=3
P 8.25 2.16615 5 P 0 0;1=3
P 8.25 2.11615 5 P 0 0;1=3
P 8.3 2.11615 5 P 0 0;1=3
P 8.3 2.06615 5 P 0 0;1=3
P 8.4 2.11615 5 P 0 0;1=3
P 8.4 2.16615 5 P 0 0;1=3
P 8.4 1.96615 5 P 0 0;1=3
P 8.35 2.01615 5 P 0 0;1=3
P 8.3 2.01615 5 P 0 0;1=3
P 8.25 2.01615 5 P 0 0;1=3
P 8.2 2.01615 5 P 0 0;1=3
P 8.3 1.96615 5 P 0 0;1=3
P 8.25 1.96615 5 P 0 0;1=3
P 8.3 1.91615 5 P 0 0;1=3
P 8.25 1.91615 5 P 0 0;1=3
P 8.2 2.16615 5 P 0 0;1=3
P 8.2 2.21615 5 P 0 0;1=3
P 8.25 2.26615 5 P 0 0;1=3
P 8.3 2.26615 5 P 0 0;1=3
P 8.25 2.21615 5 P 0 0;1=3
P 8.3 2.16615 5 P 0 0;1=3
P 8.3 2.21615 5 P 0 0;1=3
P 8.35 2.21615 5 P 0 0;1=3
P 8.35 2.16615 5 P 0 0;1=3
P 8.25 2.31615 5 P 0 0;1=3
P 8.3 2.31615 5 P 0 0;1=3
P 8.35 2.36615 5 P 0 0;1=3
P 8.4 2.31615 5 P 0 0;1=3
P 8.3 2.36615 5 P 0 0;1=3
P 8.2 2.36615 5 P 0 0;1=3
P 8.25 2.36615 5 P 0 0;1=3
P 8.25 2.41615 5 P 0 0;1=3
P 8.3 2.41615 5 P 0 0;1=3
P 8.4 2.56615 5 P 0 0;1=3
P 8.4 2.51615 5 P 0 0;1=3
P 8.4 2.46615 5 P 0 0;1=3
P 8.3 2.46615 5 P 0 0;1=3
P 8.25 2.46615 5 P 0 0;1=3
P 8.2 2.51615 5 P 0 0;1=3
P 8.25 2.51615 5 P 0 0;1=3
P 8.3 2.51615 5 P 0 0;1=3
P 8.35 2.51615 5 P 0 0;1=3
P 8.3 2.56615 5 P 0 0;1=3
P 8.3 2.61615 5 P 0 0;1=3
P 8.25 2.56615 5 P 0 0;1=3
P 8.25 2.61615 5 P 0 0;1=3
P 8.2 2.66615 5 P 0 0;1=3
P 8.25 2.66615 5 P 0 0;1=3
P 8.3 2.66615 5 P 0 0;1=3
P 8.35 2.66615 5 P 0 0;1=3
P 8.25 2.71615 5 P 0 0;1=3
P 8.3 2.71615 5 P 0 0;1=3
P 8.4 2.71615 5 P 0 0;1=3
P 8.35 2.81615 5 P 0 0;1=3
P 8.4 2.86615 5 P 0 0;1=3
P 8.3 2.91615 5 P 0 0;1=3
P 8.25 2.91615 5 P 0 0;1=3
P 8.2 2.91615 5 P 0 0;1=3
P 8.2 2.81615 5 P 0 0;1=3
P 8.25 2.81615 5 P 0 0;1=3
P 8.25 2.76615 5 P 0 0;1=3
P 8.3 2.81615 5 P 0 0;1=3
P 8.3 2.76615 5 P 0 0;1=3
P 8.35 2.91615 5 P 0 0;1=3
P 8.35 2.86615 5 P 0 0;1=3
P 8.35 3.06615 5 P 0 0;1=3
P 8.4 3.01615 5 P 0 0;1=3
P 8.2 3.06615 5 P 0 0;1=3
P 8.25 3.01615 5 P 0 0;1=3
P 8.25 2.96615 5 P 0 0;1=3
P 8.25 3.11615 5 P 0 0;1=3
P 8.25 3.06615 5 P 0 0;1=3
P 8.3 3.01615 5 P 0 0;1=3
P 8.3 2.96615 5 P 0 0;1=3
P 8.3 3.11615 5 P 0 0;1=3
P 8.3 3.06615 5 P 0 0;1=3
P 8.25 3.16615 5 P 0 0;1=3
P 8.3 3.16615 5 P 0 0;1=3
P 8.4 3.16615 5 P 0 0;1=3
P 8.25 3.41615 5 P 0 0;1=3
P 8.3 3.36615 5 P 0 0;1=3
P 8.25 3.36615 5 P 0 0;1=3
P 8.2 3.36615 5 P 0 0;1=3
P 8.25 3.31615 5 P 0 0;1=3
P 8.25 3.26615 5 P 0 0;1=3
P 8.3 3.21615 5 P 0 0;1=3
P 8.25 3.21615 5 P 0 0;1=3
P 8.2 3.21615 5 P 0 0;1=3
P 8.35 3.21615 5 P 0 0;1=3
P 8.4 3.56615 5 P 0 0;1=3
P 8.3 3.61615 5 P 0 0;1=3
P 8.25 3.66615 5 P 0 0;1=3
P 8.25 3.61615 5 P 0 0;1=3
P 8.2 3.61615 5 P 0 0;1=3
P 8.2 3.56615 5 P 0 0;1=3
P 8.2 3.51615 5 P 0 0;1=3
P 8.25 3.51615 5 P 0 0;1=3
P 8.3 3.51615 5 P 0 0;1=3
P 8.25 3.46615 5 P 0 0;1=3
P 8.25 3.86615 5 P 0 0;1=3
P 8.25 3.81615 5 P 0 0;1=3
P 8.2 3.76615 5 P 0 0;1=3
P 8.25 3.76615 5 P 0 0;1=3
P 8.3 3.76615 5 P 0 0;1=3
P 8.25 3.71615 5 P 0 0;1=3
P 8.45 1.86615 5 P 0 0;1=3
P 8.5 2.16615 5 P 0 0;1=3
P 8.5 2.11615 5 P 0 0;1=3
P 8.5 1.96615 5 P 0 0;1=3
P 8.45 2.01615 5 P 0 0;1=3
P 8.45 2.21615 5 P 0 0;1=3
P 8.45 2.16615 5 P 0 0;1=3
P 8.5 2.31615 5 P 0 0;1=3
P 8.45 2.36615 5 P 0 0;1=3
P 8.5 2.46615 5 P 0 0;1=3
P 8.5 2.51615 5 P 0 0;1=3
P 8.5 2.56615 5 P 0 0;1=3
P 8.45 2.51615 5 P 0 0;1=3
P 8.45 2.66615 5 P 0 0;1=3
P 8.5 2.71615 5 P 0 0;1=3
P 8.5 2.86615 5 P 0 0;1=3
P 8.45 2.81615 5 P 0 0;1=3
P 8.45 2.86615 5 P 0 0;1=3
P 8.45 2.91615 5 P 0 0;1=3
P 8.5 3.01615 5 P 0 0;1=3
P 8.45 3.06615 5 P 0 0;1=3
P 8.5 3.16615 5 P 0 0;1=3
P 8.5 3.41615 5 P 0 0;1=3
P 8.45 3.36615 5 P 0 0;1=3
P 8.45 3.21615 5 P 0 0;1=3
P 8.5 3.21615 5 P 0 0;1=3
P 8.5 3.26615 5 P 0 0;1=3
P 8.5 3.56615 5 P 0 0;1=3
P 8.45 3.56615 5 P 0 0;1=3
P 8.5 3.86615 5 P 0 0;1=3
P 8.5 3.71615 5 P 0 0;1=3
P 8.2 2.86615 5 P 0 0;1=3
P 8.05 3.26615 5 P 0 0;1=3
P 8.05 3.21615 5 P 0 0;1=3
P 8.3 3.26615 5 P 0 0;1=3
P 8.3 3.31615 5 P 0 0;1=3
P 8.35 3.36615 5 P 0 0;1=3
P 8.15 3.26615 5 P 0 0;1=3
P 8.15 3.21615 5 P 0 0;1=3
P 8.4 3.21615 5 P 0 0;1=3
P 8.4 3.26615 5 P 0 0;1=3
P 8.1 3.61615 5 P 0 0;1=3
P 8.3 3.46615 5 P 0 0;1=3
P 8.3 3.41615 5 P 0 0;1=3
P 8.35 3.51615 5 P 0 0;1=3
P 8.35 3.61615 5 P 0 0;1=3
P 8.35 3.56615 5 P 0 0;1=3
P 8.15 3.41615 5 P 0 0;1=3
P 8.45 3.51615 5 P 0 0;1=3
P 8.45 3.61615 5 P 0 0;1=3
P 8.4 3.41615 5 P 0 0;1=3
P 8.05 3.71615 5 P 0 0;1=3
P 8.1 3.76615 5 P 0 0;1=3
P 8.05 3.86615 5 P 0 0;1=3
P 8.3 3.71615 5 P 0 0;1=3
P 8.3 3.66615 5 P 0 0;1=3
P 8.35 3.76615 5 P 0 0;1=3
P 8.3 3.81615 5 P 0 0;1=3
P 8.3 3.86615 5 P 0 0;1=3
P 8.15 3.71615 5 P 0 0;1=3
P 8.15 3.86615 5 P 0 0;1=3
P 8.45 3.76615 5 P 0 0;1=3
P 8.4 3.71615 5 P 0 0;1=3
P 8.4 3.86615 5 P 0 0;1=3
P 3.28831004 4.68073996 4 P 0 0;1=4
P 3.22831004 4.68073996 4 P 0 0;1=4
P 3.50091004 4.62573996 4 P 0 0;1=4
P 3.44091004 4.62573996 4 P 0 0;1=4
P 7.56575 5.023 4 P 0 0;1=4
P 7.63661998 5.023 4 P 0 0;1=4
P 7.84921998 5.023 4 P 0 0;1=4
P 7.77835 5.023 4 P 0 0;1=4
P 7.70748996 5.023 4 P 0 0;1=4
P 7.92008002 5.023 4 P 0 0;1=4
P 8.06181998 5.023 4 P 0 0;1=4
P 8.13268002 5.023 4 P 0 0;1=4
P 7.99095 5.023 4 P 0 0;1=4
P 8.34528002 5.023 4 P 0 0;1=4
P 8.27441004 5.023 4 P 0 0;1=4
P 8.20355 5.023 4 P 0 0;1=4
P 8.41615 5.023 4 P 0 0;1=4
P 7.63661998 4.92 4 P 0 0;1=4
P 7.84921998 4.9207 4 P 0 0;1=4
P 7.70748996 4.9207 4 P 0 0;1=4
P 7.77835 4.9207 4 P 0 0;1=4
P 7.99095 4.9207 4 P 0 0;1=4
P 7.92008002 4.9207 4 P 0 0;1=4
P 8.06181998 4.9207 4 P 0 0;1=4
P 8.13268002 4.9207 4 P 0 0;1=4
P 8.27441004 4.9207 4 P 0 0;1=4
P 8.20355 4.9267 4 P 0 0;1=4
P 8.34528002 4.9207 4 P 0 0;1=4
P 7.63526998 4.81526998 4 P 0 0;1=4
P 7.84921998 4.81 4 P 0 0;1=4
P 7.77953996 4.812 4 P 0 0;1=4
P 7.70353996 4.812 4 P 0 0;1=4
P 8.13268002 4.81 4 P 0 0;1=4
P 8.06441004 4.81 4 P 0 0;1=4
P 7.99353996 4.81 4 P 0 0;1=4
P 7.92353996 4.81 4 P 0 0;1=4
P 8.27441004 4.81 4 P 0 0;1=4
P 8.34528002 4.81 4 P 0 0;1=4
P 8.20355 4.81 4 P 0 0;1=4
P 8.41615 4.81401998 4 P 0 0;1=4
P 8.86908996 4.81401998 4 P 0 0;1=4
P 8.73035 4.81401998 4 P 0 0;1=4
P 8.80121998 4.81401998 4 P 0 0;1=4
P 8.94495 4.81401998 4 P 0 0;1=4
P 9.08045 4.81401998 4 P 0 0;1=4
P 9.01381998 4.81401998 4 P 0 0;1=4
P 9.36815 4.81401998 4 P 0 0;1=4
P 9.29728002 4.81401998 4 P 0 0;1=4
P 9.22641998 4.81401998 4 P 0 0;1=4
P 9.15751998 4.81401998 4 P 0 0;1=4
P 9.43901004 4.81401998 4 P 0 0;1=4
P 9.50988002 4.81401998 4 P 0 0;1=4
P 9.58075 4.81401998 4 P 0 0;1=4
P 8.80121998 5.023 4 P 0 0;1=4
P 8.73035 5.023 4 P 0 0;1=4
P 8.87208996 5.023 4 P 0 0;1=4
P 9.08468002 5.023 4 P 0 0;1=4
P 9.01381998 5.023 4 P 0 0;1=4
P 8.94295 5.023 4 P 0 0;1=4
P 8.87208996 4.92 4 P 0 0;1=4
P 8.80121998 4.92 4 P 0 0;1=4
P 9.01381998 4.92 4 P 0 0;1=4
P 9.08468002 4.92 4 P 0 0;1=4
P 9.22641998 4.92 4 P 0 0;1=4
P 9.36815 4.926 4 P 0 0;1=4
P 9.50988002 4.92 4 P 0 0;1=4
P 9.43901004 4.928 4 P 0 0;1=4
P 9.36815 5.023 4 P 0 0;1=4
P 9.29728002 5.023 4 P 0 0;1=4
P 9.22641998 5.023 4 P 0 0;1=4
P 9.15555 5.023 4 P 0 0;1=4
P 9.50988002 5.023 4 P 0 0;1=4
P 9.43901004 5.023 4 P 0 0;1=4
P 9.58075 5.023 4 P 0 0;1=4
P 8.94853996 4.92 4 P 0 0;1=4
P 9.27853996 4.92 4 P 0 0;1=4
P 9.14353996 4.92 4 P 0 0;1=4
P 8.13811004 5.09223996 4 P 0 0;1=4
P 8.35071004 5.15373996 4 P 0 0;1=4
P 8.41071004 5.15373996 4 P 0 0;1=4
P 7.56575 4.81401998 4 P 0 0;1=4
P 8.88061998 4.70573996 4 P 0 0;1=4
P 2.45985 4.77875 11 P 0 0;1=9
P 1.51496998 4.77875 11 P 0 0;1=9
P 2.44016998 5.05826998 11 P 0 0;1=9
P 1.53465 5.05826998 11 P 0 0;1=9
P 3.60476998 4.77875 11 P 0 0;1=9
P 2.67956998 4.77875 11 P 0 0;1=9
P 3.60476998 5.05826998 11 P 0 0;1=9
P 2.69925 5.05826998 11 P 0 0;1=9
P 8.46338996 4.77875 11 P 0 0;1=9
P 7.51851004 4.77875 11 P 0 0;1=9
P 8.44371004 5.05826998 11 P 0 0;1=9
P 7.53818996 5.05826998 11 P 0 0;1=9
P 9.60831004 4.77875 11 P 0 0;1=9
P 8.68311004 4.77875 11 P 0 0;1=9
P 9.60831004 5.05826998 11 P 0 0;1=9
P 8.70278996 5.05826998 11 P 0 0;1=9
P 10.82676998 5.49685 13 P 0 0;1=10
P 10.99213002 5.49685 13 P 0 0;1=10
P 11.15748002 5.49685 13 P 0 0;1=10
P 11.32283996 5.49685 13 P 0 0;1=10
P 11.48818996 5.49685 13 P 0 0;1=10
P 11.65353996 5.49685 13 P 0 0;1=10
P 11.8189 5.49685 13 P 0 0;1=10
P 11.98425 5.49685 13 P 0 0;1=10
P 12.14961004 5.49685 13 P 0 0;1=11
P 10.83661998 1.50786998 25 P 0 0;1=12
P 10.83661998 1.50788002 25 P 0 0;1=12
P 8.25 1.50788002 25 P 0 0;1=12
P 8.25 1.50786998 25 P 0 0;1=12
P 6.96456998 1.52756004 25 P 0 0;1=12
P 6.96456998 1.52756004 25 P 0 0;1=12
P 6.96456998 4.20471998 25 P 0 0;1=12
P 6.96456998 4.20473002 25 P 0 0;1=12
P 8.25 4.22441004 25 P 0 0;1=12
P 8.25 4.22441004 25 P 0 0;1=12
P 10.83661998 4.22441004 25 P 0 0;1=12
P 10.83661998 4.22441004 25 P 0 0;1=12
P 12.12205 4.20471998 25 P 0 0;1=12
P 12.12205 4.20473002 25 P 0 0;1=12
P 12.12205 1.52756004 25 P 0 0;1=12
P 12.12205 1.52756004 25 P 0 0;1=12
P 11.99213002 4.20473002 4 P 0 0;1=4
P 12.03018002 4.11286004 4 P 0 0;1=4
P 12.03018002 4.2966 4 P 0 0;1=4
P 12.21391998 4.11286004 4 P 0 0;1=4
P 12.25196998 4.20473002 4 P 0 0;1=4
P 12.21391998 4.2966 4 P 0 0;1=4
P 10.7067 4.22441004 4 P 0 0;1=4
P 10.74475 4.13253996 4 P 0 0;1=4
P 10.74475 4.31628002 4 P 0 0;1=4
P 10.92848996 4.13253996 4 P 0 0;1=4
P 10.96653996 4.22441004 4 P 0 0;1=4
P 10.92848996 4.31628002 4 P 0 0;1=4
P 8.12008002 4.22441004 4 P 0 0;1=4
P 8.15813002 4.13253996 4 P 0 0;1=4
P 8.15813002 4.31628002 4 P 0 0;1=4
P 8.34186998 4.13253996 4 P 0 0;1=4
P 8.37991998 4.22441004 4 P 0 0;1=4
P 8.34186998 4.31628002 4 P 0 0;1=4
P 6.83465 4.20473002 4 P 0 0;1=4
P 6.8727 4.11286004 4 P 0 0;1=4
P 6.8727 4.2966 4 P 0 0;1=4
P 7.05643996 4.11286004 4 P 0 0;1=4
P 7.09448996 4.20473002 4 P 0 0;1=4
P 7.05643996 4.2966 4 P 0 0;1=4
P 6.83465 1.52756004 4 P 0 0;1=4
P 6.8727 1.43568996 4 P 0 0;1=4
P 6.8727 1.61943002 4 P 0 0;1=4
P 7.05643996 1.43568996 4 P 0 0;1=4
P 7.09448996 1.52756004 4 P 0 0;1=4
P 7.05643996 1.61943002 4 P 0 0;1=4
P 8.15813002 1.416 4 P 0 0;1=4
P 8.12008002 1.50786998 4 P 0 0;1=4
P 8.15813002 1.59975 4 P 0 0;1=4
P 8.34186998 1.416 4 P 0 0;1=4
P 8.34186998 1.59975 4 P 0 0;1=4
P 8.37991998 1.50786998 4 P 0 0;1=4
P 10.74475 1.59975 4 P 0 0;1=4
P 10.92848996 1.59975 4 P 0 0;1=4
P 10.96653996 1.50786998 4 P 0 0;1=4
P 10.92848996 1.416 4 P 0 0;1=4
P 10.74475 1.416 4 P 0 0;1=4
P 10.7067 1.50786998 4 P 0 0;1=4
P 12.2126 1.43701004 4 P 0 0;1=4
P 12.25196998 1.52756004 4 P 0 0;1=4
P 12.2126 1.61811004 4 P 0 0;1=4
P 12.0315 1.61811004 4 P 0 0;1=4
P 11.99213002 1.52756004 4 P 0 0;1=4
P 12.0315 1.43701004 4 P 0 0;1=4
P 4.83268002 1.50786998 25 P 0 0;1=12
P 4.83268002 1.50788002 25 P 0 0;1=12
P 2.24606004 1.50788002 25 P 0 0;1=12
P 2.24606004 1.50786998 25 P 0 0;1=12
P 0.96063002 1.52756004 25 P 0 0;1=12
P 0.96063002 1.52756004 25 P 0 0;1=12
P 0.96063002 4.20471998 25 P 0 0;1=12
P 0.96063002 4.20473002 25 P 0 0;1=12
P 2.24606004 4.22441004 25 P 0 0;1=12
P 2.24606004 4.22441004 25 P 0 0;1=12
P 4.83268002 4.22441004 25 P 0 0;1=12
P 4.83268002 4.22441004 25 P 0 0;1=12
P 6.11811004 4.20471998 25 P 0 0;1=12
P 6.11811004 4.20473002 25 P 0 0;1=12
P 6.11811004 1.52756004 25 P 0 0;1=12
P 6.11811004 1.52756004 25 P 0 0;1=12
P 5.98818996 4.20473002 4 P 0 0;1=4
P 6.02623996 4.11286004 4 P 0 0;1=4
P 6.02623996 4.2966 4 P 0 0;1=4
P 6.20998002 4.11286004 4 P 0 0;1=4
P 6.24803002 4.20473002 4 P 0 0;1=4
P 6.20998002 4.2966 4 P 0 0;1=4
P 4.70276004 4.22441004 4 P 0 0;1=4
P 4.74081004 4.13253996 4 P 0 0;1=4
P 4.74081004 4.31628002 4 P 0 0;1=4
P 4.92455 4.13253996 4 P 0 0;1=4
P 4.9626 4.22441004 4 P 0 0;1=4
P 4.92455 4.31628002 4 P 0 0;1=4
P 2.11613996 4.22441004 4 P 0 0;1=4
P 2.15418996 4.13253996 4 P 0 0;1=4
P 2.15418996 4.31628002 4 P 0 0;1=4
P 2.33793002 4.13253996 4 P 0 0;1=4
P 2.37598002 4.22441004 4 P 0 0;1=4
P 2.33793002 4.31628002 4 P 0 0;1=4
P 0.83071004 4.20473002 4 P 0 0;1=4
P 0.86876004 4.11286004 4 P 0 0;1=4
P 0.86876004 4.2966 4 P 0 0;1=4
P 1.0525 4.11286004 4 P 0 0;1=4
P 1.09055 4.20473002 4 P 0 0;1=4
P 1.0525 4.2966 4 P 0 0;1=4
P 0.83071004 1.52756004 4 P 0 0;1=4
P 0.86876004 1.43568996 4 P 0 0;1=4
P 0.86876004 1.61943002 4 P 0 0;1=4
P 1.0525 1.43568996 4 P 0 0;1=4
P 1.09055 1.52756004 4 P 0 0;1=4
P 1.0525 1.61943002 4 P 0 0;1=4
P 2.15418996 1.416 4 P 0 0;1=4
P 2.11613996 1.50786998 4 P 0 0;1=4
P 2.15418996 1.59975 4 P 0 0;1=4
P 2.33793002 1.416 4 P 0 0;1=4
P 2.33793002 1.59975 4 P 0 0;1=4
P 2.37598002 1.50786998 4 P 0 0;1=4
P 4.74081004 1.59975 4 P 0 0;1=4
P 4.92455 1.59975 4 P 0 0;1=4
P 4.9626 1.50786998 4 P 0 0;1=4
P 4.92455 1.416 4 P 0 0;1=4
P 4.74081004 1.416 4 P 0 0;1=4
P 4.70276004 1.50786998 4 P 0 0;1=4
P 6.20866004 1.43701004 4 P 0 0;1=4
P 6.24803002 1.52756004 4 P 0 0;1=4
P 6.20866004 1.61811004 4 P 0 0;1=4
P 6.02756004 1.61811004 4 P 0 0;1=4
P 5.98818996 1.52756004 4 P 0 0;1=4
P 6.02756004 1.43701004 4 P 0 0;1=4
P 12.59646998 0.8189 4 P 0 0;1=4
P 12.5571 0.72835 4 P 0 0;1=4
P 12.59646998 0.6378 4 P 0 0;1=4
P 12.68701998 0.72835 25 P 0 0;1=12
P 12.77756998 0.6378 4 P 0 0;1=4
P 12.81693996 0.72835 4 P 0 0;1=4
P 12.77756998 0.8189 4 P 0 0;1=4
P 12.68701998 0.72835 25 P 0 0;1=12
P 12.59646998 5.24803002 4 P 0 0;1=4
P 12.5571 5.15748002 4 P 0 0;1=4
P 12.59646998 5.06693002 4 P 0 0;1=4
P 12.68701998 5.15748002 25 P 0 0;1=12
P 12.77756998 5.06693002 4 P 0 0;1=4
P 12.81693996 5.15748002 4 P 0 0;1=4
P 12.77756998 5.24803002 4 P 0 0;1=4
P 12.68701998 5.15748002 25 P 0 0;1=12
P 0.1319 5.20866004 4 P 0 0;1=4
P 0.09253002 5.11811004 4 P 0 0;1=4
P 0.1319 5.02756004 4 P 0 0;1=4
P 0.22245 5.11811004 25 P 0 0;1=12
P 0.313 5.02756004 4 P 0 0;1=4
P 0.35236998 5.11811004 4 P 0 0;1=4
P 0.313 5.20866004 4 P 0 0;1=4
P 0.22245 5.11811004 25 P 0 0;1=12
P 0.1319 0.77953002 4 P 0 0;1=4
P 0.09253002 0.68898002 4 P 0 0;1=4
P 0.1319 0.59843002 4 P 0 0;1=4
P 0.22245 0.68898002 25 P 0 0;1=12
P 0.313 0.59843002 4 P 0 0;1=4
P 0.35236998 0.68898002 4 P 0 0;1=4
P 0.313 0.77953002 4 P 0 0;1=4
P 0.22245 0.68898002 25 P 0 0;1=12
P 10.80498996 5.56656004 4 P 0 0;1=4
P 10.84498996 5.56656004 4 P 0 0;1=4
P 10.80498996 5.42656004 4 P 0 0;1=4
P 10.84498996 5.42656004 4 P 0 0;1=4
P 11.01035 5.42656004 4 P 0 0;1=4
P 10.97035 5.42656004 4 P 0 0;1=4
P 11.01035 5.56656004 4 P 0 0;1=4
P 10.97035 5.56656004 4 P 0 0;1=4
P 11.17571004 5.42656004 4 P 0 0;1=4
P 11.13571004 5.42656004 4 P 0 0;1=4
P 11.17571004 5.56656004 4 P 0 0;1=4
P 11.13571004 5.56656004 4 P 0 0;1=4
P 11.34106998 5.42656004 4 P 0 0;1=4
P 11.30106998 5.42656004 4 P 0 0;1=4
P 11.34106998 5.56656004 4 P 0 0;1=4
P 11.30106998 5.56656004 4 P 0 0;1=4
P 11.50643002 5.42656004 4 P 0 0;1=4
P 11.46643002 5.42656004 4 P 0 0;1=4
P 11.50643002 5.56656004 4 P 0 0;1=4
P 11.46643002 5.56656004 4 P 0 0;1=4
P 11.67178996 5.42656004 4 P 0 0;1=4
P 11.63178996 5.42656004 4 P 0 0;1=4
P 11.67178996 5.56656004 4 P 0 0;1=4
P 11.63178996 5.56656004 4 P 0 0;1=4
P 11.83715 5.42656004 4 P 0 0;1=4
P 11.79715 5.42656004 4 P 0 0;1=4
P 11.83715 5.56656004 4 P 0 0;1=4
P 11.79715 5.56656004 4 P 0 0;1=4
P 12.00251004 5.42656004 4 P 0 0;1=4
P 11.96251004 5.42656004 4 P 0 0;1=4
P 12.00251004 5.56656004 4 P 0 0;1=4
P 11.96251004 5.56656004 4 P 0 0;1=4
P 12.16786998 5.42656004 4 P 0 0;1=4
P 12.12786998 5.42656004 4 P 0 0;1=4
P 12.16786998 5.56656004 4 P 0 0;1=4
P 12.12786998 5.56656004 4 P 0 0;1=4
P 7.32283996 0.23621998 4 P 0 0;1=4
P 7.28016998 0.33921998 4 P 0 0;1=4
P 7.17716998 0.23621998 26 P 0 0;1=13
P 7.28016998 0.13321998 4 P 0 0;1=4
P 7.17716998 0.23621998 26 P 0 0;1=13
P 7.07416998 0.13321998 4 P 0 0;1=4
P 7.0315 0.23621998 4 P 0 0;1=4
P 7.07416998 0.33921998 4 P 0 0;1=4
P 7.32283996 5.7874 4 P 0 0;1=4
P 7.28016998 5.8904 4 P 0 0;1=4
P 7.17716998 5.7874 26 P 0 0;1=13
P 7.28016998 5.6844 4 P 0 0;1=4
P 7.17716998 5.7874 26 P 0 0;1=13
P 7.07416998 5.6844 4 P 0 0;1=4
P 7.0315 5.7874 4 P 0 0;1=4
P 7.07416998 5.8904 4 P 0 0;1=4
P 2.24606004 3.56615 5 P 0 0;1=3
P 8.2 3.26615 5 P 0 0;1=3
P 7.65203996 5.0535 5 P 0 0;1=3
P 2.29606004 2.86615 5 P 0 0;1=3
P 2.29606004 3.56615 5 P 0 0;1=3
P 7.69203996 5.0535 5 P 0 0;1=3
P 8.2 3.31615 5 P 0 0;1=3
P 1.33906004 4.69351004 4 P 0 0;1=0
P 0.80806998 5.46193996 4 P 0 0;1=0
P 3.733 5.075 4 P 0 0;1=4
P 1.28906004 4.69351004 4 P 0 0;1=0
P 8.2 3.41615 5 P 0 0;1=3
P 7.86465 5.169 5 P 0 0;1=3
P 3.94 4.765 4 P 0 0;1=0
P 2.34606004 3.26615 5 P 0 0;1=3
P 2.39716998 4.742 5 P 0 0;1=3
P 8.2 3.46615 5 P 0 0;1=3
P 7.90465 5.169 5 P 0 0;1=3
P 2.06646004 5.29 4 P 0 0;1=0
P 2.34606004 3.31615 5 P 0 0;1=3
P 2.35716998 4.742 5 P 0 0;1=3
P 1.33906004 5.15351004 4 P 0 0;1=0
P 3.105 4.47 4 P 0 0;1=4
P 8 3.46615 5 P 0 0;1=3
P 7.93551004 5.0535 5 P 0 0;1=3
P 2.00146004 5.29 4 P 0 0;1=0
P 2.25855 4.667 5 P 0 0;1=3
P 2.39606004 3.31615 5 P 0 0;1=3
P 1.18906004 5.15351004 4 P 0 0;1=0
P 3.07 4.42 4 P 0 0;1=4
P 8 3.51615 5 P 0 0;1=3
P 7.97551004 5.0535 5 P 0 0;1=3
P 2.21855 4.667 5 P 0 0;1=3
P 2.39606004 3.36615 5 P 0 0;1=3
P 8.11725 5.169 5 P 0 0;1=3
P 8.4 3.46615 5 P 0 0;1=3
P 3.635 0.715 4 P 0 0;1=0
P 4.63268002 2.81615 5 P 0 0;1=3
P 2.44606004 3.26615 5 P 0 0;1=3
P 2.39716998 5.115 5 P 0 0;1=3
P 8.07725 5.169 5 P 0 0;1=3
P 8.4 3.51615 5 P 0 0;1=3
P 2.44606004 3.31615 5 P 0 0;1=3
P 2.35716998 5.115 5 P 0 0;1=3
P 8.5 3.46615 5 P 0 0;1=3
P 8.07206998 4.66688996 5 P 0 0;1=3
P 2.25543996 4.78291998 5 P 0 0;1=3
P 2.49606004 3.31615 5 P 0 0;1=3
P 8.5 3.51615 5 P 0 0;1=3
P 8.03206998 4.66688996 5 P 0 0;1=3
P 4.02 4.42 4 P 0 0;1=0
P 4.58268002 2.76615 5 P 0 0;1=3
P 2.21543996 4.78291998 5 P 0 0;1=3
P 2.49606004 3.36615 5 P 0 0;1=3
P 8.35 3.41615 5 P 0 0;1=3
P 8.11725 4.78291998 5 P 0 0;1=3
P 4.78268002 2.71615 5 P 0 0;1=3
P 2.11371004 4.78291998 5 P 0 0;1=3
P 2.34606004 3.41615 5 P 0 0;1=3
P 8.35 3.46615 5 P 0 0;1=3
P 8.07725 4.78291998 5 P 0 0;1=3
P 5.08268002 2.71615 5 P 0 0;1=3
P 4.06 4.86 4 P 0 0;1=0
P 2.07371004 4.78291998 5 P 0 0;1=3
P 2.34606004 3.46615 5 P 0 0;1=3
P 2.18456998 5.0535 5 P 0 0;1=3
P 2.44606004 3.41615 5 P 0 0;1=3
P 10.93661004 2.41615 5 P 0 0;1=3
P 2.14456998 5.0535 5 P 0 0;1=3
P 2.44606004 3.46615 5 P 0 0;1=3
P 10.93661004 2.46615 5 P 0 0;1=3
P 8.5 3.31615 5 P 0 0;1=3
P 8.25898002 4.78291998 5 P 0 0;1=3
P 4.88268002 2.71615 5 P 0 0;1=3
P 2.06853002 4.66688996 5 P 0 0;1=3
P 2.49606004 3.46615 5 P 0 0;1=3
P 8.5 3.36615 5 P 0 0;1=3
P 8.21898002 4.78291998 5 P 0 0;1=3
P 2.02853002 4.66688996 5 P 0 0;1=3
P 2.49606004 3.51615 5 P 0 0;1=3
P 8.4 3.31615 5 P 0 0;1=3
P 8.26208996 4.667 5 P 0 0;1=3
P 2.11371004 5.169 5 P 0 0;1=3
P 2.39606004 3.46615 5 P 0 0;1=3
P 8.4 3.36615 5 P 0 0;1=3
P 8.22208996 4.667 5 P 0 0;1=3
P 3.84 0.69 4 P 0 0;1=0
P 4.68268002 2.76615 5 P 0 0;1=3
P 2.07371004 5.169 5 P 0 0;1=3
P 2.39606004 3.51615 5 P 0 0;1=3
P 3.56 0.49 4 P 0 0;1=0
P 4.73268002 2.81615 5 P 0 0;1=3
P 1.57765 5.169 5 P 0 0;1=3
P 2.04606004 3.31615 5 P 0 0;1=3
P 9.10853996 4.47 4 P 0 0;1=4
P 7.3426 5.15351004 4 P 0 0;1=0
P 3.785 0.69 4 P 0 0;1=0
P 4.78268002 2.81615 5 P 0 0;1=3
P 1.61765 5.169 5 P 0 0;1=3
P 2.04606004 3.36615 5 P 0 0;1=3
P 8.1 3.26615 5 P 0 0;1=3
P 7.58118996 4.707 5 P 0 0;1=3
P 2.09606004 3.26615 5 P 0 0;1=3
P 1.57765 4.707 5 P 0 0;1=3
P 5.08268002 1.96615 5 P 0 0;1=3
P 8.1 3.31615 5 P 0 0;1=3
P 7.62118996 4.707 5 P 0 0;1=3
P 3.75998996 0.345 4 P 0 0;1=0
P 4.68268002 2.81615 5 P 0 0;1=3
P 2.09606004 3.31615 5 P 0 0;1=3
P 1.61765 4.707 5 P 0 0;1=3
P 0.58 5.591 4 P 0 0;1=0
P 11.67761998 2.85 4 P 0 0;1=4
P 11.865 4.455 4 P 0 0;1=0
P 5.67368996 2.85 4 P 0 0;1=4
P 5.855 3.07 4 P 0 0;1=4
P 5.8522 2.97 4 P 0 0;1=4
P 7.2926 5.15351004 4 P 0 0;1=4
P 7.2426 5.15351004 4 P 0 0;1=4
P 7.1926 4.95351004 4 P 0 0;1=4
P 7.42603996 5.15895 4 P 0 0;1=0
P 3.94 4.655 4 P 0 0;1=4
P 3.77 4.765 4 P 0 0;1=4
P 4.14 4.745 4 P 0 0;1=4
P 4.76 5.375 4 P 0 0;1=4
P 4.96 5.5 4 P 0 0;1=4
P 5.16 5.555 4 P 0 0;1=4
P 4.892 5.767 4 P 0 0;1=4
P 5.088 5.767 4 P 0 0;1=4
P 0.91 5.075 4 P 0 0;1=4
P 1.03 4.96 4 P 0 0;1=4
P 1.03 5.155 4 P 0 0;1=4
P 1.38906004 5.15351004 4 P 0 0;1=0
P 1.23906004 5.15351004 4 P 0 0;1=4
P 1.28906004 5.15351004 4 P 0 0;1=4
P 1.18906004 4.95351004 4 P 0 0;1=4
P 0.83 5.355 4 P 0 0;1=4
P 0.9 5.355 4 P 0 0;1=4
P 0.755 5.355 4 P 0 0;1=4
P 0.73 5.205 4 P 0 0;1=4
P 0.81016004 5.17 4 P 0 0;1=4
P 1.094 5.356 4 P 0 0;1=0
P 1.044 5.448 4 P 0 0;1=4
P 1.4 5.46 4 P 0 0;1=4
P 1.32 5.46 4 P 0 0;1=4
P 1.43798996 5.46016004 4 P 0 0;1=4
P 1.35925 5.46016004 4 P 0 0;1=4
P 0.89 5.885 4 P 0 0;1=4
P 0.81 5.885 4 P 0 0;1=4
P 0.73 5.885 4 P 0 0;1=4
P 0.97 5.885 4 P 0 0;1=4
P 1.04 5.885 4 P 0 0;1=4
P 1.12 5.885 4 P 0 0;1=4
P 8.15 3.31615 5 P 0 0;1=3
P 7.65205 4.78291998 5 P 0 0;1=3
P 11.235 3.3 4 P 0 0;1=4
P 5.815 0.925 4 P 0 0;1=0
P 3.635 0.49 4 P 0 0;1=0
P 4.58268002 2.81615 5 P 0 0;1=3
P 2.19606004 3.26615 5 P 0 0;1=3
P 1.6485 5.0535 5 P 0 0;1=3
P 8.15 3.36615 5 P 0 0;1=3
P 7.69205 4.78291998 5 P 0 0;1=3
P 2.19606004 3.31615 5 P 0 0;1=3
P 1.6885 5.0535 5 P 0 0;1=3
P 8.1 3.41615 5 P 0 0;1=3
P 7.79378996 4.78291998 5 P 0 0;1=3
P 2.14606004 3.31615 5 P 0 0;1=3
P 1.64851004 4.78291998 5 P 0 0;1=3
P 8.1 3.46615 5 P 0 0;1=3
P 7.83378996 4.78291998 5 P 0 0;1=3
P 2.14606004 3.36615 5 P 0 0;1=3
P 1.68851004 4.78291998 5 P 0 0;1=3
P 0.73 4.96 4 P 0 0;1=0
P 3.795 4.6 4 P 0 0;1=4
P 4.86 5.375 4 P 0 0;1=4
P 8.15 3.46615 5 P 0 0;1=3
P 7.86465 4.657 5 P 0 0;1=3
P 2.09606004 3.41615 5 P 0 0;1=3
P 1.79025 4.78291998 5 P 0 0;1=3
P 8.15 3.51615 5 P 0 0;1=3
P 7.90465 4.657 5 P 0 0;1=3
P 2.09606004 3.46615 5 P 0 0;1=3
P 1.83025 4.78291998 5 P 0 0;1=3
P 2.19606004 3.41615 5 P 0 0;1=3
P 1.86111004 5.169 5 P 0 0;1=3
P 2.19606004 3.46615 5 P 0 0;1=3
P 1.90111004 5.169 5 P 0 0;1=3
P 6.72708976 4.5652 28 P 0 0;1=4
P 6.76208976 4.5652 28 P 0 0;1=4
P 6.79708976 4.5652 28 P 0 0;1=4
P 6.83708976 4.5652 28 P 0 0;1=0
P 6.90208976 4.5652 28 P 0 0;1=4
P 6.87208976 4.5652 28 P 0 0;1=4
P 10.99998976 4.9531 28 P 0 0;1=4
P 11.03998976 4.9531 28 P 0 0;1=4
P 10.99998976 4.9131 28 P 0 0;1=4
P 11.03998976 4.9131 28 P 0 0;1=4
P 11.21998976 4.9531 28 P 0 0;1=4
P 11.17998976 4.9531 28 P 0 0;1=4
P 11.13498976 4.9531 28 P 0 0;1=4
P 11.08498976 4.9531 28 P 0 0;1=4
P 11.21998976 4.9131 28 P 0 0;1=4
P 11.17998976 4.9131 28 P 0 0;1=4
P 11.08498976 4.9131 28 P 0 0;1=4
P 11.13498976 4.9131 28 P 0 0;1=4
P 10.99998976 5.1631 28 P 0 0;1=4
P 11.03998976 5.1631 28 P 0 0;1=4
P 10.99998976 5.1231 28 P 0 0;1=4
P 10.99998976 5.0381 28 P 0 0;1=4
P 10.99998976 5.0831 28 P 0 0;1=4
P 10.99998976 4.9931 28 P 0 0;1=4
P 11.03998976 4.9931 28 P 0 0;1=4
P 11.03998976 5.0831 28 P 0 0;1=4
P 11.03998976 5.0381 28 P 0 0;1=4
P 11.03998976 5.1231 28 P 0 0;1=4
P 11.21998976 5.1631 28 P 0 0;1=4
P 11.17998976 5.1631 28 P 0 0;1=4
P 11.08498976 5.1631 28 P 0 0;1=4
P 11.13498976 5.1631 28 P 0 0;1=4
P 11.21998976 5.1231 28 P 0 0;1=4
P 11.21998976 5.0381 28 P 0 0;1=4
P 11.21998976 5.0831 28 P 0 0;1=4
P 11.21998976 4.9931 28 P 0 0;1=4
P 11.17998976 4.9931 28 P 0 0;1=4
P 11.17998976 5.1231 28 P 0 0;1=4
P 11.17998976 5.0831 28 P 0 0;1=4
P 11.17998976 5.0381 28 P 0 0;1=4
P 11.13498976 5.1231 28 P 0 0;1=4
P 11.08498976 5.1231 28 P 0 0;1=4
P 11.6269 4.90498976 28 P 0 0;1=4
P 11.6269 4.85498976 28 P 0 0;1=4
P 11.4269 4.80998976 28 P 0 0;1=4
P 11.4269 4.85498976 28 P 0 0;1=4
P 11.4269 4.90498976 28 P 0 0;1=4
P 11.4269 4.94998976 28 P 0 0;1=4
P 11.4769 4.94998976 28 P 0 0;1=4
P 11.4769 4.80998976 28 P 0 0;1=4
P 11.5269 4.94998976 28 P 0 0;1=4
P 11.5269 4.80998976 28 P 0 0;1=4
P 11.5769 4.94998976 28 P 0 0;1=4
P 11.6269 4.94998976 28 P 0 0;1=4
P 11.6269 4.80998976 28 P 0 0;1=4
P 11.5769 4.80998976 28 P 0 0;1=4
P 10.82676998 5.71338996 31 P 0 2;1=10
P 10.99213002 5.71338996 31 P 0 2;1=10
P 11.15748002 5.71338996 31 P 0 2;1=10
P 11.32283996 5.71338996 31 P 0 2;1=10
P 11.48818996 5.71338996 31 P 0 2;1=10
P 11.65353996 5.71338996 31 P 0 2;1=10
P 11.8189 5.71338996 31 P 0 2;1=10
P 11.98425 5.71338996 31 P 0 2;1=10
P 12.14961004 5.71338996 31 P 0 2;1=10
P 10.80498976 5.7831 28 P 0 0;1=4
P 10.84498976 5.7831 28 P 0 0;1=4
P 10.80498976 5.6431 28 P 0 0;1=4
P 10.84498976 5.6431 28 P 0 0;1=4
P 11.01035 5.6431 28 P 0 0;1=4
P 10.97035 5.6431 28 P 0 0;1=4
P 11.01035 5.7831 28 P 0 0;1=4
P 10.97035 5.7831 28 P 0 0;1=4
P 11.17570974 5.6431 28 P 0 0;1=4
P 11.13570974 5.6431 28 P 0 0;1=4
P 11.17570974 5.7831 28 P 0 0;1=4
P 11.13570974 5.7831 28 P 0 0;1=4
P 11.34106998 5.6431 28 P 0 0;1=4
P 11.30106998 5.6431 28 P 0 0;1=4
P 11.34106998 5.7831 28 P 0 0;1=4
P 11.30106998 5.7831 28 P 0 0;1=4
P 11.50642972 5.6431 28 P 0 0;1=4
P 11.46642972 5.6431 28 P 0 0;1=4
P 11.50642972 5.7831 28 P 0 0;1=4
P 11.46642972 5.7831 28 P 0 0;1=4
P 11.67178976 5.6431 28 P 0 0;1=4
P 11.63178976 5.6431 28 P 0 0;1=4
P 11.67178976 5.7831 28 P 0 0;1=4
P 11.63178976 5.7831 28 P 0 0;1=4
P 11.83715 5.6431 28 P 0 0;1=4
P 11.79715 5.6431 28 P 0 0;1=4
P 11.83715 5.7831 28 P 0 0;1=4
P 11.79715 5.7831 28 P 0 0;1=4
P 12.00250974 5.6431 28 P 0 0;1=4
P 11.96250974 5.6431 28 P 0 0;1=4
P 12.00250974 5.7831 28 P 0 0;1=4
P 11.96250974 5.7831 28 P 0 0;1=4
P 12.16786998 5.6431 28 P 0 0;1=4
P 12.12786998 5.6431 28 P 0 0;1=4
P 12.16786998 5.7831 28 P 0 0;1=4
P 12.12786998 5.7831 28 P 0 0;1=4
P 5.03605 5.1631 28 P 0 0;1=4
P 5.03605 4.9931 28 P 0 0;1=4
P 5.03605 5.0831 28 P 0 0;1=4
P 5.03605 5.0381 28 P 0 0;1=4
P 5.03605 5.1231 28 P 0 0;1=4
P 5.21605 5.1631 28 P 0 0;1=4
P 5.17605 5.1631 28 P 0 0;1=4
P 5.08105 5.1631 28 P 0 0;1=4
P 5.13105 5.1631 28 P 0 0;1=4
P 5.21605 5.1231 28 P 0 0;1=4
P 5.21605 5.0381 28 P 0 0;1=4
P 5.21605 5.0831 28 P 0 0;1=4
P 5.21605 4.9931 28 P 0 0;1=4
P 5.17605 4.9931 28 P 0 0;1=4
P 5.17605 5.1231 28 P 0 0;1=4
P 5.17605 5.0831 28 P 0 0;1=4
P 5.17605 5.0381 28 P 0 0;1=4
P 5.13105 5.1231 28 P 0 0;1=4
P 5.08105 5.1231 28 P 0 0;1=4
P 4.99605 5.1631 28 P 0 0;1=4
P 4.99605 5.1231 28 P 0 0;1=4
P 4.99605 5.0381 28 P 0 0;1=4
P 4.99605 5.0831 28 P 0 0;1=4
P 4.99605 4.9931 28 P 0 0;1=4
P 5.03605 4.9531 28 P 0 0;1=4
P 5.03605 4.9131 28 P 0 0;1=4
P 5.21605 4.9531 28 P 0 0;1=4
P 5.17605 4.9531 28 P 0 0;1=4
P 5.13105 4.9531 28 P 0 0;1=4
P 5.08105 4.9531 28 P 0 0;1=4
P 5.21605 4.9131 28 P 0 0;1=4
P 5.17605 4.9131 28 P 0 0;1=4
P 5.08105 4.9131 28 P 0 0;1=4
P 5.13105 4.9131 28 P 0 0;1=4
P 4.99605 4.9531 28 P 0 0;1=4
P 4.99605 4.9131 28 P 0 0;1=4
P 6.34948976 5.03 28 P 0 0;1=4
P 2.74225 5.14 5 P 0 0;1=3
P 2.04606004 3.61615 5 P 0 0;1=3
P 2.14606004 3.46615 5 P 0 0;1=3
P 1.86111004 4.657 5 P 0 0;1=3
P 2.78225 5.14 5 P 0 0;1=3
P 2.04606004 3.66615 5 P 0 0;1=3
P 2.14606004 3.51615 5 P 0 0;1=3
P 1.90111004 4.657 5 P 0 0;1=3
P 1.93196998 5.0535 5 P 0 0;1=3
P 1.99606004 3.46615 5 P 0 0;1=3
P 4.58268002 2.56615 5 P 0 0;1=3
P 1.97196998 5.0535 5 P 0 0;1=3
P 1.99606004 3.51615 5 P 0 0;1=3
P 2.88086998 5.17001998 5 P 0 0;1=3
P 2.14606004 3.61615 5 P 0 0;1=3
P 2.34606004 3.66615 5 P 0 0;1=3
P 3.56176998 4.71973002 5 P 0 0;1=3
P 2.92086998 5.17001998 5 P 0 0;1=3
P 2.14606004 3.66615 5 P 0 0;1=3
P 2.34606004 3.71615 5 P 0 0;1=3
P 3.52176998 4.71973002 5 P 0 0;1=3
P 2.39606004 3.61615 5 P 0 0;1=3
P 3.49091004 4.587 5 P 0 0;1=3
P 2.39606004 3.66615 5 P 0 0;1=3
P 3.45091004 4.587 5 P 0 0;1=3
P 2.49606004 3.61615 5 P 0 0;1=3
P 3.56176998 5.14 5 P 0 0;1=3
P 2.49606004 3.66615 5 P 0 0;1=3
P 3.52176998 5.14 5 P 0 0;1=3
P 2.44606004 3.66615 5 P 0 0;1=3
P 3.42003996 4.78291998 5 P 0 0;1=3
P 4.30605 4.6631 4 P 0 0;1=4
P 4.34105 4.6431 4 P 0 0;1=4
P 4.38605 4.6431 4 P 0 0;1=4
P 4.42605 4.6631 4 P 0 0;1=4
P 4.46605 4.6631 4 P 0 0;1=4
P 4.30605 4.7031 4 P 0 0;1=4
P 4.42605 4.7031 4 P 0 0;1=4
P 4.46605 4.7031 4 P 0 0;1=4
P 4.26605 4.6631 4 P 0 0;1=4
P 4.26605 4.7031 4 P 0 0;1=4
P 4.65605 4.6631 4 P 0 0;1=4
P 4.69605 4.6631 4 P 0 0;1=4
P 4.65605 4.7031 4 P 0 0;1=4
P 4.69605 4.7031 4 P 0 0;1=4
P 4.73105 4.6431 4 P 0 0;1=4
P 4.81605 4.6631 4 P 0 0;1=4
P 4.85605 4.6631 4 P 0 0;1=4
P 4.81605 4.7031 4 P 0 0;1=4
P 4.85605 4.7031 4 P 0 0;1=4
P 4.77605 4.6431 4 P 0 0;1=4
P 5.17605 4.7131 4 P 0 0;1=4
P 5.17605 4.6731 4 P 0 0;1=4
P 5.08105 4.6731 4 P 0 0;1=4
P 5.13105 4.6731 4 P 0 0;1=4
P 5.03605 4.6731 4 P 0 0;1=4
P 5.03605 4.7131 4 P 0 0;1=4
P 4.30605 4.7481 4 P 0 0;1=4
P 4.30605 4.7931 4 P 0 0;1=4
P 4.30605 4.8381 4 P 0 0;1=4
P 4.38605 4.8381 4 P 0 0;1=4
P 4.34605 4.8381 4 P 0 0;1=4
P 4.46605 4.8381 4 P 0 0;1=4
P 4.42605 4.8381 4 P 0 0;1=4
P 4.42605 4.7931 4 P 0 0;1=4
P 4.42605 4.7481 4 P 0 0;1=4
P 4.46605 4.7931 4 P 0 0;1=4
P 4.46605 4.7481 4 P 0 0;1=4
P 4.26605 4.7481 4 P 0 0;1=4
P 4.26605 4.7931 4 P 0 0;1=4
P 4.26605 4.8381 4 P 0 0;1=4
P 4.65605 4.8381 4 P 0 0;1=4
P 4.65605 4.7931 4 P 0 0;1=4
P 4.65605 4.7481 4 P 0 0;1=4
P 4.69605 4.8381 4 P 0 0;1=4
P 4.69605 4.7931 4 P 0 0;1=4
P 4.69605 4.7481 4 P 0 0;1=4
P 4.73605 4.8381 4 P 0 0;1=4
P 4.81605 4.8381 4 P 0 0;1=4
P 4.81605 4.7931 4 P 0 0;1=4
P 4.81605 4.7481 4 P 0 0;1=4
P 4.85605 4.8381 4 P 0 0;1=4
P 4.85605 4.7931 4 P 0 0;1=4
P 4.85605 4.7481 4 P 0 0;1=4
P 4.77605 4.8381 4 P 0 0;1=4
P 5.08105 4.8431 4 P 0 0;1=4
P 5.13105 4.8431 4 P 0 0;1=4
P 5.17605 4.8431 4 P 0 0;1=4
P 5.17605 4.8031 4 P 0 0;1=4
P 5.17605 4.7581 4 P 0 0;1=4
P 5.03605 4.8431 4 P 0 0;1=4
P 5.03605 4.8031 4 P 0 0;1=4
P 5.03605 4.7581 4 P 0 0;1=4
P 4.58268002 2.96615 5 P 0 0;1=3
P 4.63268002 2.96615 5 P 0 0;1=3
P 4.63268002 3.11615 5 P 0 0;1=3
P 4.58268002 3.01615 5 P 0 0;1=3
P 4.58268002 3.11615 5 P 0 0;1=3
P 4.63268002 3.01615 5 P 0 0;1=3
P 4.63268002 3.31615 5 P 0 0;1=3
P 4.58268002 3.26615 5 P 0 0;1=3
P 4.58268002 3.31615 5 P 0 0;1=3
P 4.63268002 3.26615 5 P 0 0;1=3
P 4.63268002 3.16615 5 P 0 0;1=3
P 4.58268002 3.16615 5 P 0 0;1=3
P 4.58268002 3.46615 5 P 0 0;1=3
P 4.63268002 3.41615 5 P 0 0;1=3
P 4.63268002 3.46615 5 P 0 0;1=3
P 4.58268002 3.41615 5 P 0 0;1=3
P 4.58268002 3.61615 5 P 0 0;1=3
P 4.58268002 3.56615 5 P 0 0;1=3
P 4.63268002 3.61615 5 P 0 0;1=3
P 4.63268002 3.56615 5 P 0 0;1=3
P 4.58268002 3.71615 5 P 0 0;1=3
P 4.63268002 3.71615 5 P 0 0;1=3
P 4.58268002 3.76615 5 P 0 0;1=3
P 4.58268002 3.86615 5 P 0 0;1=3
P 4.63268002 3.76615 5 P 0 0;1=3
P 4.63268002 3.86615 5 P 0 0;1=3
P 4.68268002 2.96615 5 P 0 0;1=3
P 4.73268002 2.96615 5 P 0 0;1=3
P 4.78268002 2.96615 5 P 0 0;1=3
P 4.68268002 3.11615 5 P 0 0;1=3
P 4.68268002 3.01615 5 P 0 0;1=3
P 4.73268002 3.11615 5 P 0 0;1=3
P 4.73268002 3.01615 5 P 0 0;1=3
P 4.78268002 3.11615 5 P 0 0;1=3
P 4.78268002 3.01615 5 P 0 0;1=3
P 4.73268002 3.31615 5 P 0 0;1=3
P 4.73268002 3.26615 5 P 0 0;1=3
P 4.68268002 3.26615 5 P 0 0;1=3
P 4.68268002 3.31615 5 P 0 0;1=3
P 4.78268002 3.26615 5 P 0 0;1=3
P 4.78268002 3.31615 5 P 0 0;1=3
P 4.73268002 3.16615 5 P 0 0;1=3
P 4.68268002 3.16615 5 P 0 0;1=3
P 4.78268002 3.16615 5 P 0 0;1=3
P 4.73268002 3.41615 5 P 0 0;1=3
P 4.68268002 3.41615 5 P 0 0;1=3
P 4.68268002 3.46615 5 P 0 0;1=3
P 4.73268002 3.46615 5 P 0 0;1=3
P 4.78268002 3.46615 5 P 0 0;1=3
P 4.78268002 3.41615 5 P 0 0;1=3
P 4.73268002 3.56615 5 P 0 0;1=3
P 4.73268002 3.61615 5 P 0 0;1=3
P 4.68268002 3.56615 5 P 0 0;1=3
P 4.68268002 3.61615 5 P 0 0;1=3
P 4.78268002 3.61615 5 P 0 0;1=3
P 4.78268002 3.56615 5 P 0 0;1=3
P 4.73268002 3.71615 5 P 0 0;1=3
P 4.68268002 3.71615 5 P 0 0;1=3
P 4.78268002 3.71615 5 P 0 0;1=3
P 4.73268002 3.76615 5 P 0 0;1=3
P 4.73268002 3.86615 5 P 0 0;1=3
P 4.68268002 3.76615 5 P 0 0;1=3
P 4.68268002 3.86615 5 P 0 0;1=3
P 4.78268002 3.76615 5 P 0 0;1=3
P 4.78268002 3.86615 5 P 0 0;1=3
P 4.88268002 3.86615 5 P 0 0;1=3
P 4.83268002 3.86615 5 P 0 0;1=3
P 5.03268002 3.86615 5 P 0 0;1=3
P 4.93268002 3.86615 5 P 0 0;1=3
P 4.98268002 3.86615 5 P 0 0;1=3
P 4.88268002 3.76615 5 P 0 0;1=3
P 4.83268002 3.76615 5 P 0 0;1=3
P 5.03268002 3.76615 5 P 0 0;1=3
P 4.93268002 3.76615 5 P 0 0;1=3
P 4.98268002 3.76615 5 P 0 0;1=3
P 4.88268002 3.71615 5 P 0 0;1=3
P 4.83268002 3.71615 5 P 0 0;1=3
P 5.03268002 3.71615 5 P 0 0;1=3
P 4.93268002 3.71615 5 P 0 0;1=3
P 4.98268002 3.71615 5 P 0 0;1=3
P 4.88268002 3.61615 5 P 0 0;1=3
P 4.83268002 3.61615 5 P 0 0;1=3
P 5.03268002 3.61615 5 P 0 0;1=3
P 4.93268002 3.61615 5 P 0 0;1=3
P 4.98268002 3.61615 5 P 0 0;1=3
P 4.88268002 3.56615 5 P 0 0;1=3
P 4.83268002 3.56615 5 P 0 0;1=3
P 5.03268002 3.56615 5 P 0 0;1=3
P 4.93268002 3.56615 5 P 0 0;1=3
P 4.98268002 3.56615 5 P 0 0;1=3
P 4.88268002 3.46615 5 P 0 0;1=3
P 4.83268002 3.46615 5 P 0 0;1=3
P 5.03268002 3.46615 5 P 0 0;1=3
P 4.93268002 3.46615 5 P 0 0;1=3
P 4.98268002 3.46615 5 P 0 0;1=3
P 4.88268002 3.41615 5 P 0 0;1=3
P 4.83268002 3.41615 5 P 0 0;1=3
P 5.03268002 3.41615 5 P 0 0;1=3
P 4.93268002 3.41615 5 P 0 0;1=3
P 4.98268002 3.41615 5 P 0 0;1=3
P 4.88268002 3.31615 5 P 0 0;1=3
P 4.83268002 3.31615 5 P 0 0;1=3
P 5.03268002 3.31615 5 P 0 0;1=3
P 4.93268002 3.31615 5 P 0 0;1=3
P 4.98268002 3.31615 5 P 0 0;1=3
P 4.83268002 3.26615 5 P 0 0;1=3
P 4.88268002 3.26615 5 P 0 0;1=3
P 4.98268002 3.26615 5 P 0 0;1=3
P 4.93268002 3.26615 5 P 0 0;1=3
P 5.03268002 3.26615 5 P 0 0;1=3
P 4.83268002 3.16615 5 P 0 0;1=3
P 4.88268002 3.16615 5 P 0 0;1=3
P 4.98268002 3.16615 5 P 0 0;1=3
P 4.93268002 3.16615 5 P 0 0;1=3
P 5.03268002 3.16615 5 P 0 0;1=3
P 4.83268002 3.11615 5 P 0 0;1=3
P 4.88268002 3.11615 5 P 0 0;1=3
P 4.98268002 3.11615 5 P 0 0;1=3
P 4.93268002 3.11615 5 P 0 0;1=3
P 5.03268002 3.11615 5 P 0 0;1=3
P 4.83268002 3.01615 5 P 0 0;1=3
P 4.88268002 3.01615 5 P 0 0;1=3
P 4.98268002 3.01615 5 P 0 0;1=3
P 4.93268002 3.01615 5 P 0 0;1=3
P 5.03268002 3.01615 5 P 0 0;1=3
P 4.83268002 2.96615 5 P 0 0;1=3
P 4.88268002 2.96615 5 P 0 0;1=3
P 4.98268002 2.96615 5 P 0 0;1=3
P 4.93268002 2.96615 5 P 0 0;1=3
P 5.03268002 2.96615 5 P 0 0;1=3
P 2.44606004 3.71615 5 P 0 0;1=3
P 3.38003996 4.78291998 5 P 0 0;1=3
P 2.19606004 3.81615 5 P 0 0;1=3
P 3.02571004 4.667 5 P 0 0;1=3
P 2.19606004 3.86615 5 P 0 0;1=3
P 3.06571004 4.667 5 P 0 0;1=3
P 3.27831004 4.642 5 P 0 0;1=3
P 2.39606004 3.76615 5 P 0 0;1=3
P 4.73268002 2.66615 5 P 0 0;1=3
P 10.73661004 2.66615 5 P 0 0;1=3
P 3.23831004 4.642 5 P 0 0;1=3
P 2.39606004 3.81615 5 P 0 0;1=3
P 5.03268002 2.61615 5 P 0 0;1=3
P 3.34916998 5.1035 5 P 0 0;1=3
P 2.49606004 3.76615 5 P 0 0;1=3
P 3.30916998 5.1035 5 P 0 0;1=3
P 2.49606004 3.81615 5 P 0 0;1=3
P 11.03661004 2.61615 5 P 0 0;1=3
P 2.74225 4.667 5 P 0 0;1=3
P 2.09606004 3.66615 5 P 0 0;1=3
P 2.44606004 3.81615 5 P 0 0;1=3
P 3.20743996 4.78291998 5 P 0 0;1=3
P 2.78225 4.667 5 P 0 0;1=3
P 2.09606004 3.71615 5 P 0 0;1=3
P 2.44606004 3.86615 5 P 0 0;1=3
P 3.16743996 4.78291998 5 P 0 0;1=3
P 2.34606004 3.81615 5 P 0 0;1=3
P 3.27831004 5.22001998 5 P 0 0;1=3
P 2.34606004 3.86615 5 P 0 0;1=3
P 3.23831004 5.22001998 5 P 0 0;1=3
P 4.63268002 2.61615 5 P 0 0;1=3
P 10.98661004 2.61615 5 P 0 0;1=3
P 2.19606004 3.66615 5 P 0 0;1=3
P 2.81311004 4.78291998 5 P 0 0;1=3
P 10.98661004 2.56615 5 P 0 0;1=3
P 2.19606004 3.71615 5 P 0 0;1=3
P 2.85311004 4.78291998 5 P 0 0;1=3
P 0.64808996 1.655 4 P 0 0;1=4
P 5.76 2.66 4 P 0 0;1=0
P 10.63661004 2.61615 5 P 0 0;1=3
P 2.09606004 3.81615 5 P 0 0;1=3
P 3.09656998 5.0535 5 P 0 0;1=3
P 2.09606004 3.86615 5 P 0 0;1=3
P 3.13656998 5.0535 5 P 0 0;1=3
P 2.88708002 4.667 5 P 0 0;1=3
P 2.04606004 3.76615 5 P 0 0;1=3
P 10.73661004 2.61615 5 P 0 0;1=3
P 2.92708002 4.667 5 P 0 0;1=3
P 2.04606004 3.81615 5 P 0 0;1=3
P 10.68661004 2.61615 5 P 0 0;1=3
P 5.03268002 2.46615 5 P 0 0;1=3
P 5.03268002 2.51615 5 P 0 0;1=3
P 11.08661004 2.56615 5 P 0 0;1=3
P 10.68661004 2.56615 5 P 0 0;1=3
P 9.175 5.255 4 P 0 0;1=0
P 4.73268002 2.61615 5 P 0 0;1=3
P 9.11853996 5.255 4 P 0 0;1=0
P 5.08268002 2.41615 5 P 0 0;1=3
P 10.93661004 2.66615 5 P 0 0;1=3
P 10.58661004 2.61615 5 P 0 0;1=3
P 8.15 3.76615 5 P 0 0;1=3
P 9.02925 5.165 5 P 0 0;1=3
P 4.98268002 2.21615 5 P 0 0;1=3
P 10.58661004 2.56615 5 P 0 0;1=3
P 8.15 3.81615 5 P 0 0;1=3
P 9.06925 5.165 5 P 0 0;1=3
P 11.03661004 2.66615 5 P 0 0;1=3
P 4.98268002 2.26615 5 P 0 0;1=3
P 10.93661004 2.61615 5 P 0 0;1=3
P 5.03268002 2.26615 5 P 0 0;1=3
P 11.08661004 2.61615 5 P 0 0;1=3
P 5.03268002 2.31615 5 P 0 0;1=3
P 10.63661004 2.66615 5 P 0 0;1=3
P 3.775 5.295 4 P 0 0;1=0
P 0.73 5.78 4 P 0 0;1=4
P 8.07 5.29 4 P 0 0;1=0
P 3.8399 4.765 4 P 0 0;1=0
P 0.81 5.78 4 P 0 0;1=4
P 8.005 5.29 4 P 0 0;1=0
P 11.08661004 1.91615 5 P 0 0;1=3
P 4.98268002 1.91615 5 P 0 0;1=3
P 4.98268002 1.96615 5 P 0 0;1=3
P 4.93268002 1.86615 5 P 0 0;1=3
P 4.93268002 1.91615 5 P 0 0;1=3
P 5.03268002 1.86615 5 P 0 0;1=3
P 5.08268002 1.91615 5 P 0 0;1=3
P 5.08268002 2.56615 5 P 0 0;1=3
P 8.15 2.51615 5 P 0 0;1=3
P 4.98268002 2.61615 5 P 0 0;1=3
P 10.68661004 2.71615 5 P 0 0;1=3
P 10.98661004 2.71615 5 P 0 0;1=3
P 10.78661004 2.71615 5 P 0 0;1=3
P 4.93268002 2.66615 5 P 0 0;1=3
P 10.88661004 2.71615 5 P 0 0;1=3
P 10.68661004 2.76615 5 P 0 0;1=3
P 9.64 0.71 4 P 0 0;1=0
P 10.58661004 2.81615 5 P 0 0;1=3
P 9.43296004 0.49133002 4 P 0 0;1=0
P 9.43296004 0.73633002 4 P 0 0;1=0
P 10.63661004 2.81615 5 P 0 0;1=3
P 4.68268002 2.56615 5 P 0 0;1=3
P 10.68661004 2.81615 5 P 0 0;1=3
P 9.55795 0.36633002 4 P 0 0;1=0
P 10.73661004 2.81615 5 P 0 0;1=3
P 9.35796004 0.49133002 4 P 0 0;1=0
P 5.03268002 2.66615 5 P 0 0;1=3
P 10.78661004 2.81615 5 P 0 0;1=3
P 9.58296004 0.71133002 4 P 0 0;1=0
P 5.08268002 2.61615 5 P 0 0;1=3
P 11.08661004 1.96615 5 P 0 0;1=3
P 11.03661004 1.86615 5 P 0 0;1=3
P 11.03661004 1.91615 5 P 0 0;1=3
P 10.93661004 1.86615 5 P 0 0;1=3
P 10.93661004 1.91615 5 P 0 0;1=3
P 10.98661004 1.91615 5 P 0 0;1=3
P 10.98661004 1.96615 5 P 0 0;1=3
P 4.93268002 2.61615 5 P 0 0;1=3
P 11.03661004 2.01615 5 P 0 0;1=3
P 11.03661004 2.06615 5 P 0 0;1=3
P 10.93661004 2.01615 5 P 0 0;1=3
P 10.93661004 2.06615 5 P 0 0;1=3
P 10.98661004 2.06615 5 P 0 0;1=3
P 10.98661004 2.11615 5 P 0 0;1=3
P 11.08661004 2.06615 5 P 0 0;1=3
P 11.08661004 2.11615 5 P 0 0;1=3
P 3.115 5.255 4 P 0 0;1=0
P 4.63268002 2.66615 5 P 0 0;1=3
P 11.08661004 2.21615 5 P 0 0;1=3
P 4.98268002 2.56615 5 P 0 0;1=3
P 11.08661004 2.26615 5 P 0 0;1=3
P 11.03661004 2.26615 5 P 0 0;1=3
P 2.14606004 3.76615 5 P 0 0;1=3
P 3.02571004 5.165 5 P 0 0;1=3
P 11.03661004 2.31615 5 P 0 0;1=3
P 10.98661004 2.21615 5 P 0 0;1=3
P 10.98661004 2.26615 5 P 0 0;1=3
P 3.17146004 5.255 4 P 0 0;1=0
P 4.68268002 2.61615 5 P 0 0;1=3
P 10.93661004 2.26615 5 P 0 0;1=3
P 10.58661004 2.76615 5 P 0 0;1=3
P 4 5.29 4 P 0 0;1=0
P 10.93661004 2.31615 5 P 0 0;1=3
P 10.88661004 2.16615 5 P 0 0;1=3
P 10.73661004 1.91615 5 P 0 0;1=3
P 10.395 1.28555 5 P 0 0;1=3
P 12.81495 1.96456998 10 P 0 0;1=1
P 9.42358002 5.22001998 5 P 0 0;1=3
P 8.98115 2.825 5 P 0 0;1=3
P 4.58268002 2.61615 5 P 0 0;1=3
P 9.38358002 5.22001998 5 P 0 0;1=3
P 8.98115 2.865 5 P 0 0;1=3
P 2.14606004 3.81615 5 P 0 0;1=3
P 3.06571004 5.165 5 P 0 0;1=3
P 11.08661004 2.71615 5 P 0 0;1=3
P 3.985 4.88998996 4 P 0 0;1=0
P 11.73316004 2.652 5 P 0 0;1=3
P 12.55905 4.40551004 10 P 0 0;1=1
P 11.73316004 2.612 5 P 0 0;1=3
P 12.63778996 4.44488002 10 P 0 0;1=1
P 8.3 2.86615 5 P 0 0;1=3
P 4.83268002 2.16615 5 P 0 0;1=3
P 0.69348996 1.90611998 5 P 0 0;1=3
P 11.73316004 2.492 5 P 0 0;1=3
P 12.55905 4.24803002 10 P 0 0;1=1
P 4.88268002 2.16615 5 P 0 0;1=3
P 0.69348996 1.86611998 5 P 0 0;1=3
P 11.73316004 2.452 5 P 0 0;1=3
P 12.63778996 4.2874 10 P 0 0;1=1
P 8.25 2.86615 5 P 0 0;1=3
P 12.55905 3.93306998 10 P 0 0;1=1
P 11.73316004 2.332 5 P 0 0;1=3
P 12.63778996 3.97243996 10 P 0 0;1=1
P 11.73316004 2.292 5 P 0 0;1=3
P 10.83661004 2.16615 5 P 0 0;1=3
P 11.53316004 2.092 5 P 0 0;1=3
P 12.55905 3.77558996 10 P 0 0;1=1
P 11.53316004 2.052 5 P 0 0;1=3
P 12.63778996 3.81496004 10 P 0 0;1=1
P 12.81495 3.53936998 10 P 0 0;1=1
P 10.68661004 2.26615 5 P 0 0;1=3
P 9.975 2.3758 5 P 0 0;1=3
P 12.81495 3.38188996 10 P 0 0;1=1
P 10.73661004 2.31615 5 P 0 0;1=3
P 9.975 2.23955 5 P 0 0;1=3
P 12.81495 2.20078996 10 P 0 0;1=1
P 10.68661004 1.91615 5 P 0 0;1=3
P 10.42445 1.395 5 P 0 0;1=3
P 12.81495 2.75196998 10 P 0 0;1=1
P 10.73661004 2.01615 5 P 0 0;1=3
P 10.26025 1.82845 5 P 0 0;1=3
P 12.73621004 3.73621998 10 P 0 0;1=1
P 10.58661004 2.21615 5 P 0 0;1=3
P 10.09 2.26825 5 P 0 0;1=3
P 10.73661004 2.41615 5 P 0 0;1=3
P 10.09 2.69655 5 P 0 0;1=3
P 12.73621004 4.52361998 10 P 0 0;1=1
P 7.3426 4.69351004 4 P 0 0;1=0
P 11.73316004 1.532 5 P 0 0;1=3
P 12.55905 2.27953002 10 P 0 0;1=1
P 7.2926 4.69351004 4 P 0 0;1=0
P 12.73621004 3.57873996 10 P 0 0;1=1
P 10.68661004 2.21615 5 P 0 0;1=3
P 9.975 2.3358 5 P 0 0;1=3
P 12.73621004 3.42126004 10 P 0 0;1=1
P 10.73661004 2.26615 5 P 0 0;1=3
P 9.975 2.19955 5 P 0 0;1=3
P 11.73316004 2.172 5 P 0 0;1=3
P 12.55905 3.46063002 10 P 0 0;1=1
P 4.98268002 2.36615 5 P 0 0;1=3
P 10.73661004 1.86615 5 P 0 0;1=3
P 10.395 1.32555 5 P 0 0;1=3
P 12.73621004 2.00393996 10 P 0 0;1=1
P 11.73316004 2.132 5 P 0 0;1=3
P 12.63778996 3.5 10 P 0 0;1=1
P 3.38003996 5.22001998 5 P 0 0;1=3
P 2.97721004 2.865 5 P 0 0;1=3
P 4.98268002 2.41615 5 P 0 0;1=3
P 12.63778996 1.76771998 10 P 0 0;1=1
P 3.42003996 5.22001998 5 P 0 0;1=3
P 2.97721004 2.825 5 P 0 0;1=3
P 4.88268002 2.81615 5 P 0 0;1=3
P 4.93268002 2.81615 5 P 0 0;1=3
P 4.98268002 2.81615 5 P 0 0;1=3
P 5.03268002 2.81615 5 P 0 0;1=3
P 5.08268002 2.81615 5 P 0 0;1=3
P 11.03661004 2.81615 5 P 0 0;1=3
P 11.08661004 2.81615 5 P 0 0;1=3
P 10.98661004 2.81615 5 P 0 0;1=3
P 10.93661004 2.81615 5 P 0 0;1=3
P 10.88661004 2.81615 5 P 0 0;1=3
P 5.27886004 3.0214 4 P 0 0;1=4
P 5.27886004 3.0564 4 P 0 0;1=4
P 5.27886004 3.1014 4 P 0 0;1=4
P 5.27886004 3.1364 4 P 0 0;1=4
P 5.27886004 2.9764 4 P 0 0;1=4
P 5.27886004 2.9414 4 P 0 0;1=4
P 5.27886004 3.2614 4 P 0 0;1=4
P 5.27886004 3.2964 4 P 0 0;1=4
P 5.27886004 3.2164 4 P 0 0;1=4
P 5.27886004 3.1814 4 P 0 0;1=4
P 11.28278996 3.1814 4 P 0 0;1=4
P 11.28278996 3.2164 4 P 0 0;1=4
P 11.28278996 3.2964 4 P 0 0;1=4
P 11.28278996 3.2614 4 P 0 0;1=4
P 11.28278996 2.9414 4 P 0 0;1=4
P 11.28278996 2.9764 4 P 0 0;1=4
P 11.28278996 3.1364 4 P 0 0;1=4
P 11.28278996 3.1014 4 P 0 0;1=4
P 11.28278996 3.0564 4 P 0 0;1=4
P 11.28278996 3.0214 4 P 0 0;1=4
P 5.59708996 4.7302 4 P 0 0;1=4
P 5.57708996 4.6802 4 P 0 0;1=4
P 5.75708996 4.7302 4 P 0 0;1=4
P 5.83708996 4.7302 4 P 0 0;1=4
P 5.69708996 4.6802 4 P 0 0;1=4
P 5.73708996 4.6802 4 P 0 0;1=4
P 5.77708996 4.6802 4 P 0 0;1=4
P 5.81708996 4.6802 4 P 0 0;1=4
P 5.85708996 4.6802 4 P 0 0;1=4
P 5.67708996 4.7302 4 P 0 0;1=4
P 5.65708996 4.6802 4 P 0 0;1=4
P 5.61708996 4.6802 4 P 0 0;1=4
P 6.13708996 4.7602 4 P 0 0;1=4
P 6.09708996 4.6802 4 P 0 0;1=4
P 6.13708996 4.6402 4 P 0 0;1=4
P 6.13708996 4.6802 4 P 0 0;1=4
P 6.13708996 4.7202 4 P 0 0;1=4
P 5.91708996 4.7302 4 P 0 0;1=4
P 5.99708996 4.7302 4 P 0 0;1=4
P 6.07708996 4.7302 4 P 0 0;1=4
P 5.89708996 4.6802 4 P 0 0;1=4
P 5.93708996 4.6802 4 P 0 0;1=4
P 5.97708996 4.6802 4 P 0 0;1=4
P 6.01708996 4.6802 4 P 0 0;1=4
P 6.05708996 4.6802 4 P 0 0;1=4
P 5.59708996 4.7702 4 P 0 0;1=4
P 5.59708996 4.8102 4 P 0 0;1=4
P 5.75708996 4.8102 4 P 0 0;1=4
P 5.83708996 4.8102 4 P 0 0;1=4
P 5.75708996 4.7702 4 P 0 0;1=4
P 5.83708996 4.7702 4 P 0 0;1=4
P 5.67708996 4.8102 4 P 0 0;1=4
P 5.67708996 4.7702 4 P 0 0;1=4
P 6.13708996 4.9252 4 P 0 0;1=4
P 6.13708996 4.8402 4 P 0 0;1=4
P 6.13708996 4.8002 4 P 0 0;1=4
P 6.13708996 4.8852 4 P 0 0;1=4
P 5.91708996 4.8102 4 P 0 0;1=4
P 5.99708996 4.8102 4 P 0 0;1=4
P 5.91708996 4.7702 4 P 0 0;1=4
P 5.99708996 4.7702 4 P 0 0;1=4
P 6.07708996 4.8102 4 P 0 0;1=4
P 6.07708996 4.7702 4 P 0 0;1=4
P 4.93268002 2.26615 5 P 0 0;1=3
P 4.93268002 2.31615 5 P 0 0;1=3
P 5.08268002 2.36615 5 P 0 0;1=3
P 12.81495 3.22441004 10 P 0 0;1=1
P 10.68661004 2.06615 5 P 0 0;1=3
P 10.09 2.13095 5 P 0 0;1=3
P 10.63661004 2.31615 5 P 0 0;1=3
P 10.09 2.40335 5 P 0 0;1=3
P 12.81495 3.85433002 10 P 0 0;1=1
P 11.73316004 2.012 5 P 0 0;1=3
P 12.63778996 3.1063 10 P 0 0;1=1
P 11.73316004 1.972 5 P 0 0;1=3
P 12.55905 3.14566998 10 P 0 0;1=1
P 11.53316004 1.732 5 P 0 0;1=3
P 12.55905 2.98818996 10 P 0 0;1=1
P 12.81495 3.69685 10 P 0 0;1=1
P 10.58661004 2.26615 5 P 0 0;1=3
P 10.09 2.30825 5 P 0 0;1=3
P 11.53316004 1.772 5 P 0 0;1=3
P 12.63778996 2.94881998 10 P 0 0;1=1
P 12.81495 4.32676998 10 P 0 0;1=1
P 10.63661004 2.46615 5 P 0 0;1=3
P 9.975 2.62445 5 P 0 0;1=3
P 12.63778996 2.79133996 10 P 0 0;1=1
P 11.73316004 1.852 5 P 0 0;1=3
P 12.55905 2.83071004 10 P 0 0;1=1
P 11.73316004 1.812 5 P 0 0;1=3
P 10.73661004 2.46615 5 P 0 0;1=3
P 10.09 2.73655 5 P 0 0;1=3
P 12.81495 4.48425 10 P 0 0;1=1
P 10.63661004 2.26615 5 P 0 0;1=3
P 10.09 2.44335 5 P 0 0;1=3
P 12.73621004 3.8937 10 P 0 0;1=1
P 10.58661004 2.41615 5 P 0 0;1=3
P 9.975 2.5109 5 P 0 0;1=3
P 12.81495 4.16928996 10 P 0 0;1=1
P 1.025 -0.35 30 P 0 3;1=6
P 1.325 -0.35 30 P 0 3;1=6
P 1.175 -0.35 30 P 0 3;1=6
P 0.725 -0.35 30 P 0 3;1=6
P 0.875 -0.35 30 P 0 3;1=6
P 12.73621004 4.05118002 10 P 0 0;1=1
P 10.68661004 2.36615 5 P 0 0;1=3
P 10.09 2.53845 5 P 0 0;1=3
P 12.81495 2.35826998 10 P 0 0;1=1
P 10.63661004 1.86615 5 P 0 0;1=3
P 10.35543002 1.52156998 5 P 0 0;1=3
P 5.03268002 2.01615 5 P 0 0;1=3
P 5.08268002 2.21615 5 P 0 0;1=3
P 12.73621004 2.16141998 10 P 0 0;1=1
P 10.68661004 1.96615 5 P 0 0;1=3
P 10.46445 1.395 5 P 0 0;1=3
P 0.2 -0.293 20 P 0 0;1=14
P 12.27 0.29 20 P 0 0;1=14
P 0.66 0.29 20 P 0 0;1=14
P 0.2 5.82361998 20 P 0 0;1=14
P 12.81495 1.57086998 10 P 0 0;1=1
P 12.73621004 1.5315 10 P 0 0;1=1
P 12.63778996 2.7126 10 P 0 0;1=1
P 12.55905 2.67323002 10 P 0 0;1=1
P 12.55905 1.64961004 10 P 0 0;1=1
P 12.63778996 1.61023996 10 P 0 0;1=1
P 12.55905 1.57086998 10 P 0 0;1=1
P 12.63778996 1.5315 10 P 0 0;1=1
P 12.73621004 1.68898002 10 P 0 0;1=1
P 12.81495 1.64961004 10 P 0 0;1=1
P 12.63778996 1.68898002 10 P 0 0;1=1
P 12.55905 1.72835 10 P 0 0;1=1
P 12.81495 1.72835 10 P 0 0;1=1
P 12.73621004 1.45276004 10 P 0 0;1=1
P 12.81495 1.41338996 10 P 0 0;1=1
P 12.73621004 1.37401998 10 P 0 0;1=7
P 12.63778996 1.45276004 10 P 0 0;1=1
P 12.55905 1.41338996 10 P 0 0;1=1
P 0.35038996 1.5315 10 P 0 0;1=1
P 0.27165 1.49213002 10 P 0 0;1=1
P 0.17323002 2.67323002 10 P 0 0;1=1
P 0.09448996 2.63386004 10 P 0 0;1=1
P 0.09448996 1.61023996 10 P 0 0;1=1
P 0.17323002 1.57086998 10 P 0 0;1=1
P 0.09448996 1.5315 10 P 0 0;1=1
P 0.17323002 1.49213002 10 P 0 0;1=1
P 0.27165 1.64961004 10 P 0 0;1=1
P 0.35038996 1.61023996 10 P 0 0;1=1
P 0.17323002 1.64961004 10 P 0 0;1=1
P 0.09448996 1.68898002 10 P 0 0;1=1
P 0.35038996 1.68898002 10 P 0 0;1=1
P 0.27165 1.41338996 10 P 0 0;1=1
P 0.35038996 1.37401998 10 P 0 0;1=1
P 0.27165 1.33465 10 P 0 0;1=7
P 0.17323002 1.41338996 10 P 0 0;1=1
P 0.09448996 1.37401998 10 P 0 0;1=1
P 10.20866004 5.4441 27 P 0 0;1=15
P 5.78346004 5.4441 27 P 0 0;1=15
P 12.7252 6.31661998 20 P 0 0;1=14
P 0.2 6.31661998 20 P 0 0;1=14
P 12.7252 -0.293 20 P 0 0;1=14
P 0.22245 4.87401004 17 P 0 0;1=5
P 12.68701004 0.46063002 21 P 0 0;1=16
P 12.68701998 5.4252 21 P 0 0;1=16
P 0.22245 0.42126004 21 P 0 0;1=16
P 0.22255 5.38583002 21 P 0 0;1=16
P 7.17716998 5.7874 24 P 0 0;1=17
P 7.17716998 0.23621998 24 P 0 0;1=17
P 0.22245 0.68898002 23 P 0 0;1=18
P 0.22245 5.11811004 23 P 0 0;1=18
P 12.68701998 5.15748002 23 P 0 0;1=18
P 12.68701998 0.72835 23 P 0 0;1=18
P 6.11811004 1.52756004 23 P 0 0;1=18
P 6.11811004 4.20473002 23 P 0 0;1=18
P 4.83268002 4.22441004 23 P 0 0;1=18
P 2.24606004 4.22441004 23 P 0 0;1=18
P 0.96063002 4.20473002 23 P 0 0;1=18
P 0.96063002 1.52756004 23 P 0 0;1=18
P 2.24606004 1.50786998 23 P 0 0;1=18
P 4.83268002 1.50786998 23 P 0 0;1=18
P 6.04921004 2.58268002 22 P 0 0;1=19
P 1.05905 2.58268002 29 P 0 0;1=20
P 12.12205 1.52756004 23 P 0 0;1=18
P 12.12205 4.20473002 23 P 0 0;1=18
P 10.83661998 4.22441004 23 P 0 0;1=18
P 8.25 4.22441004 23 P 0 0;1=18
P 6.96456998 4.20473002 23 P 0 0;1=18
P 6.96456998 1.52756004 23 P 0 0;1=18
P 8.25 1.50786998 23 P 0 0;1=18
P 10.83661998 1.50786998 23 P 0 0;1=18
P 12.05315 2.58268002 22 P 0 0;1=19
P 7.06298996 2.58268002 29 P 0 0;1=20
P 12.33465 5.69528002 19 P 0 0;1=21
P 3.58311004 4.91851004 14 P 0 0;1=22
P 2.72091004 4.91851004 14 P 0 0;1=22
P 9.58665 4.91851004 14 P 0 0;1=22
P 8.72445 4.91851004 14 P 0 0;1=22
P 2.41851004 4.91851004 14 P 0 0;1=22
P 1.55631004 4.91851004 14 P 0 0;1=22
P 8.42205 4.91851004 14 P 0 0;1=22
P 7.55985 4.91851004 14 P 0 0;1=22
P 0.22243996 1.79331004 16 P 0 0;1=23
P 0.22243996 4.67323002 16 P 0 0;1=23
P 12.687 1.83268002 16 P 0 0;1=23
P 12.687 4.7126 16 P 0 0;1=23
P 0.7687 5.62008002 12 P 0 0;1=24
P 1.47736004 5.62008002 12 P 0 0;1=24
L 1.88908002 -1.91246004 1.89293002 -1.91246004 0 P 0 ;0
L 1.89126998 -1.91146004 1.89656998 -1.91146004 0 P 0 ;0
L 1.89393996 -1.91046004 1.9155 -1.91046004 0 P 0 ;0
L 1.91593996 -1.91246004 1.92048996 -1.91246004 0 P 0 ;0
L 1.9126 -1.91146004 1.9184 -1.91146004 0 P 0 ;0
L 1.89763002 -1.90946004 1.91016998 -1.90946004 0 P 0 ;0
L 1.89053002 -1.96001004 1.8974 -1.96001004 0 P 0 ;0
L 1.89053002 -1.95901004 1.8974 -1.95901004 0 P 0 ;0
L 1.89053002 -1.95801004 1.8974 -1.95801004 0 P 0 ;0
L 1.89053002 -1.95701004 1.8974 -1.95701004 0 P 0 ;0
L 1.89053002 -1.95601004 1.8974 -1.95601004 0 P 0 ;0
L 1.89053002 -1.95501004 1.8974 -1.95501004 0 P 0 ;0
L 1.89053002 -1.95401004 1.8974 -1.95401004 0 P 0 ;0
L 1.89053002 -1.95301004 1.89741004 -1.95301004 0 P 0 ;0
L 1.89053002 -1.95201004 1.89741998 -1.95201004 0 P 0 ;0
L 1.89053002 -1.95101004 1.89743996 -1.95101004 0 P 0 ;0
L 1.89053002 -1.95001004 1.89745 -1.95001004 0 P 0 ;0
L 1.89053002 -1.94901004 1.89746004 -1.94901004 0 P 0 ;0
L 1.89053002 -1.94801004 1.89753002 -1.94801004 0 P 0 ;0
L 1.89053002 -1.94701004 1.8977 -1.94701004 0 P 0 ;0
L 1.89053002 -1.94601004 1.89798002 -1.94601004 0 P 0 ;0
L 1.89053002 -1.94501004 1.89861004 -1.94501004 0 P 0 ;0
L 1.89053002 -1.94401004 1.90005 -1.94401004 0 P 0 ;0
L 1.89053002 -1.94301004 1.9113 -1.94301004 0 P 0 ;0
L 1.89053002 -1.94201004 1.91168002 -1.94201004 0 P 0 ;0
L 1.89053002 -1.94101004 1.91246998 -1.94101004 0 P 0 ;0
L 1.89053002 -1.94001004 1.90093996 -1.94001004 0 P 0 ;0
L 1.89053002 -1.93901004 1.89856004 -1.93901004 0 P 0 ;0
L 1.89053002 -1.93801004 1.89786998 -1.93801004 0 P 0 ;0
L 1.89053002 -1.93701004 1.89753996 -1.93701004 0 P 0 ;0
L 1.89053002 -1.93601004 1.89746998 -1.93601004 0 P 0 ;0
L 1.89053002 -1.93501004 1.89743996 -1.93501004 0 P 0 ;0
L 1.89053002 -1.93401004 1.89741998 -1.93401004 0 P 0 ;0
L 1.89053002 -1.93301004 1.8974 -1.93301004 0 P 0 ;0
L 1.89053002 -1.93201004 1.8974 -1.93201004 0 P 0 ;0
L 1.89053002 -1.93101004 1.8974 -1.93101004 0 P 0 ;0
L 1.89053002 -1.93001004 1.8974 -1.93001004 0 P 0 ;0
L 1.89053002 -1.92901004 1.8974 -1.92901004 0 P 0 ;0
L 1.89053002 -1.92801004 1.89753002 -1.92801004 0 P 0 ;0
L 1.89053002 -1.92701004 1.89793996 -1.92701004 0 P 0 ;0
L 1.89053002 -1.92601004 1.91713002 -1.92601004 0 P 0 ;0
L 1.89053002 -1.92501004 1.91628996 -1.92501004 0 P 0 ;0
L 1.89053002 -1.92401004 1.91513996 -1.92401004 0 P 0 ;0
L 1.89053002 -1.92301004 1.91321998 -1.92301004 0 P 0 ;0
L 1.89053002 -1.92201004 1.90551004 -1.92201004 0 P 0 ;0
L 1.89438996 -1.97246004 1.91331004 -1.97246004 0 P 0 ;0
L 1.89106998 -1.97146004 1.89973002 -1.97146004 0 P 0 ;0
L 1.88878002 -1.97046004 1.8949 -1.97046004 0 P 0 ;0
L 1.88698002 -1.96946004 1.89206998 -1.96946004 0 P 0 ;0
L 1.88546004 -1.96846004 1.88986998 -1.96846004 0 P 0 ;0
L 1.88416998 -1.96746004 1.88808996 -1.96746004 0 P 0 ;0
L 1.88288002 -1.96646004 1.88655 -1.96646004 0 P 0 ;0
L 1.88176998 -1.96546004 1.88518002 -1.96546004 0 P 0 ;0
L 1.88068996 -1.96446004 1.88393996 -1.96446004 0 P 0 ;0
L 1.87968996 -1.96346004 1.88286004 -1.96346004 0 P 0 ;0
L 1.87878002 -1.96246004 1.88186004 -1.96246004 0 P 0 ;0
L 1.8786 -1.92046004 1.88126998 -1.92046004 0 P 0 ;0
L 1.87946998 -1.91946004 1.88223002 -1.91946004 0 P 0 ;0
L 1.88048002 -1.91846004 1.88321004 -1.91846004 0 P 0 ;0
L 1.88153996 -1.91746004 1.88436998 -1.91746004 0 P 0 ;0
L 1.88273002 -1.91646004 1.88558996 -1.91646004 0 P 0 ;0
L 1.88406004 -1.91546004 1.88696998 -1.91546004 0 P 0 ;0
L 1.88548996 -1.91446004 1.88853002 -1.91446004 0 P 0 ;0
L 1.88718002 -1.91346004 1.89041998 -1.91346004 0 P 0 ;0
L 1.90896004 -1.92963996 1.90921998 -1.92991998 0 P 0 ;0
L 1.90921998 -1.92991998 1.90945 -1.93021998 0 P 0 ;0
L 1.90945 -1.93021998 1.90966004 -1.93053002 0 P 0 ;0
L 1.90966004 -1.93053002 1.90983002 -1.93086004 0 P 0 ;0
L 1.90983002 -1.93086004 1.90998002 -1.93121004 0 P 0 ;0
L 1.90998002 -1.93121004 1.9101 -1.93156998 0 P 0 ;0
L 1.9101 -1.93156998 1.91018996 -1.93193996 0 P 0 ;0
L 1.91018996 -1.93193996 1.91023996 -1.93231004 0 P 0 ;0
L 1.91023996 -1.93231004 1.91026998 -1.93265 0 P 0 ;0
L 1.91026998 -1.93265 1.91026004 -1.93298002 0 P 0 ;0
L 1.91026004 -1.93298002 1.91023002 -1.93331004 0 P 0 ;0
L 1.91023002 -1.93331004 1.91016998 -1.93363996 0 P 0 ;0
L 1.91016998 -1.93363996 1.91008996 -1.93396004 0 P 0 ;0
L 1.91008996 -1.93396004 1.90998002 -1.93428002 0 P 0 ;0
L 1.90998002 -1.93428002 1.90983996 -1.93458002 0 P 0 ;0
L 1.90983996 -1.93458002 1.90968996 -1.93486998 0 P 0 ;0
L 1.90968996 -1.93486998 1.90951004 -1.93516004 0 P 0 ;0
L 1.90951004 -1.93516004 1.90921004 -1.93556004 0 P 0 ;0
L 1.90921004 -1.93556004 1.90888002 -1.93593002 0 P 0 ;0
L 1.90888002 -1.93593002 1.90853002 -1.93626998 0 P 0 ;0
L 1.90853002 -1.93626998 1.90815 -1.93658996 0 P 0 ;0
L 1.90815 -1.93658996 1.90773996 -1.93686998 0 P 0 ;0
L 1.90773996 -1.93686998 1.90731998 -1.93711998 0 P 0 ;0
L 1.90731998 -1.93711998 1.90686998 -1.93733996 0 P 0 ;0
L 1.90686998 -1.93733996 1.90615 -1.93761004 0 P 0 ;0
L 1.90615 -1.93761004 1.90541998 -1.93783002 0 P 0 ;0
L 1.90541998 -1.93783002 1.90466004 -1.93798002 0 P 0 ;0
L 1.90466004 -1.93798002 1.9039 -1.93808002 0 P 0 ;0
L 1.9039 -1.93808002 1.90311998 -1.9381 0 P 0 ;0
L 1.90311998 -1.9381 1.90196004 -1.93808002 0 P 0 ;0
L 1.90196004 -1.93808002 1.90078996 -1.93798996 0 P 0 ;0
L 1.90078996 -1.93798996 1.90068002 -1.93798002 0 P 0 ;0
L 1.90068002 -1.93798002 1.90058002 -1.93795 0 P 0 ;0
L 1.90058002 -1.93795 1.90046998 -1.93791998 0 P 0 ;0
L 1.90046998 -1.93791998 1.90038002 -1.93788002 0 P 0 ;0
L 1.90038002 -1.93788002 1.90028002 -1.93783002 0 P 0 ;0
L 1.90028002 -1.93783002 1.90018996 -1.93778002 0 P 0 ;0
L 1.90018996 -1.93778002 1.9001 -1.93771004 0 P 0 ;0
L 1.9001 -1.93771004 1.90001998 -1.93763996 0 P 0 ;0
L 1.90001998 -1.93763996 1.89988002 -1.93748002 0 P 0 ;0
L 1.89988002 -1.93748002 1.89978002 -1.93733996 0 P 0 ;0
L 1.89978002 -1.93733996 1.89961998 -1.93703996 0 P 0 ;0
L 1.89961998 -1.93703996 1.89956998 -1.93688002 0 P 0 ;0
L 1.89956998 -1.93688002 1.89951998 -1.93671004 0 P 0 ;0
L 1.89951998 -1.93671004 1.89948996 -1.93655 0 P 0 ;0
L 1.89948996 -1.93655 1.89946998 -1.93636998 0 P 0 ;0
L 1.89946998 -1.93636998 1.8994 -1.93323002 0 P 0 ;0
L 1.8994 -1.93323002 1.8994 -1.92833002 0 P 0 ;0
L 1.8994 -1.92833002 1.90353996 -1.92833002 0 P 0 ;0
L 1.90353996 -1.92833002 1.90436998 -1.92835 0 P 0 ;0
L 1.90436998 -1.92835 1.9052 -1.92843002 0 P 0 ;0
L 1.9052 -1.92843002 1.90603002 -1.92853996 0 P 0 ;0
L 1.90603002 -1.92853996 1.90683996 -1.92871004 0 P 0 ;0
L 1.90683996 -1.92871004 1.90751004 -1.9289 0 P 0 ;0
L 1.90751004 -1.9289 1.90818002 -1.92913002 0 P 0 ;0
L 1.90818002 -1.92913002 1.90851998 -1.92928996 0 P 0 ;0
L 1.90851998 -1.92928996 1.90868002 -1.92938996 0 P 0 ;0
L 1.90868002 -1.92938996 1.90883002 -1.92951004 0 P 0 ;0
L 1.90883002 -1.92951004 1.90896004 -1.92963996 0 P 0 ;0
L 1.91188996 -1.96001004 1.91638996 -1.96001004 0 P 0 ;0
L 1.91156998 -1.95901004 1.91926998 -1.95901004 0 P 0 ;0
L 1.91125 -1.95801004 1.91891998 -1.95801004 0 P 0 ;0
L 1.91091998 -1.95701004 1.91853002 -1.95701004 0 P 0 ;0
L 1.9106 -1.95601004 1.91811004 -1.95601004 0 P 0 ;0
L 1.91025 -1.95501004 1.91765 -1.95501004 0 P 0 ;0
L 1.90988996 -1.95401004 1.91718996 -1.95401004 0 P 0 ;0
L 1.90953002 -1.95301004 1.91673002 -1.95301004 0 P 0 ;0
L 1.90918002 -1.95201004 1.91626998 -1.95201004 0 P 0 ;0
L 1.90881998 -1.95101004 1.91576004 -1.95101004 0 P 0 ;0
L 1.90841004 -1.95001004 1.91523996 -1.95001004 0 P 0 ;0
L 1.90793996 -1.94901004 1.91471004 -1.94901004 0 P 0 ;0
L 1.90738996 -1.94801004 1.91418002 -1.94801004 0 P 0 ;0
L 1.90676998 -1.94701004 1.9136 -1.94701004 0 P 0 ;0
L 1.90598996 -1.94601004 1.91261004 -1.94601004 0 P 0 ;0
L 1.90495 -1.94501004 1.91175 -1.94501004 0 P 0 ;0
L 1.90325 -1.94401004 1.91133002 -1.94401004 0 P 0 ;0
L 1.90456004 -1.94001004 1.91383002 -1.94001004 0 P 0 ;0
L 1.90801004 -1.93901004 1.91523002 -1.93901004 0 P 0 ;0
L 1.90956998 -1.93801004 1.91635 -1.93801004 0 P 0 ;0
L 1.9106 -1.93701004 1.91718002 -1.93701004 0 P 0 ;0
L 1.91133996 -1.93601004 1.91781004 -1.93601004 0 P 0 ;0
L 1.91183996 -1.93501004 1.91826004 -1.93501004 0 P 0 ;0
L 1.91213002 -1.93401004 1.9186 -1.93401004 0 P 0 ;0
L 1.91226004 -1.93301004 1.9188 -1.93301004 0 P 0 ;0
L 1.91221998 -1.93201004 1.9189 -1.93201004 0 P 0 ;0
L 1.91201998 -1.93101004 1.9189 -1.93101004 0 P 0 ;0
L 1.91163996 -1.93001004 1.91878996 -1.93001004 0 P 0 ;0
L 1.91105 -1.92901004 1.91856998 -1.92901004 0 P 0 ;0
L 1.91013996 -1.92801004 1.91823002 -1.92801004 0 P 0 ;0
L 1.90816998 -1.92701004 1.91776004 -1.92701004 0 P 0 ;0
L 1.90313996 -1.94011004 1.90316998 -1.9401 0 P 0 ;0
L 1.90316998 -1.9401 1.9032 -1.9401 0 P 0 ;0
L 1.9032 -1.9401 1.90398002 -1.94006998 0 P 0 ;0
L 1.90398002 -1.94006998 1.90406004 -1.94006998 0 P 0 ;0
L 1.90406004 -1.94006998 1.90413996 -1.94006004 0 P 0 ;0
L 1.90413996 -1.94006004 1.9049 -1.93996998 0 P 0 ;0
L 1.9049 -1.93996998 1.90493996 -1.93996004 0 P 0 ;0
L 1.90493996 -1.93996004 1.90498996 -1.93996004 0 P 0 ;0
L 1.90498996 -1.93996004 1.90506998 -1.93993996 0 P 0 ;0
L 1.90506998 -1.93993996 1.90581998 -1.93978002 0 P 0 ;0
L 1.90581998 -1.93978002 1.90586004 -1.93978002 0 P 0 ;0
L 1.90586004 -1.93978002 1.90593996 -1.93976004 0 P 0 ;0
L 1.90593996 -1.93976004 1.90596998 -1.93973996 0 P 0 ;0
L 1.90596998 -1.93973996 1.90671004 -1.93953002 0 P 0 ;0
L 1.90671004 -1.93953002 1.90678996 -1.93951004 0 P 0 ;0
L 1.90678996 -1.93951004 1.90758996 -1.93921004 0 P 0 ;0
L 1.90758996 -1.93921004 1.90766004 -1.93916998 0 P 0 ;0
L 1.90766004 -1.93916998 1.9077 -1.93915 0 P 0 ;0
L 1.9077 -1.93915 1.90773996 -1.93913996 0 P 0 ;0
L 1.90773996 -1.93913996 1.90818996 -1.93891998 0 P 0 ;0
L 1.90818996 -1.93891998 1.90821998 -1.9389 0 P 0 ;0
L 1.90821998 -1.9389 1.90826004 -1.93888996 0 P 0 ;0
L 1.90826004 -1.93888996 1.90828996 -1.93886998 0 P 0 ;0
L 1.90828996 -1.93886998 1.90833002 -1.93885 0 P 0 ;0
L 1.90833002 -1.93885 1.90875 -1.9386 0 P 0 ;0
L 1.90875 -1.9386 1.90883002 -1.93856004 0 P 0 ;0
L 1.90883002 -1.93856004 1.90888996 -1.93851004 0 P 0 ;0
L 1.90888996 -1.93851004 1.90928996 -1.93823002 0 P 0 ;0
L 1.90928996 -1.93823002 1.90933002 -1.9382 0 P 0 ;0
L 1.90933002 -1.9382 1.90936004 -1.93818002 0 P 0 ;0
L 1.90936004 -1.93818002 1.90938996 -1.93815 0 P 0 ;0
L 1.90938996 -1.93815 1.90941998 -1.93813002 0 P 0 ;0
L 1.90941998 -1.93813002 1.9098 -1.93781998 0 P 0 ;0
L 1.9098 -1.93781998 1.90986004 -1.93776004 0 P 0 ;0
L 1.90986004 -1.93776004 1.90988996 -1.93773996 0 P 0 ;0
L 1.90988996 -1.93773996 1.90991998 -1.93771004 0 P 0 ;0
L 1.90991998 -1.93771004 1.91028002 -1.93736004 0 P 0 ;0
L 1.91028002 -1.93736004 1.91038996 -1.93725 0 P 0 ;0
L 1.91038996 -1.93725 1.91071004 -1.93688002 0 P 0 ;0
L 1.91071004 -1.93688002 1.91073996 -1.93685 0 P 0 ;0
L 1.91073996 -1.93685 1.91116004 -1.9363 0 P 0 ;0
L 1.91116004 -1.9363 1.9112 -1.93623002 0 P 0 ;0
L 1.9112 -1.93623002 1.91138002 -1.93595 0 P 0 ;0
L 1.91138002 -1.93595 1.9114 -1.93591004 0 P 0 ;0
L 1.9114 -1.93591004 1.91143996 -1.93585 0 P 0 ;0
L 1.91143996 -1.93585 1.91146004 -1.93581004 0 P 0 ;0
L 1.91146004 -1.93581004 1.91161004 -1.93551998 0 P 0 ;0
L 1.91161004 -1.93551998 1.91163002 -1.93548996 0 P 0 ;0
L 1.91163002 -1.93548996 1.91165 -1.93545 0 P 0 ;0
L 1.91165 -1.93545 1.91166004 -1.93541004 0 P 0 ;0
L 1.91166004 -1.93541004 1.91168002 -1.93538002 0 P 0 ;0
L 1.91168002 -1.93538002 1.91181004 -1.93506998 0 P 0 ;0
L 1.91181004 -1.93506998 1.91183996 -1.935 0 P 0 ;0
L 1.91183996 -1.935 1.91186004 -1.93496004 0 P 0 ;0
L 1.91186004 -1.93496004 1.91186998 -1.93493002 0 P 0 ;0
L 1.91186998 -1.93493002 1.91198002 -1.93461004 0 P 0 ;0
L 1.91198002 -1.93461004 1.91198996 -1.93456998 0 P 0 ;0
L 1.91198996 -1.93456998 1.912 -1.93453996 0 P 0 ;0
L 1.912 -1.93453996 1.9121 -1.93413996 0 P 0 ;0
L 1.9121 -1.93413996 1.91211998 -1.9341 0 P 0 ;0
L 1.91211998 -1.9341 1.91211998 -1.93406004 0 P 0 ;0
L 1.91211998 -1.93406004 1.91213002 -1.93401998 0 P 0 ;0
L 1.91213002 -1.93401998 1.91213996 -1.93398996 0 P 0 ;0
L 1.91213996 -1.93398996 1.9122 -1.93366004 0 P 0 ;0
L 1.9122 -1.93366004 1.91221004 -1.93358002 0 P 0 ;0
L 1.91221004 -1.93358002 1.91221004 -1.93353996 0 P 0 ;0
L 1.91221004 -1.93353996 1.91221998 -1.9335 0 P 0 ;0
L 1.91221998 -1.9335 1.91225 -1.93316998 0 P 0 ;0
L 1.91225 -1.93316998 1.91226004 -1.93308996 0 P 0 ;0
L 1.91226004 -1.93308996 1.91226004 -1.93268002 0 P 0 ;0
L 1.91226004 -1.93268002 1.91226998 -1.93263996 0 P 0 ;0
L 1.91226998 -1.93263996 1.91226998 -1.9326 0 P 0 ;0
L 1.91226998 -1.9326 1.91226004 -1.93251998 0 P 0 ;0
L 1.91226004 -1.93251998 1.91223996 -1.93218996 0 P 0 ;0
L 1.91223996 -1.93218996 1.91223996 -1.93215 0 P 0 ;0
L 1.91223996 -1.93215 1.91223002 -1.9321 0 P 0 ;0
L 1.91223002 -1.9321 1.91223002 -1.93206004 0 P 0 ;0
L 1.91223002 -1.93206004 1.91221998 -1.93201998 0 P 0 ;0
L 1.91221998 -1.93201998 1.91216998 -1.93163996 0 P 0 ;0
L 1.91216998 -1.93163996 1.91216004 -1.9316 0 P 0 ;0
L 1.91216004 -1.9316 1.91213996 -1.93151004 0 P 0 ;0
L 1.91213996 -1.93151004 1.91213002 -1.93146998 0 P 0 ;0
L 1.91213002 -1.93146998 1.91205 -1.93111004 0 P 0 ;0
L 1.91205 -1.93111004 1.91203996 -1.93106004 0 P 0 ;0
L 1.91203996 -1.93106004 1.91203002 -1.93101998 0 P 0 ;0
L 1.91203002 -1.93101998 1.91201004 -1.93098002 0 P 0 ;0
L 1.91201004 -1.93098002 1.912 -1.93093996 0 P 0 ;0
L 1.912 -1.93093996 1.91188002 -1.93058002 0 P 0 ;0
L 1.91188002 -1.93058002 1.91186998 -1.93053996 0 P 0 ;0
L 1.91186998 -1.93053996 1.91185 -1.9305 0 P 0 ;0
L 1.91185 -1.9305 1.91183996 -1.93046004 0 P 0 ;0
L 1.91183996 -1.93046004 1.91181998 -1.93043002 0 P 0 ;0
L 1.91181998 -1.93043002 1.91166998 -1.93008002 0 P 0 ;0
L 1.91166998 -1.93008002 1.91166004 -1.93003996 0 P 0 ;0
L 1.91166004 -1.93003996 1.9116 -1.92991998 0 P 0 ;0
L 1.9116 -1.92991998 1.91141998 -1.92958996 0 P 0 ;0
L 1.91141998 -1.92958996 1.9114 -1.92955 0 P 0 ;0
L 1.9114 -1.92955 1.91138002 -1.92951998 0 P 0 ;0
L 1.91138002 -1.92951998 1.91133002 -1.92945 0 P 0 ;0
L 1.91133002 -1.92945 1.91113002 -1.92913002 0 P 0 ;0
L 1.91113002 -1.92913002 1.91111004 -1.92908996 0 P 0 ;0
L 1.91111004 -1.92908996 1.91108996 -1.92906004 0 P 0 ;0
L 1.91108996 -1.92906004 1.91106004 -1.92901998 0 P 0 ;0
L 1.91106004 -1.92901998 1.91103002 -1.92898996 0 P 0 ;0
L 1.91103002 -1.92898996 1.9108 -1.92868996 0 P 0 ;0
L 1.9108 -1.92868996 1.91076998 -1.92866004 0 P 0 ;0
L 1.91076998 -1.92866004 1.91075 -1.92861998 0 P 0 ;0
L 1.91075 -1.92861998 1.91068996 -1.92856004 0 P 0 ;0
L 1.91068996 -1.92856004 1.91043002 -1.92828002 0 P 0 ;0
L 1.91043002 -1.92828002 1.91035 -1.9282 0 P 0 ;0
L 1.91035 -1.9282 1.91033002 -1.92816998 0 P 0 ;0
L 1.91033002 -1.92816998 1.91018996 -1.92803996 0 P 0 ;0
L 1.91018996 -1.92803996 1.91018002 -1.92803996 0 P 0 ;0
L 1.91018002 -1.92803996 1.91016004 -1.92801998 0 P 0 ;0
L 1.91016004 -1.92801998 1.91011998 -1.92798996 0 P 0 ;0
L 1.91011998 -1.92798996 1.91006004 -1.92793002 0 P 0 ;0
L 1.91006004 -1.92793002 1.90991004 -1.92781998 0 P 0 ;0
L 1.90991004 -1.92781998 1.90988002 -1.9278 0 P 0 ;0
L 1.90988002 -1.9278 1.90983996 -1.92776998 0 P 0 ;0
L 1.90983996 -1.92776998 1.90976998 -1.92771998 0 P 0 ;0
L 1.90976998 -1.92771998 1.90961004 -1.92761998 0 P 0 ;0
L 1.90961004 -1.92761998 1.90953996 -1.92756998 0 P 0 ;0
L 1.90953996 -1.92756998 1.9095 -1.92755 0 P 0 ;0
L 1.9095 -1.92755 1.90946998 -1.92753002 0 P 0 ;0
L 1.90946998 -1.92753002 1.9093 -1.92743996 0 P 0 ;0
L 1.9093 -1.92743996 1.90926004 -1.92741998 0 P 0 ;0
L 1.90926004 -1.92741998 1.90923002 -1.9274 0 P 0 ;0
L 1.90923002 -1.9274 1.90915 -1.92736998 0 P 0 ;0
L 1.90915 -1.92736998 1.90896998 -1.92728996 0 P 0 ;0
L 1.90896998 -1.92728996 1.90893996 -1.92728002 0 P 0 ;0
L 1.90893996 -1.92728002 1.9089 -1.92726004 0 P 0 ;0
L 1.9089 -1.92726004 1.90886998 -1.92725 0 P 0 ;0
L 1.90886998 -1.92725 1.90883002 -1.92723996 0 P 0 ;0
L 1.90883002 -1.92723996 1.90816004 -1.92701004 0 P 0 ;0
L 1.90816004 -1.92701004 1.90813996 -1.927 0 P 0 ;0
L 1.90813996 -1.927 1.9081 -1.92698996 0 P 0 ;0
L 1.9081 -1.92698996 1.90803996 -1.92696998 0 P 0 ;0
L 1.90803996 -1.92696998 1.90736998 -1.92678002 0 P 0 ;0
L 1.90736998 -1.92678002 1.90723996 -1.92675 0 P 0 ;0
L 1.90723996 -1.92675 1.90643002 -1.92658996 0 P 0 ;0
L 1.90643002 -1.92658996 1.90636998 -1.92656998 0 P 0 ;0
L 1.90636998 -1.92656998 1.90633996 -1.92656998 0 P 0 ;0
L 1.90633996 -1.92656998 1.90631004 -1.92656004 0 P 0 ;0
L 1.90631004 -1.92656004 1.90548996 -1.92645 0 P 0 ;0
L 1.90548996 -1.92645 1.90543996 -1.92643996 0 P 0 ;0
L 1.90543996 -1.92643996 1.9054 -1.92643002 0 P 0 ;0
L 1.9054 -1.92643002 1.90538002 -1.92643002 0 P 0 ;0
L 1.90538002 -1.92643002 1.90455 -1.92636004 0 P 0 ;0
L 1.90455 -1.92636004 1.90443002 -1.92636004 0 P 0 ;0
L 1.90443002 -1.92636004 1.9036 -1.92633002 0 P 0 ;0
L 1.9036 -1.92633002 1.8994 -1.92633002 0 P 0 ;0
L 1.8994 -1.92633002 1.89798002 -1.92691004 0 P 0 ;0
L 1.89798002 -1.92691004 1.8974 -1.92833002 0 P 0 ;0
L 1.8974 -1.92833002 1.8974 -1.93328002 0 P 0 ;0
L 1.8974 -1.93328002 1.89748002 -1.93643002 0 P 0 ;0
L 1.89748002 -1.93643002 1.89748002 -1.93656004 0 P 0 ;0
L 1.89748002 -1.93656004 1.8975 -1.93673002 0 P 0 ;0
L 1.8975 -1.93673002 1.89751004 -1.93681004 0 P 0 ;0
L 1.89751004 -1.93681004 1.89751998 -1.9369 0 P 0 ;0
L 1.89751998 -1.9369 1.89755 -1.93706004 0 P 0 ;0
L 1.89755 -1.93706004 1.89758002 -1.93718996 0 P 0 ;0
L 1.89758002 -1.93718996 1.89758996 -1.93723002 0 P 0 ;0
L 1.89758996 -1.93723002 1.89763002 -1.9374 0 P 0 ;0
L 1.89763002 -1.9374 1.89763996 -1.93743996 0 P 0 ;0
L 1.89763996 -1.93743996 1.89766004 -1.93748002 0 P 0 ;0
L 1.89766004 -1.93748002 1.89768002 -1.93756004 0 P 0 ;0
L 1.89768002 -1.93756004 1.89773996 -1.93771998 0 P 0 ;0
L 1.89773996 -1.93771998 1.89776004 -1.93776004 0 P 0 ;0
L 1.89776004 -1.93776004 1.89776998 -1.9378 0 P 0 ;0
L 1.89776998 -1.9378 1.89781004 -1.93788002 0 P 0 ;0
L 1.89781004 -1.93788002 1.89788002 -1.93803996 0 P 0 ;0
L 1.89788002 -1.93803996 1.8979 -1.93808002 0 P 0 ;0
L 1.8979 -1.93808002 1.89791998 -1.93811004 0 P 0 ;0
L 1.89791998 -1.93811004 1.89796004 -1.93818996 0 P 0 ;0
L 1.89796004 -1.93818996 1.89803996 -1.93833996 0 P 0 ;0
L 1.89803996 -1.93833996 1.89813996 -1.93848002 0 P 0 ;0
L 1.89813996 -1.93848002 1.89823002 -1.93861998 0 P 0 ;0
L 1.89823002 -1.93861998 1.89828002 -1.93868996 0 P 0 ;0
L 1.89828002 -1.93868996 1.89831004 -1.93873002 0 P 0 ;0
L 1.89831004 -1.93873002 1.89833996 -1.93876004 0 P 0 ;0
L 1.89833996 -1.93876004 1.8984 -1.93883996 0 P 0 ;0
L 1.8984 -1.93883996 1.89848996 -1.93893002 0 P 0 ;0
L 1.89848996 -1.93893002 1.89851004 -1.93896004 0 P 0 ;0
L 1.89851004 -1.93896004 1.89868002 -1.93913002 0 P 0 ;0
L 1.89868002 -1.93913002 1.89871004 -1.93915 0 P 0 ;0
L 1.89871004 -1.93915 1.89878996 -1.93921998 0 P 0 ;0
L 1.89878996 -1.93921998 1.89885 -1.93928002 0 P 0 ;0
L 1.89885 -1.93928002 1.89888002 -1.9393 0 P 0 ;0
L 1.89888002 -1.9393 1.89891998 -1.93931998 0 P 0 ;0
L 1.89891998 -1.93931998 1.89901004 -1.93938996 0 P 0 ;0
L 1.89901004 -1.93938996 1.89903996 -1.93941004 0 P 0 ;0
L 1.89903996 -1.93941004 1.89906998 -1.93943996 0 P 0 ;0
L 1.89906998 -1.93943996 1.8991 -1.93946004 0 P 0 ;0
L 1.8991 -1.93946004 1.89913996 -1.93948002 0 P 0 ;0
L 1.89913996 -1.93948002 1.89923002 -1.93953996 0 P 0 ;0
L 1.89923002 -1.93953996 1.89926998 -1.93956004 0 P 0 ;0
L 1.89926998 -1.93956004 1.8993 -1.93958002 0 P 0 ;0
L 1.8993 -1.93958002 1.89933996 -1.9396 0 P 0 ;0
L 1.89933996 -1.9396 1.89936998 -1.93961004 0 P 0 ;0
L 1.89936998 -1.93961004 1.89938002 -1.93961004 0 P 0 ;0
L 1.89938002 -1.93961004 1.89946998 -1.93966004 0 P 0 ;0
L 1.89946998 -1.93966004 1.89953996 -1.9397 0 P 0 ;0
L 1.89953996 -1.9397 1.89971998 -1.93976998 0 P 0 ;0
L 1.89971998 -1.93976998 1.89975 -1.93978996 0 P 0 ;0
L 1.89975 -1.93978996 1.89978996 -1.9398 0 P 0 ;0
L 1.89978996 -1.9398 1.89986998 -1.93983002 0 P 0 ;0
L 1.89986998 -1.93983002 1.89996998 -1.93986004 0 P 0 ;0
L 1.89996998 -1.93986004 1.90001004 -1.93986998 0 P 0 ;0
L 1.90001004 -1.93986998 1.90005 -1.93988996 0 P 0 ;0
L 1.90005 -1.93988996 1.90013002 -1.9399 0 P 0 ;0
L 1.90013002 -1.9399 1.90023002 -1.93993002 0 P 0 ;0
L 1.90023002 -1.93993002 1.90023996 -1.93993002 0 P 0 ;0
L 1.90023996 -1.93993002 1.90028002 -1.93993996 0 P 0 ;0
L 1.90028002 -1.93993996 1.90031004 -1.93995 0 P 0 ;0
L 1.90031004 -1.93995 1.90036004 -1.93995 0 P 0 ;0
L 1.90036004 -1.93995 1.9004 -1.93996004 0 P 0 ;0
L 1.9004 -1.93996004 1.9005 -1.93996998 0 P 0 ;0
L 1.9005 -1.93996998 1.90061004 -1.93998996 0 P 0 ;0
L 1.90061004 -1.93998996 1.90063996 -1.93998996 0 P 0 ;0
L 1.90063996 -1.93998996 1.90181004 -1.94006998 0 P 0 ;0
L 1.90181004 -1.94006998 1.90183996 -1.94008002 0 P 0 ;0
L 1.90183996 -1.94008002 1.90191004 -1.94008002 0 P 0 ;0
L 1.90191004 -1.94008002 1.90308002 -1.9401 0 P 0 ;0
L 1.90308002 -1.9401 1.90311004 -1.9401 0 P 0 ;0
L 1.90311004 -1.9401 1.90313996 -1.94011004 0 P 0 ;0
L 1.90841004 -1.97146004 1.91683996 -1.97146004 0 P 0 ;0
L 1.9135 -1.97046004 1.91931004 -1.97046004 0 P 0 ;0
L 1.91655 -1.96946004 1.92131004 -1.96946004 0 P 0 ;0
L 1.91891998 -1.96846004 1.92301004 -1.96846004 0 P 0 ;0
L 1.92088996 -1.96746004 1.9245 -1.96746004 0 P 0 ;0
L 1.92251004 -1.96646004 1.9258 -1.96646004 0 P 0 ;0
L 1.92391004 -1.96546004 1.92696004 -1.96546004 0 P 0 ;0
L 1.92513002 -1.96446004 1.92803002 -1.96446004 0 P 0 ;0
L 1.9262 -1.96346004 1.92898996 -1.96346004 0 P 0 ;0
L 1.92713996 -1.96246004 1.92986004 -1.96246004 0 P 0 ;0
L 1.928 -1.96146004 1.93068996 -1.96146004 0 P 0 ;0
L 1.92878002 -1.96046004 1.93143002 -1.96046004 0 P 0 ;0
L 1.92951004 -1.95946004 1.93216004 -1.95946004 0 P 0 ;0
L 1.93016998 -1.95846004 1.93278996 -1.95846004 0 P 0 ;0
L 1.93078002 -1.95746004 1.93341004 -1.95746004 0 P 0 ;0
L 1.93133002 -1.95646004 1.93396004 -1.95646004 0 P 0 ;0
L 1.93185 -1.95546004 1.93448996 -1.95546004 0 P 0 ;0
L 1.93231004 -1.95446004 1.93495 -1.95446004 0 P 0 ;0
L 1.93275 -1.95346004 1.93541004 -1.95346004 0 P 0 ;0
L 1.93311998 -1.95246004 1.93586004 -1.95246004 0 P 0 ;0
L 1.93348002 -1.95146004 1.93628996 -1.95146004 0 P 0 ;0
L 1.93376998 -1.95046004 1.93666004 -1.95046004 0 P 0 ;0
L 1.93405 -1.94946004 1.93693002 -1.94946004 0 P 0 ;0
L 1.93428002 -1.94846004 1.93715 -1.94846004 0 P 0 ;0
L 1.93446998 -1.94746004 1.93733002 -1.94746004 0 P 0 ;0
L 1.93466004 -1.94646004 1.93743002 -1.94646004 0 P 0 ;0
L 1.93478996 -1.94546004 1.93748996 -1.94546004 0 P 0 ;0
L 1.9349 -1.94446998 1.93751998 -1.94446998 0 P 0 ;0
L 1.93496998 -1.94346004 1.93755 -1.94346004 0 P 0 ;0
L 1.93501998 -1.94246004 1.93758002 -1.94246004 0 P 0 ;0
L 1.93505 -1.94146998 1.93758996 -1.94146998 0 P 0 ;0
L 1.93503002 -1.94046004 1.93755 -1.94046004 0 P 0 ;0
L 1.935 -1.93946004 1.93751998 -1.93946004 0 P 0 ;0
L 1.93491998 -1.93846004 1.93748002 -1.93846004 0 P 0 ;0
L 1.93481004 -1.93746004 1.93738996 -1.93746004 0 P 0 ;0
L 1.93468996 -1.93646004 1.93726998 -1.93646004 0 P 0 ;0
L 1.93451004 -1.93546004 1.93716004 -1.93546004 0 P 0 ;0
L 1.93433002 -1.93446004 1.93703996 -1.93446004 0 P 0 ;0
L 1.93408996 -1.93346004 1.93685 -1.93346004 0 P 0 ;0
L 1.93383002 -1.93246004 1.93666004 -1.93246004 0 P 0 ;0
L 1.93353002 -1.93146004 1.93638996 -1.93146004 0 P 0 ;0
L 1.9332 -1.93046004 1.93611998 -1.93046004 0 P 0 ;0
L 1.93283996 -1.92946004 1.93576998 -1.92946004 0 P 0 ;0
L 1.93241004 -1.92846004 1.93541004 -1.92846004 0 P 0 ;0
L 1.93198996 -1.92746004 1.93498002 -1.92746004 0 P 0 ;0
L 1.93146998 -1.92646004 1.93451004 -1.92646004 0 P 0 ;0
L 1.93096004 -1.92546004 1.93398002 -1.92546004 0 P 0 ;0
L 1.93035 -1.92446998 1.93338002 -1.92446998 0 P 0 ;0
L 1.92973002 -1.92346004 1.93275 -1.92346004 0 P 0 ;0
L 1.92903002 -1.92246004 1.93201004 -1.92246004 0 P 0 ;0
L 1.92831004 -1.92146004 1.93125 -1.92146004 0 P 0 ;0
L 1.92746998 -1.92046004 1.93041004 -1.92046004 0 P 0 ;0
L 1.92661004 -1.91946004 1.92948996 -1.91946004 0 P 0 ;0
L 1.92558996 -1.91846004 1.92851004 -1.91846004 0 P 0 ;0
L 1.9245 -1.91746004 1.92741998 -1.91746004 0 P 0 ;0
L 1.92328996 -1.91646004 1.92621998 -1.91646004 0 P 0 ;0
L 1.92188002 -1.91546004 1.92491998 -1.91546004 0 P 0 ;0
L 1.92026004 -1.91446004 1.92358996 -1.91446004 0 P 0 ;0
L 1.91835 -1.91346004 1.92208002 -1.91346004 0 P 0 ;0
L 1.82446998 -2.08323996 1.87608002 -2.08323996 0 P 0 ;0
L 1.82403002 -2.08223996 1.87601004 -2.08223996 0 P 0 ;0
L 1.8234 -2.08123996 1.87591004 -2.08123996 0 P 0 ;0
L 1.82256004 -2.08023996 1.87578002 -2.08023996 0 P 0 ;0
L 1.82166004 -2.07923996 1.87558996 -2.07923996 0 P 0 ;0
L 1.82061998 -2.07823996 1.87533002 -2.07823996 0 P 0 ;0
L 1.81946004 -2.07723996 1.87498996 -2.07723996 0 P 0 ;0
L 1.81818002 -2.07623996 1.8746 -2.07623996 0 P 0 ;0
L 1.8168 -2.07523996 1.87416998 -2.07523996 0 P 0 ;0
L 1.81541998 -2.07423996 1.87371004 -2.07423996 0 P 0 ;0
L 1.81403002 -2.07323996 1.87316998 -2.07323996 0 P 0 ;0
L 1.81265 -2.07223996 1.87261004 -2.07223996 0 P 0 ;0
L 1.81126998 -2.07123996 1.87196004 -2.07123996 0 P 0 ;0
L 1.80986004 -2.07023996 1.87128002 -2.07023996 0 P 0 ;0
L 1.80843996 -2.06923996 1.87051998 -2.06923996 0 P 0 ;0
L 1.80703002 -2.06823996 1.8697 -2.06823996 0 P 0 ;0
L 1.80561004 -2.06723996 1.86883002 -2.06723996 0 P 0 ;0
L 1.8042 -2.06623996 1.86796004 -2.06623996 0 P 0 ;0
L 1.80278002 -2.06523996 1.86705 -2.06523996 0 P 0 ;0
L 1.80136004 -2.06423996 1.86608002 -2.06423996 0 P 0 ;0
L 1.79995 -2.06323996 1.8651 -2.06323996 0 P 0 ;0
L 1.79865 -2.06223996 1.86411004 -2.06223996 0 P 0 ;0
L 1.79735 -2.06123996 1.86301998 -2.06123996 0 P 0 ;0
L 1.79605 -2.06023996 1.86193002 -2.06023996 0 P 0 ;0
L 1.79475 -2.05923996 1.86083996 -2.05923996 0 P 0 ;0
L 1.79345 -2.05823996 1.85966998 -2.05823996 0 P 0 ;0
L 1.79215 -2.05723996 1.85846004 -2.05723996 0 P 0 ;0
L 1.79088002 -2.05623996 1.85726004 -2.05623996 0 P 0 ;0
L 1.78971998 -2.05523996 1.85598996 -2.05523996 0 P 0 ;0
L 1.78856004 -2.05423996 1.85461998 -2.05423996 0 P 0 ;0
L 1.7874 -2.05323996 1.85326004 -2.05323996 0 P 0 ;0
L 1.78623002 -2.05223996 1.8519 -2.05223996 0 P 0 ;0
L 1.78506998 -2.05123996 1.85053996 -2.05123996 0 P 0 ;0
L 1.78398002 -2.05023996 1.84918002 -2.05023996 0 P 0 ;0
L 1.783 -2.04923996 1.84781004 -2.04923996 0 P 0 ;0
L 1.87086004 -2.03023996 1.87535 -2.03023996 0 P 0 ;0
L 1.91633002 -1.91473002 1.9183 -1.91565 0 P 0 ;0
L 1.9183 -1.91565 1.92018996 -1.91673002 0 P 0 ;0
L 1.92018996 -1.91673002 1.92196998 -1.91796998 0 P 0 ;0
L 1.92196998 -1.91796998 1.92365 -1.91936004 0 P 0 ;0
L 1.92365 -1.91936004 1.9252 -1.92088002 0 P 0 ;0
L 1.9252 -1.92088002 1.92661004 -1.92253996 0 P 0 ;0
L 1.92661004 -1.92253996 1.92795 -1.92436998 0 P 0 ;0
L 1.92795 -1.92436998 1.92913996 -1.9263 0 P 0 ;0
L 1.92913996 -1.9263 1.93018002 -1.92831998 0 P 0 ;0
L 1.93018002 -1.92831998 1.93106998 -1.93041004 0 P 0 ;0
L 1.93106998 -1.93041004 1.93178996 -1.93256004 0 P 0 ;0
L 1.93178996 -1.93256004 1.93236004 -1.93476004 0 P 0 ;0
L 1.93236004 -1.93476004 1.93276004 -1.93703996 0 P 0 ;0
L 1.93276004 -1.93703996 1.93298996 -1.93933996 0 P 0 ;0
L 1.93298996 -1.93933996 1.93306004 -1.94165 0 P 0 ;0
L 1.93306004 -1.94165 1.93295 -1.94396998 0 P 0 ;0
L 1.93295 -1.94396998 1.93268002 -1.94626004 0 P 0 ;0
L 1.93268002 -1.94626004 1.93223002 -1.94853996 0 P 0 ;0
L 1.93223002 -1.94853996 1.93161998 -1.95071998 0 P 0 ;0
L 1.93161998 -1.95071998 1.93085 -1.95285 0 P 0 ;0
L 1.93085 -1.95285 1.92991004 -1.95491004 0 P 0 ;0
L 1.92991004 -1.95491004 1.92881004 -1.95688996 0 P 0 ;0
L 1.92881004 -1.95688996 1.92756004 -1.95878002 0 P 0 ;0
L 1.92756004 -1.95878002 1.92616004 -1.96056998 0 P 0 ;0
L 1.92616004 -1.96056998 1.92493996 -1.9619 0 P 0 ;0
L 1.92493996 -1.9619 1.92361998 -1.96313996 0 P 0 ;0
L 1.92361998 -1.96313996 1.9222 -1.96426004 0 P 0 ;0
L 1.9222 -1.96426004 1.9207 -1.96526998 0 P 0 ;0
L 1.9207 -1.96526998 1.91911004 -1.96616998 0 P 0 ;0
L 1.91911004 -1.96616998 1.91686998 -1.96721004 0 P 0 ;0
L 1.91686998 -1.96721004 1.91456004 -1.96806998 0 P 0 ;0
L 1.91456004 -1.96806998 1.91218996 -1.96876004 0 P 0 ;0
L 1.91218996 -1.96876004 1.90975 -1.96926998 0 P 0 ;0
L 1.90975 -1.96926998 1.90725 -1.9696 0 P 0 ;0
L 1.90725 -1.9696 1.90473002 -1.96973996 0 P 0 ;0
L 1.90473002 -1.96973996 1.9022 -1.96968996 0 P 0 ;0
L 1.9022 -1.96968996 1.89966998 -1.96945 0 P 0 ;0
L 1.89966998 -1.96945 1.89778002 -1.96913002 0 P 0 ;0
L 1.89778002 -1.96913002 1.89591998 -1.96868996 0 P 0 ;0
L 1.89591998 -1.96868996 1.8941 -1.96811004 0 P 0 ;0
L 1.8941 -1.96811004 1.89231004 -1.96741004 0 P 0 ;0
L 1.89231004 -1.96741004 1.89058002 -1.96658002 0 P 0 ;0
L 1.89058002 -1.96658002 1.88875 -1.96553996 0 P 0 ;0
L 1.88875 -1.96553996 1.88698996 -1.96435 0 P 0 ;0
L 1.88698996 -1.96435 1.88533996 -1.96303002 0 P 0 ;0
L 1.88533996 -1.96303002 1.88378996 -1.9616 0 P 0 ;0
L 1.88378996 -1.9616 1.88235 -1.96003996 0 P 0 ;0
L 1.88235 -1.96003996 1.88103002 -1.95838996 0 P 0 ;0
L 1.88103002 -1.95838996 1.87983996 -1.95663002 0 P 0 ;0
L 1.87983996 -1.95663002 1.87861998 -1.95446998 0 P 0 ;0
L 1.87861998 -1.95446998 1.87758002 -1.9522 0 P 0 ;0
L 1.87758002 -1.9522 1.87673996 -1.94986004 0 P 0 ;0
L 1.87673996 -1.94986004 1.8761 -1.94745 0 P 0 ;0
L 1.8761 -1.94745 1.87568002 -1.945 0 P 0 ;0
L 1.87568002 -1.945 1.87546004 -1.94248996 0 P 0 ;0
L 1.87546004 -1.94248996 1.87546004 -1.93998996 0 P 0 ;0
L 1.87546004 -1.93998996 1.87566998 -1.93748996 0 P 0 ;0
L 1.87566998 -1.93748996 1.87608996 -1.93501998 0 P 0 ;0
L 1.87608996 -1.93501998 1.87671998 -1.9326 0 P 0 ;0
L 1.87671998 -1.9326 1.87755 -1.93023002 0 P 0 ;0
L 1.87755 -1.93023002 1.8786 -1.92793002 0 P 0 ;0
L 1.8786 -1.92793002 1.87981998 -1.92575 0 P 0 ;0
L 1.87981998 -1.92575 1.88123002 -1.92368002 0 P 0 ;0
L 1.88123002 -1.92368002 1.88281004 -1.92175 0 P 0 ;0
L 1.88281004 -1.92175 1.88455 -1.91996004 0 P 0 ;0
L 1.88455 -1.91996004 1.88643002 -1.91831998 0 P 0 ;0
L 1.88643002 -1.91831998 1.88845 -1.91686004 0 P 0 ;0
L 1.88845 -1.91686004 1.88986998 -1.91598996 0 P 0 ;0
L 1.88986998 -1.91598996 1.89135 -1.91523002 0 P 0 ;0
L 1.89135 -1.91523002 1.89288002 -1.91458996 0 P 0 ;0
L 1.89288002 -1.91458996 1.89446998 -1.91406004 0 P 0 ;0
L 1.89446998 -1.91406004 1.89688996 -1.91343996 0 P 0 ;0
L 1.89688996 -1.91343996 1.89935 -1.91298996 0 P 0 ;0
L 1.89935 -1.91298996 1.90183996 -1.91271004 0 P 0 ;0
L 1.90183996 -1.91271004 1.9044 -1.91261004 0 P 0 ;0
L 1.9044 -1.91261004 1.90695 -1.91268002 0 P 0 ;0
L 1.90695 -1.91268002 1.90948996 -1.91291998 0 P 0 ;0
L 1.90948996 -1.91291998 1.91181998 -1.91331998 0 P 0 ;0
L 1.91181998 -1.91331998 1.91408996 -1.91393002 0 P 0 ;0
L 1.91408996 -1.91393002 1.91633002 -1.91473002 0 P 0 ;0
L 1.89498002 -1.90801998 1.8922 -1.90893002 0 P 0 ;0
L 1.8922 -1.90893002 1.88948002 -1.91003002 0 P 0 ;0
L 1.88948002 -1.91003002 1.88686004 -1.91133002 0 P 0 ;0
L 1.88686004 -1.91133002 1.88431004 -1.91283996 0 P 0 ;0
L 1.88431004 -1.91283996 1.88201004 -1.91446004 0 P 0 ;0
L 1.88201004 -1.91446004 1.87985 -1.91626998 0 P 0 ;0
L 1.87985 -1.91626998 1.87785 -1.91826004 0 P 0 ;0
L 1.87785 -1.91826004 1.87601998 -1.92041004 0 P 0 ;0
L 1.87601998 -1.92041004 1.87441004 -1.92266998 0 P 0 ;0
L 1.87441004 -1.92266998 1.87298996 -1.92505 0 P 0 ;0
L 1.87298996 -1.92505 1.87178002 -1.92756004 0 P 0 ;0
L 1.87178002 -1.92756004 1.87078996 -1.93015 0 P 0 ;0
L 1.87078996 -1.93015 1.87 -1.93286998 0 P 0 ;0
L 1.87 -1.93286998 1.86943996 -1.93563996 0 P 0 ;0
L 1.86943996 -1.93563996 1.86908996 -1.93845 0 P 0 ;0
L 1.86908996 -1.93845 1.86898002 -1.94128996 0 P 0 ;0
L 1.86898002 -1.94128996 1.86911998 -1.94485 0 P 0 ;0
L 1.86911998 -1.94485 1.86953996 -1.94841004 0 P 0 ;0
L 1.86953996 -1.94841004 1.86996004 -1.95048996 0 P 0 ;0
L 1.86996004 -1.95048996 1.87053002 -1.95251998 0 P 0 ;0
L 1.87053002 -1.95251998 1.87125 -1.95451998 0 P 0 ;0
L 1.87125 -1.95451998 1.87211004 -1.95643002 0 P 0 ;0
L 1.87211004 -1.95643002 1.8731 -1.95826004 0 P 0 ;0
L 1.8731 -1.95826004 1.87423996 -1.96001998 0 P 0 ;0
L 1.87423996 -1.96001998 1.87636998 -1.96278996 0 P 0 ;0
L 1.87636998 -1.96278996 1.87871998 -1.96536998 0 P 0 ;0
L 1.87871998 -1.96536998 1.88145 -1.96788002 0 P 0 ;0
L 1.88145 -1.96788002 1.88436998 -1.97015 0 P 0 ;0
L 1.88436998 -1.97015 1.88621004 -1.97135 0 P 0 ;0
L 1.88621004 -1.97135 1.88813002 -1.97238002 0 P 0 ;0
L 1.88813002 -1.97238002 1.89013002 -1.97326004 0 P 0 ;0
L 1.89013002 -1.97326004 1.89228002 -1.97398996 0 P 0 ;0
L 1.89228002 -1.97398996 1.89446998 -1.97455 0 P 0 ;0
L 1.89446998 -1.97455 1.89671004 -1.97493996 0 P 0 ;0
L 1.89671004 -1.97493996 1.90076998 -1.97533996 0 P 0 ;0
L 1.90076998 -1.97533996 1.90485 -1.97546998 0 P 0 ;0
L 1.90485 -1.97546998 1.90821004 -1.97531998 0 P 0 ;0
L 1.90821004 -1.97531998 1.91153996 -1.97488996 0 P 0 ;0
L 1.91153996 -1.97488996 1.91481998 -1.97418996 0 P 0 ;0
L 1.91481998 -1.97418996 1.9171 -1.9735 0 P 0 ;0
L 1.9171 -1.9735 1.91933002 -1.97266004 0 P 0 ;0
L 1.91933002 -1.97266004 1.92148002 -1.97166004 0 P 0 ;0
L 1.92148002 -1.97166004 1.92356998 -1.97048996 0 P 0 ;0
L 1.92356998 -1.97048996 1.92553996 -1.96918996 0 P 0 ;0
L 1.92553996 -1.96918996 1.92741004 -1.96773996 0 P 0 ;0
L 1.92741004 -1.96773996 1.92916004 -1.96616998 0 P 0 ;0
L 1.92916004 -1.96616998 1.93081004 -1.96446004 0 P 0 ;0
L 1.93081004 -1.96446004 1.93236998 -1.96256998 0 P 0 ;0
L 1.93236998 -1.96256998 1.93381004 -1.96058996 0 P 0 ;0
L 1.93381004 -1.96058996 1.93511998 -1.95851004 0 P 0 ;0
L 1.93511998 -1.95851004 1.93628996 -1.95633996 0 P 0 ;0
L 1.93628996 -1.95633996 1.93803996 -1.95251998 0 P 0 ;0
L 1.93803996 -1.95251998 1.93858002 -1.95101998 0 P 0 ;0
L 1.93858002 -1.95101998 1.93898996 -1.94948002 0 P 0 ;0
L 1.93898996 -1.94948002 1.93928996 -1.94786998 0 P 0 ;0
L 1.93928996 -1.94786998 1.93946004 -1.94625 0 P 0 ;0
L 1.93946004 -1.94625 1.9396 -1.94178002 0 P 0 ;0
L 1.9396 -1.94178002 1.93946004 -1.93803996 0 P 0 ;0
L 1.93946004 -1.93803996 1.93905 -1.9343 0 P 0 ;0
L 1.93905 -1.9343 1.93863996 -1.93213996 0 P 0 ;0
L 1.93863996 -1.93213996 1.93808002 -1.93001998 0 P 0 ;0
L 1.93808002 -1.93001998 1.93736004 -1.92795 0 P 0 ;0
L 1.93736004 -1.92795 1.93653002 -1.92601004 0 P 0 ;0
L 1.93653002 -1.92601004 1.93555 -1.92415 0 P 0 ;0
L 1.93555 -1.92415 1.93441998 -1.92236004 0 P 0 ;0
L 1.93441998 -1.92236004 1.9331 -1.92056004 0 P 0 ;0
L 1.9331 -1.92056004 1.93166998 -1.91885 0 P 0 ;0
L 1.93166998 -1.91885 1.93011998 -1.91723002 0 P 0 ;0
L 1.93011998 -1.91723002 1.92896004 -1.91615 0 P 0 ;0
L 1.92896004 -1.91615 1.92775 -1.91511004 0 P 0 ;0
L 1.92775 -1.91511004 1.92493002 -1.91295 0 P 0 ;0
L 1.92493002 -1.91295 1.9221 -1.91108002 0 P 0 ;0
L 1.9221 -1.91108002 1.92095 -1.91043002 0 P 0 ;0
L 1.92095 -1.91043002 1.91975 -1.90985 0 P 0 ;0
L 1.91975 -1.90985 1.91796004 -1.90913996 0 P 0 ;0
L 1.91796004 -1.90913996 1.91613002 -1.90856004 0 P 0 ;0
L 1.91613002 -1.90856004 1.91423996 -1.9081 0 P 0 ;0
L 1.91423996 -1.9081 1.91086004 -1.90751998 0 P 0 ;0
L 1.91086004 -1.90751998 1.90743002 -1.90716004 0 P 0 ;0
L 1.90743002 -1.90716004 1.90401004 -1.90701004 0 P 0 ;0
L 1.90401004 -1.90701004 1.90058002 -1.90708002 0 P 0 ;0
L 1.90058002 -1.90708002 1.8987 -1.90726004 0 P 0 ;0
L 1.8987 -1.90726004 1.89683002 -1.90756998 0 P 0 ;0
L 1.89683002 -1.90756998 1.89498002 -1.90801998 0 P 0 ;0
L 1.86643002 -2.02923996 1.87525 -2.02923996 0 P 0 ;0
L 1.86176998 -2.02823996 1.87515 -2.02823996 0 P 0 ;0
L 1.85588996 -2.02723996 1.87505 -2.02723996 0 P 0 ;0
L 1.78365 -2.00523996 1.87281004 -2.00523996 0 P 0 ;0
L 1.78451004 -2.00423996 1.87271004 -2.00423996 0 P 0 ;0
L 1.78546998 -2.00323996 1.87261004 -2.00323996 0 P 0 ;0
L 1.78655 -2.00223996 1.8725 -2.00223996 0 P 0 ;0
L 1.78776004 -2.00123996 1.8724 -2.00123996 0 P 0 ;0
L 1.78915 -2.00023996 1.8723 -2.00023996 0 P 0 ;0
L 1.79078996 -1.99923996 1.8722 -1.99923996 0 P 0 ;0
L 1.79263996 -1.99823996 1.87208996 -1.99823996 0 P 0 ;0
L 1.79458996 -1.99723996 1.87198996 -1.99723996 0 P 0 ;0
L 1.79686998 -1.99623996 1.87188002 -1.99623996 0 P 0 ;0
L 1.79946004 -1.99523996 1.87178002 -1.99523996 0 P 0 ;0
L 1.80231004 -1.99423996 1.86961998 -1.99423996 0 P 0 ;0
L 1.80596004 -1.99323996 1.86218002 -1.99323996 0 P 0 ;0
L 1.81051004 -1.99223996 1.85398002 -1.99223996 0 P 0 ;0
L 1.81676004 -1.99123996 1.84395 -1.99123996 0 P 0 ;0
L 1.87786998 -1.96146004 1.88093996 -1.96146004 0 P 0 ;0
L 1.8771 -1.96046004 1.88013002 -1.96046004 0 P 0 ;0
L 1.87633996 -1.95946004 1.87933996 -1.95946004 0 P 0 ;0
L 1.87561998 -1.95846004 1.87866998 -1.95846004 0 P 0 ;0
L 1.87496998 -1.95746004 1.87801998 -1.95746004 0 P 0 ;0
L 1.8744 -1.95646004 1.87745 -1.95646004 0 P 0 ;0
L 1.87386998 -1.95546004 1.87688002 -1.95546004 0 P 0 ;0
L 1.87341998 -1.95446004 1.87641998 -1.95446004 0 P 0 ;0
L 1.87298996 -1.95346004 1.87596004 -1.95346004 0 P 0 ;0
L 1.87263002 -1.95246004 1.87555 -1.95246004 0 P 0 ;0
L 1.87231004 -1.95146004 1.87518996 -1.95146004 0 P 0 ;0
L 1.87203002 -1.95046004 1.87483002 -1.95046004 0 P 0 ;0
L 1.87178996 -1.94946004 1.87456998 -1.94946004 0 P 0 ;0
L 1.87158996 -1.94846004 1.87431004 -1.94846004 0 P 0 ;0
L 1.87143996 -1.94746004 1.87408002 -1.94746004 0 P 0 ;0
L 1.87133002 -1.94646004 1.8739 -1.94646004 0 P 0 ;0
L 1.87121004 -1.94546004 1.87373002 -1.94546004 0 P 0 ;0
L 1.8711 -1.94446998 1.87361998 -1.94446998 0 P 0 ;0
L 1.87106998 -1.94346004 1.87353996 -1.94346004 0 P 0 ;0
L 1.87103002 -1.94246004 1.87346004 -1.94246004 0 P 0 ;0
L 1.87098996 -1.94146998 1.87346004 -1.94146998 0 P 0 ;0
L 1.87101004 -1.94046004 1.87346004 -1.94046004 0 P 0 ;0
L 1.87106004 -1.93946004 1.87348996 -1.93946004 0 P 0 ;0
L 1.87111004 -1.93846004 1.87358002 -1.93846004 0 P 0 ;0
L 1.87123002 -1.93746004 1.87366004 -1.93746004 0 P 0 ;0
L 1.87135 -1.93646004 1.87381998 -1.93646004 0 P 0 ;0
L 1.87151004 -1.93546004 1.87398996 -1.93546004 0 P 0 ;0
L 1.87171998 -1.93446004 1.87416998 -1.93446004 0 P 0 ;0
L 1.87191998 -1.93346004 1.87443002 -1.93346004 0 P 0 ;0
L 1.8722 -1.93246004 1.87468996 -1.93246004 0 P 0 ;0
L 1.87248996 -1.93146004 1.875 -1.93146004 0 P 0 ;0
L 1.87281004 -1.93046004 1.87535 -1.93046004 0 P 0 ;0
L 1.87318996 -1.92946004 1.87571004 -1.92946004 0 P 0 ;0
L 1.87356998 -1.92846004 1.87616004 -1.92846004 0 P 0 ;0
L 1.87405 -1.92746004 1.87661004 -1.92746004 0 P 0 ;0
L 1.87453002 -1.92646004 1.87711998 -1.92646004 0 P 0 ;0
L 1.87506998 -1.92546004 1.87768996 -1.92546004 0 P 0 ;0
L 1.87566004 -1.92446998 1.87826998 -1.92446998 0 P 0 ;0
L 1.87628996 -1.92346004 1.87896004 -1.92346004 0 P 0 ;0
L 1.87701004 -1.92246004 1.87963996 -1.92246004 0 P 0 ;0
L 1.87775 -1.92146004 1.88046004 -1.92146004 0 P 0 ;0
L 1.90483996 -1.97346004 1.9009 -1.97333996 0 P 0 ;0
L 1.9009 -1.97333996 1.89698002 -1.97295 0 P 0 ;0
L 1.89698002 -1.97295 1.89488996 -1.97258996 0 P 0 ;0
L 1.89488996 -1.97258996 1.89285 -1.97206998 0 P 0 ;0
L 1.89285 -1.97206998 1.89086004 -1.97138996 0 P 0 ;0
L 1.89086004 -1.97138996 1.889 -1.97058002 0 P 0 ;0
L 1.889 -1.97058002 1.88723002 -1.96961998 0 P 0 ;0
L 1.88723002 -1.96961998 1.88553002 -1.96851998 0 P 0 ;0
L 1.88553002 -1.96851998 1.88273996 -1.96636004 0 P 0 ;0
L 1.88273996 -1.96636004 1.88013996 -1.96396004 0 P 0 ;0
L 1.88013996 -1.96396004 1.8779 -1.9615 0 P 0 ;0
L 1.8779 -1.9615 1.87588002 -1.95886998 0 P 0 ;0
L 1.87588002 -1.95886998 1.87483002 -1.95723996 0 P 0 ;0
L 1.87483002 -1.95723996 1.8739 -1.95553996 0 P 0 ;0
L 1.8739 -1.95553996 1.87311004 -1.95376998 0 P 0 ;0
L 1.87311004 -1.95376998 1.87243002 -1.95191004 0 P 0 ;0
L 1.87243002 -1.95191004 1.8719 -1.95001998 0 P 0 ;0
L 1.8719 -1.95001998 1.87151998 -1.9481 0 P 0 ;0
L 1.87151998 -1.9481 1.87111004 -1.94468996 0 P 0 ;0
L 1.87111004 -1.94468996 1.87098002 -1.94128996 0 P 0 ;0
L 1.87098002 -1.94128996 1.87108996 -1.93861004 0 P 0 ;0
L 1.87108996 -1.93861004 1.87141004 -1.93596998 0 P 0 ;0
L 1.87141004 -1.93596998 1.87195 -1.93335 0 P 0 ;0
L 1.87195 -1.93335 1.87268996 -1.93078996 0 P 0 ;0
L 1.87268996 -1.93078996 1.87361998 -1.92835 0 P 0 ;0
L 1.87361998 -1.92835 1.87475 -1.926 0 P 0 ;0
L 1.87475 -1.926 1.87608996 -1.92376004 0 P 0 ;0
L 1.87608996 -1.92376004 1.8776 -1.92163996 0 P 0 ;0
L 1.8776 -1.92163996 1.87931998 -1.91961998 0 P 0 ;0
L 1.87931998 -1.91961998 1.8812 -1.91775 0 P 0 ;0
L 1.8812 -1.91775 1.88323002 -1.91605 0 P 0 ;0
L 1.88323002 -1.91605 1.8854 -1.91451998 0 P 0 ;0
L 1.8854 -1.91451998 1.88781004 -1.91308996 0 P 0 ;0
L 1.88781004 -1.91308996 1.89031004 -1.91186004 0 P 0 ;0
L 1.89031004 -1.91186004 1.89288002 -1.9108 0 P 0 ;0
L 1.89288002 -1.9108 1.89553002 -1.90995 0 P 0 ;0
L 1.89553002 -1.90995 1.89723002 -1.90953002 0 P 0 ;0
L 1.89723002 -1.90953002 1.89896004 -1.90923996 0 P 0 ;0
L 1.89896004 -1.90923996 1.90068996 -1.90908002 0 P 0 ;0
L 1.90068996 -1.90908002 1.90398996 -1.90901004 0 P 0 ;0
L 1.90398996 -1.90901004 1.90728002 -1.90915 0 P 0 ;0
L 1.90728002 -1.90915 1.91058996 -1.90951004 0 P 0 ;0
L 1.91058996 -1.90951004 1.91383996 -1.91006004 0 P 0 ;0
L 1.91383996 -1.91006004 1.91558996 -1.91048996 0 P 0 ;0
L 1.91558996 -1.91048996 1.91728996 -1.91101998 0 P 0 ;0
L 1.91728996 -1.91101998 1.91895 -1.91168002 0 P 0 ;0
L 1.91895 -1.91168002 1.92001998 -1.9122 0 P 0 ;0
L 1.92001998 -1.9122 1.92105 -1.91278996 0 P 0 ;0
L 1.92105 -1.91278996 1.92376998 -1.91458002 0 P 0 ;0
L 1.92376998 -1.91458002 1.92648996 -1.91666998 0 P 0 ;0
L 1.92648996 -1.91666998 1.92763002 -1.91763996 0 P 0 ;0
L 1.92763002 -1.91763996 1.92871004 -1.91865 0 P 0 ;0
L 1.92871004 -1.91865 1.93018002 -1.92018996 0 P 0 ;0
L 1.93018002 -1.92018996 1.93153002 -1.9218 0 P 0 ;0
L 1.93153002 -1.9218 1.93276998 -1.92348996 0 P 0 ;0
L 1.93276998 -1.92348996 1.93381004 -1.92515 0 P 0 ;0
L 1.93381004 -1.92515 1.93471998 -1.92686998 0 P 0 ;0
L 1.93471998 -1.92686998 1.9355 -1.92866998 0 P 0 ;0
L 1.9355 -1.92866998 1.93616998 -1.93061004 0 P 0 ;0
L 1.93616998 -1.93061004 1.93668996 -1.93258002 0 P 0 ;0
L 1.93668996 -1.93258002 1.93706998 -1.93458996 0 P 0 ;0
L 1.93706998 -1.93458996 1.93746998 -1.93818996 0 P 0 ;0
L 1.93746998 -1.93818996 1.9376 -1.94178996 0 P 0 ;0
L 1.9376 -1.94178996 1.93746004 -1.94611004 0 P 0 ;0
L 1.93746004 -1.94611004 1.93731004 -1.94758996 0 P 0 ;0
L 1.93731004 -1.94758996 1.93705 -1.94903996 0 P 0 ;0
L 1.93705 -1.94903996 1.93666998 -1.95041998 0 P 0 ;0
L 1.93666998 -1.95041998 1.93618002 -1.95176004 0 P 0 ;0
L 1.93618002 -1.95176004 1.9345 -1.95545 0 P 0 ;0
L 1.9345 -1.95545 1.93338996 -1.9575 0 P 0 ;0
L 1.93338996 -1.9575 1.93216004 -1.95946998 0 P 0 ;0
L 1.93216004 -1.95946998 1.93078996 -1.96133996 0 P 0 ;0
L 1.93078996 -1.96133996 1.92931004 -1.96311998 0 P 0 ;0
L 1.92931004 -1.96311998 1.92776998 -1.96473002 0 P 0 ;0
L 1.92776998 -1.96473002 1.92613002 -1.96621004 0 P 0 ;0
L 1.92613002 -1.96621004 1.92438002 -1.96756004 0 P 0 ;0
L 1.92438002 -1.96756004 1.92253002 -1.96878002 0 P 0 ;0
L 1.92253002 -1.96878002 1.92056998 -1.96986998 0 P 0 ;0
L 1.92056998 -1.96986998 1.91855 -1.97081998 0 P 0 ;0
L 1.91855 -1.97081998 1.91646004 -1.97161004 0 P 0 ;0
L 1.91646004 -1.97161004 1.91433002 -1.97223996 0 P 0 ;0
L 1.91433002 -1.97223996 1.9112 -1.97291004 0 P 0 ;0
L 1.9112 -1.97291004 1.90803996 -1.97331998 0 P 0 ;0
L 1.90803996 -1.97331998 1.90483996 -1.97346004 0 P 0 ;0
L 1.90476004 -1.97173996 1.9048 -1.97173996 0 P 0 ;0
L 1.9048 -1.97173996 1.90483996 -1.97173002 0 P 0 ;0
L 1.90483996 -1.97173002 1.90736004 -1.9716 0 P 0 ;0
L 1.90736004 -1.9716 1.9074 -1.97158996 0 P 0 ;0
L 1.9074 -1.97158996 1.90746998 -1.97158996 0 P 0 ;0
L 1.90746998 -1.97158996 1.90751004 -1.97158002 0 P 0 ;0
L 1.90751004 -1.97158002 1.91001004 -1.97126004 0 P 0 ;0
L 1.91001004 -1.97126004 1.91005 -1.97125 0 P 0 ;0
L 1.91005 -1.97125 1.91008002 -1.97123996 0 P 0 ;0
L 1.91008002 -1.97123996 1.91011998 -1.97123996 0 P 0 ;0
L 1.91011998 -1.97123996 1.91016004 -1.97123002 0 P 0 ;0
L 1.91016004 -1.97123002 1.9126 -1.97071998 0 P 0 ;0
L 1.9126 -1.97071998 1.9126 -1.97071004 0 P 0 ;0
L 1.9126 -1.97071004 1.91266998 -1.97071004 0 P 0 ;0
L 1.91266998 -1.97071004 1.91271004 -1.97068996 0 P 0 ;0
L 1.91271004 -1.97068996 1.91275 -1.97068002 0 P 0 ;0
L 1.91275 -1.97068002 1.91511998 -1.96998996 0 P 0 ;0
L 1.91511998 -1.96998996 1.91515 -1.96998996 0 P 0 ;0
L 1.91515 -1.96998996 1.91518996 -1.96996998 0 P 0 ;0
L 1.91518996 -1.96996998 1.91523002 -1.96996004 0 P 0 ;0
L 1.91523002 -1.96996004 1.91526004 -1.96995 0 P 0 ;0
L 1.91526004 -1.96995 1.91756998 -1.96908002 0 P 0 ;0
L 1.91756998 -1.96908002 1.91761004 -1.96906998 0 P 0 ;0
L 1.91761004 -1.96906998 1.91768002 -1.96903996 0 P 0 ;0
L 1.91768002 -1.96903996 1.91771004 -1.96901998 0 P 0 ;0
L 1.91771004 -1.96901998 1.91995 -1.96798002 0 P 0 ;0
L 1.91995 -1.96798002 1.92001998 -1.96795 0 P 0 ;0
L 1.92001998 -1.96795 1.92005 -1.96793002 0 P 0 ;0
L 1.92005 -1.96793002 1.92008996 -1.96791004 0 P 0 ;0
L 1.92008996 -1.96791004 1.92168002 -1.96701998 0 P 0 ;0
L 1.92168002 -1.96701998 1.92171998 -1.967 0 P 0 ;0
L 1.92171998 -1.967 1.92175 -1.96698002 0 P 0 ;0
L 1.92175 -1.96698002 1.92178996 -1.96695 0 P 0 ;0
L 1.92178996 -1.96695 1.92181998 -1.96693002 0 P 0 ;0
L 1.92181998 -1.96693002 1.92331998 -1.96591998 0 P 0 ;0
L 1.92331998 -1.96591998 1.92336004 -1.9659 0 P 0 ;0
L 1.92336004 -1.9659 1.92341998 -1.96586004 0 P 0 ;0
L 1.92341998 -1.96586004 1.92345 -1.96583002 0 P 0 ;0
L 1.92345 -1.96583002 1.92486004 -1.9647 0 P 0 ;0
L 1.92486004 -1.9647 1.92493002 -1.96465 0 P 0 ;0
L 1.92493002 -1.96465 1.92496004 -1.96463002 0 P 0 ;0
L 1.92496004 -1.96463002 1.92498996 -1.9646 0 P 0 ;0
L 1.92498996 -1.9646 1.92631004 -1.96336998 0 P 0 ;0
L 1.92631004 -1.96336998 1.9264 -1.96328002 0 P 0 ;0
L 1.9264 -1.96328002 1.92641998 -1.96325 0 P 0 ;0
L 1.92641998 -1.96325 1.92763996 -1.96191998 0 P 0 ;0
L 1.92763996 -1.96191998 1.92766998 -1.96188996 0 P 0 ;0
L 1.92766998 -1.96188996 1.92768996 -1.96186004 0 P 0 ;0
L 1.92768996 -1.96186004 1.92771998 -1.96183002 0 P 0 ;0
L 1.92771998 -1.96183002 1.92773996 -1.9618 0 P 0 ;0
L 1.92773996 -1.9618 1.92913996 -1.96001004 0 P 0 ;0
L 1.92913996 -1.96001004 1.92918996 -1.95995 0 P 0 ;0
L 1.92918996 -1.95995 1.92921004 -1.95991004 0 P 0 ;0
L 1.92921004 -1.95991004 1.92923002 -1.95988002 0 P 0 ;0
L 1.92923002 -1.95988002 1.93048002 -1.95798996 0 P 0 ;0
L 1.93048002 -1.95798996 1.93051998 -1.95793002 0 P 0 ;0
L 1.93051998 -1.95793002 1.93053996 -1.95788996 0 P 0 ;0
L 1.93053996 -1.95788996 1.93056004 -1.95786004 0 P 0 ;0
L 1.93056004 -1.95786004 1.93166004 -1.95588002 0 P 0 ;0
L 1.93166004 -1.95588002 1.93171004 -1.95576998 0 P 0 ;0
L 1.93171004 -1.95576998 1.93173002 -1.95573996 0 P 0 ;0
L 1.93173002 -1.95573996 1.93266998 -1.95366998 0 P 0 ;0
L 1.93266998 -1.95366998 1.93271004 -1.95356998 0 P 0 ;0
L 1.93271004 -1.95356998 1.93273002 -1.95353002 0 P 0 ;0
L 1.93273002 -1.95353002 1.9335 -1.9514 0 P 0 ;0
L 1.9335 -1.9514 1.93351004 -1.95136998 0 P 0 ;0
L 1.93351004 -1.95136998 1.93353002 -1.95133002 0 P 0 ;0
L 1.93353002 -1.95133002 1.93355 -1.95125 0 P 0 ;0
L 1.93355 -1.95125 1.93416004 -1.94906998 0 P 0 ;0
L 1.93416004 -1.94906998 1.93416998 -1.94903002 0 P 0 ;0
L 1.93416998 -1.94903002 1.93418002 -1.949 0 P 0 ;0
L 1.93418002 -1.949 1.93418002 -1.94896004 0 P 0 ;0
L 1.93418002 -1.94896004 1.93418996 -1.94891998 0 P 0 ;0
L 1.93418996 -1.94891998 1.93463996 -1.94665 0 P 0 ;0
L 1.93463996 -1.94665 1.93463996 -1.94661004 0 P 0 ;0
L 1.93463996 -1.94661004 1.93465 -1.94656998 0 P 0 ;0
L 1.93465 -1.94656998 1.93466004 -1.9465 0 P 0 ;0
L 1.93466004 -1.9465 1.93493996 -1.9442 0 P 0 ;0
L 1.93493996 -1.9442 1.93493996 -1.94413002 0 P 0 ;0
L 1.93493996 -1.94413002 1.93495 -1.94408996 0 P 0 ;0
L 1.93495 -1.94408996 1.93495 -1.94406004 0 P 0 ;0
L 1.93495 -1.94406004 1.93505 -1.94173996 0 P 0 ;0
L 1.93505 -1.94173996 1.93506004 -1.94171004 0 P 0 ;0
L 1.93506004 -1.94171004 1.93506004 -1.9416 0 P 0 ;0
L 1.93506004 -1.9416 1.93498996 -1.93928996 0 P 0 ;0
L 1.93498996 -1.93928996 1.93498996 -1.93921004 0 P 0 ;0
L 1.93498996 -1.93921004 1.93498002 -1.93913996 0 P 0 ;0
L 1.93498002 -1.93913996 1.93475 -1.93683996 0 P 0 ;0
L 1.93475 -1.93683996 1.93473996 -1.93676998 0 P 0 ;0
L 1.93473996 -1.93676998 1.93473002 -1.93673002 0 P 0 ;0
L 1.93473002 -1.93673002 1.93473002 -1.93668996 0 P 0 ;0
L 1.93473002 -1.93668996 1.93433002 -1.93441004 0 P 0 ;0
L 1.93433002 -1.93441004 1.93431998 -1.93436998 0 P 0 ;0
L 1.93431998 -1.93436998 1.93431004 -1.93433996 0 P 0 ;0
L 1.93431004 -1.93433996 1.93428996 -1.93426004 0 P 0 ;0
L 1.93428996 -1.93426004 1.93373002 -1.93206004 0 P 0 ;0
L 1.93373002 -1.93206004 1.93368996 -1.93191998 0 P 0 ;0
L 1.93368996 -1.93191998 1.93296004 -1.92976998 0 P 0 ;0
L 1.93296004 -1.92976998 1.93293996 -1.9297 0 P 0 ;0
L 1.93293996 -1.9297 1.93291004 -1.92963002 0 P 0 ;0
L 1.93291004 -1.92963002 1.93201998 -1.92753996 0 P 0 ;0
L 1.93201998 -1.92753996 1.93196998 -1.92743002 0 P 0 ;0
L 1.93196998 -1.92743002 1.93196004 -1.9274 0 P 0 ;0
L 1.93196004 -1.9274 1.93091998 -1.92538996 0 P 0 ;0
L 1.93091998 -1.92538996 1.9309 -1.92536004 0 P 0 ;0
L 1.9309 -1.92536004 1.93088002 -1.92531998 0 P 0 ;0
L 1.93088002 -1.92531998 1.93086004 -1.92528996 0 P 0 ;0
L 1.93086004 -1.92528996 1.93083996 -1.92525 0 P 0 ;0
L 1.93083996 -1.92525 1.92965 -1.92331998 0 P 0 ;0
L 1.92965 -1.92331998 1.92956998 -1.9232 0 P 0 ;0
L 1.92956998 -1.9232 1.92823002 -1.92136004 0 P 0 ;0
L 1.92823002 -1.92136004 1.92818002 -1.9213 0 P 0 ;0
L 1.92818002 -1.9213 1.92816004 -1.92126998 0 P 0 ;0
L 1.92816004 -1.92126998 1.92813002 -1.92123996 0 P 0 ;0
L 1.92813002 -1.92123996 1.92671998 -1.91958002 0 P 0 ;0
L 1.92671998 -1.91958002 1.9266 -1.91946004 0 P 0 ;0
L 1.9266 -1.91946004 1.92505 -1.91793002 0 P 0 ;0
L 1.92505 -1.91793002 1.92498996 -1.91786998 0 P 0 ;0
L 1.92498996 -1.91786998 1.92493002 -1.91781998 0 P 0 ;0
L 1.92493002 -1.91781998 1.92325 -1.91643002 0 P 0 ;0
L 1.92325 -1.91643002 1.92318996 -1.91636998 0 P 0 ;0
L 1.92318996 -1.91636998 1.92311998 -1.91631998 0 P 0 ;0
L 1.92311998 -1.91631998 1.92133002 -1.91508002 0 P 0 ;0
L 1.92133002 -1.91508002 1.92126004 -1.91503996 0 P 0 ;0
L 1.92126004 -1.91503996 1.92121998 -1.91501004 0 P 0 ;0
L 1.92121998 -1.91501004 1.92118002 -1.91498996 0 P 0 ;0
L 1.92118002 -1.91498996 1.91928996 -1.91391004 0 P 0 ;0
L 1.91928996 -1.91391004 1.91926004 -1.91388996 0 P 0 ;0
L 1.91926004 -1.91388996 1.91913996 -1.91383002 0 P 0 ;0
L 1.91913996 -1.91383002 1.91716998 -1.91291004 0 P 0 ;0
L 1.91716998 -1.91291004 1.91711998 -1.91288996 0 P 0 ;0
L 1.91711998 -1.91288996 1.91705 -1.91286004 0 P 0 ;0
L 1.91705 -1.91286004 1.917 -1.91285 0 P 0 ;0
L 1.917 -1.91285 1.91476998 -1.91203996 0 P 0 ;0
L 1.91476998 -1.91203996 1.91468996 -1.91201998 0 P 0 ;0
L 1.91468996 -1.91201998 1.91465 -1.912 0 P 0 ;0
L 1.91465 -1.912 1.9146 -1.91198996 0 P 0 ;0
L 1.9146 -1.91198996 1.91233002 -1.91138996 0 P 0 ;0
L 1.91233002 -1.91138996 1.91228002 -1.91138002 0 P 0 ;0
L 1.91228002 -1.91138002 1.91223996 -1.91136998 0 P 0 ;0
L 1.91223996 -1.91136998 1.91216004 -1.91136004 0 P 0 ;0
L 1.91216004 -1.91136004 1.90983002 -1.91095 0 P 0 ;0
L 1.90983002 -1.91095 1.9098 -1.91093996 0 P 0 ;0
L 1.9098 -1.91093996 1.90976004 -1.91093996 0 P 0 ;0
L 1.90976004 -1.91093996 1.90971998 -1.91093002 0 P 0 ;0
L 1.90971998 -1.91093002 1.90968002 -1.91093002 0 P 0 ;0
L 1.90968002 -1.91093002 1.90713996 -1.91068996 0 P 0 ;0
L 1.90713996 -1.91068996 1.9071 -1.91068002 0 P 0 ;0
L 1.9071 -1.91068002 1.907 -1.91068002 0 P 0 ;0
L 1.907 -1.91068002 1.90445 -1.91061004 0 P 0 ;0
L 1.90445 -1.91061004 1.90431004 -1.91061004 0 P 0 ;0
L 1.90431004 -1.91061004 1.90176004 -1.91071004 0 P 0 ;0
L 1.90176004 -1.91071004 1.90173002 -1.91071998 0 P 0 ;0
L 1.90173002 -1.91071998 1.90166004 -1.91071998 0 P 0 ;0
L 1.90166004 -1.91071998 1.90161998 -1.91073002 0 P 0 ;0
L 1.90161998 -1.91073002 1.89913002 -1.911 0 P 0 ;0
L 1.89913002 -1.911 1.89906004 -1.91101004 0 P 0 ;0
L 1.89906004 -1.91101004 1.89901998 -1.91101998 0 P 0 ;0
L 1.89901998 -1.91101998 1.89898996 -1.91101998 0 P 0 ;0
L 1.89898996 -1.91101998 1.89653002 -1.91146998 0 P 0 ;0
L 1.89653002 -1.91146998 1.8965 -1.91148002 0 P 0 ;0
L 1.8965 -1.91148002 1.89646004 -1.91148002 0 P 0 ;0
L 1.89646004 -1.91148002 1.8964 -1.9115 0 P 0 ;0
L 1.8964 -1.9115 1.89396998 -1.91211998 0 P 0 ;0
L 1.89396998 -1.91211998 1.89393996 -1.91213002 0 P 0 ;0
L 1.89393996 -1.91213002 1.89383002 -1.91216004 0 P 0 ;0
L 1.89383002 -1.91216004 1.89225 -1.91268996 0 P 0 ;0
L 1.89225 -1.91268996 1.89218002 -1.91271998 0 P 0 ;0
L 1.89218002 -1.91271998 1.89211004 -1.91273996 0 P 0 ;0
L 1.89211004 -1.91273996 1.8921 -1.91273996 0 P 0 ;0
L 1.8921 -1.91273996 1.89058002 -1.91338996 0 P 0 ;0
L 1.89058002 -1.91338996 1.89043996 -1.91345 0 P 0 ;0
L 1.89043996 -1.91345 1.88896004 -1.91421004 0 P 0 ;0
L 1.88896004 -1.91421004 1.88893002 -1.91423002 0 P 0 ;0
L 1.88893002 -1.91423002 1.8889 -1.91423996 0 P 0 ;0
L 1.8889 -1.91423996 1.88886004 -1.91426004 0 P 0 ;0
L 1.88886004 -1.91426004 1.88883002 -1.91428002 0 P 0 ;0
L 1.88883002 -1.91428002 1.88741004 -1.91515 0 P 0 ;0
L 1.88741004 -1.91515 1.88733996 -1.91518996 0 P 0 ;0
L 1.88733996 -1.91518996 1.88728002 -1.91523996 0 P 0 ;0
L 1.88728002 -1.91523996 1.88526004 -1.9167 0 P 0 ;0
L 1.88526004 -1.9167 1.88521998 -1.91673002 0 P 0 ;0
L 1.88521998 -1.91673002 1.88518996 -1.91675 0 P 0 ;0
L 1.88518996 -1.91675 1.88516004 -1.91678002 0 P 0 ;0
L 1.88516004 -1.91678002 1.88511998 -1.91681004 0 P 0 ;0
L 1.88511998 -1.91681004 1.88323002 -1.91845 0 P 0 ;0
L 1.88323002 -1.91845 1.8832 -1.91846998 0 P 0 ;0
L 1.8832 -1.91846998 1.88311004 -1.91856004 0 P 0 ;0
L 1.88311004 -1.91856004 1.88136998 -1.92036004 0 P 0 ;0
L 1.88136998 -1.92036004 1.88128002 -1.92045 0 P 0 ;0
L 1.88128002 -1.92045 1.88125 -1.92048996 0 P 0 ;0
L 1.88125 -1.92048996 1.87968002 -1.92241998 0 P 0 ;0
L 1.87968002 -1.92241998 1.87965 -1.92245 0 P 0 ;0
L 1.87965 -1.92245 1.87961998 -1.92248996 0 P 0 ;0
L 1.87961998 -1.92248996 1.87956998 -1.92256004 0 P 0 ;0
L 1.87956998 -1.92256004 1.87816998 -1.92461998 0 P 0 ;0
L 1.87816998 -1.92461998 1.8781 -1.92473002 0 P 0 ;0
L 1.8781 -1.92473002 1.87808002 -1.92476998 0 P 0 ;0
L 1.87808002 -1.92476998 1.87685 -1.92695 0 P 0 ;0
L 1.87685 -1.92695 1.87683002 -1.92698996 0 P 0 ;0
L 1.87683002 -1.92698996 1.87681004 -1.92701998 0 P 0 ;0
L 1.87681004 -1.92701998 1.87678996 -1.92706998 0 P 0 ;0
L 1.87678996 -1.92706998 1.87676998 -1.92711004 0 P 0 ;0
L 1.87676998 -1.92711004 1.87573002 -1.92941004 0 P 0 ;0
L 1.87573002 -1.92941004 1.87571004 -1.92945 0 P 0 ;0
L 1.87571004 -1.92945 1.8757 -1.92948996 0 P 0 ;0
L 1.8757 -1.92948996 1.87568002 -1.92951998 0 P 0 ;0
L 1.87568002 -1.92951998 1.87566998 -1.92956998 0 P 0 ;0
L 1.87566998 -1.92956998 1.87483996 -1.93193002 0 P 0 ;0
L 1.87483996 -1.93193002 1.87481004 -1.93201004 0 P 0 ;0
L 1.87481004 -1.93201004 1.87478996 -1.93208996 0 P 0 ;0
L 1.87478996 -1.93208996 1.87416004 -1.93451998 0 P 0 ;0
L 1.87416004 -1.93451998 1.87413996 -1.93456004 0 P 0 ;0
L 1.87413996 -1.93456004 1.87413002 -1.9346 0 P 0 ;0
L 1.87413002 -1.9346 1.87413002 -1.93463996 0 P 0 ;0
L 1.87413002 -1.93463996 1.87411998 -1.93468002 0 P 0 ;0
L 1.87411998 -1.93468002 1.8737 -1.93715 0 P 0 ;0
L 1.8737 -1.93715 1.87368996 -1.93718996 0 P 0 ;0
L 1.87368996 -1.93718996 1.87368002 -1.93723996 0 P 0 ;0
L 1.87368002 -1.93723996 1.87368002 -1.93731998 0 P 0 ;0
L 1.87368002 -1.93731998 1.87346998 -1.93981998 0 P 0 ;0
L 1.87346998 -1.93981998 1.87346004 -1.93986004 0 P 0 ;0
L 1.87346004 -1.93986004 1.87346004 -1.94258002 0 P 0 ;0
L 1.87346004 -1.94258002 1.87346998 -1.94266004 0 P 0 ;0
L 1.87346998 -1.94266004 1.87368002 -1.94516998 0 P 0 ;0
L 1.87368002 -1.94516998 1.87368996 -1.94521004 0 P 0 ;0
L 1.87368996 -1.94521004 1.87368996 -1.94525 0 P 0 ;0
L 1.87368996 -1.94525 1.87371004 -1.94533996 0 P 0 ;0
L 1.87371004 -1.94533996 1.87413996 -1.94778996 0 P 0 ;0
L 1.87413996 -1.94778996 1.87413996 -1.94783996 0 P 0 ;0
L 1.87413996 -1.94783996 1.87416998 -1.94796004 0 P 0 ;0
L 1.87416998 -1.94796004 1.87481004 -1.95036998 0 P 0 ;0
L 1.87481004 -1.95036998 1.87483996 -1.95048996 0 P 0 ;0
L 1.87483996 -1.95048996 1.87486004 -1.95053002 0 P 0 ;0
L 1.87486004 -1.95053002 1.8757 -1.95288002 0 P 0 ;0
L 1.8757 -1.95288002 1.87571004 -1.95291998 0 P 0 ;0
L 1.87571004 -1.95291998 1.87575 -1.953 0 P 0 ;0
L 1.87575 -1.953 1.87576004 -1.95303996 0 P 0 ;0
L 1.87576004 -1.95303996 1.8768 -1.9553 0 P 0 ;0
L 1.8768 -1.9553 1.87686004 -1.95541998 0 P 0 ;0
L 1.87686004 -1.95541998 1.87688002 -1.95545 0 P 0 ;0
L 1.87688002 -1.95545 1.8781 -1.95761004 0 P 0 ;0
L 1.8781 -1.95761004 1.87811998 -1.95761004 0 P 0 ;0
L 1.87811998 -1.95761004 1.8781 -1.95761998 0 P 0 ;0
L 1.8781 -1.95761998 1.87813996 -1.95768996 0 P 0 ;0
L 1.87813996 -1.95768996 1.87816998 -1.95771998 0 P 0 ;0
L 1.87816998 -1.95771998 1.87818996 -1.95775 0 P 0 ;0
L 1.87818996 -1.95775 1.87938002 -1.95951004 0 P 0 ;0
L 1.87938002 -1.95951004 1.87943996 -1.9596 0 P 0 ;0
L 1.87943996 -1.9596 1.87946998 -1.95963002 0 P 0 ;0
L 1.87946998 -1.95963002 1.88078002 -1.96128996 0 P 0 ;0
L 1.88078002 -1.96128996 1.88081004 -1.96131998 0 P 0 ;0
L 1.88081004 -1.96131998 1.88083002 -1.96135 0 P 0 ;0
L 1.88083002 -1.96135 1.88086004 -1.96136998 0 P 0 ;0
L 1.88086004 -1.96136998 1.88088002 -1.9614 0 P 0 ;0
L 1.88088002 -1.9614 1.88231998 -1.96295 0 P 0 ;0
L 1.88231998 -1.96295 1.88233996 -1.96298002 0 P 0 ;0
L 1.88233996 -1.96298002 1.8824 -1.96303996 0 P 0 ;0
L 1.8824 -1.96303996 1.88243002 -1.96306004 0 P 0 ;0
L 1.88243002 -1.96306004 1.88398002 -1.9645 0 P 0 ;0
L 1.88398002 -1.9645 1.88401004 -1.96451998 0 P 0 ;0
L 1.88401004 -1.96451998 1.88403002 -1.96455 0 P 0 ;0
L 1.88403002 -1.96455 1.88406998 -1.96458002 0 P 0 ;0
L 1.88406998 -1.96458002 1.88408996 -1.9646 0 P 0 ;0
L 1.88408996 -1.9646 1.88575 -1.96591004 0 P 0 ;0
L 1.88575 -1.96591004 1.88578002 -1.96593996 0 P 0 ;0
L 1.88578002 -1.96593996 1.88586998 -1.966 0 P 0 ;0
L 1.88586998 -1.966 1.88761998 -1.96718996 0 P 0 ;0
L 1.88761998 -1.96718996 1.88766004 -1.96721004 0 P 0 ;0
L 1.88766004 -1.96721004 1.88775 -1.96726998 0 P 0 ;0
L 1.88775 -1.96726998 1.88958996 -1.96831998 0 P 0 ;0
L 1.88958996 -1.96831998 1.88965 -1.96836004 0 P 0 ;0
L 1.88965 -1.96836004 1.88968002 -1.96836998 0 P 0 ;0
L 1.88968002 -1.96836998 1.88971998 -1.96838996 0 P 0 ;0
L 1.88971998 -1.96838996 1.89145 -1.96921998 0 P 0 ;0
L 1.89145 -1.96921998 1.89151004 -1.96925 0 P 0 ;0
L 1.89151004 -1.96925 1.89155 -1.96926004 0 P 0 ;0
L 1.89155 -1.96926004 1.89158002 -1.96926998 0 P 0 ;0
L 1.89158002 -1.96926998 1.89336004 -1.96996998 0 P 0 ;0
L 1.89336004 -1.96996998 1.89336004 -1.96998002 0 P 0 ;0
L 1.89336004 -1.96998002 1.89346004 -1.97001004 0 P 0 ;0
L 1.89346004 -1.97001004 1.89348996 -1.97001998 0 P 0 ;0
L 1.89348996 -1.97001998 1.89531998 -1.9706 0 P 0 ;0
L 1.89531998 -1.9706 1.89536004 -1.97061004 0 P 0 ;0
L 1.89536004 -1.97061004 1.89541998 -1.97063002 0 P 0 ;0
L 1.89541998 -1.97063002 1.89546004 -1.97063002 0 P 0 ;0
L 1.89546004 -1.97063002 1.89731998 -1.97108002 0 P 0 ;0
L 1.89731998 -1.97108002 1.89741998 -1.9711 0 P 0 ;0
L 1.89741998 -1.9711 1.89746004 -1.9711 0 P 0 ;0
L 1.89746004 -1.9711 1.89746004 -1.97111004 0 P 0 ;0
L 1.89746004 -1.97111004 1.89933996 -1.97141998 0 P 0 ;0
L 1.89933996 -1.97141998 1.89936998 -1.97143002 0 P 0 ;0
L 1.89936998 -1.97143002 1.89941004 -1.97143002 0 P 0 ;0
L 1.89941004 -1.97143002 1.89945 -1.97143996 0 P 0 ;0
L 1.89945 -1.97143996 1.89948002 -1.97143996 0 P 0 ;0
L 1.89948002 -1.97143996 1.90201004 -1.97168002 0 P 0 ;0
L 1.90201004 -1.97168002 1.90205 -1.97168002 0 P 0 ;0
L 1.90205 -1.97168002 1.90208996 -1.97168996 0 P 0 ;0
L 1.90208996 -1.97168996 1.90216004 -1.97168996 0 P 0 ;0
L 1.90216004 -1.97168996 1.90468996 -1.97173996 0 P 0 ;0
L 1.90468996 -1.97173996 1.90476004 -1.97173996 0 P 0 ;0
L 1.80616004 -2.12823996 1.83348996 -2.12823996 0 P 0 ;0
L 1.79591998 -2.12723996 1.8396 -2.12723996 0 P 0 ;0
L 1.78818002 -2.12623996 1.84465 -2.12623996 0 P 0 ;0
L 1.82003996 -2.09123996 1.87618996 -2.09123996 0 P 0 ;0
L 1.82198996 -2.09023996 1.8762 -2.09023996 0 P 0 ;0
L 1.82325 -2.08923996 1.8762 -2.08923996 0 P 0 ;0
L 1.82411998 -2.08823996 1.87618996 -2.08823996 0 P 0 ;0
L 1.82463002 -2.08723996 1.87616998 -2.08723996 0 P 0 ;0
L 1.82488002 -2.08623996 1.87615 -2.08623996 0 P 0 ;0
L 1.82493002 -2.08523996 1.87613002 -2.08523996 0 P 0 ;0
L 1.82476998 -2.08423996 1.87611004 -2.08423996 0 P 0 ;0
L 1.64846004 -2.08295 1.73316998 -2.08295 0 P 0 ;0
L 1.64811998 -2.08195 1.73356998 -2.08195 0 P 0 ;0
L 1.64776998 -2.08095 1.73398002 -2.08095 0 P 0 ;0
L 1.64743002 -2.07995 1.73438002 -2.07995 0 P 0 ;0
L 1.64708996 -2.07895 1.73478996 -2.07895 0 P 0 ;0
L 1.64673996 -2.07795 1.7352 -2.07795 0 P 0 ;0
L 1.6464 -2.07695 1.7356 -2.07695 0 P 0 ;0
L 1.64605 -2.07595 1.73601004 -2.07595 0 P 0 ;0
L 1.64571004 -2.07495 1.73641004 -2.07495 0 P 0 ;0
L 1.64536004 -2.07395 1.73681004 -2.07395 0 P 0 ;0
L 1.64501998 -2.07295 1.73721998 -2.07295 0 P 0 ;0
L 1.64466998 -2.07195 1.73761998 -2.07195 0 P 0 ;0
L 1.64433002 -2.07095 1.73803002 -2.07095 0 P 0 ;0
L 1.64398002 -2.06995 1.69251004 -2.06995 0 P 0 ;0
L 1.69583002 -2.06995 1.73843996 -2.06995 0 P 0 ;0
L 1.64363002 -2.06895 1.69168002 -2.06895 0 P 0 ;0
L 1.69671998 -2.06895 1.73883996 -2.06895 0 P 0 ;0
L 1.64328996 -2.06795 1.69136004 -2.06795 0 P 0 ;0
L 1.69708996 -2.06795 1.73925 -2.06795 0 P 0 ;0
L 1.64293996 -2.06695 1.69108002 -2.06695 0 P 0 ;0
L 1.69738002 -2.06695 1.73965 -2.06695 0 P 0 ;0
L 1.64258996 -2.06595 1.6908 -2.06595 0 P 0 ;0
L 1.69768002 -2.06595 1.74006004 -2.06595 0 P 0 ;0
L 1.64223996 -2.06495 1.69051998 -2.06495 0 P 0 ;0
L 1.69796998 -2.06495 1.74046004 -2.06495 0 P 0 ;0
L 1.6419 -2.06395 1.69023002 -2.06395 0 P 0 ;0
L 1.69826998 -2.06395 1.74086004 -2.06395 0 P 0 ;0
L 1.64155 -2.06295 1.68996004 -2.06295 0 P 0 ;0
L 1.69856004 -2.06295 1.74126998 -2.06295 0 P 0 ;0
L 1.6412 -2.06195 1.68966998 -2.06195 0 P 0 ;0
L 1.69886004 -2.06195 1.74168002 -2.06195 0 P 0 ;0
L 1.64085 -2.06095 1.68938996 -2.06095 0 P 0 ;0
L 1.69915 -2.06095 1.74208002 -2.06095 0 P 0 ;0
L 1.6405 -2.05995 1.68911004 -2.05995 0 P 0 ;0
L 1.69945 -2.05995 1.74248002 -2.05995 0 P 0 ;0
L 1.64016004 -2.05895 1.68883002 -2.05895 0 P 0 ;0
L 1.69973996 -2.05895 1.74288996 -2.05895 0 P 0 ;0
L 1.63981004 -2.05795 1.68855 -2.05795 0 P 0 ;0
L 1.70003996 -2.05795 1.74328996 -2.05795 0 P 0 ;0
L 1.63946004 -2.05695 1.68826998 -2.05695 0 P 0 ;0
L 1.70033002 -2.05695 1.7437 -2.05695 0 P 0 ;0
L 1.63911004 -2.05595 1.68798996 -2.05595 0 P 0 ;0
L 1.70063002 -2.05595 1.7441 -2.05595 0 P 0 ;0
L 1.63876998 -2.05495 1.68771004 -2.05495 0 P 0 ;0
L 1.70091998 -2.05495 1.74451004 -2.05495 0 P 0 ;0
L 1.63841998 -2.05395 1.68741998 -2.05395 0 P 0 ;0
L 1.70121998 -2.05395 1.74491004 -2.05395 0 P 0 ;0
L 1.63806998 -2.05295 1.68713996 -2.05295 0 P 0 ;0
L 1.70151004 -2.05295 1.74531004 -2.05295 0 P 0 ;0
L 1.63771998 -2.05195 1.68686004 -2.05195 0 P 0 ;0
L 1.70181004 -2.05195 1.74571998 -2.05195 0 P 0 ;0
L 1.63738002 -2.05095 1.68658002 -2.05095 0 P 0 ;0
L 1.7021 -2.05095 1.74611998 -2.05095 0 P 0 ;0
L 1.63703002 -2.04995 1.6863 -2.04995 0 P 0 ;0
L 1.7024 -2.04995 1.74653002 -2.04995 0 P 0 ;0
L 1.63668002 -2.04895 1.68601998 -2.04895 0 P 0 ;0
L 1.70268996 -2.04895 1.74693002 -2.04895 0 P 0 ;0
L 1.63633002 -2.04795 1.68573996 -2.04795 0 P 0 ;0
L 1.70298996 -2.04795 1.74733002 -2.04795 0 P 0 ;0
L 1.63598002 -2.04695 1.68546004 -2.04695 0 P 0 ;0
L 1.70328002 -2.04695 1.74773996 -2.04695 0 P 0 ;0
L 1.63563996 -2.04595 1.68518002 -2.04595 0 P 0 ;0
L 1.70358002 -2.04595 1.74813996 -2.04595 0 P 0 ;0
L 1.63528996 -2.04495 1.6849 -2.04495 0 P 0 ;0
L 1.70386998 -2.04495 1.74855 -2.04495 0 P 0 ;0
L 1.63493996 -2.04395 1.68461004 -2.04395 0 P 0 ;0
L 1.70416998 -2.04395 1.74895 -2.04395 0 P 0 ;0
L 1.63458996 -2.04295 1.68433002 -2.04295 0 P 0 ;0
L 1.70446004 -2.04295 1.74936004 -2.04295 0 P 0 ;0
L 1.63425 -2.04195 1.68405 -2.04195 0 P 0 ;0
L 1.70475 -2.04195 1.74976004 -2.04195 0 P 0 ;0
L 1.6339 -2.04095 1.68376998 -2.04095 0 P 0 ;0
L 1.70503002 -2.04095 1.75016004 -2.04095 0 P 0 ;0
L 1.63355 -2.03995 1.68348996 -2.03995 0 P 0 ;0
L 1.70531998 -2.03995 1.75056998 -2.03995 0 P 0 ;0
L 1.6332 -2.03895 1.68321004 -2.03895 0 P 0 ;0
L 1.7056 -2.03895 1.75096998 -2.03895 0 P 0 ;0
L 1.63286004 -2.03795 1.68293002 -2.03795 0 P 0 ;0
L 1.70588996 -2.03795 1.75138002 -2.03795 0 P 0 ;0
L 1.63251004 -2.03695 1.68266004 -2.03695 0 P 0 ;0
L 1.70618002 -2.03695 1.75178002 -2.03695 0 P 0 ;0
L 1.63216004 -2.03595 1.68238002 -2.03595 0 P 0 ;0
L 1.70646998 -2.03595 1.75218996 -2.03595 0 P 0 ;0
L 1.63181004 -2.03495 1.6821 -2.03495 0 P 0 ;0
L 1.70675 -2.03495 1.75258996 -2.03495 0 P 0 ;0
L 1.63146998 -2.03395 1.68183002 -2.03395 0 P 0 ;0
L 1.70703996 -2.03395 1.75298996 -2.03395 0 P 0 ;0
L 1.63111998 -2.03295 1.68155 -2.03295 0 P 0 ;0
L 1.70733002 -2.03295 1.7534 -2.03295 0 P 0 ;0
L 1.63076998 -2.03195 1.68126998 -2.03195 0 P 0 ;0
L 1.70761004 -2.03195 1.75381004 -2.03195 0 P 0 ;0
L 1.63041998 -2.03095 1.68098996 -2.03095 0 P 0 ;0
L 1.7079 -2.03095 1.75421004 -2.03095 0 P 0 ;0
L 1.63006998 -2.02995 1.68071004 -2.02995 0 P 0 ;0
L 1.70818996 -2.02995 1.75461004 -2.02995 0 P 0 ;0
L 1.62973002 -2.02895 1.68043996 -2.02895 0 P 0 ;0
L 1.70846998 -2.02895 1.75501998 -2.02895 0 P 0 ;0
L 1.62938002 -2.02795 1.68016004 -2.02795 0 P 0 ;0
L 1.70876004 -2.02795 1.75541998 -2.02795 0 P 0 ;0
L 1.62903002 -2.02695 1.67988002 -2.02695 0 P 0 ;0
L 1.70905 -2.02695 1.75583002 -2.02695 0 P 0 ;0
L 1.62868002 -2.02595 1.6796 -2.02595 0 P 0 ;0
L 1.70933996 -2.02595 1.75623002 -2.02595 0 P 0 ;0
L 1.62831004 -2.02495 1.67933002 -2.02495 0 P 0 ;0
L 1.70961998 -2.02495 1.75663996 -2.02495 0 P 0 ;0
L 1.62793996 -2.02395 1.67905 -2.02395 0 P 0 ;0
L 1.70991004 -2.02395 1.75703996 -2.02395 0 P 0 ;0
L 1.62756998 -2.02295 1.67876998 -2.02295 0 P 0 ;0
L 1.7102 -2.02295 1.75743996 -2.02295 0 P 0 ;0
L 1.6272 -2.02195 1.6785 -2.02195 0 P 0 ;0
L 1.71048002 -2.02195 1.75785 -2.02195 0 P 0 ;0
L 1.62683002 -2.02095 1.67821998 -2.02095 0 P 0 ;0
L 1.71076004 -2.02095 1.75825 -2.02095 0 P 0 ;0
L 1.62646998 -2.01995 1.67793996 -2.01995 0 P 0 ;0
L 1.71101004 -2.01995 1.75866004 -2.01995 0 P 0 ;0
L 1.6261 -2.01895 1.67766004 -2.01895 0 P 0 ;0
L 1.71126998 -2.01895 1.75906004 -2.01895 0 P 0 ;0
L 1.62573002 -2.01795 1.67738996 -2.01795 0 P 0 ;0
L 1.71151998 -2.01795 1.75946998 -2.01795 0 P 0 ;0
L 1.62536004 -2.01695 1.67711004 -2.01695 0 P 0 ;0
L 1.71176998 -2.01695 1.75986998 -2.01695 0 P 0 ;0
L 1.62498996 -2.01595 1.67683002 -2.01595 0 P 0 ;0
L 1.71203002 -2.01595 1.76026998 -2.01595 0 P 0 ;0
L 1.62461998 -2.01495 1.67656004 -2.01495 0 P 0 ;0
L 1.71228002 -2.01495 1.76068002 -2.01495 0 P 0 ;0
L 1.62425 -2.01395 1.67628002 -2.01395 0 P 0 ;0
L 1.71253996 -2.01395 1.76108002 -2.01395 0 P 0 ;0
L 1.62388002 -2.01295 1.67601998 -2.01295 0 P 0 ;0
L 1.71278996 -2.01295 1.76148996 -2.01295 0 P 0 ;0
L 1.62351004 -2.01195 1.67576998 -2.01195 0 P 0 ;0
L 1.71305 -2.01195 1.76188996 -2.01195 0 P 0 ;0
L 1.62313996 -2.01095 1.67551998 -2.01095 0 P 0 ;0
L 1.7133 -2.01095 1.76228996 -2.01095 0 P 0 ;0
L 1.62276998 -2.00995 1.67528002 -2.00995 0 P 0 ;0
L 1.71355 -2.00995 1.7627 -2.00995 0 P 0 ;0
L 1.6224 -2.00895 1.67503002 -2.00895 0 P 0 ;0
L 1.71381004 -2.00895 1.7631 -2.00895 0 P 0 ;0
L 1.62203002 -2.00795 1.67478996 -2.00795 0 P 0 ;0
L 1.71406004 -2.00795 1.76351004 -2.00795 0 P 0 ;0
L 1.62166004 -2.00695 1.67453996 -2.00695 0 P 0 ;0
L 1.71431004 -2.00695 1.76391004 -2.00695 0 P 0 ;0
L 1.62128996 -2.00595 1.67428996 -2.00595 0 P 0 ;0
L 1.71453996 -2.00595 1.76431998 -2.00595 0 P 0 ;0
L 1.62091004 -2.00495 1.67405 -2.00495 0 P 0 ;0
L 1.71476998 -2.00495 1.76471998 -2.00495 0 P 0 ;0
L 1.62051998 -2.00395 1.6738 -2.00395 0 P 0 ;0
L 1.715 -2.00395 1.76511998 -2.00395 0 P 0 ;0
L 1.62013002 -2.00295 1.67355 -2.00295 0 P 0 ;0
L 1.71523002 -2.00295 1.76553002 -2.00295 0 P 0 ;0
L 1.61973996 -2.00195 1.67331004 -2.00195 0 P 0 ;0
L 1.71546004 -2.00195 1.76593996 -2.00195 0 P 0 ;0
L 1.61935 -2.00095 1.67306004 -2.00095 0 P 0 ;0
L 1.71568996 -2.00095 1.76633996 -2.00095 0 P 0 ;0
L 1.61896004 -1.99995 1.67283996 -1.99995 0 P 0 ;0
L 1.71591998 -1.99995 1.76673996 -1.99995 0 P 0 ;0
L 1.61856998 -1.99895 1.67261998 -1.99895 0 P 0 ;0
L 1.71613996 -1.99895 1.76715 -1.99895 0 P 0 ;0
L 1.71638002 -1.99795 1.76755 -1.99795 0 P 0 ;0
L 1.7166 -1.99695 1.76796004 -1.99695 0 P 0 ;0
L 1.71683002 -1.99595 1.76836004 -1.99595 0 P 0 ;0
L 1.71866998 -1.99495 1.76876998 -1.99495 0 P 0 ;0
L 1.78213996 -2.04823996 1.84641998 -2.04823996 0 P 0 ;0
L 1.78138002 -2.04723996 1.84498996 -2.04723996 0 P 0 ;0
L 1.78071004 -2.04623996 1.84356004 -2.04623996 0 P 0 ;0
L 1.7801 -2.04523996 1.84213996 -2.04523996 0 P 0 ;0
L 1.77956004 -2.04423996 1.84071004 -2.04423996 0 P 0 ;0
L 1.77908996 -2.04323996 1.83928002 -2.04323996 0 P 0 ;0
L 1.77866004 -2.04223996 1.83786004 -2.04223996 0 P 0 ;0
L 1.77831004 -2.04123996 1.83658996 -2.04123996 0 P 0 ;0
L 1.77796004 -2.04023996 1.83536004 -2.04023996 0 P 0 ;0
L 1.77761004 -2.03923996 1.83428002 -2.03923996 0 P 0 ;0
L 1.77733996 -2.03823996 1.83321998 -2.03823996 0 P 0 ;0
L 1.77706998 -2.03723996 1.83236998 -2.03723996 0 P 0 ;0
L 1.7768 -2.03623996 1.83171004 -2.03623996 0 P 0 ;0
L 1.7766 -2.03523996 1.83121004 -2.03523996 0 P 0 ;0
L 1.77641004 -2.03423996 1.83085 -2.03423996 0 P 0 ;0
L 1.77621004 -2.03323996 1.83071004 -2.03323996 0 P 0 ;0
L 1.77608002 -2.03223996 1.83076998 -2.03223996 0 P 0 ;0
L 1.77596004 -2.03123996 1.83106004 -2.03123996 0 P 0 ;0
L 1.77583996 -2.03023996 1.83158996 -2.03023996 0 P 0 ;0
L 1.77576004 -2.02923996 1.83238002 -2.02923996 0 P 0 ;0
L 1.7757 -2.02823996 1.83356998 -2.02823996 0 P 0 ;0
L 1.7757 -2.02723996 1.83591998 -2.02723996 0 P 0 ;0
L 1.77571998 -2.02623996 1.87495 -2.02623996 0 P 0 ;0
L 1.7758 -2.02523996 1.87485 -2.02523996 0 P 0 ;0
L 1.77588996 -2.02423996 1.87475 -2.02423996 0 P 0 ;0
L 1.77605 -2.02323996 1.87465 -2.02323996 0 P 0 ;0
L 1.77621004 -2.02223996 1.87455 -2.02223996 0 P 0 ;0
L 1.7764 -2.02123996 1.87445 -2.02123996 0 P 0 ;0
L 1.77665 -2.02023996 1.87433996 -2.02023996 0 P 0 ;0
L 1.7769 -2.01923996 1.87425 -2.01923996 0 P 0 ;0
L 1.7772 -2.01823996 1.87413996 -2.01823996 0 P 0 ;0
L 1.77753002 -2.01723996 1.87405 -2.01723996 0 P 0 ;0
L 1.77786004 -2.01623996 1.87393996 -2.01623996 0 P 0 ;0
L 1.77823002 -2.01523996 1.87383996 -2.01523996 0 P 0 ;0
L 1.77863996 -2.01423996 1.87373996 -2.01423996 0 P 0 ;0
L 1.77903996 -2.01323996 1.87363996 -2.01323996 0 P 0 ;0
L 1.7795 -2.01223996 1.87353996 -2.01223996 0 P 0 ;0
L 1.77998996 -2.01123996 1.87343996 -2.01123996 0 P 0 ;0
L 1.78046998 -2.01023996 1.87333002 -2.01023996 0 P 0 ;0
L 1.78103996 -2.00923996 1.87323002 -2.00923996 0 P 0 ;0
L 1.78161004 -2.00823996 1.87311998 -2.00823996 0 P 0 ;0
L 1.78221004 -2.00723996 1.87301998 -2.00723996 0 P 0 ;0
L 1.78288002 -2.00623996 1.87291998 -2.00623996 0 P 0 ;0
L 1.64213996 -2.14795 1.70566004 -2.14795 0 P 0 ;0
L 1.64518996 -2.14695 1.7062 -2.14695 0 P 0 ;0
L 1.64728996 -2.14595 1.70673996 -2.14595 0 P 0 ;0
L 1.64906998 -2.14495 1.70728002 -2.14495 0 P 0 ;0
L 1.65058002 -2.14395 1.70783002 -2.14395 0 P 0 ;0
L 1.6519 -2.14295 1.70836998 -2.14295 0 P 0 ;0
L 1.65311998 -2.14195 1.70881998 -2.14195 0 P 0 ;0
L 1.65416998 -2.14095 1.70926998 -2.14095 0 P 0 ;0
L 1.65508996 -2.13995 1.70973002 -2.13995 0 P 0 ;0
L 1.65588002 -2.13895 1.71018002 -2.13895 0 P 0 ;0
L 1.65658002 -2.13795 1.71063002 -2.13795 0 P 0 ;0
L 1.65726998 -2.13695 1.71108996 -2.13695 0 P 0 ;0
L 1.65791998 -2.13595 1.71153996 -2.13595 0 P 0 ;0
L 1.65853002 -2.13495 1.71198996 -2.13495 0 P 0 ;0
L 1.65913002 -2.13395 1.71245 -2.13395 0 P 0 ;0
L 1.65968002 -2.13295 1.7129 -2.13295 0 P 0 ;0
L 1.66021998 -2.13195 1.71331004 -2.13195 0 P 0 ;0
L 1.66071998 -2.13095 1.71371998 -2.13095 0 P 0 ;0
L 1.66121004 -2.12995 1.71411998 -2.12995 0 P 0 ;0
L 1.66166998 -2.12895 1.71453002 -2.12895 0 P 0 ;0
L 1.66201004 -2.12795 1.71493996 -2.12795 0 P 0 ;0
L 1.66223996 -2.12695 1.71533996 -2.12695 0 P 0 ;0
L 1.66235 -2.12595 1.71575 -2.12595 0 P 0 ;0
L 1.66236004 -2.12495 1.71615 -2.12495 0 P 0 ;0
L 1.66228002 -2.12395 1.71656004 -2.12395 0 P 0 ;0
L 1.66211998 -2.12295 1.71696004 -2.12295 0 P 0 ;0
L 1.66188002 -2.12195 1.71736004 -2.12195 0 P 0 ;0
L 1.66156004 -2.12095 1.71776998 -2.12095 0 P 0 ;0
L 1.66121004 -2.11995 1.71818002 -2.11995 0 P 0 ;0
L 1.66086998 -2.11895 1.71858002 -2.11895 0 P 0 ;0
L 1.66053002 -2.11795 1.71898996 -2.11795 0 P 0 ;0
L 1.66018002 -2.11695 1.71938996 -2.11695 0 P 0 ;0
L 1.65983996 -2.11595 1.7198 -2.11595 0 P 0 ;0
L 1.65948996 -2.11495 1.7202 -2.11495 0 P 0 ;0
L 1.65913996 -2.11395 1.72061004 -2.11395 0 P 0 ;0
L 1.6588 -2.11295 1.72101004 -2.11295 0 P 0 ;0
L 1.65846004 -2.11195 1.72141998 -2.11195 0 P 0 ;0
L 1.65811004 -2.11095 1.72181998 -2.11095 0 P 0 ;0
L 1.65776998 -2.10995 1.72223002 -2.10995 0 P 0 ;0
L 1.65741998 -2.10895 1.72263002 -2.10895 0 P 0 ;0
L 1.65708002 -2.10795 1.72303996 -2.10795 0 P 0 ;0
L 1.65673002 -2.10695 1.72343996 -2.10695 0 P 0 ;0
L 1.65638996 -2.10595 1.72385 -2.10595 0 P 0 ;0
L 1.65605 -2.10495 1.72425 -2.10495 0 P 0 ;0
L 1.6557 -2.10395 1.72466004 -2.10395 0 P 0 ;0
L 1.65536004 -2.10295 1.72506998 -2.10295 0 P 0 ;0
L 1.65501004 -2.10195 1.72546998 -2.10195 0 P 0 ;0
L 1.65466998 -2.10095 1.72588002 -2.10095 0 P 0 ;0
L 1.65431998 -2.09995 1.72628002 -2.09995 0 P 0 ;0
L 1.65398002 -2.09895 1.72668996 -2.09895 0 P 0 ;0
L 1.65363002 -2.09795 1.72708996 -2.09795 0 P 0 ;0
L 1.65328996 -2.09695 1.72748996 -2.09695 0 P 0 ;0
L 1.65293996 -2.09595 1.7279 -2.09595 0 P 0 ;0
L 1.6526 -2.09495 1.72831004 -2.09495 0 P 0 ;0
L 1.65225 -2.09395 1.72871004 -2.09395 0 P 0 ;0
L 1.65191004 -2.09295 1.72911998 -2.09295 0 P 0 ;0
L 1.65156998 -2.09195 1.72951998 -2.09195 0 P 0 ;0
L 1.65121998 -2.09095 1.72993002 -2.09095 0 P 0 ;0
L 1.65088002 -2.08995 1.73033002 -2.08995 0 P 0 ;0
L 1.65053002 -2.08895 1.73073996 -2.08895 0 P 0 ;0
L 1.65018996 -2.08795 1.73113996 -2.08795 0 P 0 ;0
L 1.64983996 -2.08695 1.73155 -2.08695 0 P 0 ;0
L 1.6495 -2.08595 1.73195 -2.08595 0 P 0 ;0
L 1.64915 -2.08495 1.73236004 -2.08495 0 P 0 ;0
L 1.64881004 -2.08395 1.73276004 -2.08395 0 P 0 ;0
L 1.81726998 -1.98915 1.81196004 -1.9899 0 P 0 ;0
L 1.81196004 -1.9899 1.80668996 -1.99096998 0 P 0 ;0
L 1.80668996 -1.99096998 1.8019 -1.99226004 0 P 0 ;0
L 1.8019 -1.99226004 1.79718996 -1.99391004 0 P 0 ;0
L 1.79718996 -1.99391004 1.79316004 -1.99568002 0 P 0 ;0
L 1.79316004 -1.99568002 1.78926998 -1.99778002 0 P 0 ;0
L 1.78926998 -1.99778002 1.78771004 -1.99878002 0 P 0 ;0
L 1.78771004 -1.99878002 1.78623002 -1.99988002 0 P 0 ;0
L 1.78623002 -1.99988002 1.78481004 -2.00108002 0 P 0 ;0
L 1.78481004 -2.00108002 1.78346998 -2.00238996 0 P 0 ;0
L 1.78346998 -2.00238996 1.78228996 -2.00371998 0 P 0 ;0
L 1.78228996 -2.00371998 1.78121004 -2.00513002 0 P 0 ;0
L 1.78121004 -2.00513002 1.78023002 -2.00661004 0 P 0 ;0
L 1.78023002 -2.00661004 1.77868002 -2.00933996 0 P 0 ;0
L 1.77868002 -2.00933996 1.77731998 -2.01216998 0 P 0 ;0
L 1.77731998 -2.01216998 1.77611004 -2.01516004 0 P 0 ;0
L 1.77611004 -2.01516004 1.77508996 -2.01823002 0 P 0 ;0
L 1.77508996 -2.01823002 1.77436998 -2.02111004 0 P 0 ;0
L 1.77436998 -2.02111004 1.77388996 -2.02406004 0 P 0 ;0
L 1.77388996 -2.02406004 1.77371998 -2.02603996 0 P 0 ;0
L 1.77371998 -2.02603996 1.77368996 -2.02801998 0 P 0 ;0
L 1.77368996 -2.02801998 1.7738 -2.03001998 0 P 0 ;0
L 1.7738 -2.03001998 1.7742 -2.03338996 0 P 0 ;0
L 1.7742 -2.03338996 1.77485 -2.03671004 0 P 0 ;0
L 1.77485 -2.03671004 1.77573002 -2.03993996 0 P 0 ;0
L 1.77573002 -2.03993996 1.77683996 -2.04308002 0 P 0 ;0
L 1.77683996 -2.04308002 1.7776 -2.04481998 0 P 0 ;0
L 1.7776 -2.04481998 1.7785 -2.04648996 0 P 0 ;0
L 1.7785 -2.04648996 1.77953002 -2.04808996 0 P 0 ;0
L 1.77953002 -2.04808996 1.78061004 -2.04953996 0 P 0 ;0
L 1.78061004 -2.04953996 1.78181004 -2.05091004 0 P 0 ;0
L 1.78181004 -2.05091004 1.78311004 -2.05218996 0 P 0 ;0
L 1.78311004 -2.05218996 1.78988996 -2.05801998 0 P 0 ;0
L 1.78988996 -2.05801998 1.79883996 -2.06491004 0 P 0 ;0
L 1.79883996 -2.06491004 1.80976998 -2.07261004 0 P 0 ;0
L 1.80976998 -2.07261004 1.81753002 -2.07823002 0 P 0 ;0
L 1.81753002 -2.07823002 1.81896998 -2.07943002 0 P 0 ;0
L 1.81896998 -2.07943002 1.82033002 -2.08073002 0 P 0 ;0
L 1.82033002 -2.08073002 1.82156998 -2.08213996 0 P 0 ;0
L 1.82156998 -2.08213996 1.82186004 -2.08251004 0 P 0 ;0
L 1.82186004 -2.08251004 1.82211004 -2.0829 0 P 0 ;0
L 1.82211004 -2.0829 1.82233002 -2.08331004 0 P 0 ;0
L 1.82233002 -2.08331004 1.82253002 -2.08373996 0 P 0 ;0
L 1.82253002 -2.08373996 1.82268002 -2.08418002 0 P 0 ;0
L 1.82268002 -2.08418002 1.82281004 -2.08463002 0 P 0 ;0
L 1.82281004 -2.08463002 1.8229 -2.0851 0 P 0 ;0
L 1.8229 -2.0851 1.82293002 -2.08533996 0 P 0 ;0
L 1.82293002 -2.08533996 1.82293996 -2.08558996 0 P 0 ;0
L 1.82293996 -2.08558996 1.82291998 -2.08583996 0 P 0 ;0
L 1.82291998 -2.08583996 1.82288002 -2.08608002 0 P 0 ;0
L 1.82288002 -2.08608002 1.82283002 -2.08631998 0 P 0 ;0
L 1.82283002 -2.08631998 1.82275 -2.08656004 0 P 0 ;0
L 1.82275 -2.08656004 1.82265 -2.08678996 0 P 0 ;0
L 1.82265 -2.08678996 1.82253996 -2.087 0 P 0 ;0
L 1.82253996 -2.087 1.8224 -2.08721004 0 P 0 ;0
L 1.8224 -2.08721004 1.82225 -2.08741004 0 P 0 ;0
L 1.82225 -2.08741004 1.82208996 -2.08758996 0 P 0 ;0
L 1.82208996 -2.08758996 1.8216 -2.08803996 0 P 0 ;0
L 1.8216 -2.08803996 1.82106998 -2.08845 0 P 0 ;0
L 1.82106998 -2.08845 1.82051004 -2.08881004 0 P 0 ;0
L 1.82051004 -2.08881004 1.81991998 -2.08911998 0 P 0 ;0
L 1.81991998 -2.08911998 1.81931004 -2.08936998 0 P 0 ;0
L 1.81931004 -2.08936998 1.81868002 -2.08958002 0 P 0 ;0
L 1.81868002 -2.08958002 1.81803002 -2.08973002 0 P 0 ;0
L 1.81803002 -2.08973002 1.81736004 -2.08981998 0 P 0 ;0
L 1.81736004 -2.08981998 1.81293002 -2.09001998 0 P 0 ;0
L 1.81293002 -2.09001998 1.80846998 -2.08986004 0 P 0 ;0
L 1.80846998 -2.08986004 1.80256998 -2.08923002 0 P 0 ;0
L 1.80256998 -2.08923002 1.79668002 -2.08818996 0 P 0 ;0
L 1.79668002 -2.08818996 1.78223002 -2.08458002 0 P 0 ;0
L 1.78223002 -2.08458002 1.77788996 -2.08338002 0 P 0 ;0
L 1.77788996 -2.08338002 1.77415 -2.08246004 0 P 0 ;0
L 1.77415 -2.08246004 1.77095 -2.08175 0 P 0 ;0
L 1.77095 -2.08175 1.7709 -2.08173996 0 P 0 ;0
L 1.7709 -2.08173996 1.77076998 -2.08173996 0 P 0 ;0
L 1.77076998 -2.08173996 1.77068996 -2.08176004 0 P 0 ;0
L 1.77068996 -2.08176004 1.77053002 -2.08183996 0 P 0 ;0
L 1.77053002 -2.08183996 1.77043002 -2.08193996 0 P 0 ;0
L 1.77043002 -2.08193996 1.77036998 -2.08201998 0 P 0 ;0
L 1.77036998 -2.08201998 1.77031998 -2.08211998 0 P 0 ;0
L 1.77031998 -2.08211998 1.7703 -2.08216998 0 P 0 ;0
L 1.7703 -2.08216998 1.77028996 -2.08223002 0 P 0 ;0
L 1.77028996 -2.08223002 1.77028002 -2.08228002 0 P 0 ;0
L 1.77028002 -2.08228002 1.77028002 -2.08238996 0 P 0 ;0
L 1.77028002 -2.08238996 1.77056998 -2.08838996 0 P 0 ;0
L 1.77056998 -2.08838996 1.77096004 -2.09526004 0 P 0 ;0
L 1.77096004 -2.09526004 1.77153996 -2.1033 0 P 0 ;0
L 1.77153996 -2.1033 1.77236004 -2.11291004 0 P 0 ;0
L 1.77236004 -2.11291004 1.77311004 -2.1194 0 P 0 ;0
L 1.77311004 -2.1194 1.77383002 -2.12398002 0 P 0 ;0
L 1.77383002 -2.12398002 1.77386004 -2.12411004 0 P 0 ;0
L 1.77386004 -2.12411004 1.7739 -2.12423002 0 P 0 ;0
L 1.7739 -2.12423002 1.77395 -2.12436004 0 P 0 ;0
L 1.77395 -2.12436004 1.77401004 -2.12448002 0 P 0 ;0
L 1.77401004 -2.12448002 1.77408002 -2.12458996 0 P 0 ;0
L 1.77408002 -2.12458996 1.77416004 -2.1247 0 P 0 ;0
L 1.77416004 -2.1247 1.77425 -2.1248 0 P 0 ;0
L 1.77425 -2.1248 1.77435 -2.12488996 0 P 0 ;0
L 1.77435 -2.12488996 1.77445 -2.12496998 0 P 0 ;0
L 1.77445 -2.12496998 1.77456998 -2.12505 0 P 0 ;0
L 1.77456998 -2.12505 1.77571004 -2.12568996 0 P 0 ;0
L 1.77571004 -2.12568996 1.7769 -2.12623996 0 P 0 ;0
L 1.7769 -2.12623996 1.77813002 -2.12668996 0 P 0 ;0
L 1.77813002 -2.12668996 1.7794 -2.12703996 0 P 0 ;0
L 1.7794 -2.12703996 1.78068996 -2.12728996 0 P 0 ;0
L 1.78068996 -2.12728996 1.79791998 -2.12951004 0 P 0 ;0
L 1.79791998 -2.12951004 1.81536004 -2.13106004 0 P 0 ;0
L 1.81536004 -2.13106004 1.82125 -2.13123996 0 P 0 ;0
L 1.82125 -2.13123996 1.82716004 -2.13098996 0 P 0 ;0
L 1.82716004 -2.13098996 1.83583996 -2.12998002 0 P 0 ;0
L 1.83583996 -2.12998002 1.84445 -2.12836004 0 P 0 ;0
L 1.84445 -2.12836004 1.84911998 -2.12711004 0 P 0 ;0
L 1.84911998 -2.12711004 1.85366004 -2.12548002 0 P 0 ;0
L 1.85366004 -2.12548002 1.85806998 -2.12348002 0 P 0 ;0
L 1.85806998 -2.12348002 1.86078996 -2.12196998 0 P 0 ;0
L 1.86078996 -2.12196998 1.8634 -2.12026998 0 P 0 ;0
L 1.8634 -2.12026998 1.86586998 -2.11836998 0 P 0 ;0
L 1.86586998 -2.11836998 1.86821004 -2.11628002 0 P 0 ;0
L 1.86821004 -2.11628002 1.87026004 -2.11413002 0 P 0 ;0
L 1.87026004 -2.11413002 1.8721 -2.11181998 0 P 0 ;0
L 1.8721 -2.11181998 1.87375 -2.10936004 0 P 0 ;0
L 1.87375 -2.10936004 1.87516998 -2.10673996 0 P 0 ;0
L 1.87516998 -2.10673996 1.87605 -2.10483996 0 P 0 ;0
L 1.87605 -2.10483996 1.87683996 -2.10291004 0 P 0 ;0
L 1.87683996 -2.10291004 1.8772 -2.10188002 0 P 0 ;0
L 1.8772 -2.10188002 1.87748996 -2.10083002 0 P 0 ;0
L 1.87748996 -2.10083002 1.87771004 -2.09976998 0 P 0 ;0
L 1.87771004 -2.09976998 1.87798002 -2.09788996 0 P 0 ;0
L 1.87798002 -2.09788996 1.87811998 -2.09601004 0 P 0 ;0
L 1.87811998 -2.09601004 1.87821004 -2.08966998 0 P 0 ;0
L 1.87821004 -2.08966998 1.8781 -2.08353996 0 P 0 ;0
L 1.8781 -2.08353996 1.87798002 -2.08166004 0 P 0 ;0
L 1.87798002 -2.08166004 1.87773002 -2.07976998 0 P 0 ;0
L 1.87773002 -2.07976998 1.87753002 -2.07873996 0 P 0 ;0
L 1.87753002 -2.07873996 1.87726998 -2.07773996 0 P 0 ;0
L 1.87726998 -2.07773996 1.87695 -2.07673996 0 P 0 ;0
L 1.87695 -2.07673996 1.87628996 -2.07505 0 P 0 ;0
L 1.87628996 -2.07505 1.87553002 -2.07338002 0 P 0 ;0
L 1.87553002 -2.07338002 1.87441004 -2.07133996 0 P 0 ;0
L 1.87441004 -2.07133996 1.87313996 -2.06938002 0 P 0 ;0
L 1.87313996 -2.06938002 1.87171004 -2.06751004 0 P 0 ;0
L 1.87171004 -2.06751004 1.8688 -2.06416004 0 P 0 ;0
L 1.8688 -2.06416004 1.86566998 -2.06095 0 P 0 ;0
L 1.86566998 -2.06095 1.86181998 -2.05741998 0 P 0 ;0
L 1.86181998 -2.05741998 1.85778002 -2.05406998 0 P 0 ;0
L 1.85778002 -2.05406998 1.84833996 -2.04715 0 P 0 ;0
L 1.84833996 -2.04715 1.83913996 -2.0407 0 P 0 ;0
L 1.83913996 -2.0407 1.83686004 -2.0389 0 P 0 ;0
L 1.83686004 -2.0389 1.83471998 -2.03691998 0 P 0 ;0
L 1.83471998 -2.03691998 1.83428002 -2.03643002 0 P 0 ;0
L 1.83428002 -2.03643002 1.83386998 -2.0359 0 P 0 ;0
L 1.83386998 -2.0359 1.83351004 -2.03535 0 P 0 ;0
L 1.83351004 -2.03535 1.83318996 -2.03476004 0 P 0 ;0
L 1.83318996 -2.03476004 1.83291998 -2.03415 0 P 0 ;0
L 1.83291998 -2.03415 1.83283996 -2.03393996 0 P 0 ;0
L 1.83283996 -2.03393996 1.83278002 -2.03371004 0 P 0 ;0
L 1.83278002 -2.03371004 1.83273002 -2.03348996 0 P 0 ;0
L 1.83273002 -2.03348996 1.83271004 -2.03326004 0 P 0 ;0
L 1.83271004 -2.03326004 1.8327 -2.03303002 0 P 0 ;0
L 1.8327 -2.03303002 1.83271004 -2.0328 0 P 0 ;0
L 1.83271004 -2.0328 1.83275 -2.03258002 0 P 0 ;0
L 1.83275 -2.03258002 1.83278996 -2.03235 0 P 0 ;0
L 1.83278996 -2.03235 1.83286004 -2.03213002 0 P 0 ;0
L 1.83286004 -2.03213002 1.83293996 -2.03191998 0 P 0 ;0
L 1.83293996 -2.03191998 1.83305 -2.03171004 0 P 0 ;0
L 1.83305 -2.03171004 1.83325 -2.03135 0 P 0 ;0
L 1.83325 -2.03135 1.83348996 -2.03101998 0 P 0 ;0
L 1.83348996 -2.03101998 1.83375 -2.03071004 0 P 0 ;0
L 1.83375 -2.03071004 1.83403002 -2.03041004 0 P 0 ;0
L 1.83403002 -2.03041004 1.83433996 -2.03015 0 P 0 ;0
L 1.83433996 -2.03015 1.83466998 -2.02991004 0 P 0 ;0
L 1.83466998 -2.02991004 1.83501998 -2.02968996 0 P 0 ;0
L 1.83501998 -2.02968996 1.83538002 -2.02951004 0 P 0 ;0
L 1.83538002 -2.02951004 1.83576004 -2.02936004 0 P 0 ;0
L 1.83576004 -2.02936004 1.83615 -2.02923996 0 P 0 ;0
L 1.83615 -2.02923996 1.83655 -2.02915 0 P 0 ;0
L 1.83655 -2.02915 1.8392 -2.02873996 0 P 0 ;0
L 1.8392 -2.02873996 1.84188002 -2.0285 0 P 0 ;0
L 1.84188002 -2.0285 1.84458002 -2.02841004 0 P 0 ;0
L 1.84458002 -2.02841004 1.84993996 -2.02858002 0 P 0 ;0
L 1.84993996 -2.02858002 1.85526998 -2.02916004 0 P 0 ;0
L 1.85526998 -2.02916004 1.86155 -2.03023002 0 P 0 ;0
L 1.86155 -2.03023002 1.86778002 -2.03158002 0 P 0 ;0
L 1.86778002 -2.03158002 1.8713 -2.03238996 0 P 0 ;0
L 1.8713 -2.03238996 1.87428996 -2.03303002 0 P 0 ;0
L 1.87428996 -2.03303002 1.8769 -2.03356004 0 P 0 ;0
L 1.8769 -2.03356004 1.87691998 -2.03356998 0 P 0 ;0
L 1.87691998 -2.03356998 1.87696004 -2.03356998 0 P 0 ;0
L 1.87696004 -2.03356998 1.87696998 -2.03356004 0 P 0 ;0
L 1.87696998 -2.03356004 1.87701004 -2.03356004 0 P 0 ;0
L 1.87701004 -2.03356004 1.87703996 -2.03353996 0 P 0 ;0
L 1.87703996 -2.03353996 1.87706004 -2.03353002 0 P 0 ;0
L 1.87706004 -2.03353002 1.87706998 -2.03351998 0 P 0 ;0
L 1.87706998 -2.03351998 1.87708996 -2.03351004 0 P 0 ;0
L 1.87708996 -2.03351004 1.8771 -2.03348996 0 P 0 ;0
L 1.8771 -2.03348996 1.87711004 -2.03348002 0 P 0 ;0
L 1.87711004 -2.03348002 1.87721998 -2.0333 0 P 0 ;0
L 1.87721998 -2.0333 1.87731998 -2.0331 0 P 0 ;0
L 1.87731998 -2.0331 1.8774 -2.0329 0 P 0 ;0
L 1.8774 -2.0329 1.87746004 -2.03268996 0 P 0 ;0
L 1.87746004 -2.03268996 1.87751004 -2.03248002 0 P 0 ;0
L 1.87751004 -2.03248002 1.87753002 -2.03226998 0 P 0 ;0
L 1.87753002 -2.03226998 1.87753996 -2.03205 0 P 0 ;0
L 1.87753996 -2.03205 1.87753002 -2.03183002 0 P 0 ;0
L 1.87753002 -2.03183002 1.87565 -2.01323996 0 P 0 ;0
L 1.87565 -2.01323996 1.87371004 -1.99451998 0 P 0 ;0
L 1.87371004 -1.99451998 1.8737 -1.99438996 0 P 0 ;0
L 1.8737 -1.99438996 1.87366998 -1.99426998 0 P 0 ;0
L 1.87366998 -1.99426998 1.87363002 -1.99415 0 P 0 ;0
L 1.87363002 -1.99415 1.87358002 -1.99403002 0 P 0 ;0
L 1.87358002 -1.99403002 1.87351998 -1.99391004 0 P 0 ;0
L 1.87351998 -1.99391004 1.87346004 -1.9938 0 P 0 ;0
L 1.87346004 -1.9938 1.87338002 -1.9937 0 P 0 ;0
L 1.87338002 -1.9937 1.87328996 -1.9936 0 P 0 ;0
L 1.87328996 -1.9936 1.8732 -1.99351004 0 P 0 ;0
L 1.8732 -1.99351004 1.8731 -1.99343002 0 P 0 ;0
L 1.8731 -1.99343002 1.87298996 -1.99335 0 P 0 ;0
L 1.87298996 -1.99335 1.87248002 -1.99305 0 P 0 ;0
L 1.87248002 -1.99305 1.87193996 -1.99278002 0 P 0 ;0
L 1.87193996 -1.99278002 1.87136998 -1.99256998 0 P 0 ;0
L 1.87136998 -1.99256998 1.87078996 -1.99241004 0 P 0 ;0
L 1.87078996 -1.99241004 1.8702 -1.9923 0 P 0 ;0
L 1.8702 -1.9923 1.85876004 -1.99076004 0 P 0 ;0
L 1.85876004 -1.99076004 1.84691998 -1.98943002 0 P 0 ;0
L 1.84691998 -1.98943002 1.83693002 -1.98876004 0 P 0 ;0
L 1.83693002 -1.98876004 1.8318 -1.98863002 0 P 0 ;0
L 1.8318 -1.98863002 1.82623002 -1.98866998 0 P 0 ;0
L 1.82623002 -1.98866998 1.82106004 -1.98883996 0 P 0 ;0
L 1.82106004 -1.98883996 1.81726998 -1.98915 0 P 0 ;0
L 1.78061004 -2.12523996 1.84838002 -2.12523996 0 P 0 ;0
L 1.77733002 -2.12423996 1.85121004 -2.12423996 0 P 0 ;0
L 1.77573996 -2.12323996 1.85376998 -2.12323996 0 P 0 ;0
L 1.77558002 -2.12223996 1.85596998 -2.12223996 0 P 0 ;0
L 1.77541998 -2.12123996 1.85798996 -2.12123996 0 P 0 ;0
L 1.77526998 -2.12023996 1.85978996 -2.12023996 0 P 0 ;0
L 1.77511004 -2.11923996 1.86131998 -2.11923996 0 P 0 ;0
L 1.77498996 -2.11823996 1.86276004 -2.11823996 0 P 0 ;0
L 1.77486998 -2.11723996 1.86406998 -2.11723996 0 P 0 ;0
L 1.77475 -2.11623996 1.86526004 -2.11623996 0 P 0 ;0
L 1.77463996 -2.11523996 1.86638002 -2.11523996 0 P 0 ;0
L 1.77451998 -2.11423996 1.8674 -2.11423996 0 P 0 ;0
L 1.77441004 -2.11323996 1.86835 -2.11323996 0 P 0 ;0
L 1.77431004 -2.11223996 1.86921004 -2.11223996 0 P 0 ;0
L 1.77421998 -2.11123996 1.87001004 -2.11123996 0 P 0 ;0
L 1.77413996 -2.11023996 1.87075 -2.11023996 0 P 0 ;0
L 1.77405 -2.10923996 1.87141998 -2.10923996 0 P 0 ;0
L 1.77396998 -2.10823996 1.87208002 -2.10823996 0 P 0 ;0
L 1.77388002 -2.10723996 1.87261998 -2.10723996 0 P 0 ;0
L 1.7738 -2.10623996 1.87316998 -2.10623996 0 P 0 ;0
L 1.77371004 -2.10523996 1.87366004 -2.10523996 0 P 0 ;0
L 1.77363002 -2.10423996 1.87411998 -2.10423996 0 P 0 ;0
L 1.77353996 -2.10323996 1.87453996 -2.10323996 0 P 0 ;0
L 1.77346998 -2.10223996 1.87495 -2.10223996 0 P 0 ;0
L 1.7734 -2.10123996 1.8753 -2.10123996 0 P 0 ;0
L 1.77333002 -2.10023996 1.87556998 -2.10023996 0 P 0 ;0
L 1.77325 -2.09923996 1.87576998 -2.09923996 0 P 0 ;0
L 1.77318002 -2.09823996 1.87591998 -2.09823996 0 P 0 ;0
L 1.77311004 -2.09723996 1.87603002 -2.09723996 0 P 0 ;0
L 1.77303996 -2.09623996 1.8761 -2.09623996 0 P 0 ;0
L 1.77296998 -2.09523996 1.87613002 -2.09523996 0 P 0 ;0
L 1.77291004 -2.09423996 1.87613996 -2.09423996 0 P 0 ;0
L 1.77285 -2.09323996 1.87616004 -2.09323996 0 P 0 ;0
L 1.77278996 -2.09223996 1.87616998 -2.09223996 0 P 0 ;0
L 1.77273002 -2.09123996 1.80256998 -2.09123996 0 P 0 ;0
L 1.77268002 -2.09023996 1.7968 -2.09023996 0 P 0 ;0
L 1.77261998 -2.08923996 1.79263002 -2.08923996 0 P 0 ;0
L 1.77256004 -2.08823996 1.78861998 -2.08823996 0 P 0 ;0
L 1.77251004 -2.08723996 1.7846 -2.08723996 0 P 0 ;0
L 1.77246004 -2.08623996 1.7807 -2.08623996 0 P 0 ;0
L 1.77241998 -2.08523996 1.77705 -2.08523996 0 P 0 ;0
L 1.77236998 -2.08423996 1.77293996 -2.08423996 0 P 0 ;0
L 1.62463996 -2.18195 1.65948996 -2.18195 0 P 0 ;0
L 1.61963996 -2.18095 1.66483002 -2.18095 0 P 0 ;0
L 1.61818002 -1.99795 1.6724 -1.99795 0 P 0 ;0
L 1.61778996 -1.99695 1.67218002 -1.99695 0 P 0 ;0
L 1.6174 -1.99595 1.67196004 -1.99595 0 P 0 ;0
L 1.61701004 -1.99495 1.67173996 -1.99495 0 P 0 ;0
L 1.61391998 -2.15695 1.70026004 -2.15695 0 P 0 ;0
L 1.61386004 -2.15595 1.70088002 -2.15595 0 P 0 ;0
L 1.61381004 -2.15495 1.70151004 -2.15495 0 P 0 ;0
L 1.61375 -2.15395 1.70213996 -2.15395 0 P 0 ;0
L 1.6137 -2.15295 1.70276004 -2.15295 0 P 0 ;0
L 1.61365 -2.15195 1.70338996 -2.15195 0 P 0 ;0
L 1.6136 -2.15095 1.70401004 -2.15095 0 P 0 ;0
L 1.61355 -2.14995 1.70456998 -2.14995 0 P 0 ;0
L 1.61348996 -2.14895 1.70511998 -2.14895 0 P 0 ;0
L 1.61343996 -2.14795 1.61738002 -2.14795 0 P 0 ;0
L 1.55341004 -2.08286998 1.60538002 -2.08286998 0 P 0 ;0
L 1.55286004 -2.08186998 1.60526998 -2.08186998 0 P 0 ;0
L 1.5521 -2.08086998 1.6051 -2.08086998 0 P 0 ;0
L 1.55126998 -2.07986998 1.6049 -2.07986998 0 P 0 ;0
L 1.55033996 -2.07886998 1.60463996 -2.07886998 0 P 0 ;0
L 1.54928996 -2.07786998 1.60433002 -2.07786998 0 P 0 ;0
L 1.54806998 -2.07686998 1.60398996 -2.07686998 0 P 0 ;0
L 1.5467 -2.07586998 1.60356998 -2.07586998 0 P 0 ;0
L 1.54531004 -2.07486998 1.6031 -2.07486998 0 P 0 ;0
L 1.54391004 -2.07386998 1.60258996 -2.07386998 0 P 0 ;0
L 1.54251004 -2.07286998 1.60201004 -2.07286998 0 P 0 ;0
L 1.54111998 -2.07186998 1.60138002 -2.07186998 0 P 0 ;0
L 1.53971998 -2.07086998 1.60068002 -2.07086998 0 P 0 ;0
L 1.53833002 -2.06986998 1.59993002 -2.06986998 0 P 0 ;0
L 1.53693002 -2.06886998 1.59908002 -2.06886998 0 P 0 ;0
L 1.53556004 -2.06786998 1.59821004 -2.06786998 0 P 0 ;0
L 1.53418996 -2.06686998 1.59733996 -2.06686998 0 P 0 ;0
L 1.53281998 -2.06586998 1.59646998 -2.06586998 0 P 0 ;0
L 1.53145 -2.06486998 1.5955 -2.06486998 0 P 0 ;0
L 1.53008002 -2.06386998 1.59453002 -2.06386998 0 P 0 ;0
L 1.52871004 -2.06286998 1.59356004 -2.06286998 0 P 0 ;0
L 1.52733996 -2.06186998 1.59253002 -2.06186998 0 P 0 ;0
L 1.52596998 -2.06086998 1.59145 -2.06086998 0 P 0 ;0
L 1.5246 -2.05986998 1.59038002 -2.05986998 0 P 0 ;0
L 1.52323002 -2.05886998 1.5893 -2.05886998 0 P 0 ;0
L 1.52186004 -2.05786998 1.58813996 -2.05786998 0 P 0 ;0
L 1.52053996 -2.05686998 1.58696004 -2.05686998 0 P 0 ;0
L 1.51935 -2.05586998 1.58576998 -2.05586998 0 P 0 ;0
L 1.51816004 -2.05486998 1.58456998 -2.05486998 0 P 0 ;0
L 1.51706998 -2.05386998 1.58321004 -2.05386998 0 P 0 ;0
L 1.51603996 -2.05286998 1.58185 -2.05286998 0 P 0 ;0
L 1.51501998 -2.05186998 1.58048996 -2.05186998 0 P 0 ;0
L 1.51408996 -2.05086998 1.57913002 -2.05086998 0 P 0 ;0
L 1.5132 -2.04986998 1.57776998 -2.04986998 0 P 0 ;0
L 1.51231998 -2.04886998 1.57641998 -2.04886998 0 P 0 ;0
L 1.51151004 -2.04786998 1.57505 -2.04786998 0 P 0 ;0
L 1.51075 -2.04686998 1.57365 -2.04686998 0 P 0 ;0
L 1.51008002 -2.04586998 1.57223002 -2.04586998 0 P 0 ;0
L 1.50945 -2.04486998 1.57081004 -2.04486998 0 P 0 ;0
L 1.50888002 -2.04386998 1.56938996 -2.04386998 0 P 0 ;0
L 1.50836004 -2.04286998 1.56796998 -2.04286998 0 P 0 ;0
L 1.5079 -2.04186998 1.56655 -2.04186998 0 P 0 ;0
L 1.50748002 -2.04086998 1.56518996 -2.04086998 0 P 0 ;0
L 1.50708996 -2.03986998 1.564 -2.03986998 0 P 0 ;0
L 1.50676004 -2.03886998 1.56296998 -2.03886998 0 P 0 ;0
L 1.50641998 -2.03786998 1.56206004 -2.03786998 0 P 0 ;0
L 1.50616998 -2.03686998 1.56125 -2.03686998 0 P 0 ;0
L 1.50591004 -2.03586998 1.56066998 -2.03586998 0 P 0 ;0
L 1.5057 -2.03486998 1.56031998 -2.03486998 0 P 0 ;0
L 1.50551998 -2.03386998 1.56016004 -2.03386998 0 P 0 ;0
L 1.50533996 -2.03286998 1.56016998 -2.03286998 0 P 0 ;0
L 1.50523996 -2.03186998 1.56036004 -2.03186998 0 P 0 ;0
L 1.50513002 -2.03086998 1.56071998 -2.03086998 0 P 0 ;0
L 1.50506998 -2.02986998 1.56131004 -2.02986998 0 P 0 ;0
L 1.50503996 -2.02886998 1.5622 -2.02886998 0 P 0 ;0
L 1.50501004 -2.02786998 1.56355 -2.02786998 0 P 0 ;0
L 1.50501998 -2.02686998 1.5657 -2.02686998 0 P 0 ;0
L 1.50506998 -2.02586998 1.60378996 -2.02586998 0 P 0 ;0
L 1.50511998 -2.02486998 1.60371004 -2.02486998 0 P 0 ;0
L 1.50521004 -2.02386998 1.60363996 -2.02386998 0 P 0 ;0
L 1.50533996 -2.02286998 1.60356998 -2.02286998 0 P 0 ;0
L 1.50546998 -2.02186998 1.6035 -2.02186998 0 P 0 ;0
L 1.50563996 -2.02086998 1.60343002 -2.02086998 0 P 0 ;0
L 1.50585 -2.01986998 1.60336004 -2.01986998 0 P 0 ;0
L 1.50606004 -2.01886998 1.60328996 -2.01886998 0 P 0 ;0
L 1.50633002 -2.01786998 1.60321998 -2.01786998 0 P 0 ;0
L 1.50661998 -2.01686998 1.60315 -2.01686998 0 P 0 ;0
L 1.50691004 -2.01586998 1.60308002 -2.01586998 0 P 0 ;0
L 1.50726998 -2.01486998 1.603 -2.01486998 0 P 0 ;0
L 1.50766004 -2.01386998 1.60293002 -2.01386998 0 P 0 ;0
L 1.50808996 -2.01286998 1.60285 -2.01286998 0 P 0 ;0
L 1.50856998 -2.01186998 1.60278002 -2.01186998 0 P 0 ;0
L 1.50908996 -2.01086998 1.6027 -2.01086998 0 P 0 ;0
L 1.50966004 -2.00986998 1.60261998 -2.00986998 0 P 0 ;0
L 1.51028996 -2.00886998 1.60255 -2.00886998 0 P 0 ;0
L 1.51096998 -2.00786998 1.60246998 -2.00786998 0 P 0 ;0
L 1.51171998 -2.00686998 1.6024 -2.00686998 0 P 0 ;0
L 1.51253996 -2.00586998 1.60233002 -2.00586998 0 P 0 ;0
L 1.51343996 -2.00486998 1.60225 -2.00486998 0 P 0 ;0
L 1.5144 -2.00386998 1.60218002 -2.00386998 0 P 0 ;0
L 1.51551998 -2.00286998 1.6021 -2.00286998 0 P 0 ;0
L 1.51663996 -2.00186998 1.60203002 -2.00186998 0 P 0 ;0
L 1.51795 -2.00086998 1.60195 -2.00086998 0 P 0 ;0
L 1.51928996 -1.99986998 1.60183996 -1.99986998 0 P 0 ;0
L 1.52086998 -1.99886998 1.60173002 -1.99886998 0 P 0 ;0
L 1.52258996 -1.99786998 1.60156998 -1.99786998 0 P 0 ;0
L 1.52451004 -1.99686998 1.60138996 -1.99686998 0 P 0 ;0
L 1.52686998 -1.99586998 1.60106998 -1.99586998 0 P 0 ;0
L 1.52976004 -1.99486998 1.59943996 -1.99486998 0 P 0 ;0
L 1.53283002 -1.99386998 1.59543002 -1.99386998 0 P 0 ;0
L 1.53678996 -1.99286998 1.59003996 -1.99286998 0 P 0 ;0
L 1.54173996 -1.99186998 1.58073996 -1.99186998 0 P 0 ;0
L 1.55036998 -1.99086998 1.56493002 -1.99086998 0 P 0 ;0
L 1.6036 -2.03086998 1.60413996 -2.03086998 0 P 0 ;0
L 1.59891004 -2.02986998 1.60406998 -2.02986998 0 P 0 ;0
L 1.59435 -2.02886998 1.604 -2.02886998 0 P 0 ;0
L 1.58838996 -2.02786998 1.60393002 -2.02786998 0 P 0 ;0
L 1.57981004 -2.02686998 1.60386004 -2.02686998 0 P 0 ;0
L 1.54575 -1.98923996 1.53931998 -1.99021998 0 P 0 ;0
L 1.53931998 -1.99021998 1.53298996 -1.99171998 0 P 0 ;0
L 1.53298996 -1.99171998 1.52678996 -1.99373996 0 P 0 ;0
L 1.52678996 -1.99373996 1.52376998 -1.995 0 P 0 ;0
L 1.52376998 -1.995 1.52086998 -1.99651004 0 P 0 ;0
L 1.52086998 -1.99651004 1.5181 -1.99826004 0 P 0 ;0
L 1.5181 -1.99826004 1.51548002 -2.00023002 0 P 0 ;0
L 1.51548002 -2.00023002 1.51301004 -2.00243002 0 P 0 ;0
L 1.51301004 -2.00243002 1.51128996 -2.00423002 0 P 0 ;0
L 1.51128996 -2.00423002 1.50971998 -2.00616004 0 P 0 ;0
L 1.50971998 -2.00616004 1.50831004 -2.00821004 0 P 0 ;0
L 1.50831004 -2.00821004 1.50706998 -2.01036998 0 P 0 ;0
L 1.50706998 -2.01036998 1.50598996 -2.01261998 0 P 0 ;0
L 1.50598996 -2.01261998 1.50508996 -2.01496998 0 P 0 ;0
L 1.50508996 -2.01496998 1.5042 -2.01801004 0 P 0 ;0
L 1.5042 -2.01801004 1.50355 -2.02111004 0 P 0 ;0
L 1.50355 -2.02111004 1.50313996 -2.02426004 0 P 0 ;0
L 1.50313996 -2.02426004 1.50298996 -2.02743002 0 P 0 ;0
L 1.50298996 -2.02743002 1.50308996 -2.03063002 0 P 0 ;0
L 1.50308996 -2.03063002 1.50338002 -2.03326998 0 P 0 ;0
L 1.50338002 -2.03326998 1.50385 -2.03588002 0 P 0 ;0
L 1.50385 -2.03588002 1.50451004 -2.03845 0 P 0 ;0
L 1.50451004 -2.03845 1.50535 -2.04096998 0 P 0 ;0
L 1.50535 -2.04096998 1.50633002 -2.0433 0 P 0 ;0
L 1.50633002 -2.0433 1.5075 -2.04553002 0 P 0 ;0
L 1.5075 -2.04553002 1.50883996 -2.04766998 0 P 0 ;0
L 1.50883996 -2.04766998 1.51036998 -2.04968996 0 P 0 ;0
L 1.51036998 -2.04968996 1.51323002 -2.05291998 0 P 0 ;0
L 1.51323002 -2.05291998 1.51631998 -2.05593996 0 P 0 ;0
L 1.51631998 -2.05593996 1.51961998 -2.05871004 0 P 0 ;0
L 1.51961998 -2.05871004 1.53591004 -2.0706 0 P 0 ;0
L 1.53591004 -2.0706 1.54668002 -2.07831004 0 P 0 ;0
L 1.54668002 -2.07831004 1.54793996 -2.07933996 0 P 0 ;0
L 1.54793996 -2.07933996 1.54911998 -2.08046998 0 P 0 ;0
L 1.54911998 -2.08046998 1.55021004 -2.08168002 0 P 0 ;0
L 1.55021004 -2.08168002 1.5512 -2.08298996 0 P 0 ;0
L 1.5512 -2.08298996 1.55136004 -2.08323002 0 P 0 ;0
L 1.55136004 -2.08323002 1.5515 -2.08348002 0 P 0 ;0
L 1.5515 -2.08348002 1.55161004 -2.08373996 0 P 0 ;0
L 1.55161004 -2.08373996 1.5517 -2.08401998 0 P 0 ;0
L 1.5517 -2.08401998 1.55176998 -2.0843 0 P 0 ;0
L 1.55176998 -2.0843 1.55181004 -2.08458002 0 P 0 ;0
L 1.55181004 -2.08458002 1.55183002 -2.08486998 0 P 0 ;0
L 1.55183002 -2.08486998 1.55181998 -2.08516004 0 P 0 ;0
L 1.55181998 -2.08516004 1.55178996 -2.08545 0 P 0 ;0
L 1.55178996 -2.08545 1.55173996 -2.08573002 0 P 0 ;0
L 1.55173996 -2.08573002 1.55166004 -2.086 0 P 0 ;0
L 1.55166004 -2.086 1.55156004 -2.08628002 0 P 0 ;0
L 1.55156004 -2.08628002 1.55136998 -2.08666998 0 P 0 ;0
L 1.55136998 -2.08666998 1.55115 -2.08703996 0 P 0 ;0
L 1.55115 -2.08703996 1.5509 -2.08738996 0 P 0 ;0
L 1.5509 -2.08738996 1.55063002 -2.08771998 0 P 0 ;0
L 1.55063002 -2.08771998 1.55033002 -2.08803002 0 P 0 ;0
L 1.55033002 -2.08803002 1.55 -2.08831004 0 P 0 ;0
L 1.55 -2.08831004 1.54966004 -2.08856004 0 P 0 ;0
L 1.54966004 -2.08856004 1.54928996 -2.08878996 0 P 0 ;0
L 1.54928996 -2.08878996 1.5489 -2.08898996 0 P 0 ;0
L 1.5489 -2.08898996 1.54786004 -2.08941004 0 P 0 ;0
L 1.54786004 -2.08941004 1.54678996 -2.08973996 0 P 0 ;0
L 1.54678996 -2.08973996 1.54568002 -2.08998002 0 P 0 ;0
L 1.54568002 -2.08998002 1.54456998 -2.09011998 0 P 0 ;0
L 1.54456998 -2.09011998 1.54343996 -2.09016998 0 P 0 ;0
L 1.54343996 -2.09016998 1.53906998 -2.09003002 0 P 0 ;0
L 1.53906998 -2.09003002 1.53468002 -2.08961998 0 P 0 ;0
L 1.53468002 -2.08961998 1.52908996 -2.08878996 0 P 0 ;0
L 1.52908996 -2.08878996 1.52351004 -2.08766004 0 P 0 ;0
L 1.52351004 -2.08766004 1.51005 -2.08418996 0 P 0 ;0
L 1.51005 -2.08418996 1.50631004 -2.08318002 0 P 0 ;0
L 1.50631004 -2.08318002 1.50308002 -2.08238996 0 P 0 ;0
L 1.50308002 -2.08238996 1.50033996 -2.08183002 0 P 0 ;0
L 1.50033996 -2.08183002 1.5003 -2.08181998 0 P 0 ;0
L 1.5003 -2.08181998 1.50016004 -2.08181998 0 P 0 ;0
L 1.50016004 -2.08181998 1.50011998 -2.08183002 0 P 0 ;0
L 1.50011998 -2.08183002 1.50006998 -2.08183996 0 P 0 ;0
L 1.50006998 -2.08183996 1.50003002 -2.08186004 0 P 0 ;0
L 1.50003002 -2.08186004 1.49998996 -2.08186998 0 P 0 ;0
L 1.49998996 -2.08186998 1.49995 -2.08188996 0 P 0 ;0
L 1.49995 -2.08188996 1.49991004 -2.08191998 0 P 0 ;0
L 1.49991004 -2.08191998 1.49988002 -2.08195 0 P 0 ;0
L 1.49988002 -2.08195 1.49983996 -2.08198002 0 P 0 ;0
L 1.49983996 -2.08198002 1.4997 -2.08213996 0 P 0 ;0
L 1.4997 -2.08213996 1.49956004 -2.08231998 0 P 0 ;0
L 1.49956004 -2.08231998 1.49943996 -2.0825 0 P 0 ;0
L 1.49943996 -2.0825 1.49933996 -2.0827 0 P 0 ;0
L 1.49933996 -2.0827 1.49925 -2.0829 0 P 0 ;0
L 1.49925 -2.0829 1.49918996 -2.08311004 0 P 0 ;0
L 1.49918996 -2.08311004 1.49913996 -2.08333002 0 P 0 ;0
L 1.49913996 -2.08333002 1.49911004 -2.08355 0 P 0 ;0
L 1.49911004 -2.08355 1.4991 -2.08376998 0 P 0 ;0
L 1.4991 -2.08376998 1.49911004 -2.08398996 0 P 0 ;0
L 1.49911004 -2.08398996 1.50071004 -2.10395 0 P 0 ;0
L 1.50071004 -2.10395 1.5024 -2.12403996 0 P 0 ;0
L 1.5024 -2.12403996 1.50241998 -2.12418002 0 P 0 ;0
L 1.50241998 -2.12418002 1.50246004 -2.12431004 0 P 0 ;0
L 1.50246004 -2.12431004 1.50248996 -2.12445 0 P 0 ;0
L 1.50248996 -2.12445 1.50255 -2.12456998 0 P 0 ;0
L 1.50255 -2.12456998 1.50261004 -2.1247 0 P 0 ;0
L 1.50261004 -2.1247 1.50276998 -2.12491998 0 P 0 ;0
L 1.50276998 -2.12491998 1.50286004 -2.12501998 0 P 0 ;0
L 1.50286004 -2.12501998 1.50296998 -2.12511998 0 P 0 ;0
L 1.50296998 -2.12511998 1.50308002 -2.12521004 0 P 0 ;0
L 1.50308002 -2.12521004 1.50318996 -2.12528002 0 P 0 ;0
L 1.50318996 -2.12528002 1.50331998 -2.12535 0 P 0 ;0
L 1.50331998 -2.12535 1.50343996 -2.1254 0 P 0 ;0
L 1.50343996 -2.1254 1.50391998 -2.12556004 0 P 0 ;0
L 1.50391998 -2.12556004 1.5044 -2.12568996 0 P 0 ;0
L 1.5044 -2.12568996 1.50848002 -2.12648996 0 P 0 ;0
L 1.50848002 -2.12648996 1.51328996 -2.12738002 0 P 0 ;0
L 1.51328996 -2.12738002 1.51873996 -2.12833996 0 P 0 ;0
L 1.51873996 -2.12833996 1.52606004 -2.12945 0 P 0 ;0
L 1.52606004 -2.12945 1.53343996 -2.13023002 0 P 0 ;0
L 1.53343996 -2.13023002 1.54886998 -2.13086998 0 P 0 ;0
L 1.54886998 -2.13086998 1.56305 -2.1303 0 P 0 ;0
L 1.56305 -2.1303 1.56666004 -2.12988996 0 P 0 ;0
L 1.56666004 -2.12988996 1.57023002 -2.12926998 0 P 0 ;0
L 1.57023002 -2.12926998 1.5738 -2.12843002 0 P 0 ;0
L 1.5738 -2.12843002 1.57945 -2.12668996 0 P 0 ;0
L 1.57945 -2.12668996 1.58498002 -2.12456998 0 P 0 ;0
L 1.58498002 -2.12456998 1.58793996 -2.12318002 0 P 0 ;0
L 1.58793996 -2.12318002 1.59078996 -2.12156004 0 P 0 ;0
L 1.59078996 -2.12156004 1.59348996 -2.11971998 0 P 0 ;0
L 1.59348996 -2.11971998 1.59525 -2.11833002 0 P 0 ;0
L 1.59525 -2.11833002 1.5969 -2.11681998 0 P 0 ;0
L 1.5969 -2.11681998 1.59846004 -2.11521004 0 P 0 ;0
L 1.59846004 -2.11521004 1.59991004 -2.11348002 0 P 0 ;0
L 1.59991004 -2.11348002 1.60175 -2.11093996 0 P 0 ;0
L 1.60175 -2.11093996 1.60338002 -2.10826998 0 P 0 ;0
L 1.60338002 -2.10826998 1.60481004 -2.10548002 0 P 0 ;0
L 1.60481004 -2.10548002 1.60573002 -2.10321004 0 P 0 ;0
L 1.60573002 -2.10321004 1.60646004 -2.10088002 0 P 0 ;0
L 1.60646004 -2.10088002 1.60698002 -2.09848996 0 P 0 ;0
L 1.60698002 -2.09848996 1.60756004 -2.09421998 0 P 0 ;0
L 1.60756004 -2.09421998 1.6078 -2.08991004 0 P 0 ;0
L 1.6078 -2.08991004 1.60768996 -2.08565 0 P 0 ;0
L 1.60768996 -2.08565 1.60723002 -2.08141998 0 P 0 ;0
L 1.60723002 -2.08141998 1.60691998 -2.07968002 0 P 0 ;0
L 1.60691998 -2.07968002 1.60646998 -2.07796998 0 P 0 ;0
L 1.60646998 -2.07796998 1.60591998 -2.0763 0 P 0 ;0
L 1.60591998 -2.0763 1.60523002 -2.07466998 0 P 0 ;0
L 1.60523002 -2.07466998 1.60411998 -2.07246998 0 P 0 ;0
L 1.60411998 -2.07246998 1.60281004 -2.07038002 0 P 0 ;0
L 1.60281004 -2.07038002 1.60131998 -2.06838996 0 P 0 ;0
L 1.60131998 -2.06838996 1.59803996 -2.06461998 0 P 0 ;0
L 1.59803996 -2.06461998 1.59455 -2.06101998 0 P 0 ;0
L 1.59455 -2.06101998 1.59031998 -2.05708996 0 P 0 ;0
L 1.59031998 -2.05708996 1.58586004 -2.05333996 0 P 0 ;0
L 1.58586004 -2.05333996 1.57588002 -2.04598996 0 P 0 ;0
L 1.57588002 -2.04598996 1.56685 -2.03963996 0 P 0 ;0
L 1.56685 -2.03963996 1.56578002 -2.03878996 0 P 0 ;0
L 1.56578002 -2.03878996 1.56476998 -2.03786004 0 P 0 ;0
L 1.56476998 -2.03786004 1.56383002 -2.03686998 0 P 0 ;0
L 1.56383002 -2.03686998 1.56295 -2.0358 0 P 0 ;0
L 1.56295 -2.0358 1.56276998 -2.03555 0 P 0 ;0
L 1.56276998 -2.03555 1.56261004 -2.03528002 0 P 0 ;0
L 1.56261004 -2.03528002 1.56246998 -2.035 0 P 0 ;0
L 1.56246998 -2.035 1.56236004 -2.03471998 0 P 0 ;0
L 1.56236004 -2.03471998 1.56226998 -2.03441998 0 P 0 ;0
L 1.56226998 -2.03441998 1.5622 -2.03411998 0 P 0 ;0
L 1.5622 -2.03411998 1.56216004 -2.03381998 0 P 0 ;0
L 1.56216004 -2.03381998 1.56213996 -2.03351004 0 P 0 ;0
L 1.56213996 -2.03351004 1.56215 -2.0332 0 P 0 ;0
L 1.56215 -2.0332 1.56218002 -2.03288996 0 P 0 ;0
L 1.56218002 -2.03288996 1.56225 -2.03253996 0 P 0 ;0
L 1.56225 -2.03253996 1.56233996 -2.03221004 0 P 0 ;0
L 1.56233996 -2.03221004 1.56246004 -2.03186998 0 P 0 ;0
L 1.56246004 -2.03186998 1.56261004 -2.03156004 0 P 0 ;0
L 1.56261004 -2.03156004 1.56278996 -2.03125 0 P 0 ;0
L 1.56278996 -2.03125 1.56298002 -2.03096004 0 P 0 ;0
L 1.56298002 -2.03096004 1.56321004 -2.03068996 0 P 0 ;0
L 1.56321004 -2.03068996 1.56345 -2.03043996 0 P 0 ;0
L 1.56345 -2.03043996 1.56371004 -2.0302 0 P 0 ;0
L 1.56371004 -2.0302 1.56416004 -2.02986004 0 P 0 ;0
L 1.56416004 -2.02986004 1.56463002 -2.02955 0 P 0 ;0
L 1.56463002 -2.02955 1.56511998 -2.02928002 0 P 0 ;0
L 1.56511998 -2.02928002 1.56561998 -2.02903002 0 P 0 ;0
L 1.56561998 -2.02903002 1.56611998 -2.02883996 0 P 0 ;0
L 1.56611998 -2.02883996 1.56663996 -2.02866998 0 P 0 ;0
L 1.56663996 -2.02866998 1.56716004 -2.02855 0 P 0 ;0
L 1.56716004 -2.02855 1.5677 -2.02846998 0 P 0 ;0
L 1.5677 -2.02846998 1.56926998 -2.02835 0 P 0 ;0
L 1.56926998 -2.02835 1.57085 -2.02833996 0 P 0 ;0
L 1.57085 -2.02833996 1.57725 -2.02866998 0 P 0 ;0
L 1.57725 -2.02866998 1.58205 -2.02906004 0 P 0 ;0
L 1.58205 -2.02906004 1.58746998 -2.02975 0 P 0 ;0
L 1.58746998 -2.02975 1.59271004 -2.03056998 0 P 0 ;0
L 1.59271004 -2.03056998 1.59681004 -2.03143002 0 P 0 ;0
L 1.59681004 -2.03143002 1.60016004 -2.03221998 0 P 0 ;0
L 1.60016004 -2.03221998 1.60308002 -2.03281004 0 P 0 ;0
L 1.60308002 -2.03281004 1.60553996 -2.03323996 0 P 0 ;0
L 1.60553996 -2.03323996 1.60568996 -2.03323996 0 P 0 ;0
L 1.60568996 -2.03323996 1.60576998 -2.03321998 0 P 0 ;0
L 1.60576998 -2.03321998 1.60586004 -2.03316004 0 P 0 ;0
L 1.60586004 -2.03316004 1.6059 -2.03313996 0 P 0 ;0
L 1.6059 -2.03313996 1.60591998 -2.03311004 0 P 0 ;0
L 1.60591998 -2.03311004 1.60598996 -2.03303996 0 P 0 ;0
L 1.60598996 -2.03303996 1.60605 -2.03296998 0 P 0 ;0
L 1.60605 -2.03296998 1.6061 -2.03288996 0 P 0 ;0
L 1.6061 -2.03288996 1.60618002 -2.03273002 0 P 0 ;0
L 1.60618002 -2.03273002 1.60621004 -2.03263002 0 P 0 ;0
L 1.60621004 -2.03263002 1.60623002 -2.03253996 0 P 0 ;0
L 1.60623002 -2.03253996 1.60625 -2.03236004 0 P 0 ;0
L 1.60625 -2.03236004 1.60623996 -2.03226004 0 P 0 ;0
L 1.60623996 -2.03226004 1.60508002 -2.01578002 0 P 0 ;0
L 1.60508002 -2.01578002 1.60393996 -2.00068002 0 P 0 ;0
L 1.60393996 -2.00068002 1.60368002 -1.99833996 0 P 0 ;0
L 1.60368002 -1.99833996 1.60326998 -1.99601004 0 P 0 ;0
L 1.60326998 -1.99601004 1.60321004 -1.99576998 0 P 0 ;0
L 1.60321004 -1.99576998 1.60313996 -1.99553002 0 P 0 ;0
L 1.60313996 -1.99553002 1.60303996 -1.9953 0 P 0 ;0
L 1.60303996 -1.9953 1.60293002 -1.99508002 0 P 0 ;0
L 1.60293002 -1.99508002 1.60281004 -1.99486004 0 P 0 ;0
L 1.60281004 -1.99486004 1.60261998 -1.9946 0 P 0 ;0
L 1.60261998 -1.9946 1.60241004 -1.99435 0 P 0 ;0
L 1.60241004 -1.99435 1.60218002 -1.99411998 0 P 0 ;0
L 1.60218002 -1.99411998 1.60191998 -1.99391004 0 P 0 ;0
L 1.60191998 -1.99391004 1.60161004 -1.99368996 0 P 0 ;0
L 1.60161004 -1.99368996 1.60128996 -1.99348996 0 P 0 ;0
L 1.60128996 -1.99348996 1.60095 -1.99331998 0 P 0 ;0
L 1.60095 -1.99331998 1.6006 -1.99316004 0 P 0 ;0
L 1.6006 -1.99316004 1.59966004 -1.99283002 0 P 0 ;0
L 1.59966004 -1.99283002 1.59871004 -1.99255 0 P 0 ;0
L 1.59871004 -1.99255 1.5933 -1.99135 0 P 0 ;0
L 1.5933 -1.99135 1.5878 -1.9905 0 P 0 ;0
L 1.5878 -1.9905 1.57285 -1.98915 0 P 0 ;0
L 1.57285 -1.98915 1.55763996 -1.98861004 0 P 0 ;0
L 1.55763996 -1.98861004 1.55171004 -1.98876004 0 P 0 ;0
L 1.55171004 -1.98876004 1.54575 -1.98923996 0 P 0 ;0
L 1.53011998 -2.12786998 1.5666 -2.12786998 0 P 0 ;0
L 1.52236004 -2.12686998 1.57168002 -2.12686998 0 P 0 ;0
L 1.51621998 -2.12586998 1.5753 -2.12586998 0 P 0 ;0
L 1.51071004 -2.12486998 1.57856004 -2.12486998 0 P 0 ;0
L 1.50553002 -2.12386998 1.58121004 -2.12386998 0 P 0 ;0
L 1.50431004 -2.12286998 1.58381998 -2.12286998 0 P 0 ;0
L 1.50423002 -2.12186998 1.58601998 -2.12186998 0 P 0 ;0
L 1.50413996 -2.12086998 1.58796004 -2.12086998 0 P 0 ;0
L 1.50406004 -2.11986998 1.58971004 -2.11986998 0 P 0 ;0
L 1.50396998 -2.11886998 1.59118002 -2.11886998 0 P 0 ;0
L 1.50388996 -2.11786998 1.5926 -2.11786998 0 P 0 ;0
L 1.50381004 -2.11686998 1.59386004 -2.11686998 0 P 0 ;0
L 1.50371998 -2.11586998 1.59496998 -2.11586998 0 P 0 ;0
L 1.50363996 -2.11486998 1.59601004 -2.11486998 0 P 0 ;0
L 1.50355 -2.11386998 1.59696998 -2.11386998 0 P 0 ;0
L 1.50346998 -2.11286998 1.59781004 -2.11286998 0 P 0 ;0
L 1.50338002 -2.11186998 1.5986 -2.11186998 0 P 0 ;0
L 1.5033 -2.11086998 1.59933002 -2.11086998 0 P 0 ;0
L 1.50321004 -2.10986998 1.60005 -2.10986998 0 P 0 ;0
L 1.50313002 -2.10886998 1.60066998 -2.10886998 0 P 0 ;0
L 1.50305 -2.10786998 1.60128002 -2.10786998 0 P 0 ;0
L 1.50296004 -2.10686998 1.60185 -2.10686998 0 P 0 ;0
L 1.50288002 -2.10586998 1.60236004 -2.10586998 0 P 0 ;0
L 1.50278996 -2.10486998 1.60286998 -2.10486998 0 P 0 ;0
L 1.50271004 -2.10386998 1.6033 -2.10386998 0 P 0 ;0
L 1.50263002 -2.10286998 1.60371004 -2.10286998 0 P 0 ;0
L 1.50255 -2.10186998 1.60405 -2.10186998 0 P 0 ;0
L 1.50246998 -2.10086998 1.60436004 -2.10086998 0 P 0 ;0
L 1.50238996 -2.09986998 1.60463002 -2.09986998 0 P 0 ;0
L 1.50231004 -2.09886998 1.60485 -2.09886998 0 P 0 ;0
L 1.50223002 -2.09786998 1.60505 -2.09786998 0 P 0 ;0
L 1.50215 -2.09686998 1.60518002 -2.09686998 0 P 0 ;0
L 1.50206998 -2.09586998 1.60531998 -2.09586998 0 P 0 ;0
L 1.50198996 -2.09486998 1.60545 -2.09486998 0 P 0 ;0
L 1.50191004 -2.09386998 1.60558002 -2.09386998 0 P 0 ;0
L 1.50183002 -2.09286998 1.60563002 -2.09286998 0 P 0 ;0
L 1.50175 -2.09186998 1.53725 -2.09186998 0 P 0 ;0
L 1.54638996 -2.09186998 1.60568996 -2.09186998 0 P 0 ;0
L 1.50166998 -2.09086998 1.5295 -2.09086998 0 P 0 ;0
L 1.54956998 -2.09086998 1.60573996 -2.09086998 0 P 0 ;0
L 1.50158996 -2.08986998 1.52436004 -2.08986998 0 P 0 ;0
L 1.55125 -2.08986998 1.60578996 -2.08986998 0 P 0 ;0
L 1.50151004 -2.08886998 1.52021004 -2.08886998 0 P 0 ;0
L 1.55226998 -2.08886998 1.60576998 -2.08886998 0 P 0 ;0
L 1.50143002 -2.08786998 1.51633002 -2.08786998 0 P 0 ;0
L 1.55298002 -2.08786998 1.60573996 -2.08786998 0 P 0 ;0
L 1.50133996 -2.08686998 1.51246004 -2.08686998 0 P 0 ;0
L 1.55346998 -2.08686998 1.60571998 -2.08686998 0 P 0 ;0
L 1.50126998 -2.08586998 1.50861998 -2.08586998 0 P 0 ;0
L 1.55375 -2.08586998 1.60568996 -2.08586998 0 P 0 ;0
L 1.50118002 -2.08486998 1.50481004 -2.08486998 0 P 0 ;0
L 1.55383002 -2.08486998 1.60558996 -2.08486998 0 P 0 ;0
L 1.55371998 -2.08386998 1.60548996 -2.08386998 0 P 0 ;0
L 1.54886998 -2.12886998 1.53358996 -2.12823996 0 P 0 ;0
L 1.53358996 -2.12823996 1.52631998 -2.12746998 0 P 0 ;0
L 1.52631998 -2.12746998 1.51906004 -2.12636998 0 P 0 ;0
L 1.51906004 -2.12636998 1.51363002 -2.12541004 0 P 0 ;0
L 1.51363002 -2.12541004 1.50886998 -2.12451998 0 P 0 ;0
L 1.50886998 -2.12451998 1.50483996 -2.12373996 0 P 0 ;0
L 1.50483996 -2.12373996 1.50448996 -2.12365 0 P 0 ;0
L 1.50448996 -2.12365 1.50438002 -2.12361004 0 P 0 ;0
L 1.50438002 -2.12361004 1.5027 -2.10378002 0 P 0 ;0
L 1.5027 -2.10378002 1.50111998 -2.08403002 0 P 0 ;0
L 1.50111998 -2.08403002 1.50263996 -2.08433996 0 P 0 ;0
L 1.50263996 -2.08433996 1.50581004 -2.08511004 0 P 0 ;0
L 1.50581004 -2.08511004 1.50955 -2.08611998 0 P 0 ;0
L 1.50955 -2.08611998 1.52306004 -2.08961004 0 P 0 ;0
L 1.52306004 -2.08961004 1.52311004 -2.08961998 0 P 0 ;0
L 1.52311004 -2.08961998 1.52875 -2.09076004 0 P 0 ;0
L 1.52875 -2.09076004 1.5288 -2.09076004 0 P 0 ;0
L 1.5288 -2.09076004 1.53443996 -2.09161004 0 P 0 ;0
L 1.53443996 -2.09161004 1.53893996 -2.09203002 0 P 0 ;0
L 1.53893996 -2.09203002 1.54346004 -2.09216998 0 P 0 ;0
L 1.54346004 -2.09216998 1.54473996 -2.09211004 0 P 0 ;0
L 1.54473996 -2.09211004 1.54603002 -2.09195 0 P 0 ;0
L 1.54603002 -2.09195 1.54728996 -2.09166998 0 P 0 ;0
L 1.54728996 -2.09166998 1.54853002 -2.09128996 0 P 0 ;0
L 1.54853002 -2.09128996 1.54973002 -2.09081004 0 P 0 ;0
L 1.54973002 -2.09081004 1.55026998 -2.09053996 0 P 0 ;0
L 1.55026998 -2.09053996 1.55076998 -2.09023002 0 P 0 ;0
L 1.55076998 -2.09023002 1.55118002 -2.08991998 0 P 0 ;0
L 1.55118002 -2.08991998 1.55118002 -2.08991004 0 P 0 ;0
L 1.55118002 -2.08991004 1.5512 -2.08991004 0 P 0 ;0
L 1.5512 -2.08991004 1.55125 -2.08986998 0 P 0 ;0
L 1.55125 -2.08986998 1.55131004 -2.08981998 0 P 0 ;0
L 1.55131004 -2.08981998 1.55126998 -2.08978002 0 P 0 ;0
L 1.55126998 -2.08978002 1.55136004 -2.08978002 0 P 0 ;0
L 1.55136004 -2.08978002 1.5517 -2.08948996 0 P 0 ;0
L 1.5517 -2.08948996 1.55206004 -2.08911998 0 P 0 ;0
L 1.55206004 -2.08911998 1.55205 -2.08911004 0 P 0 ;0
L 1.55205 -2.08911004 1.55206004 -2.08911004 0 P 0 ;0
L 1.55206004 -2.08911004 1.55211998 -2.08906004 0 P 0 ;0
L 1.55211998 -2.08906004 1.55248996 -2.08861004 0 P 0 ;0
L 1.55248996 -2.08861004 1.55283996 -2.08811998 0 P 0 ;0
L 1.55283996 -2.08811998 1.55313996 -2.08761004 0 P 0 ;0
L 1.55313996 -2.08761004 1.5534 -2.08706998 0 P 0 ;0
L 1.5534 -2.08706998 1.55356004 -2.08663002 0 P 0 ;0
L 1.55356004 -2.08663002 1.55368996 -2.08618996 0 P 0 ;0
L 1.55368996 -2.08618996 1.55376998 -2.08573996 0 P 0 ;0
L 1.55376998 -2.08573996 1.55378002 -2.08565 0 P 0 ;0
L 1.55378002 -2.08565 1.55381998 -2.08528002 0 P 0 ;0
L 1.55381998 -2.08528002 1.55383002 -2.08481998 0 P 0 ;0
L 1.55383002 -2.08481998 1.5538 -2.08436998 0 P 0 ;0
L 1.5538 -2.08436998 1.55373002 -2.08391998 0 P 0 ;0
L 1.55373002 -2.08391998 1.55361998 -2.08346998 0 P 0 ;0
L 1.55361998 -2.08346998 1.55348002 -2.08303996 0 P 0 ;0
L 1.55348002 -2.08303996 1.5533 -2.08261004 0 P 0 ;0
L 1.5533 -2.08261004 1.55308996 -2.08221004 0 P 0 ;0
L 1.55308996 -2.08221004 1.55283996 -2.08183002 0 P 0 ;0
L 1.55283996 -2.08183002 1.55175 -2.0804 0 P 0 ;0
L 1.55175 -2.0804 1.55055 -2.07908002 0 P 0 ;0
L 1.55055 -2.07908002 1.54926004 -2.07783996 0 P 0 ;0
L 1.54926004 -2.07783996 1.54788996 -2.07671998 0 P 0 ;0
L 1.54788996 -2.07671998 1.53706998 -2.06898002 0 P 0 ;0
L 1.53706998 -2.06898002 1.52085 -2.05713996 0 P 0 ;0
L 1.52085 -2.05713996 1.51766004 -2.05445 0 P 0 ;0
L 1.51766004 -2.05445 1.51468002 -2.05153996 0 P 0 ;0
L 1.51468002 -2.05153996 1.51191998 -2.04841998 0 P 0 ;0
L 1.51191998 -2.04841998 1.51048996 -2.04651998 0 P 0 ;0
L 1.51048996 -2.04651998 1.50923002 -2.04453002 0 P 0 ;0
L 1.50923002 -2.04453002 1.50813996 -2.04245 0 P 0 ;0
L 1.50813996 -2.04245 1.50721998 -2.04026004 0 P 0 ;0
L 1.50721998 -2.04026004 1.50643002 -2.03788002 0 P 0 ;0
L 1.50643002 -2.03788002 1.50581004 -2.03545 0 P 0 ;0
L 1.50581004 -2.03545 1.50536004 -2.03298996 0 P 0 ;0
L 1.50536004 -2.03298996 1.50508996 -2.0305 0 P 0 ;0
L 1.50508996 -2.0305 1.50498996 -2.02745 0 P 0 ;0
L 1.50498996 -2.02745 1.50513996 -2.02443996 0 P 0 ;0
L 1.50513996 -2.02443996 1.50551998 -2.02145 0 P 0 ;0
L 1.50551998 -2.02145 1.50613996 -2.0185 0 P 0 ;0
L 1.50613996 -2.0185 1.50698996 -2.01561004 0 P 0 ;0
L 1.50698996 -2.01561004 1.50783002 -2.01341004 0 P 0 ;0
L 1.50783002 -2.01341004 1.50883002 -2.0113 0 P 0 ;0
L 1.50883002 -2.0113 1.51 -2.00928002 0 P 0 ;0
L 1.51 -2.00928002 1.51133002 -2.00736004 0 P 0 ;0
L 1.51133002 -2.00736004 1.5128 -2.00555 0 P 0 ;0
L 1.5128 -2.00555 1.5144 -2.00386004 0 P 0 ;0
L 1.5144 -2.00386004 1.51675 -2.00176998 0 P 0 ;0
L 1.51675 -2.00176998 1.51923002 -1.9999 0 P 0 ;0
L 1.51923002 -1.9999 1.52186004 -1.99823996 0 P 0 ;0
L 1.52186004 -1.99823996 1.52461998 -1.99681004 0 P 0 ;0
L 1.52461998 -1.99681004 1.52748996 -1.99561004 0 P 0 ;0
L 1.52748996 -1.99561004 1.53353002 -1.99363996 0 P 0 ;0
L 1.53353002 -1.99363996 1.5397 -1.99218002 0 P 0 ;0
L 1.5397 -1.99218002 1.54598002 -1.99123002 0 P 0 ;0
L 1.54598002 -1.99123002 1.55181004 -1.99075 0 P 0 ;0
L 1.55181004 -1.99075 1.55763002 -1.99061998 0 P 0 ;0
L 1.55763002 -1.99061998 1.57273002 -1.99113996 0 P 0 ;0
L 1.57273002 -1.99113996 1.58755 -1.99248996 0 P 0 ;0
L 1.58755 -1.99248996 1.59293002 -1.99331998 0 P 0 ;0
L 1.59293002 -1.99331998 1.59821004 -1.99448996 0 P 0 ;0
L 1.59821004 -1.99448996 1.59905 -1.99473002 0 P 0 ;0
L 1.59905 -1.99473002 1.59986004 -1.99501998 0 P 0 ;0
L 1.59986004 -1.99501998 1.60008002 -1.99511998 0 P 0 ;0
L 1.60008002 -1.99511998 1.6003 -1.99523002 0 P 0 ;0
L 1.6003 -1.99523002 1.60051004 -1.99536004 0 P 0 ;0
L 1.60051004 -1.99536004 1.60071004 -1.9955 0 P 0 ;0
L 1.60071004 -1.9955 1.60083002 -1.99561004 0 P 0 ;0
L 1.60083002 -1.99561004 1.60093996 -1.99571004 0 P 0 ;0
L 1.60093996 -1.99571004 1.60103996 -1.99583002 0 P 0 ;0
L 1.60103996 -1.99583002 1.60111998 -1.99595 0 P 0 ;0
L 1.60111998 -1.99595 1.60116998 -1.99601998 0 P 0 ;0
L 1.60116998 -1.99601998 1.60121004 -1.99611004 0 P 0 ;0
L 1.60121004 -1.99611004 1.60125 -1.99621004 0 P 0 ;0
L 1.60125 -1.99621004 1.60128002 -1.9963 0 P 0 ;0
L 1.60128002 -1.9963 1.60131004 -1.99641004 0 P 0 ;0
L 1.60131004 -1.99641004 1.6017 -1.99861998 0 P 0 ;0
L 1.6017 -1.99861998 1.60195 -2.00086998 0 P 0 ;0
L 1.60195 -2.00086998 1.60308002 -2.01593002 0 P 0 ;0
L 1.60308002 -2.01593002 1.60415 -2.03096998 0 P 0 ;0
L 1.60415 -2.03096998 1.60345 -2.03083996 0 P 0 ;0
L 1.60345 -2.03083996 1.60058996 -2.03026004 0 P 0 ;0
L 1.60058996 -2.03026004 1.59723002 -2.02948002 0 P 0 ;0
L 1.59723002 -2.02948002 1.59721998 -2.02948002 0 P 0 ;0
L 1.59721998 -2.02948002 1.59306998 -2.0286 0 P 0 ;0
L 1.59306998 -2.0286 1.58776004 -2.02776998 0 P 0 ;0
L 1.58776004 -2.02776998 1.58226004 -2.02708002 0 P 0 ;0
L 1.58226004 -2.02708002 1.57738002 -2.02666998 0 P 0 ;0
L 1.57738002 -2.02666998 1.5709 -2.02633996 0 P 0 ;0
L 1.5709 -2.02633996 1.56918996 -2.02635 0 P 0 ;0
L 1.56918996 -2.02635 1.56746998 -2.02648996 0 P 0 ;0
L 1.56746998 -2.02648996 1.56678996 -2.02658996 0 P 0 ;0
L 1.56678996 -2.02658996 1.56611998 -2.02673996 0 P 0 ;0
L 1.56611998 -2.02673996 1.56546004 -2.02695 0 P 0 ;0
L 1.56546004 -2.02695 1.56481998 -2.0272 0 P 0 ;0
L 1.56481998 -2.0272 1.56418996 -2.0275 0 P 0 ;0
L 1.56418996 -2.0275 1.56358002 -2.02785 0 P 0 ;0
L 1.56358002 -2.02785 1.563 -2.02823002 0 P 0 ;0
L 1.563 -2.02823002 1.56245 -2.02865 0 P 0 ;0
L 1.56245 -2.02865 1.56206998 -2.02898996 0 P 0 ;0
L 1.56206998 -2.02898996 1.56171004 -2.02936004 0 P 0 ;0
L 1.56171004 -2.02936004 1.56138002 -2.02976004 0 P 0 ;0
L 1.56138002 -2.02976004 1.56108996 -2.03018996 0 P 0 ;0
L 1.56108996 -2.03018996 1.56083002 -2.03063996 0 P 0 ;0
L 1.56083002 -2.03063996 1.56061998 -2.0311 0 P 0 ;0
L 1.56061998 -2.0311 1.56043996 -2.03158996 0 P 0 ;0
L 1.56043996 -2.03158996 1.5603 -2.03208002 0 P 0 ;0
L 1.5603 -2.03208002 1.5602 -2.0326 0 P 0 ;0
L 1.5602 -2.0326 1.56015 -2.03308002 0 P 0 ;0
L 1.56015 -2.03308002 1.56013996 -2.03353996 0 P 0 ;0
L 1.56013996 -2.03353996 1.56016004 -2.03391004 0 P 0 ;0
L 1.56016004 -2.03391004 1.56048002 -2.03391004 0 P 0 ;0
L 1.56048002 -2.03391004 1.56016004 -2.03393002 0 P 0 ;0
L 1.56016004 -2.03393002 1.56016998 -2.03401004 0 P 0 ;0
L 1.56016998 -2.03401004 1.56023002 -2.03448002 0 P 0 ;0
L 1.56023002 -2.03448002 1.56025 -2.03456004 0 P 0 ;0
L 1.56025 -2.03456004 1.56033002 -2.03493002 0 P 0 ;0
L 1.56033002 -2.03493002 1.56046998 -2.03538002 0 P 0 ;0
L 1.56046998 -2.03538002 1.56063996 -2.03581998 0 P 0 ;0
L 1.56063996 -2.03581998 1.56085 -2.03623996 0 P 0 ;0
L 1.56085 -2.03623996 1.56108996 -2.03663996 0 P 0 ;0
L 1.56108996 -2.03663996 1.56136004 -2.03701998 0 P 0 ;0
L 1.56136004 -2.03701998 1.56233002 -2.03818996 0 P 0 ;0
L 1.56233002 -2.03818996 1.56336998 -2.03928996 0 P 0 ;0
L 1.56336998 -2.03928996 1.56448002 -2.04031004 0 P 0 ;0
L 1.56448002 -2.04031004 1.56566004 -2.04123996 0 P 0 ;0
L 1.56566004 -2.04123996 1.57471004 -2.04761998 0 P 0 ;0
L 1.57471004 -2.04761998 1.58461998 -2.05491004 0 P 0 ;0
L 1.58461998 -2.05491004 1.58898996 -2.05858996 0 P 0 ;0
L 1.58898996 -2.05858996 1.59315 -2.06245 0 P 0 ;0
L 1.59315 -2.06245 1.59656998 -2.06596998 0 P 0 ;0
L 1.59656998 -2.06596998 1.59976004 -2.06965 0 P 0 ;0
L 1.59976004 -2.06965 1.60116004 -2.07151004 0 P 0 ;0
L 1.60116004 -2.07151004 1.60238002 -2.07346004 0 P 0 ;0
L 1.60238002 -2.07346004 1.60341998 -2.0755 0 P 0 ;0
L 1.60341998 -2.0755 1.60403996 -2.077 0 P 0 ;0
L 1.60403996 -2.077 1.60456004 -2.07853996 0 P 0 ;0
L 1.60456004 -2.07853996 1.60496004 -2.08011004 0 P 0 ;0
L 1.60496004 -2.08011004 1.60525 -2.0817 0 P 0 ;0
L 1.60525 -2.0817 1.60568996 -2.08578002 0 P 0 ;0
L 1.60568996 -2.08578002 1.60578996 -2.08988002 0 P 0 ;0
L 1.60578996 -2.08988002 1.60556998 -2.09403002 0 P 0 ;0
L 1.60556998 -2.09403002 1.60501004 -2.09813996 0 P 0 ;0
L 1.60501004 -2.09813996 1.60451998 -2.10036998 0 P 0 ;0
L 1.60451998 -2.10036998 1.60383996 -2.10253996 0 P 0 ;0
L 1.60383996 -2.10253996 1.60298996 -2.10465 0 P 0 ;0
L 1.60298996 -2.10465 1.60163996 -2.1073 0 P 0 ;0
L 1.60163996 -2.1073 1.60008002 -2.10983002 0 P 0 ;0
L 1.60008002 -2.10983002 1.59833002 -2.11225 0 P 0 ;0
L 1.59833002 -2.11225 1.59696998 -2.11386998 0 P 0 ;0
L 1.59696998 -2.11386998 1.59551004 -2.11538996 0 P 0 ;0
L 1.59551004 -2.11538996 1.59395 -2.1168 0 P 0 ;0
L 1.59395 -2.1168 1.59231004 -2.11811004 0 P 0 ;0
L 1.59231004 -2.11811004 1.58973002 -2.11986004 0 P 0 ;0
L 1.58973002 -2.11986004 1.58701998 -2.1214 0 P 0 ;0
L 1.58701998 -2.1214 1.5842 -2.12273002 0 P 0 ;0
L 1.5842 -2.12273002 1.5788 -2.1248 0 P 0 ;0
L 1.5788 -2.1248 1.57326998 -2.12648996 0 P 0 ;0
L 1.57326998 -2.12648996 1.56983002 -2.12731004 0 P 0 ;0
L 1.56983002 -2.12731004 1.56638002 -2.12791004 0 P 0 ;0
L 1.56638002 -2.12791004 1.56288996 -2.1283 0 P 0 ;0
L 1.56288996 -2.1283 1.54886998 -2.12886998 0 P 0 ;0
L 1.35851998 -2.06545 1.47866004 -2.06545 0 P 0 ;0
L 1.35936004 -2.06445 1.47871004 -2.06445 0 P 0 ;0
L 1.36041004 -2.06345 1.47875 -2.06345 0 P 0 ;0
L 1.36163996 -2.06245 1.4788 -2.06245 0 P 0 ;0
L 1.36293996 -2.06145 1.47883996 -2.06145 0 P 0 ;0
L 1.36436004 -2.06045 1.47888996 -2.06045 0 P 0 ;0
L 1.36598002 -2.05945 1.47893996 -2.05945 0 P 0 ;0
L 1.36776004 -2.05845 1.47898996 -2.05845 0 P 0 ;0
L 1.36971004 -2.05745 1.47903002 -2.05745 0 P 0 ;0
L 1.37166004 -2.05645 1.47908002 -2.05645 0 P 0 ;0
L 1.37391004 -2.05545 1.47911998 -2.05545 0 P 0 ;0
L 1.37616998 -2.05445 1.47916998 -2.05445 0 P 0 ;0
L 1.37873002 -2.05345 1.47921004 -2.05345 0 P 0 ;0
L 1.38136004 -2.05245 1.47926004 -2.05245 0 P 0 ;0
L 1.36875 -2.03345 1.37108996 -2.03345 0 P 0 ;0
L 1.36886004 -2.03245 1.37385 -2.03245 0 P 0 ;0
L 1.36896998 -2.03145 1.37678002 -2.03145 0 P 0 ;0
L 1.36908996 -2.03045 1.3797 -2.03045 0 P 0 ;0
L 1.36921004 -2.02945 1.38261998 -2.02945 0 P 0 ;0
L 1.36933002 -2.02845 1.38638996 -2.02845 0 P 0 ;0
L 1.36946004 -2.02745 1.39023996 -2.02745 0 P 0 ;0
L 1.36958002 -2.02645 1.39503002 -2.02645 0 P 0 ;0
L 1.3697 -2.02545 1.40068002 -2.02545 0 P 0 ;0
L 1.36981998 -2.02445 1.41053996 -2.02445 0 P 0 ;0
L 1.36993996 -2.02345 1.47993996 -2.02345 0 P 0 ;0
L 1.37008002 -2.02245 1.47988002 -2.02245 0 P 0 ;0
L 1.37021004 -2.02145 1.47978002 -2.02145 0 P 0 ;0
L 1.37033996 -2.02045 1.47968002 -2.02045 0 P 0 ;0
L 1.37046998 -2.01945 1.47953002 -2.01945 0 P 0 ;0
L 1.3706 -2.01845 1.47936004 -2.01845 0 P 0 ;0
L 1.37073002 -2.01745 1.47918002 -2.01745 0 P 0 ;0
L 1.37086004 -2.01645 1.47893002 -2.01645 0 P 0 ;0
L 1.37098996 -2.01545 1.47868002 -2.01545 0 P 0 ;0
L 1.37113002 -2.01445 1.4784 -2.01445 0 P 0 ;0
L 1.37126998 -2.01345 1.47806004 -2.01345 0 P 0 ;0
L 1.3714 -2.01245 1.47773002 -2.01245 0 P 0 ;0
L 1.37153996 -2.01145 1.47733002 -2.01145 0 P 0 ;0
L 1.37168002 -2.01045 1.47691004 -2.01045 0 P 0 ;0
L 1.37181004 -2.00945 1.47641004 -2.00945 0 P 0 ;0
L 1.37195 -2.00845 1.47588996 -2.00845 0 P 0 ;0
L 1.37208002 -2.00745 1.47528002 -2.00745 0 P 0 ;0
L 1.37221004 -2.00645 1.47463996 -2.00645 0 P 0 ;0
L 1.37235 -2.00545 1.47391998 -2.00545 0 P 0 ;0
L 1.37248996 -2.00445 1.47311004 -2.00445 0 P 0 ;0
L 1.37261998 -2.00345 1.47225 -2.00345 0 P 0 ;0
L 1.37276004 -2.00245 1.47126998 -2.00245 0 P 0 ;0
L 1.3729 -2.00145 1.4702 -2.00145 0 P 0 ;0
L 1.37303002 -2.00045 1.46903996 -2.00045 0 P 0 ;0
L 1.37316998 -1.99945 1.46775 -1.99945 0 P 0 ;0
L 1.3733 -1.99845 1.46625 -1.99845 0 P 0 ;0
L 1.37343996 -1.99745 1.46455 -1.99745 0 P 0 ;0
L 1.37356998 -1.99645 1.46253996 -1.99645 0 P 0 ;0
L 1.37753002 -1.99545 1.46041004 -1.99545 0 P 0 ;0
L 1.38218996 -1.99445 1.45781004 -1.99445 0 P 0 ;0
L 1.42925 -2.08345 1.47785 -2.08345 0 P 0 ;0
L 1.42931998 -2.08245 1.47788996 -2.08245 0 P 0 ;0
L 1.42938002 -2.08145 1.47793002 -2.08145 0 P 0 ;0
L 1.42945 -2.08045 1.47796998 -2.08045 0 P 0 ;0
L 1.42951004 -2.07945 1.47801004 -2.07945 0 P 0 ;0
L 1.42958002 -2.07845 1.47806004 -2.07845 0 P 0 ;0
L 1.42963996 -2.07745 1.4781 -2.07745 0 P 0 ;0
L 1.4297 -2.07645 1.47815 -2.07645 0 P 0 ;0
L 1.42976998 -2.07545 1.4782 -2.07545 0 P 0 ;0
L 1.42983002 -2.07445 1.47825 -2.07445 0 P 0 ;0
L 1.4299 -2.07345 1.47828996 -2.07345 0 P 0 ;0
L 1.42963996 -2.07245 1.47833996 -2.07245 0 P 0 ;0
L 1.42918996 -2.07145 1.47838002 -2.07145 0 P 0 ;0
L 1.38425 -2.05145 1.47931004 -2.05145 0 P 0 ;0
L 1.38731998 -2.05045 1.47933996 -2.05045 0 P 0 ;0
L 1.39088002 -2.04945 1.47938002 -2.04945 0 P 0 ;0
L 1.3947 -2.04845 1.47941004 -2.04845 0 P 0 ;0
L 1.39851004 -2.04745 1.47945 -2.04745 0 P 0 ;0
L 1.40233002 -2.04645 1.47948002 -2.04645 0 P 0 ;0
L 1.40608002 -2.04545 1.47951004 -2.04545 0 P 0 ;0
L 1.40983002 -2.04445 1.47955 -2.04445 0 P 0 ;0
L 1.41306998 -2.04345 1.47958996 -2.04345 0 P 0 ;0
L 1.41591998 -2.04245 1.47961998 -2.04245 0 P 0 ;0
L 1.41876998 -2.04145 1.47965 -2.04145 0 P 0 ;0
L 1.42133996 -2.04045 1.47968996 -2.04045 0 P 0 ;0
L 1.42361998 -2.03945 1.47971998 -2.03945 0 P 0 ;0
L 1.42591004 -2.03845 1.47975 -2.03845 0 P 0 ;0
L 1.42805 -2.03745 1.47978002 -2.03745 0 P 0 ;0
L 1.42936004 -2.03645 1.47981004 -2.03645 0 P 0 ;0
L 1.43003002 -2.03545 1.47983002 -2.03545 0 P 0 ;0
L 1.43081998 -2.03445 1.47986004 -2.03445 0 P 0 ;0
L 1.43121004 -2.03345 1.47988002 -2.03345 0 P 0 ;0
L 1.43141998 -2.03245 1.4799 -2.03245 0 P 0 ;0
L 1.43146998 -2.03145 1.47993002 -2.03145 0 P 0 ;0
L 1.43136004 -2.03045 1.47996004 -2.03045 0 P 0 ;0
L 1.43108002 -2.02945 1.47998002 -2.02945 0 P 0 ;0
L 1.4306 -2.02845 1.48001004 -2.02845 0 P 0 ;0
L 1.42986998 -2.02745 1.48001004 -2.02745 0 P 0 ;0
L 1.42875 -2.02645 1.47998996 -2.02645 0 P 0 ;0
L 1.42658996 -2.02545 1.47996998 -2.02545 0 P 0 ;0
L 1.42203996 -2.02445 1.47996004 -2.02445 0 P 0 ;0
L 1.38748002 -1.99345 1.45483002 -1.99345 0 P 0 ;0
L 1.39331998 -1.99245 1.45108996 -1.99245 0 P 0 ;0
L 1.40051004 -1.99145 1.44503002 -1.99145 0 P 0 ;0
L 1.38096998 -2.12745 1.4051 -2.12745 0 P 0 ;0
L 1.37671004 -2.12645 1.41113996 -2.12645 0 P 0 ;0
L 1.3736 -2.12545 1.41238996 -2.12545 0 P 0 ;0
L 1.37096998 -2.12445 1.41268002 -2.12445 0 P 0 ;0
L 1.36876998 -2.12345 1.41296998 -2.12345 0 P 0 ;0
L 1.36685 -2.12245 1.41326998 -2.12245 0 P 0 ;0
L 1.36516004 -2.12145 1.41356004 -2.12145 0 P 0 ;0
L 1.36366004 -2.12045 1.41385 -2.12045 0 P 0 ;0
L 1.36225 -2.11945 1.41413996 -2.11945 0 P 0 ;0
L 1.361 -2.11845 1.41443002 -2.11845 0 P 0 ;0
L 1.35983002 -2.11745 1.41471998 -2.11745 0 P 0 ;0
L 1.35876004 -2.11645 1.41501004 -2.11645 0 P 0 ;0
L 1.42661998 -2.12445 1.47693002 -2.12445 0 P 0 ;0
L 1.42665 -2.12345 1.47693002 -2.12345 0 P 0 ;0
L 1.4267 -2.12245 1.47693002 -2.12245 0 P 0 ;0
L 1.42675 -2.12145 1.47693002 -2.12145 0 P 0 ;0
L 1.42681004 -2.12045 1.47693002 -2.12045 0 P 0 ;0
L 1.42686998 -2.11945 1.47693002 -2.11945 0 P 0 ;0
L 1.42691998 -2.11845 1.47693002 -2.11845 0 P 0 ;0
L 1.42698996 -2.11745 1.47693002 -2.11745 0 P 0 ;0
L 1.42705 -2.11645 1.47693002 -2.11645 0 P 0 ;0
L 1.42711004 -2.11545 1.47693002 -2.11545 0 P 0 ;0
L 1.42716998 -2.11445 1.47693002 -2.11445 0 P 0 ;0
L 1.42723002 -2.11345 1.47693996 -2.11345 0 P 0 ;0
L 1.4273 -2.11245 1.47695 -2.11245 0 P 0 ;0
L 1.42736998 -2.11145 1.47696004 -2.11145 0 P 0 ;0
L 1.42743996 -2.11045 1.47698002 -2.11045 0 P 0 ;0
L 1.42751004 -2.10945 1.47698996 -2.10945 0 P 0 ;0
L 1.42758002 -2.10845 1.47701004 -2.10845 0 P 0 ;0
L 1.42765 -2.10745 1.47703002 -2.10745 0 P 0 ;0
L 1.42771004 -2.10645 1.47703996 -2.10645 0 P 0 ;0
L 1.42778002 -2.10545 1.47706998 -2.10545 0 P 0 ;0
L 1.42783996 -2.10445 1.4771 -2.10445 0 P 0 ;0
L 1.42791004 -2.10345 1.47713002 -2.10345 0 P 0 ;0
L 1.42798002 -2.10245 1.47716004 -2.10245 0 P 0 ;0
L 1.42805 -2.10145 1.4772 -2.10145 0 P 0 ;0
L 1.42811004 -2.10045 1.47723002 -2.10045 0 P 0 ;0
L 1.40953002 -2.09945 1.41973002 -2.09945 0 P 0 ;0
L 1.42818002 -2.09945 1.47726004 -2.09945 0 P 0 ;0
L 1.41618002 -2.09845 1.41996998 -2.09845 0 P 0 ;0
L 1.42825 -2.09845 1.47728996 -2.09845 0 P 0 ;0
L 1.42831998 -2.09745 1.47733002 -2.09745 0 P 0 ;0
L 1.42838996 -2.09645 1.47736004 -2.09645 0 P 0 ;0
L 1.42846004 -2.09545 1.47738996 -2.09545 0 P 0 ;0
L 1.42851998 -2.09445 1.47741998 -2.09445 0 P 0 ;0
L 1.42858996 -2.09345 1.47746004 -2.09345 0 P 0 ;0
L 1.42866004 -2.09245 1.4775 -2.09245 0 P 0 ;0
L 1.42873002 -2.09145 1.47753996 -2.09145 0 P 0 ;0
L 1.42878996 -2.09045 1.47758002 -2.09045 0 P 0 ;0
L 1.42886004 -2.08945 1.47761998 -2.08945 0 P 0 ;0
L 1.42893002 -2.08845 1.47766004 -2.08845 0 P 0 ;0
L 1.42898996 -2.08745 1.4777 -2.08745 0 P 0 ;0
L 1.42906004 -2.08645 1.47773002 -2.08645 0 P 0 ;0
L 1.42911998 -2.08545 1.47776998 -2.08545 0 P 0 ;0
L 1.42918996 -2.08445 1.47781004 -2.08445 0 P 0 ;0
L 1.61686004 -2.17995 1.66846004 -2.17995 0 P 0 ;0
L 1.61591004 -2.17895 1.67158996 -2.17895 0 P 0 ;0
L 1.61553996 -2.17795 1.67431998 -2.17795 0 P 0 ;0
L 1.61526998 -2.17695 1.67675 -2.17695 0 P 0 ;0
L 1.61508002 -2.17595 1.67903996 -2.17595 0 P 0 ;0
L 1.61496998 -2.17495 1.68108002 -2.17495 0 P 0 ;0
L 1.61491004 -2.17395 1.68295 -2.17395 0 P 0 ;0
L 1.61485 -2.17295 1.68458996 -2.17295 0 P 0 ;0
L 1.61478996 -2.17195 1.6861 -2.17195 0 P 0 ;0
L 1.61473002 -2.17095 1.6875 -2.17095 0 P 0 ;0
L 1.61466998 -2.16995 1.68876998 -2.16995 0 P 0 ;0
L 1.61461004 -2.16895 1.68998002 -2.16895 0 P 0 ;0
L 1.61455 -2.16795 1.69108002 -2.16795 0 P 0 ;0
L 1.61448996 -2.16695 1.69211998 -2.16695 0 P 0 ;0
L 1.61443002 -2.16595 1.69316004 -2.16595 0 P 0 ;0
L 1.61436998 -2.16495 1.69411998 -2.16495 0 P 0 ;0
L 1.61431004 -2.16395 1.69498996 -2.16395 0 P 0 ;0
L 1.61425 -2.16295 1.69586004 -2.16295 0 P 0 ;0
L 1.61418996 -2.16195 1.69673002 -2.16195 0 P 0 ;0
L 1.61413002 -2.16095 1.69746998 -2.16095 0 P 0 ;0
L 1.61406998 -2.15995 1.6982 -2.15995 0 P 0 ;0
L 1.61401998 -2.15895 1.69893996 -2.15895 0 P 0 ;0
L 1.61396998 -2.15795 1.69963002 -2.15795 0 P 0 ;0
L 1.64433002 -2.18295 1.63151004 -2.18271004 0 P 0 ;0
L 1.63151004 -2.18271004 1.62658002 -2.18226998 0 P 0 ;0
L 1.62658002 -2.18226998 1.62168996 -2.18146998 0 P 0 ;0
L 1.62168996 -2.18146998 1.6201 -2.1811 0 P 0 ;0
L 1.6201 -2.1811 1.61853996 -2.18061004 0 P 0 ;0
L 1.61853996 -2.18061004 1.61701004 -2.18001998 0 P 0 ;0
L 1.61701004 -2.18001998 1.61686004 -2.17995 0 P 0 ;0
L 1.61686004 -2.17995 1.61671004 -2.17986998 0 P 0 ;0
L 1.61671004 -2.17986998 1.61656998 -2.17976998 0 P 0 ;0
L 1.61656998 -2.17976998 1.61643996 -2.17966998 0 P 0 ;0
L 1.61643996 -2.17966998 1.61631998 -2.17955 0 P 0 ;0
L 1.61631998 -2.17955 1.61621004 -2.17943002 0 P 0 ;0
L 1.61621004 -2.17943002 1.6161 -2.1793 0 P 0 ;0
L 1.6161 -2.1793 1.61601004 -2.17915 0 P 0 ;0
L 1.61601004 -2.17915 1.61593002 -2.179 0 P 0 ;0
L 1.61593002 -2.179 1.61586004 -2.17885 0 P 0 ;0
L 1.61586004 -2.17885 1.61553002 -2.17791004 0 P 0 ;0
L 1.61553002 -2.17791004 1.61526998 -2.17696004 0 P 0 ;0
L 1.61526998 -2.17696004 1.61508996 -2.17598996 0 P 0 ;0
L 1.61508996 -2.17598996 1.61496998 -2.17496998 0 P 0 ;0
L 1.61496998 -2.17496998 1.61408002 -2.16011004 0 P 0 ;0
L 1.61408002 -2.16011004 1.61341998 -2.14758996 0 P 0 ;0
L 1.61341998 -2.14758996 1.6202 -2.14821004 0 P 0 ;0
L 1.6202 -2.14821004 1.62023002 -2.14821004 0 P 0 ;0
L 1.62023002 -2.14821004 1.63216998 -2.14893996 0 P 0 ;0
L 1.63216998 -2.14893996 1.6349 -2.14893002 0 P 0 ;0
L 1.6349 -2.14893002 1.63761998 -2.14873002 0 P 0 ;0
L 1.63761998 -2.14873002 1.64031998 -2.14835 0 P 0 ;0
L 1.64031998 -2.14835 1.64198996 -2.14798996 0 P 0 ;0
L 1.64198996 -2.14798996 1.64363002 -2.14751998 0 P 0 ;0
L 1.64363002 -2.14751998 1.64523002 -2.14693002 0 P 0 ;0
L 1.64523002 -2.14693002 1.64678996 -2.14623002 0 P 0 ;0
L 1.64678996 -2.14623002 1.64888002 -2.14506998 0 P 0 ;0
L 1.64888002 -2.14506998 1.65086998 -2.14376004 0 P 0 ;0
L 1.65086998 -2.14376004 1.65093996 -2.14371004 0 P 0 ;0
L 1.65093996 -2.14371004 1.65275 -2.14228996 0 P 0 ;0
L 1.65275 -2.14228996 1.6539 -2.14123996 0 P 0 ;0
L 1.6539 -2.14123996 1.65496004 -2.14011004 0 P 0 ;0
L 1.65496004 -2.14011004 1.65591998 -2.13891004 0 P 0 ;0
L 1.65591998 -2.13891004 1.65755 -2.13653996 0 P 0 ;0
L 1.65755 -2.13653996 1.65901998 -2.13415 0 P 0 ;0
L 1.65901998 -2.13415 1.65903002 -2.13413002 0 P 0 ;0
L 1.65903002 -2.13413002 1.66035 -2.13171998 0 P 0 ;0
L 1.66035 -2.13171998 1.66155 -2.12925 0 P 0 ;0
L 1.66155 -2.12925 1.66183996 -2.12851998 0 P 0 ;0
L 1.66183996 -2.12851998 1.66206998 -2.12776004 0 P 0 ;0
L 1.66206998 -2.12776004 1.66223996 -2.12696998 0 P 0 ;0
L 1.66223996 -2.12696998 1.66233996 -2.12618002 0 P 0 ;0
L 1.66233996 -2.12618002 1.66236998 -2.12538996 0 P 0 ;0
L 1.66236998 -2.12538996 1.66233002 -2.12436004 0 P 0 ;0
L 1.66233002 -2.12436004 1.66221004 -2.12335 0 P 0 ;0
L 1.66221004 -2.12335 1.662 -2.12235 0 P 0 ;0
L 1.662 -2.12235 1.66171004 -2.12141004 0 P 0 ;0
L 1.66171004 -2.12141004 1.64438996 -2.07113002 0 P 0 ;0
L 1.64438996 -2.07113002 1.62871998 -2.02606004 0 P 0 ;0
L 1.62871998 -2.02606004 1.62116004 -2.00558996 0 P 0 ;0
L 1.62116004 -2.00558996 1.62116004 -2.00556998 0 P 0 ;0
L 1.62116004 -2.00556998 1.61681004 -1.99443996 0 P 0 ;0
L 1.61681004 -1.99443996 1.67163002 -1.99443996 0 P 0 ;0
L 1.67163002 -1.99443996 1.67301004 -2.00076004 0 P 0 ;0
L 1.67301004 -2.00076004 1.67613002 -2.01341998 0 P 0 ;0
L 1.67613002 -2.01341998 1.68331004 -2.03931998 0 P 0 ;0
L 1.68331004 -2.03931998 1.69153002 -2.06856998 0 P 0 ;0
L 1.69153002 -2.06856998 1.6916 -2.06876004 0 P 0 ;0
L 1.6916 -2.06876004 1.69168996 -2.06896998 0 P 0 ;0
L 1.69168996 -2.06896998 1.69181004 -2.06918002 0 P 0 ;0
L 1.69181004 -2.06918002 1.69193002 -2.06936998 0 P 0 ;0
L 1.69193002 -2.06936998 1.69208002 -2.06956004 0 P 0 ;0
L 1.69208002 -2.06956004 1.69223996 -2.06973002 0 P 0 ;0
L 1.69223996 -2.06973002 1.69241998 -2.06988002 0 P 0 ;0
L 1.69241998 -2.06988002 1.6926 -2.07001998 0 P 0 ;0
L 1.6926 -2.07001998 1.6928 -2.07015 0 P 0 ;0
L 1.6928 -2.07015 1.69301004 -2.07025 0 P 0 ;0
L 1.69301004 -2.07025 1.69323002 -2.07033996 0 P 0 ;0
L 1.69323002 -2.07033996 1.69346004 -2.07041004 0 P 0 ;0
L 1.69346004 -2.07041004 1.69368002 -2.07045 0 P 0 ;0
L 1.69368002 -2.07045 1.69391998 -2.07048002 0 P 0 ;0
L 1.69391998 -2.07048002 1.69413996 -2.07048996 0 P 0 ;0
L 1.69413996 -2.07048996 1.6944 -2.07048002 0 P 0 ;0
L 1.6944 -2.07048002 1.69465 -2.07045 0 P 0 ;0
L 1.69465 -2.07045 1.69488996 -2.07038996 0 P 0 ;0
L 1.69488996 -2.07038996 1.69513996 -2.07031998 0 P 0 ;0
L 1.69513996 -2.07031998 1.69536998 -2.07021998 0 P 0 ;0
L 1.69536998 -2.07021998 1.69558996 -2.0701 0 P 0 ;0
L 1.69558996 -2.0701 1.69581004 -2.06996998 0 P 0 ;0
L 1.69581004 -2.06996998 1.69601004 -2.06981998 0 P 0 ;0
L 1.69601004 -2.06981998 1.6962 -2.06965 0 P 0 ;0
L 1.6962 -2.06965 1.69636998 -2.06946004 0 P 0 ;0
L 1.69636998 -2.06946004 1.69653002 -2.06926004 0 P 0 ;0
L 1.69653002 -2.06926004 1.69666004 -2.06905 0 P 0 ;0
L 1.69666004 -2.06905 1.69678996 -2.06883002 0 P 0 ;0
L 1.69678996 -2.06883002 1.69688002 -2.0686 0 P 0 ;0
L 1.69688002 -2.0686 1.69695 -2.0684 0 P 0 ;0
L 1.69695 -2.0684 1.70426004 -2.04365 0 P 0 ;0
L 1.70426004 -2.04365 1.70426004 -2.04363002 0 P 0 ;0
L 1.70426004 -2.04363002 1.71066998 -2.0213 0 P 0 ;0
L 1.71066998 -2.0213 1.71068002 -2.02126004 0 P 0 ;0
L 1.71068002 -2.02126004 1.71431998 -2.00693996 0 P 0 ;0
L 1.71431998 -2.00693996 1.71706004 -1.99496998 0 P 0 ;0
L 1.71706004 -1.99496998 1.74335 -1.9947 0 P 0 ;0
L 1.74335 -1.9947 1.75403002 -1.99461004 0 P 0 ;0
L 1.75403002 -1.99461004 1.76301004 -1.99465 0 P 0 ;0
L 1.76301004 -1.99465 1.76886004 -1.99471004 0 P 0 ;0
L 1.76886004 -1.99471004 1.76883996 -1.99476004 0 P 0 ;0
L 1.76883996 -1.99476004 1.74021004 -2.06556004 0 P 0 ;0
L 1.74021004 -2.06556004 1.71298002 -2.13276998 0 P 0 ;0
L 1.71298002 -2.13276998 1.70836998 -2.14293996 0 P 0 ;0
L 1.70836998 -2.14293996 1.70413996 -2.15076004 0 P 0 ;0
L 1.70413996 -2.15076004 1.69941998 -2.15828996 0 P 0 ;0
L 1.69941998 -2.15828996 1.6967 -2.16198996 0 P 0 ;0
L 1.6967 -2.16198996 1.6937 -2.16541998 0 P 0 ;0
L 1.6937 -2.16541998 1.69041998 -2.1686 0 P 0 ;0
L 1.69041998 -2.1686 1.68793996 -2.17063002 0 P 0 ;0
L 1.68793996 -2.17063002 1.68535 -2.17248002 0 P 0 ;0
L 1.68535 -2.17248002 1.68263996 -2.17413996 0 P 0 ;0
L 1.68263996 -2.17413996 1.67981004 -2.17561004 0 P 0 ;0
L 1.67981004 -2.17561004 1.67525 -2.17761004 0 P 0 ;0
L 1.67525 -2.17761004 1.6706 -2.17931998 0 P 0 ;0
L 1.6706 -2.17931998 1.66586004 -2.18073002 0 P 0 ;0
L 1.66586004 -2.18073002 1.66141998 -2.1817 0 P 0 ;0
L 1.66141998 -2.1817 1.65691998 -2.18228996 0 P 0 ;0
L 1.65691998 -2.18228996 1.64433002 -2.18295 0 P 0 ;0
L 1.61928996 -2.00628002 1.62683996 -2.02673002 0 P 0 ;0
L 1.62683996 -2.02673002 1.6425 -2.07178002 0 P 0 ;0
L 1.6425 -2.07178002 1.65981004 -2.12201998 0 P 0 ;0
L 1.65981004 -2.12201998 1.66006004 -2.12283996 0 P 0 ;0
L 1.66006004 -2.12283996 1.66023002 -2.12368002 0 P 0 ;0
L 1.66023002 -2.12368002 1.66033996 -2.12451998 0 P 0 ;0
L 1.66033996 -2.12451998 1.66036998 -2.12538002 0 P 0 ;0
L 1.66036998 -2.12538002 1.66033996 -2.12601004 0 P 0 ;0
L 1.66033996 -2.12601004 1.66026998 -2.12663996 0 P 0 ;0
L 1.66026998 -2.12663996 1.66013996 -2.12725 0 P 0 ;0
L 1.66013996 -2.12725 1.65995 -2.12786004 0 P 0 ;0
L 1.65995 -2.12786004 1.65971004 -2.12843996 0 P 0 ;0
L 1.65971004 -2.12843996 1.65856998 -2.1308 0 P 0 ;0
L 1.65856998 -2.1308 1.6573 -2.13313002 0 P 0 ;0
L 1.6573 -2.13313002 1.65586998 -2.13545 0 P 0 ;0
L 1.65586998 -2.13545 1.65431004 -2.13771998 0 P 0 ;0
L 1.65431004 -2.13771998 1.65343996 -2.1388 0 P 0 ;0
L 1.65343996 -2.1388 1.65248996 -2.13981998 0 P 0 ;0
L 1.65248996 -2.13981998 1.65146004 -2.14076004 0 P 0 ;0
L 1.65146004 -2.14076004 1.64971004 -2.14213002 0 P 0 ;0
L 1.64971004 -2.14213002 1.64785 -2.14336004 0 P 0 ;0
L 1.64785 -2.14336004 1.64588996 -2.14443996 0 P 0 ;0
L 1.64588996 -2.14443996 1.64446998 -2.14508002 0 P 0 ;0
L 1.64446998 -2.14508002 1.64301004 -2.14561998 0 P 0 ;0
L 1.64301004 -2.14561998 1.64151004 -2.14605 0 P 0 ;0
L 1.64151004 -2.14605 1.63996998 -2.14636998 0 P 0 ;0
L 1.63996998 -2.14636998 1.63741004 -2.14673996 0 P 0 ;0
L 1.63741004 -2.14673996 1.63483002 -2.14693002 0 P 0 ;0
L 1.63483002 -2.14693002 1.63223002 -2.14693996 0 P 0 ;0
L 1.63223002 -2.14693996 1.62036004 -2.14621998 0 P 0 ;0
L 1.62036004 -2.14621998 1.6113 -2.14538002 0 P 0 ;0
L 1.6113 -2.14538002 1.61208996 -2.16023002 0 P 0 ;0
L 1.61208996 -2.16023002 1.61298002 -2.17515 0 P 0 ;0
L 1.61298002 -2.17515 1.6131 -2.17628002 0 P 0 ;0
L 1.6131 -2.17628002 1.61331998 -2.17741004 0 P 0 ;0
L 1.61331998 -2.17741004 1.61361998 -2.17851004 0 P 0 ;0
L 1.61361998 -2.17851004 1.614 -2.17958996 0 P 0 ;0
L 1.614 -2.17958996 1.61413996 -2.17988996 0 P 0 ;0
L 1.61413996 -2.17988996 1.61428996 -2.18018002 0 P 0 ;0
L 1.61428996 -2.18018002 1.61446998 -2.18045 0 P 0 ;0
L 1.61446998 -2.18045 1.61466998 -2.18071004 0 P 0 ;0
L 1.61466998 -2.18071004 1.61488996 -2.18095 0 P 0 ;0
L 1.61488996 -2.18095 1.61511998 -2.18116998 0 P 0 ;0
L 1.61511998 -2.18116998 1.61538002 -2.18138002 0 P 0 ;0
L 1.61538002 -2.18138002 1.61565 -2.18156004 0 P 0 ;0
L 1.61565 -2.18156004 1.61593002 -2.18173002 0 P 0 ;0
L 1.61593002 -2.18173002 1.61623002 -2.18186004 0 P 0 ;0
L 1.61623002 -2.18186004 1.61788002 -2.1825 0 P 0 ;0
L 1.61788002 -2.1825 1.61956998 -2.18301998 0 P 0 ;0
L 1.61956998 -2.18301998 1.6213 -2.18343002 0 P 0 ;0
L 1.6213 -2.18343002 1.62633002 -2.18426004 0 P 0 ;0
L 1.62633002 -2.18426004 1.6314 -2.18471004 0 P 0 ;0
L 1.6314 -2.18471004 1.64436004 -2.18495 0 P 0 ;0
L 1.64436004 -2.18495 1.65711004 -2.18428002 0 P 0 ;0
L 1.65711004 -2.18428002 1.66176998 -2.18366998 0 P 0 ;0
L 1.66176998 -2.18366998 1.66636004 -2.18266998 0 P 0 ;0
L 1.66636004 -2.18266998 1.67123002 -2.18121004 0 P 0 ;0
L 1.67123002 -2.18121004 1.676 -2.17946998 0 P 0 ;0
L 1.676 -2.17946998 1.68068002 -2.17741998 0 P 0 ;0
L 1.68068002 -2.17741998 1.68361998 -2.17588002 0 P 0 ;0
L 1.68361998 -2.17588002 1.68646004 -2.17415 0 P 0 ;0
L 1.68646004 -2.17415 1.68916004 -2.17221998 0 P 0 ;0
L 1.68916004 -2.17221998 1.69175 -2.17008996 0 P 0 ;0
L 1.69175 -2.17008996 1.69515 -2.1668 0 P 0 ;0
L 1.69515 -2.1668 1.69826004 -2.16323996 0 P 0 ;0
L 1.69826004 -2.16323996 1.70108002 -2.15941998 0 P 0 ;0
L 1.70108002 -2.15941998 1.70586004 -2.15176998 0 P 0 ;0
L 1.70586004 -2.15176998 1.71016004 -2.14383002 0 P 0 ;0
L 1.71016004 -2.14383002 1.71481998 -2.13356004 0 P 0 ;0
L 1.71481998 -2.13356004 1.74206998 -2.06631004 0 P 0 ;0
L 1.74206998 -2.06631004 1.77071004 -1.99548002 0 P 0 ;0
L 1.77071004 -1.99548002 1.77088002 -1.99498996 0 P 0 ;0
L 1.77088002 -1.99498996 1.77101998 -1.99448996 0 P 0 ;0
L 1.77101998 -1.99448996 1.77111998 -1.99398996 0 P 0 ;0
L 1.77111998 -1.99398996 1.77118002 -1.99346998 0 P 0 ;0
L 1.77118002 -1.99346998 1.7712 -1.99295 0 P 0 ;0
L 1.7712 -1.99295 1.7712 -1.99293002 0 P 0 ;0
L 1.7712 -1.99293002 1.77118996 -1.99286998 0 P 0 ;0
L 1.77118996 -1.99286998 1.77118002 -1.99286004 0 P 0 ;0
L 1.77118002 -1.99286004 1.77118002 -1.99283996 0 P 0 ;0
L 1.77118002 -1.99283996 1.77111004 -1.99276998 0 P 0 ;0
L 1.77111004 -1.99276998 1.77106998 -1.99275 0 P 0 ;0
L 1.77106998 -1.99275 1.77106004 -1.99273996 0 P 0 ;0
L 1.77106004 -1.99273996 1.771 -1.99273002 0 P 0 ;0
L 1.771 -1.99273002 1.77098002 -1.99273002 0 P 0 ;0
L 1.77098002 -1.99273002 1.76301004 -1.99265 0 P 0 ;0
L 1.76301004 -1.99265 1.75401998 -1.99261004 0 P 0 ;0
L 1.75401998 -1.99261004 1.74333002 -1.9927 0 P 0 ;0
L 1.74333002 -1.9927 1.71546004 -1.99298996 0 P 0 ;0
L 1.71546004 -1.99298996 1.71236998 -2.00646998 0 P 0 ;0
L 1.71236998 -2.00646998 1.70873996 -2.02078002 0 P 0 ;0
L 1.70873996 -2.02078002 1.70233996 -2.04308002 0 P 0 ;0
L 1.70233996 -2.04308002 1.69505 -2.0678 0 P 0 ;0
L 1.69505 -2.0678 1.69501998 -2.06788002 0 P 0 ;0
L 1.69501998 -2.06788002 1.69498996 -2.06795 0 P 0 ;0
L 1.69498996 -2.06795 1.69495 -2.06801998 0 P 0 ;0
L 1.69495 -2.06801998 1.69485 -2.06816004 0 P 0 ;0
L 1.69485 -2.06816004 1.69478996 -2.06821998 0 P 0 ;0
L 1.69478996 -2.06821998 1.69466998 -2.06831998 0 P 0 ;0
L 1.69466998 -2.06831998 1.69453002 -2.0684 0 P 0 ;0
L 1.69453002 -2.0684 1.69445 -2.06843002 0 P 0 ;0
L 1.69445 -2.06843002 1.69438002 -2.06846004 0 P 0 ;0
L 1.69438002 -2.06846004 1.69428996 -2.06846998 0 P 0 ;0
L 1.69428996 -2.06846998 1.69421004 -2.06848996 0 P 0 ;0
L 1.69421004 -2.06848996 1.69406998 -2.06848996 0 P 0 ;0
L 1.69406998 -2.06848996 1.69395 -2.06846998 0 P 0 ;0
L 1.69395 -2.06846998 1.69383002 -2.06843002 0 P 0 ;0
L 1.69383002 -2.06843002 1.69373002 -2.06836998 0 P 0 ;0
L 1.69373002 -2.06836998 1.69363002 -2.06828996 0 P 0 ;0
L 1.69363002 -2.06828996 1.69358996 -2.06823996 0 P 0 ;0
L 1.69358996 -2.06823996 1.69355 -2.0682 0 P 0 ;0
L 1.69355 -2.0682 1.69351998 -2.06815 0 P 0 ;0
L 1.69351998 -2.06815 1.69346004 -2.06803996 0 P 0 ;0
L 1.69346004 -2.06803996 1.69343996 -2.06798002 0 P 0 ;0
L 1.69343996 -2.06798002 1.68523002 -2.03878002 0 P 0 ;0
L 1.68523002 -2.03878002 1.67806998 -2.01291998 0 P 0 ;0
L 1.67806998 -2.01291998 1.67496004 -2.00031004 0 P 0 ;0
L 1.67496004 -2.00031004 1.67323002 -1.99243996 0 P 0 ;0
L 1.67323002 -1.99243996 1.61388002 -1.99243996 0 P 0 ;0
L 1.61388002 -1.99243996 1.61928996 -2.00628002 0 P 0 ;0
L 1.35018002 -2.08345 1.39488996 -2.08345 0 P 0 ;0
L 1.35026004 -2.08245 1.39586004 -2.08245 0 P 0 ;0
L 1.35041004 -2.08145 1.39708996 -2.08145 0 P 0 ;0
L 1.35058996 -2.08045 1.39853002 -2.08045 0 P 0 ;0
L 1.35083996 -2.07945 1.40031998 -2.07945 0 P 0 ;0
L 1.35116998 -2.07845 1.40271004 -2.07845 0 P 0 ;0
L 1.35158002 -2.07745 1.40561998 -2.07745 0 P 0 ;0
L 1.35203002 -2.07645 1.4092 -2.07645 0 P 0 ;0
L 1.35248002 -2.07545 1.41288996 -2.07545 0 P 0 ;0
L 1.35293002 -2.07445 1.4164 -2.07445 0 P 0 ;0
L 1.35338996 -2.07345 1.41975 -2.07345 0 P 0 ;0
L 1.35393996 -2.07245 1.42293996 -2.07245 0 P 0 ;0
L 1.35448996 -2.07145 1.42606998 -2.07145 0 P 0 ;0
L 1.35505 -2.07045 1.47843002 -2.07045 0 P 0 ;0
L 1.3557 -2.06945 1.47846998 -2.06945 0 P 0 ;0
L 1.35635 -2.06845 1.47851998 -2.06845 0 P 0 ;0
L 1.35701998 -2.06745 1.47856998 -2.06745 0 P 0 ;0
L 1.35776998 -2.06645 1.47861004 -2.06645 0 P 0 ;0
L 1.29346998 -2.00516004 1.33388996 -2.00516004 0 P 0 ;0
L 1.29448996 -2.00416004 1.33385 -2.00416004 0 P 0 ;0
L 1.29551004 -2.00316004 1.33381004 -2.00316004 0 P 0 ;0
L 1.29653996 -2.00216004 1.33376004 -2.00216004 0 P 0 ;0
L 1.29756004 -2.00116004 1.33371004 -2.00116004 0 P 0 ;0
L 1.29861998 -2.00016004 1.33366004 -2.00016004 0 P 0 ;0
L 1.29973002 -1.99916004 1.3336 -1.99916004 0 P 0 ;0
L 1.30101004 -1.99816004 1.33355 -1.99816004 0 P 0 ;0
L 1.30238996 -1.99716004 1.3335 -1.99716004 0 P 0 ;0
L 1.30393996 -1.99616004 1.33345 -1.99616004 0 P 0 ;0
L 1.30571004 -1.99516004 1.33338996 -1.99516004 0 P 0 ;0
L 1.3077 -1.99416004 1.33333002 -1.99416004 0 P 0 ;0
L 1.31001004 -1.99316004 1.33328002 -1.99316004 0 P 0 ;0
L 1.31288002 -1.99216004 1.33321998 -1.99216004 0 P 0 ;0
L 1.31688996 -1.99116004 1.33316004 -1.99116004 0 P 0 ;0
L 1.39798996 -1.98971998 1.39326998 -1.99043002 0 P 0 ;0
L 1.39326998 -1.99043002 1.38806998 -1.9913 0 P 0 ;0
L 1.38806998 -1.9913 1.38316004 -1.9922 0 P 0 ;0
L 1.38316004 -1.9922 1.37946004 -1.99296998 0 P 0 ;0
L 1.37946004 -1.99296998 1.3718 -1.99466998 0 P 0 ;0
L 1.3718 -1.99466998 1.36896004 -2.01553996 0 P 0 ;0
L 1.36896004 -2.01553996 1.36791004 -2.02358996 0 P 0 ;0
L 1.36791004 -2.02358996 1.36708002 -2.03043002 0 P 0 ;0
L 1.36708002 -2.03043002 1.36638996 -2.03646004 0 P 0 ;0
L 1.36638996 -2.03646004 1.36638002 -2.03648996 0 P 0 ;0
L 1.36638002 -2.03648996 1.36638996 -2.03653002 0 P 0 ;0
L 1.36638996 -2.03653002 1.36638996 -2.03656998 0 P 0 ;0
L 1.36638996 -2.03656998 1.3664 -2.03663996 0 P 0 ;0
L 1.3664 -2.03663996 1.36641998 -2.03666998 0 P 0 ;0
L 1.36641998 -2.03666998 1.36643002 -2.03671004 0 P 0 ;0
L 1.36643002 -2.03671004 1.36648996 -2.0368 0 P 0 ;0
L 1.36648996 -2.0368 1.36656004 -2.03686004 0 P 0 ;0
L 1.36656004 -2.03686004 1.3666 -2.03688996 0 P 0 ;0
L 1.3666 -2.03688996 1.36663002 -2.03691004 0 P 0 ;0
L 1.36663002 -2.03691004 1.36666004 -2.03691004 0 P 0 ;0
L 1.36666004 -2.03691004 1.36671004 -2.03693002 0 P 0 ;0
L 1.36671004 -2.03693002 1.36676998 -2.03693002 0 P 0 ;0
L 1.36676998 -2.03693002 1.36685 -2.03691998 0 P 0 ;0
L 1.36685 -2.03691998 1.36895 -2.03628002 0 P 0 ;0
L 1.36895 -2.03628002 1.37143002 -2.03545 0 P 0 ;0
L 1.37143002 -2.03545 1.37428996 -2.03441004 0 P 0 ;0
L 1.37428996 -2.03441004 1.38346004 -2.03126998 0 P 0 ;0
L 1.38346004 -2.03126998 1.39251998 -2.02891998 0 P 0 ;0
L 1.39251998 -2.02891998 1.40156004 -2.02731998 0 P 0 ;0
L 1.40156004 -2.02731998 1.41068002 -2.02643996 0 P 0 ;0
L 1.41068002 -2.02643996 1.41566998 -2.02628002 0 P 0 ;0
L 1.41566998 -2.02628002 1.42066004 -2.02633996 0 P 0 ;0
L 1.42066004 -2.02633996 1.42221004 -2.02646998 0 P 0 ;0
L 1.42221004 -2.02646998 1.42375 -2.02671998 0 P 0 ;0
L 1.42375 -2.02671998 1.42525 -2.0271 0 P 0 ;0
L 1.42525 -2.0271 1.42671998 -2.02761004 0 P 0 ;0
L 1.42671998 -2.02761004 1.42706004 -2.02776004 0 P 0 ;0
L 1.42706004 -2.02776004 1.42738002 -2.02793002 0 P 0 ;0
L 1.42738002 -2.02793002 1.42768002 -2.02813996 0 P 0 ;0
L 1.42768002 -2.02813996 1.42796998 -2.02836004 0 P 0 ;0
L 1.42796998 -2.02836004 1.42823002 -2.02861004 0 P 0 ;0
L 1.42823002 -2.02861004 1.42848002 -2.02888996 0 P 0 ;0
L 1.42848002 -2.02888996 1.4287 -2.02918002 0 P 0 ;0
L 1.4287 -2.02918002 1.42888996 -2.02948996 0 P 0 ;0
L 1.42888996 -2.02948996 1.42906004 -2.02981004 0 P 0 ;0
L 1.42906004 -2.02981004 1.4292 -2.03015 0 P 0 ;0
L 1.4292 -2.03015 1.42931998 -2.0305 0 P 0 ;0
L 1.42931998 -2.0305 1.4294 -2.03086004 0 P 0 ;0
L 1.4294 -2.03086004 1.42945 -2.03121998 0 P 0 ;0
L 1.42945 -2.03121998 1.42946998 -2.03158002 0 P 0 ;0
L 1.42946998 -2.03158002 1.42946004 -2.03195 0 P 0 ;0
L 1.42946004 -2.03195 1.42941998 -2.03231004 0 P 0 ;0
L 1.42941998 -2.03231004 1.42935 -2.03266998 0 P 0 ;0
L 1.42935 -2.03266998 1.42925 -2.03301998 0 P 0 ;0
L 1.42925 -2.03301998 1.42911998 -2.03336004 0 P 0 ;0
L 1.42911998 -2.03336004 1.42896004 -2.03368996 0 P 0 ;0
L 1.42896004 -2.03368996 1.42875 -2.03405 0 P 0 ;0
L 1.42875 -2.03405 1.42851004 -2.03438996 0 P 0 ;0
L 1.42851004 -2.03438996 1.42825 -2.03471004 0 P 0 ;0
L 1.42825 -2.03471004 1.42796004 -2.03501004 0 P 0 ;0
L 1.42796004 -2.03501004 1.42765 -2.03528996 0 P 0 ;0
L 1.42765 -2.03528996 1.42731998 -2.03553996 0 P 0 ;0
L 1.42731998 -2.03553996 1.42696998 -2.03576004 0 P 0 ;0
L 1.42696998 -2.03576004 1.4266 -2.03596004 0 P 0 ;0
L 1.4266 -2.03596004 1.41951004 -2.03906004 0 P 0 ;0
L 1.41951004 -2.03906004 1.4109 -2.04208996 0 P 0 ;0
L 1.4109 -2.04208996 1.40178002 -2.04451998 0 P 0 ;0
L 1.40178002 -2.04451998 1.3878 -2.04818996 0 P 0 ;0
L 1.3878 -2.04818996 1.38176998 -2.05015 0 P 0 ;0
L 1.38176998 -2.05015 1.3758 -2.05243002 0 P 0 ;0
L 1.3758 -2.05243002 1.37086998 -2.0546 0 P 0 ;0
L 1.37086998 -2.0546 1.36603996 -2.05708002 0 P 0 ;0
L 1.36603996 -2.05708002 1.36356004 -2.05856004 0 P 0 ;0
L 1.36356004 -2.05856004 1.36118996 -2.06023002 0 P 0 ;0
L 1.36118996 -2.06023002 1.35895 -2.06206004 0 P 0 ;0
L 1.35895 -2.06206004 1.35805 -2.06291004 0 P 0 ;0
L 1.35805 -2.06291004 1.35721998 -2.06385 0 P 0 ;0
L 1.35721998 -2.06385 1.35518996 -2.06655 0 P 0 ;0
L 1.35518996 -2.06655 1.3532 -2.06961998 0 P 0 ;0
L 1.3532 -2.06961998 1.35156004 -2.07263002 0 P 0 ;0
L 1.35156004 -2.07263002 1.34951004 -2.07718002 0 P 0 ;0
L 1.34951004 -2.07718002 1.34911004 -2.07825 0 P 0 ;0
L 1.34911004 -2.07825 1.34878996 -2.07935 0 P 0 ;0
L 1.34878996 -2.07935 1.34853002 -2.08046998 0 P 0 ;0
L 1.34853002 -2.08046998 1.34825 -2.08238002 0 P 0 ;0
L 1.34825 -2.08238002 1.34811998 -2.08431004 0 P 0 ;0
L 1.34811998 -2.08431004 1.348 -2.09128996 0 P 0 ;0
L 1.348 -2.09128996 1.3481 -2.09761004 0 P 0 ;0
L 1.3481 -2.09761004 1.34823002 -2.09961004 0 P 0 ;0
L 1.34823002 -2.09961004 1.34846998 -2.10161004 0 P 0 ;0
L 1.34846998 -2.10161004 1.34876998 -2.10321998 0 P 0 ;0
L 1.34876998 -2.10321998 1.3492 -2.10478996 0 P 0 ;0
L 1.3492 -2.10478996 1.3498 -2.10648996 0 P 0 ;0
L 1.3498 -2.10648996 1.3505 -2.10815 0 P 0 ;0
L 1.3505 -2.10815 1.35178996 -2.11066004 0 P 0 ;0
L 1.35178996 -2.11066004 1.35328002 -2.11305 0 P 0 ;0
L 1.35328002 -2.11305 1.35496998 -2.1153 0 P 0 ;0
L 1.35496998 -2.1153 1.35685 -2.1174 0 P 0 ;0
L 1.35685 -2.1174 1.35891998 -2.11933996 0 P 0 ;0
L 1.35891998 -2.11933996 1.36126998 -2.12121998 0 P 0 ;0
L 1.36126998 -2.12121998 1.36373996 -2.12293002 0 P 0 ;0
L 1.36373996 -2.12293002 1.36633002 -2.12446004 0 P 0 ;0
L 1.36633002 -2.12446004 1.36901004 -2.1258 0 P 0 ;0
L 1.36901004 -2.1258 1.3718 -2.12695 0 P 0 ;0
L 1.3718 -2.12695 1.37578996 -2.12828002 0 P 0 ;0
L 1.37578996 -2.12828002 1.37986998 -2.12928996 0 P 0 ;0
L 1.37986998 -2.12928996 1.38401998 -2.12998996 0 P 0 ;0
L 1.38401998 -2.12998996 1.3882 -2.13036004 0 P 0 ;0
L 1.3882 -2.13036004 1.39443002 -2.13045 0 P 0 ;0
L 1.39443002 -2.13045 1.40066004 -2.13006998 0 P 0 ;0
L 1.40066004 -2.13006998 1.40685 -2.12923002 0 P 0 ;0
L 1.40685 -2.12923002 1.41371004 -2.12801998 0 P 0 ;0
L 1.41371004 -2.12801998 1.41583002 -2.12081004 0 P 0 ;0
L 1.41583002 -2.12081004 1.41953996 -2.10798996 0 P 0 ;0
L 1.41953996 -2.10798996 1.42135 -2.10126998 0 P 0 ;0
L 1.42135 -2.10126998 1.42236998 -2.097 0 P 0 ;0
L 1.42236998 -2.097 1.42238996 -2.09691004 0 P 0 ;0
L 1.42238996 -2.09691004 1.4224 -2.09681998 0 P 0 ;0
L 1.4224 -2.09681998 1.4224 -2.09673996 0 P 0 ;0
L 1.4224 -2.09673996 1.42238002 -2.09656004 0 P 0 ;0
L 1.42238002 -2.09656004 1.42235 -2.09648002 0 P 0 ;0
L 1.42235 -2.09648002 1.42233002 -2.09638996 0 P 0 ;0
L 1.42233002 -2.09638996 1.42225 -2.09623002 0 P 0 ;0
L 1.42225 -2.09623002 1.4222 -2.09616004 0 P 0 ;0
L 1.4222 -2.09616004 1.42213996 -2.09608996 0 P 0 ;0
L 1.42213996 -2.09608996 1.42208996 -2.09601998 0 P 0 ;0
L 1.42208996 -2.09601998 1.42203996 -2.09598996 0 P 0 ;0
L 1.42203996 -2.09598996 1.42198996 -2.09595 0 P 0 ;0
L 1.42198996 -2.09595 1.42188996 -2.09588996 0 P 0 ;0
L 1.42188996 -2.09588996 1.42183002 -2.09586004 0 P 0 ;0
L 1.42183002 -2.09586004 1.42178002 -2.09585 0 P 0 ;0
L 1.42178002 -2.09585 1.42171998 -2.09583002 0 P 0 ;0
L 1.42171998 -2.09583002 1.42166004 -2.09581998 0 P 0 ;0
L 1.42166004 -2.09581998 1.42153996 -2.09581998 0 P 0 ;0
L 1.42153996 -2.09581998 1.41978002 -2.09591004 0 P 0 ;0
L 1.41978002 -2.09591004 1.41763996 -2.09615 0 P 0 ;0
L 1.41763996 -2.09615 1.41521998 -2.09658002 0 P 0 ;0
L 1.41521998 -2.09658002 1.4107 -2.09733002 0 P 0 ;0
L 1.4107 -2.09733002 1.40613002 -2.09775 0 P 0 ;0
L 1.40613002 -2.09775 1.40481004 -2.09778002 0 P 0 ;0
L 1.40481004 -2.09778002 1.40348996 -2.09771998 0 P 0 ;0
L 1.40348996 -2.09771998 1.40216998 -2.09756004 0 P 0 ;0
L 1.40216998 -2.09756004 1.40086998 -2.0973 0 P 0 ;0
L 1.40086998 -2.0973 1.39958996 -2.09695 0 P 0 ;0
L 1.39958996 -2.09695 1.39895 -2.09671998 0 P 0 ;0
L 1.39895 -2.09671998 1.39831998 -2.09643002 0 P 0 ;0
L 1.39831998 -2.09643002 1.39773002 -2.0961 0 P 0 ;0
L 1.39773002 -2.0961 1.39716004 -2.09571004 0 P 0 ;0
L 1.39716004 -2.09571004 1.39663002 -2.09528002 0 P 0 ;0
L 1.39663002 -2.09528002 1.39613996 -2.0948 0 P 0 ;0
L 1.39613996 -2.0948 1.39568002 -2.09428002 0 P 0 ;0
L 1.39568002 -2.09428002 1.39533996 -2.09381998 0 P 0 ;0
L 1.39533996 -2.09381998 1.39505 -2.09333996 0 P 0 ;0
L 1.39505 -2.09333996 1.39478996 -2.09281998 0 P 0 ;0
L 1.39478996 -2.09281998 1.39456998 -2.09228996 0 P 0 ;0
L 1.39456998 -2.09228996 1.3944 -2.09173996 0 P 0 ;0
L 1.3944 -2.09173996 1.39428002 -2.09118996 0 P 0 ;0
L 1.39428002 -2.09118996 1.39421004 -2.09061998 0 P 0 ;0
L 1.39421004 -2.09061998 1.39418002 -2.09003996 0 P 0 ;0
L 1.39418002 -2.09003996 1.39421004 -2.08943002 0 P 0 ;0
L 1.39421004 -2.08943002 1.39428002 -2.08883002 0 P 0 ;0
L 1.39428002 -2.08883002 1.39441004 -2.08823002 0 P 0 ;0
L 1.39441004 -2.08823002 1.3946 -2.08765 0 P 0 ;0
L 1.3946 -2.08765 1.39483002 -2.08708002 0 P 0 ;0
L 1.39483002 -2.08708002 1.39511004 -2.08653996 0 P 0 ;0
L 1.39511004 -2.08653996 1.39555 -2.08583996 0 P 0 ;0
L 1.39555 -2.08583996 1.39603996 -2.08518002 0 P 0 ;0
L 1.39603996 -2.08518002 1.39658002 -2.08456004 0 P 0 ;0
L 1.39658002 -2.08456004 1.39716004 -2.08396998 0 P 0 ;0
L 1.39716004 -2.08396998 1.39778002 -2.08343002 0 P 0 ;0
L 1.39778002 -2.08343002 1.39878996 -2.08266998 0 P 0 ;0
L 1.39878996 -2.08266998 1.39985 -2.08196998 0 P 0 ;0
L 1.39985 -2.08196998 1.40096004 -2.08135 0 P 0 ;0
L 1.40096004 -2.08135 1.40211998 -2.08081004 0 P 0 ;0
L 1.40211998 -2.08081004 1.40503002 -2.07971004 0 P 0 ;0
L 1.40503002 -2.07971004 1.40801998 -2.07881998 0 P 0 ;0
L 1.40801998 -2.07881998 1.41128996 -2.07796004 0 P 0 ;0
L 1.41128996 -2.07796004 1.41506004 -2.07691998 0 P 0 ;0
L 1.41506004 -2.07691998 1.41871998 -2.07585 0 P 0 ;0
L 1.41871998 -2.07585 1.42165 -2.07495 0 P 0 ;0
L 1.42165 -2.07495 1.42791998 -2.07295 0 P 0 ;0
L 1.42791998 -2.07295 1.42731998 -2.08241004 0 P 0 ;0
L 1.42731998 -2.08241004 1.42701004 -2.08708002 0 P 0 ;0
L 1.42701004 -2.08708002 1.42658002 -2.09353996 0 P 0 ;0
L 1.42658002 -2.09353996 1.4261 -2.10055 0 P 0 ;0
L 1.4261 -2.10055 1.42566998 -2.10706004 0 P 0 ;0
L 1.42566998 -2.10706004 1.42525 -2.11306004 0 P 0 ;0
L 1.42525 -2.11306004 1.42491998 -2.11851998 0 P 0 ;0
L 1.42491998 -2.11851998 1.42466004 -2.1231 0 P 0 ;0
L 1.42466004 -2.1231 1.42461004 -2.12471004 0 P 0 ;0
L 1.42461004 -2.12471004 1.4246 -2.12716004 0 P 0 ;0
L 1.4246 -2.12716004 1.47893002 -2.12716004 0 P 0 ;0
L 1.47893002 -2.12716004 1.47893002 -2.11358002 0 P 0 ;0
L 1.47893002 -2.11358002 1.47905 -2.10616998 0 P 0 ;0
L 1.47905 -2.10616998 1.47943996 -2.09385 0 P 0 ;0
L 1.47943996 -2.09385 1.48 -2.07968996 0 P 0 ;0
L 1.48 -2.07968996 1.48066004 -2.0655 0 P 0 ;0
L 1.48066004 -2.0655 1.4813 -2.05168996 0 P 0 ;0
L 1.4813 -2.05168996 1.48175 -2.03873996 0 P 0 ;0
L 1.48175 -2.03873996 1.48201998 -2.02785 0 P 0 ;0
L 1.48201998 -2.02785 1.48191998 -2.02286004 0 P 0 ;0
L 1.48191998 -2.02286004 1.48165 -2.01995 0 P 0 ;0
L 1.48165 -2.01995 1.48115 -2.01708002 0 P 0 ;0
L 1.48115 -2.01708002 1.48043996 -2.01425 0 P 0 ;0
L 1.48043996 -2.01425 1.47951004 -2.01146998 0 P 0 ;0
L 1.47951004 -2.01146998 1.47866998 -2.00946998 0 P 0 ;0
L 1.47866998 -2.00946998 1.47768002 -2.00753996 0 P 0 ;0
L 1.47768002 -2.00753996 1.47655 -2.00568002 0 P 0 ;0
L 1.47655 -2.00568002 1.47528002 -2.00391998 0 P 0 ;0
L 1.47528002 -2.00391998 1.47388002 -2.00225 0 P 0 ;0
L 1.47388002 -2.00225 1.47228996 -2.00063002 0 P 0 ;0
L 1.47228996 -2.00063002 1.4706 -1.99911998 0 P 0 ;0
L 1.4706 -1.99911998 1.4688 -1.99773002 0 P 0 ;0
L 1.4688 -1.99773002 1.46691004 -1.99648002 0 P 0 ;0
L 1.46691004 -1.99648002 1.46491998 -1.99535 0 P 0 ;0
L 1.46491998 -1.99535 1.46098996 -1.99351004 0 P 0 ;0
L 1.46098996 -1.99351004 1.45693002 -1.99196998 0 P 0 ;0
L 1.45693002 -1.99196998 1.45276004 -1.99076004 0 P 0 ;0
L 1.45276004 -1.99076004 1.44953996 -1.99006004 0 P 0 ;0
L 1.44953996 -1.99006004 1.44628996 -1.98956004 0 P 0 ;0
L 1.44628996 -1.98956004 1.44298002 -1.98923996 0 P 0 ;0
L 1.44298002 -1.98923996 1.42695 -1.98856998 0 P 0 ;0
L 1.42695 -1.98856998 1.41038996 -1.98865 0 P 0 ;0
L 1.41038996 -1.98865 1.4042 -1.98901004 0 P 0 ;0
L 1.4042 -1.98901004 1.39798996 -1.98971998 0 P 0 ;0
L 1.35778996 -2.11545 1.4153 -2.11545 0 P 0 ;0
L 1.35688996 -2.11445 1.41558996 -2.11445 0 P 0 ;0
L 1.35608002 -2.11345 1.41588002 -2.11345 0 P 0 ;0
L 1.35533002 -2.11245 1.41616998 -2.11245 0 P 0 ;0
L 1.35463996 -2.11145 1.41646004 -2.11145 0 P 0 ;0
L 1.35401004 -2.11045 1.41675 -2.11045 0 P 0 ;0
L 1.35341004 -2.10945 1.41703996 -2.10945 0 P 0 ;0
L 1.3529 -2.10845 1.41733002 -2.10845 0 P 0 ;0
L 1.35238002 -2.10745 1.41761998 -2.10745 0 P 0 ;0
L 1.35195 -2.10645 1.41788002 -2.10645 0 P 0 ;0
L 1.35155 -2.10545 1.41816004 -2.10545 0 P 0 ;0
L 1.3512 -2.10445 1.41841998 -2.10445 0 P 0 ;0
L 1.35091004 -2.10345 1.41868996 -2.10345 0 P 0 ;0
L 1.35066004 -2.10245 1.41896004 -2.10245 0 P 0 ;0
L 1.35046998 -2.10145 1.41923002 -2.10145 0 P 0 ;0
L 1.35033996 -2.10045 1.41948996 -2.10045 0 P 0 ;0
L 1.35021998 -2.09945 1.40141004 -2.09945 0 P 0 ;0
L 1.35016004 -2.09845 1.39791004 -2.09845 0 P 0 ;0
L 1.3501 -2.09745 1.39616004 -2.09745 0 P 0 ;0
L 1.35008002 -2.09645 1.39496004 -2.09645 0 P 0 ;0
L 1.35006998 -2.09545 1.39406004 -2.09545 0 P 0 ;0
L 1.35005 -2.09445 1.39338002 -2.09445 0 P 0 ;0
L 1.35003996 -2.09345 1.39288002 -2.09345 0 P 0 ;0
L 1.35001998 -2.09245 1.39253002 -2.09245 0 P 0 ;0
L 1.35001004 -2.09145 1.3923 -2.09145 0 P 0 ;0
L 1.35001998 -2.09045 1.3922 -2.09045 0 P 0 ;0
L 1.35003002 -2.08945 1.3922 -2.08945 0 P 0 ;0
L 1.35005 -2.08845 1.39231998 -2.08845 0 P 0 ;0
L 1.35006998 -2.08745 1.39256004 -2.08745 0 P 0 ;0
L 1.35008002 -2.08645 1.39293002 -2.08645 0 P 0 ;0
L 1.3501 -2.08545 1.39343002 -2.08545 0 P 0 ;0
L 1.35011004 -2.08445 1.39408996 -2.08445 0 P 0 ;0
L 1.39438002 -2.12845 1.3883 -2.12836004 0 P 0 ;0
L 1.3883 -2.12836004 1.38426998 -2.128 0 P 0 ;0
L 1.38426998 -2.128 1.38028002 -2.12733002 0 P 0 ;0
L 1.38028002 -2.12733002 1.37635 -2.12636004 0 P 0 ;0
L 1.37635 -2.12636004 1.37248996 -2.12508002 0 P 0 ;0
L 1.37248996 -2.12508002 1.36983996 -2.12398002 0 P 0 ;0
L 1.36983996 -2.12398002 1.36728996 -2.1227 0 P 0 ;0
L 1.36728996 -2.1227 1.36481998 -2.12123996 0 P 0 ;0
L 1.36481998 -2.12123996 1.36246004 -2.11961004 0 P 0 ;0
L 1.36246004 -2.11961004 1.36023002 -2.11781998 0 P 0 ;0
L 1.36023002 -2.11781998 1.35828996 -2.116 0 P 0 ;0
L 1.35828996 -2.116 1.35651998 -2.11403002 0 P 0 ;0
L 1.35651998 -2.11403002 1.35493002 -2.11191004 0 P 0 ;0
L 1.35493002 -2.11191004 1.35353002 -2.10966998 0 P 0 ;0
L 1.35353002 -2.10966998 1.35231004 -2.10731004 0 P 0 ;0
L 1.35231004 -2.10731004 1.35166998 -2.10576998 0 P 0 ;0
L 1.35166998 -2.10576998 1.35111004 -2.1042 0 P 0 ;0
L 1.35111004 -2.1042 1.35071998 -2.10276004 0 P 0 ;0
L 1.35071998 -2.10276004 1.35045 -2.1013 0 P 0 ;0
L 1.35045 -2.1013 1.35021998 -2.09943002 0 P 0 ;0
L 1.35021998 -2.09943002 1.3501 -2.09753002 0 P 0 ;0
L 1.3501 -2.09753002 1.35001004 -2.09128002 0 P 0 ;0
L 1.35001004 -2.09128002 1.35011998 -2.0844 0 P 0 ;0
L 1.35011998 -2.0844 1.35023996 -2.08258996 0 P 0 ;0
L 1.35023996 -2.08258996 1.3505 -2.08083996 0 P 0 ;0
L 1.3505 -2.08083996 1.35071998 -2.07985 0 P 0 ;0
L 1.35071998 -2.07985 1.35101004 -2.07888002 0 P 0 ;0
L 1.35101004 -2.07888002 1.35136004 -2.07793002 0 P 0 ;0
L 1.35136004 -2.07793002 1.35335 -2.07351998 0 P 0 ;0
L 1.35335 -2.07351998 1.35491998 -2.07065 0 P 0 ;0
L 1.35491998 -2.07065 1.35683002 -2.0677 0 P 0 ;0
L 1.35683002 -2.0677 1.35876998 -2.06511004 0 P 0 ;0
L 1.35876998 -2.06511004 1.35948996 -2.0643 0 P 0 ;0
L 1.35948996 -2.0643 1.36026998 -2.06356004 0 P 0 ;0
L 1.36026998 -2.06356004 1.3624 -2.06181998 0 P 0 ;0
L 1.3624 -2.06181998 1.36465 -2.06023996 0 P 0 ;0
L 1.36465 -2.06023996 1.36701004 -2.05883002 0 P 0 ;0
L 1.36701004 -2.05883002 1.37173002 -2.05641004 0 P 0 ;0
L 1.37173002 -2.05641004 1.37656004 -2.05426998 0 P 0 ;0
L 1.37656004 -2.05426998 1.38243002 -2.05203996 0 P 0 ;0
L 1.38243002 -2.05203996 1.38836004 -2.0501 0 P 0 ;0
L 1.38836004 -2.0501 1.4023 -2.04645 0 P 0 ;0
L 1.4023 -2.04645 1.41148996 -2.044 0 P 0 ;0
L 1.41148996 -2.044 1.42016998 -2.04095 0 P 0 ;0
L 1.42016998 -2.04095 1.42016998 -2.04093996 0 P 0 ;0
L 1.42016998 -2.04093996 1.42021004 -2.04093996 0 P 0 ;0
L 1.42021004 -2.04093996 1.42023996 -2.04093002 0 P 0 ;0
L 1.42023996 -2.04093002 1.42746998 -2.03776004 0 P 0 ;0
L 1.42746998 -2.03776004 1.42753002 -2.03773002 0 P 0 ;0
L 1.42753002 -2.03773002 1.42796998 -2.03748996 0 P 0 ;0
L 1.42796998 -2.03748996 1.42846004 -2.03718996 0 P 0 ;0
L 1.42846004 -2.03718996 1.42891998 -2.03683996 0 P 0 ;0
L 1.42891998 -2.03683996 1.42935 -2.03646004 0 P 0 ;0
L 1.42935 -2.03646004 1.42975 -2.03603996 0 P 0 ;0
L 1.42975 -2.03603996 1.43011004 -2.0356 0 P 0 ;0
L 1.43011004 -2.0356 1.43016004 -2.03553002 0 P 0 ;0
L 1.43016004 -2.03553002 1.4299 -2.03535 0 P 0 ;0
L 1.4299 -2.03535 1.43028002 -2.03535 0 P 0 ;0
L 1.43028002 -2.03535 1.43043996 -2.03513002 0 P 0 ;0
L 1.43043996 -2.03513002 1.43048002 -2.03506004 0 P 0 ;0
L 1.43048002 -2.03506004 1.43041998 -2.03501998 0 P 0 ;0
L 1.43041998 -2.03501998 1.4305 -2.03501998 0 P 0 ;0
L 1.4305 -2.03501998 1.43073002 -2.03463002 0 P 0 ;0
L 1.43073002 -2.03463002 1.43096004 -2.03415 0 P 0 ;0
L 1.43096004 -2.03415 1.43115 -2.03365 0 P 0 ;0
L 1.43115 -2.03365 1.4313 -2.03313002 0 P 0 ;0
L 1.4313 -2.03313002 1.4314 -2.03261004 0 P 0 ;0
L 1.4314 -2.03261004 1.43146004 -2.03208002 0 P 0 ;0
L 1.43146004 -2.03208002 1.43146998 -2.03155 0 P 0 ;0
L 1.43146998 -2.03155 1.43143996 -2.03101004 0 P 0 ;0
L 1.43143996 -2.03101004 1.43143002 -2.03093002 0 P 0 ;0
L 1.43143002 -2.03093002 1.43136004 -2.03048996 0 P 0 ;0
L 1.43136004 -2.03048996 1.43125 -2.02996998 0 P 0 ;0
L 1.43125 -2.02996998 1.43108002 -2.02946004 0 P 0 ;0
L 1.43108002 -2.02946004 1.43086998 -2.02896004 0 P 0 ;0
L 1.43086998 -2.02896004 1.43063002 -2.02848996 0 P 0 ;0
L 1.43063002 -2.02848996 1.43033996 -2.02803996 0 P 0 ;0
L 1.43033996 -2.02803996 1.43001998 -2.02761004 0 P 0 ;0
L 1.43001998 -2.02761004 1.42966004 -2.02721004 0 P 0 ;0
L 1.42966004 -2.02721004 1.42928002 -2.02685 0 P 0 ;0
L 1.42928002 -2.02685 1.42886004 -2.02651998 0 P 0 ;0
L 1.42886004 -2.02651998 1.42841998 -2.02623002 0 P 0 ;0
L 1.42841998 -2.02623002 1.42795 -2.02596998 0 P 0 ;0
L 1.42795 -2.02596998 1.42746004 -2.02575 0 P 0 ;0
L 1.42746004 -2.02575 1.42583002 -2.02518002 0 P 0 ;0
L 1.42583002 -2.02518002 1.42416004 -2.02476004 0 P 0 ;0
L 1.42416004 -2.02476004 1.42245 -2.02448002 0 P 0 ;0
L 1.42245 -2.02448002 1.42075 -2.02435 0 P 0 ;0
L 1.42075 -2.02435 1.41565 -2.02428002 0 P 0 ;0
L 1.41565 -2.02428002 1.4156 -2.02428002 0 P 0 ;0
L 1.4156 -2.02428002 1.41055 -2.02445 0 P 0 ;0
L 1.41055 -2.02445 1.41048002 -2.02445 0 P 0 ;0
L 1.41048002 -2.02445 1.40128996 -2.02533996 0 P 0 ;0
L 1.40128996 -2.02533996 1.39208996 -2.02696998 0 P 0 ;0
L 1.39208996 -2.02696998 1.38288002 -2.02936004 0 P 0 ;0
L 1.38288002 -2.02936004 1.37363002 -2.03251998 0 P 0 ;0
L 1.37363002 -2.03251998 1.37076998 -2.03356004 0 P 0 ;0
L 1.37076998 -2.03356004 1.36865 -2.03426998 0 P 0 ;0
L 1.36865 -2.03426998 1.36906004 -2.03066998 0 P 0 ;0
L 1.36906004 -2.03066998 1.36988996 -2.02383996 0 P 0 ;0
L 1.36988996 -2.02383996 1.37095 -2.01581004 0 P 0 ;0
L 1.37095 -2.01581004 1.37358996 -1.99631998 0 P 0 ;0
L 1.37358996 -1.99631998 1.37988002 -1.99491998 0 P 0 ;0
L 1.37988002 -1.99491998 1.38353996 -1.99416998 0 P 0 ;0
L 1.38353996 -1.99416998 1.38841998 -1.99326998 0 P 0 ;0
L 1.38841998 -1.99326998 1.39358002 -1.9924 0 P 0 ;0
L 1.39358002 -1.9924 1.39825 -1.9917 0 P 0 ;0
L 1.39825 -1.9917 1.40436998 -1.991 0 P 0 ;0
L 1.40436998 -1.991 1.41045 -1.99065 0 P 0 ;0
L 1.41045 -1.99065 1.42691004 -1.99056998 0 P 0 ;0
L 1.42691004 -1.99056998 1.44283996 -1.99123996 0 P 0 ;0
L 1.44283996 -1.99123996 1.44603996 -1.99153996 0 P 0 ;0
L 1.44603996 -1.99153996 1.44918002 -1.99203002 0 P 0 ;0
L 1.44918002 -1.99203002 1.45226004 -1.9927 0 P 0 ;0
L 1.45226004 -1.9927 1.4563 -1.99386998 0 P 0 ;0
L 1.4563 -1.99386998 1.46021004 -1.99535 0 P 0 ;0
L 1.46021004 -1.99535 1.464 -1.99713002 0 P 0 ;0
L 1.464 -1.99713002 1.46586004 -1.99818996 0 P 0 ;0
L 1.46586004 -1.99818996 1.46763996 -1.99936004 0 P 0 ;0
L 1.46763996 -1.99936004 1.46931998 -2.00066004 0 P 0 ;0
L 1.46931998 -2.00066004 1.47091004 -2.00206998 0 P 0 ;0
L 1.47091004 -2.00206998 1.47238996 -2.00358996 0 P 0 ;0
L 1.47238996 -2.00358996 1.4737 -2.00515 0 P 0 ;0
L 1.4737 -2.00515 1.47488002 -2.00678996 0 P 0 ;0
L 1.47488002 -2.00678996 1.47593996 -2.00851004 0 P 0 ;0
L 1.47593996 -2.00851004 1.47686004 -2.01031004 0 P 0 ;0
L 1.47686004 -2.01031004 1.47763996 -2.01216998 0 P 0 ;0
L 1.47763996 -2.01216998 1.47851998 -2.01481004 0 P 0 ;0
L 1.47851998 -2.01481004 1.47918996 -2.01748996 0 P 0 ;0
L 1.47918996 -2.01748996 1.47966004 -2.02021998 0 P 0 ;0
L 1.47966004 -2.02021998 1.47993002 -2.02296998 0 P 0 ;0
L 1.47993002 -2.02296998 1.48001998 -2.02783996 0 P 0 ;0
L 1.48001998 -2.02783996 1.47975 -2.03868996 0 P 0 ;0
L 1.47975 -2.03868996 1.4793 -2.05161004 0 P 0 ;0
L 1.4793 -2.05161004 1.47866004 -2.06543002 0 P 0 ;0
L 1.47866004 -2.06543002 1.47801004 -2.07961004 0 P 0 ;0
L 1.47801004 -2.07961004 1.47743996 -2.09378996 0 P 0 ;0
L 1.47743996 -2.09378996 1.47705 -2.10613002 0 P 0 ;0
L 1.47705 -2.10613002 1.47693002 -2.11356004 0 P 0 ;0
L 1.47693002 -2.11356004 1.47693002 -2.12516004 0 P 0 ;0
L 1.47693002 -2.12516004 1.42661004 -2.12516004 0 P 0 ;0
L 1.42661004 -2.12516004 1.42661004 -2.12473996 0 P 0 ;0
L 1.42661004 -2.12473996 1.42666004 -2.12318002 0 P 0 ;0
L 1.42666004 -2.12318002 1.42691004 -2.11863996 0 P 0 ;0
L 1.42691004 -2.11863996 1.42725 -2.1132 0 P 0 ;0
L 1.42725 -2.1132 1.42766004 -2.1072 0 P 0 ;0
L 1.42766004 -2.1072 1.42766004 -2.10718996 0 P 0 ;0
L 1.42766004 -2.10718996 1.4281 -2.10068996 0 P 0 ;0
L 1.4281 -2.10068996 1.42858002 -2.09368002 0 P 0 ;0
L 1.42858002 -2.09368002 1.42901004 -2.08721004 0 P 0 ;0
L 1.42901004 -2.08721004 1.42901004 -2.0872 0 P 0 ;0
L 1.42901004 -2.0872 1.42931004 -2.08256004 0 P 0 ;0
L 1.42931004 -2.08256004 1.42991998 -2.07308002 0 P 0 ;0
L 1.42991998 -2.07308002 1.42916004 -2.07136998 0 P 0 ;0
L 1.42916004 -2.07136998 1.42731998 -2.07105 0 P 0 ;0
L 1.42731998 -2.07105 1.42105 -2.07303996 0 P 0 ;0
L 1.42105 -2.07303996 1.41815 -2.07393002 0 P 0 ;0
L 1.41815 -2.07393002 1.41451004 -2.075 0 P 0 ;0
L 1.41451004 -2.075 1.41076004 -2.07603002 0 P 0 ;0
L 1.41076004 -2.07603002 1.40748002 -2.0769 0 P 0 ;0
L 1.40748002 -2.0769 1.40438996 -2.07781004 0 P 0 ;0
L 1.40438996 -2.07781004 1.40431998 -2.07783996 0 P 0 ;0
L 1.40431998 -2.07783996 1.40133996 -2.07896998 0 P 0 ;0
L 1.40133996 -2.07896998 1.40005 -2.07956998 0 P 0 ;0
L 1.40005 -2.07956998 1.39881998 -2.08026004 0 P 0 ;0
L 1.39881998 -2.08026004 1.39763996 -2.08103002 0 P 0 ;0
L 1.39763996 -2.08103002 1.39651998 -2.08188002 0 P 0 ;0
L 1.39651998 -2.08188002 1.39578996 -2.08251004 0 P 0 ;0
L 1.39578996 -2.08251004 1.39573996 -2.08256004 0 P 0 ;0
L 1.39573996 -2.08256004 1.3951 -2.08318996 0 P 0 ;0
L 1.3951 -2.08318996 1.39446998 -2.08393002 0 P 0 ;0
L 1.39446998 -2.08393002 1.3939 -2.08471004 0 P 0 ;0
L 1.3939 -2.08471004 1.39336998 -2.08553996 0 P 0 ;0
L 1.39336998 -2.08553996 1.39301004 -2.08623996 0 P 0 ;0
L 1.39301004 -2.08623996 1.39271004 -2.08696998 0 P 0 ;0
L 1.39271004 -2.08696998 1.39248002 -2.08771998 0 P 0 ;0
L 1.39248002 -2.08771998 1.39231004 -2.08848996 0 P 0 ;0
L 1.39231004 -2.08848996 1.39221004 -2.08926004 0 P 0 ;0
L 1.39221004 -2.08926004 1.39218002 -2.09003996 0 P 0 ;0
L 1.39218002 -2.09003996 1.39221004 -2.0908 0 P 0 ;0
L 1.39221004 -2.0908 1.39231004 -2.09153002 0 P 0 ;0
L 1.39231004 -2.09153002 1.39246998 -2.09226004 0 P 0 ;0
L 1.39246998 -2.09226004 1.39268996 -2.09296998 0 P 0 ;0
L 1.39268996 -2.09296998 1.39296004 -2.09365 0 P 0 ;0
L 1.39296004 -2.09365 1.3933 -2.09431004 0 P 0 ;0
L 1.3933 -2.09431004 1.39368996 -2.09493996 0 P 0 ;0
L 1.39368996 -2.09493996 1.39411998 -2.09553996 0 P 0 ;0
L 1.39411998 -2.09553996 1.39468996 -2.09618002 0 P 0 ;0
L 1.39468996 -2.09618002 1.3953 -2.09678002 0 P 0 ;0
L 1.3953 -2.09678002 1.39596004 -2.09731998 0 P 0 ;0
L 1.39596004 -2.09731998 1.39666998 -2.0978 0 P 0 ;0
L 1.39666998 -2.0978 1.39673996 -2.09783996 0 P 0 ;0
L 1.39673996 -2.09783996 1.39741004 -2.09821998 0 P 0 ;0
L 1.39741004 -2.09821998 1.39748996 -2.09825 0 P 0 ;0
L 1.39748996 -2.09825 1.39818996 -2.09856998 0 P 0 ;0
L 1.39818996 -2.09856998 1.39898996 -2.09886004 0 P 0 ;0
L 1.39898996 -2.09886004 1.39906998 -2.09888002 0 P 0 ;0
L 1.39906998 -2.09888002 1.40043996 -2.09888002 0 P 0 ;0
L 1.40043996 -2.09888002 1.40033996 -2.09923002 0 P 0 ;0
L 1.40033996 -2.09923002 1.40041998 -2.09925 0 P 0 ;0
L 1.40041998 -2.09925 1.40186004 -2.09953002 0 P 0 ;0
L 1.40186004 -2.09953002 1.40331004 -2.09971004 0 P 0 ;0
L 1.40331004 -2.09971004 1.40478002 -2.09978002 0 P 0 ;0
L 1.40478002 -2.09978002 1.40625 -2.09975 0 P 0 ;0
L 1.40625 -2.09975 1.41096004 -2.09931004 0 P 0 ;0
L 1.41096004 -2.09931004 1.41556998 -2.09855 0 P 0 ;0
L 1.41556998 -2.09855 1.41791998 -2.09813002 0 P 0 ;0
L 1.41791998 -2.09813002 1.41995 -2.09791004 0 P 0 ;0
L 1.41995 -2.09791004 1.4201 -2.0979 0 P 0 ;0
L 1.4201 -2.0979 1.41941004 -2.10078002 0 P 0 ;0
L 1.41941004 -2.10078002 1.41761004 -2.10745 0 P 0 ;0
L 1.41761004 -2.10745 1.41391004 -2.12025 0 P 0 ;0
L 1.41391004 -2.12025 1.41215 -2.12626998 0 P 0 ;0
L 1.41215 -2.12626998 1.40655 -2.12725 0 P 0 ;0
L 1.40655 -2.12725 1.40046004 -2.12808002 0 P 0 ;0
L 1.40046004 -2.12808002 1.39438002 -2.12845 0 P 0 ;0
L 1.15303002 -2.08283002 1.20788996 -2.08283002 0 P 0 ;0
L 1.15398996 -2.08183002 1.20795 -2.08183002 0 P 0 ;0
L 1.15483002 -2.08083002 1.208 -2.08083002 0 P 0 ;0
L 1.15555 -2.07983002 1.20805 -2.07983002 0 P 0 ;0
L 1.15621998 -2.07883002 1.2081 -2.07883002 0 P 0 ;0
L 1.15681998 -2.07783002 1.20816004 -2.07783002 0 P 0 ;0
L 1.15733002 -2.07683002 1.20821004 -2.07683002 0 P 0 ;0
L 1.15778996 -2.07583002 1.20826004 -2.07583002 0 P 0 ;0
L 1.15818002 -2.07483002 1.20831004 -2.07483002 0 P 0 ;0
L 1.15853996 -2.07383002 1.20836998 -2.07383002 0 P 0 ;0
L 1.15881998 -2.07283002 1.20841998 -2.07283002 0 P 0 ;0
L 1.1591 -2.07183002 1.20846998 -2.07183002 0 P 0 ;0
L 1.15938002 -2.07083002 1.20853002 -2.07083002 0 P 0 ;0
L 1.1596 -2.06983002 1.20858002 -2.06983002 0 P 0 ;0
L 1.15981004 -2.06883002 1.20863996 -2.06883002 0 P 0 ;0
L 1.16001004 -2.06783002 1.20868996 -2.06783002 0 P 0 ;0
L 1.1602 -2.06683002 1.20875 -2.06683002 0 P 0 ;0
L 1.16033996 -2.06583002 1.2088 -2.06583002 0 P 0 ;0
L 1.16048996 -2.06483002 1.20886004 -2.06483002 0 P 0 ;0
L 1.16063996 -2.06383002 1.20891998 -2.06383002 0 P 0 ;0
L 1.16078002 -2.06283002 1.20896998 -2.06283002 0 P 0 ;0
L 1.16088996 -2.06183002 1.20903002 -2.06183002 0 P 0 ;0
L 1.16098996 -2.06083002 1.20908002 -2.06083002 0 P 0 ;0
L 1.16108996 -2.05983002 1.20913996 -2.05983002 0 P 0 ;0
L 1.16118002 -2.05883002 1.20918996 -2.05883002 0 P 0 ;0
L 1.16128002 -2.05783002 1.20925 -2.05783002 0 P 0 ;0
L 1.16133996 -2.05683002 1.2093 -2.05683002 0 P 0 ;0
L 1.1614 -2.05583002 1.20936004 -2.05583002 0 P 0 ;0
L 1.16146004 -2.05483002 1.20941004 -2.05483002 0 P 0 ;0
L 1.16151998 -2.05383002 1.20946998 -2.05383002 0 P 0 ;0
L 1.16158002 -2.05283002 1.20951998 -2.05283002 0 P 0 ;0
L 1.16163996 -2.05183002 1.20958002 -2.05183002 0 P 0 ;0
L 1.1617 -2.05083002 1.20963996 -2.05083002 0 P 0 ;0
L 1.16175 -2.04983002 1.2097 -2.04983002 0 P 0 ;0
L 1.16181004 -2.04883002 1.20975 -2.04883002 0 P 0 ;0
L 1.16186998 -2.04783002 1.20981004 -2.04783002 0 P 0 ;0
L 1.16193002 -2.04683002 1.20986998 -2.04683002 0 P 0 ;0
L 1.16198996 -2.04583002 1.20993002 -2.04583002 0 P 0 ;0
L 1.16205 -2.04483002 1.20998996 -2.04483002 0 P 0 ;0
L 1.16211004 -2.04383002 1.21005 -2.04383002 0 P 0 ;0
L 1.16215 -2.04283002 1.2101 -2.04283002 0 P 0 ;0
L 1.1622 -2.04183002 1.21016004 -2.04183002 0 P 0 ;0
L 1.16225 -2.04083002 1.21021998 -2.04083002 0 P 0 ;0
L 1.16228996 -2.03983002 1.21028002 -2.03983002 0 P 0 ;0
L 1.16233996 -2.03883002 1.21033996 -2.03883002 0 P 0 ;0
L 1.16238002 -2.03783002 1.2104 -2.03783002 0 P 0 ;0
L 1.16243002 -2.03683002 1.21046004 -2.03683002 0 P 0 ;0
L 1.16246998 -2.03583002 1.21051004 -2.03583002 0 P 0 ;0
L 1.16251998 -2.03483002 1.21056998 -2.03483002 0 P 0 ;0
L 1.16256998 -2.03383002 1.21063996 -2.03383002 0 P 0 ;0
L 1.16261004 -2.03283002 1.2107 -2.03283002 0 P 0 ;0
L 1.16266004 -2.03183002 1.21076004 -2.03183002 0 P 0 ;0
L 1.1627 -2.03083002 1.21083002 -2.03083002 0 P 0 ;0
L 1.16015 -1.97631004 1.17066004 -1.97631004 0 P 0 ;0
L 1.15961998 -1.97531004 1.17026004 -1.97531004 0 P 0 ;0
L 1.1591 -1.97431004 1.16986998 -1.97431004 0 P 0 ;0
L 1.15856998 -1.97331004 1.16946998 -1.97331004 0 P 0 ;0
L 1.15803996 -1.97231004 1.16903002 -1.97231004 0 P 0 ;0
L 1.15746998 -1.97131004 1.16858996 -1.97131004 0 P 0 ;0
L 1.1569 -1.97031004 1.16815 -1.97031004 0 P 0 ;0
L 1.15631998 -1.96931004 1.16771004 -1.96931004 0 P 0 ;0
L 1.15573996 -1.96831004 1.16726998 -1.96831004 0 P 0 ;0
L 1.15516004 -1.96731004 1.16681998 -1.96731004 0 P 0 ;0
L 1.15458996 -1.96631004 1.16638002 -1.96631004 0 P 0 ;0
L 1.15398002 -1.96531004 1.16593996 -1.96531004 0 P 0 ;0
L 1.1533 -1.96431004 1.16548996 -1.96431004 0 P 0 ;0
L 1.15261998 -1.96331004 1.16503002 -1.96331004 0 P 0 ;0
L 1.15193996 -1.96231004 1.16448002 -1.96231004 0 P 0 ;0
L 1.15126004 -1.96131004 1.16393002 -1.96131004 0 P 0 ;0
L 1.15058002 -1.96031004 1.16338002 -1.96031004 0 P 0 ;0
L 1.1499 -1.95931004 1.16283002 -1.95931004 0 P 0 ;0
L 1.1491 -1.95831004 1.16228996 -1.95831004 0 P 0 ;0
L 1.14831004 -1.95731004 1.16173996 -1.95731004 0 P 0 ;0
L 1.14751004 -1.95631004 1.16118996 -1.95631004 0 P 0 ;0
L 1.14671004 -1.95531004 1.16063996 -1.95531004 0 P 0 ;0
L 1.14591998 -1.95431004 1.16008996 -1.95431004 0 P 0 ;0
L 1.14511998 -1.95331004 1.15943996 -1.95331004 0 P 0 ;0
L 1.1442 -1.95231004 1.15878002 -1.95231004 0 P 0 ;0
L 1.14326998 -1.95131004 1.15811004 -1.95131004 0 P 0 ;0
L 1.14233996 -1.95031004 1.15745 -1.95031004 0 P 0 ;0
L 1.14141004 -1.94931004 1.15678002 -1.94931004 0 P 0 ;0
L 1.14048996 -1.94831004 1.15611998 -1.94831004 0 P 0 ;0
L 1.1395 -1.94731004 1.15545 -1.94731004 0 P 0 ;0
L 1.13843002 -1.94631004 1.15478996 -1.94631004 0 P 0 ;0
L 1.13736004 -1.94531004 1.15411998 -1.94531004 0 P 0 ;0
L 1.13628996 -1.94431004 1.15333002 -1.94431004 0 P 0 ;0
L 1.13521004 -1.94331004 1.15253002 -1.94331004 0 P 0 ;0
L 1.13413996 -1.94231004 1.15173996 -1.94231004 0 P 0 ;0
L 1.13306998 -1.94131004 1.15093996 -1.94131004 0 P 0 ;0
L 1.132 -1.94031004 1.15013996 -1.94031004 0 P 0 ;0
L 1.13081004 -1.93931004 1.14935 -1.93931004 0 P 0 ;0
L 1.12958002 -1.93831004 1.14855 -1.93831004 0 P 0 ;0
L 1.12833996 -1.93731004 1.14775 -1.93731004 0 P 0 ;0
L 1.1271 -1.93631004 1.14688996 -1.93631004 0 P 0 ;0
L 1.12586004 -1.93531004 1.14593996 -1.93531004 0 P 0 ;0
L 1.12461998 -1.93431004 1.14498996 -1.93431004 0 P 0 ;0
L 1.12338002 -1.93331004 1.14405 -1.93331004 0 P 0 ;0
L 1.12203002 -1.93231004 1.1431 -1.93231004 0 P 0 ;0
L 1.1206 -1.93131004 1.14216004 -1.93131004 0 P 0 ;0
L 1.11916004 -1.93031004 1.14121004 -1.93031004 0 P 0 ;0
L 1.11771998 -1.92931004 1.14026998 -1.92931004 0 P 0 ;0
L 1.11628996 -1.92831004 1.13931998 -1.92831004 0 P 0 ;0
L 1.11483996 -1.92731004 1.13838002 -1.92731004 0 P 0 ;0
L 1.11338996 -1.92631004 1.13743002 -1.92631004 0 P 0 ;0
L 1.11171998 -1.92531004 1.13648996 -1.92531004 0 P 0 ;0
L 1.11005 -1.92431004 1.13538002 -1.92431004 0 P 0 ;0
L 1.10838002 -1.92331004 1.13426998 -1.92331004 0 P 0 ;0
L 1.1067 -1.92231004 1.13315 -1.92231004 0 P 0 ;0
L 1.10503002 -1.92131004 1.13203002 -1.92131004 0 P 0 ;0
L 1.10336004 -1.92031004 1.13091998 -1.92031004 0 P 0 ;0
L 1.1015 -1.91931004 1.1298 -1.91931004 0 P 0 ;0
L 1.09955 -1.91831004 1.12868002 -1.91831004 0 P 0 ;0
L 1.16275 -2.02983002 1.21088996 -2.02983002 0 P 0 ;0
L 1.16278996 -2.02883002 1.21095 -2.02883002 0 P 0 ;0
L 1.16283996 -2.02783002 1.21101004 -2.02783002 0 P 0 ;0
L 1.16226998 -2.02683002 1.21108002 -2.02683002 0 P 0 ;0
L 1.16153996 -2.02583002 1.21113996 -2.02583002 0 P 0 ;0
L 1.15846004 -2.02483002 1.2112 -2.02483002 0 P 0 ;0
L 1.10036004 -2.00383002 1.21255 -2.00383002 0 P 0 ;0
L 1.10226004 -2.00283002 1.2126 -2.00283002 0 P 0 ;0
L 1.10433996 -2.00183002 1.21266998 -2.00183002 0 P 0 ;0
L 1.1065 -2.00083002 1.21273002 -2.00083002 0 P 0 ;0
L 1.10886998 -1.99983002 1.21278996 -1.99983002 0 P 0 ;0
L 1.11138002 -1.99883002 1.21285 -1.99883002 0 P 0 ;0
L 1.11436998 -1.99783002 1.21288002 -1.99783002 0 P 0 ;0
L 1.11748996 -1.99683002 1.21255 -1.99683002 0 P 0 ;0
L 1.12061998 -1.99583002 1.2089 -1.99583002 0 P 0 ;0
L 1.12433996 -1.99483002 1.2036 -1.99483002 0 P 0 ;0
L 1.12863996 -1.99383002 1.19728002 -1.99383002 0 P 0 ;0
L 1.13295 -1.99283002 1.19096998 -1.99283002 0 P 0 ;0
L 1.13985 -1.99183002 1.18111998 -1.99183002 0 P 0 ;0
L 1.14948002 -1.99083002 1.1651 -1.99083002 0 P 0 ;0
L 1.24218002 -2.08316004 1.29143996 -2.08316004 0 P 0 ;0
L 1.24223002 -2.08216004 1.29151004 -2.08216004 0 P 0 ;0
L 1.24228002 -2.08116004 1.29158996 -2.08116004 0 P 0 ;0
L 1.24233996 -2.08016004 1.29166004 -2.08016004 0 P 0 ;0
L 1.24238996 -2.07916004 1.29173002 -2.07916004 0 P 0 ;0
L 1.24245 -2.07816004 1.29181004 -2.07816004 0 P 0 ;0
L 1.2425 -2.07716004 1.29188002 -2.07716004 0 P 0 ;0
L 1.24256004 -2.07616004 1.29195 -2.07616004 0 P 0 ;0
L 1.24261004 -2.07516004 1.29203002 -2.07516004 0 P 0 ;0
L 1.24266998 -2.07416004 1.2921 -2.07416004 0 P 0 ;0
L 1.24271998 -2.07316004 1.29216998 -2.07316004 0 P 0 ;0
L 1.24278002 -2.07216004 1.29223996 -2.07216004 0 P 0 ;0
L 1.24283002 -2.07116004 1.29231998 -2.07116004 0 P 0 ;0
L 1.24288002 -2.07016004 1.29238996 -2.07016004 0 P 0 ;0
L 1.24293002 -2.06916004 1.29246004 -2.06916004 0 P 0 ;0
L 1.24296998 -2.06816004 1.29253002 -2.06816004 0 P 0 ;0
L 1.24301998 -2.06716004 1.29261004 -2.06716004 0 P 0 ;0
L 1.24306004 -2.06616004 1.2927 -2.06616004 0 P 0 ;0
L 1.24311004 -2.06516004 1.29281004 -2.06516004 0 P 0 ;0
L 1.24315 -2.06416004 1.29291998 -2.06416004 0 P 0 ;0
L 1.2432 -2.06316004 1.29303002 -2.06316004 0 P 0 ;0
L 1.24323996 -2.06216004 1.29315 -2.06216004 0 P 0 ;0
L 1.24328996 -2.06116004 1.29331998 -2.06116004 0 P 0 ;0
L 1.24333002 -2.06016004 1.2935 -2.06016004 0 P 0 ;0
L 1.24338002 -2.05916004 1.29366998 -2.05916004 0 P 0 ;0
L 1.24341998 -2.05816004 1.29385 -2.05816004 0 P 0 ;0
L 1.24346998 -2.05716004 1.29408996 -2.05716004 0 P 0 ;0
L 1.24351004 -2.05616004 1.29433996 -2.05616004 0 P 0 ;0
L 1.24355 -2.05516004 1.29458996 -2.05516004 0 P 0 ;0
L 1.2436 -2.05416004 1.29485 -2.05416004 0 P 0 ;0
L 1.24363996 -2.05316004 1.29516998 -2.05316004 0 P 0 ;0
L 1.24368996 -2.05216004 1.29551998 -2.05216004 0 P 0 ;0
L 1.24373002 -2.05116004 1.29586004 -2.05116004 0 P 0 ;0
L 1.24378002 -2.05016004 1.29621004 -2.05016004 0 P 0 ;0
L 1.24383002 -2.04916004 1.29663996 -2.04916004 0 P 0 ;0
L 1.24386998 -2.04816004 1.29708002 -2.04816004 0 P 0 ;0
L 1.24391004 -2.04716004 1.29753002 -2.04716004 0 P 0 ;0
L 1.24396004 -2.04616004 1.29796998 -2.04616004 0 P 0 ;0
L 1.244 -2.04516004 1.29851004 -2.04516004 0 P 0 ;0
L 1.24405 -2.04416004 1.2991 -2.04416004 0 P 0 ;0
L 1.24408996 -2.04316004 1.29975 -2.04316004 0 P 0 ;0
L 1.24413996 -2.04216004 1.3005 -2.04216004 0 P 0 ;0
L 1.24418002 -2.04116004 1.30131998 -2.04116004 0 P 0 ;0
L 1.24423002 -2.04016004 1.30223002 -2.04016004 0 P 0 ;0
L 1.24426998 -2.03916004 1.30326998 -2.03916004 0 P 0 ;0
L 1.24431998 -2.03816004 1.30446004 -2.03816004 0 P 0 ;0
L 1.24436004 -2.03716004 1.30581998 -2.03716004 0 P 0 ;0
L 1.24441004 -2.03616004 1.30738002 -2.03616004 0 P 0 ;0
L 1.24445 -2.03516004 1.30923002 -2.03516004 0 P 0 ;0
L 1.24448996 -2.03416004 1.31156004 -2.03416004 0 P 0 ;0
L 1.24453996 -2.03316004 1.31478996 -2.03316004 0 P 0 ;0
L 1.24458996 -2.03216004 1.32013002 -2.03216004 0 P 0 ;0
L 1.24461998 -2.03116004 1.33481004 -2.03116004 0 P 0 ;0
L 1.24463996 -2.03016004 1.33478002 -2.03016004 0 P 0 ;0
L 1.24466004 -2.02916004 1.33473996 -2.02916004 0 P 0 ;0
L 1.24468002 -2.02816004 1.33471004 -2.02816004 0 P 0 ;0
L 1.2447 -2.02716004 1.33468002 -2.02716004 0 P 0 ;0
L 1.24471998 -2.02616004 1.33463996 -2.02616004 0 P 0 ;0
L 1.24473996 -2.02516004 1.3346 -2.02516004 0 P 0 ;0
L 1.24476004 -2.02416004 1.33456998 -2.02416004 0 P 0 ;0
L 1.24478002 -2.02316004 1.33453002 -2.02316004 0 P 0 ;0
L 1.2448 -2.02216004 1.3345 -2.02216004 0 P 0 ;0
L 1.24481998 -2.02116004 1.33446998 -2.02116004 0 P 0 ;0
L 1.24483996 -2.02016004 1.33443002 -2.02016004 0 P 0 ;0
L 1.24486004 -2.01916004 1.3344 -2.01916004 0 P 0 ;0
L 1.24488002 -2.01816004 1.33436004 -2.01816004 0 P 0 ;0
L 1.2449 -2.01716004 1.33433002 -2.01716004 0 P 0 ;0
L 1.24491998 -2.01616004 1.33428996 -2.01616004 0 P 0 ;0
L 1.24493996 -2.01516004 1.33426004 -2.01516004 0 P 0 ;0
L 1.24496004 -2.01416004 1.33421998 -2.01416004 0 P 0 ;0
L 1.24498002 -2.01316004 1.33418996 -2.01316004 0 P 0 ;0
L 1.245 -2.01216004 1.33415 -2.01216004 0 P 0 ;0
L 1.24501998 -2.01116004 1.33411998 -2.01116004 0 P 0 ;0
L 1.24503996 -2.01016004 1.33408002 -2.01016004 0 P 0 ;0
L 1.24506004 -2.00916004 1.33403996 -2.00916004 0 P 0 ;0
L 1.24508002 -2.00816004 1.334 -2.00816004 0 P 0 ;0
L 1.2451 -2.00716004 1.33396004 -2.00716004 0 P 0 ;0
L 1.24511998 -2.00616004 1.33393002 -2.00616004 0 P 0 ;0
L 1.24513996 -2.00516004 1.29098996 -2.00516004 0 P 0 ;0
L 1.24513996 -2.00416004 1.29033002 -2.00416004 0 P 0 ;0
L 1.24513996 -2.00316004 1.29005 -2.00316004 0 P 0 ;0
L 1.24513996 -2.00216004 1.29005 -2.00216004 0 P 0 ;0
L 1.24513996 -2.00116004 1.29005 -2.00116004 0 P 0 ;0
L 1.24515 -2.00016004 1.29005 -2.00016004 0 P 0 ;0
L 1.24515 -1.99916004 1.29005 -1.99916004 0 P 0 ;0
L 1.24515 -1.99816004 1.29005 -1.99816004 0 P 0 ;0
L 1.24515 -1.99716004 1.29005 -1.99716004 0 P 0 ;0
L 1.24515 -1.99616004 1.29005 -1.99616004 0 P 0 ;0
L 1.24515 -1.99516004 1.29005 -1.99516004 0 P 0 ;0
L 1.16085 -2.02753002 1.1601 -2.04393002 0 P 0 ;0
L 1.1601 -2.04393002 1.15928996 -2.05771998 0 P 0 ;0
L 1.15928996 -2.05771998 1.15883996 -2.06228002 0 P 0 ;0
L 1.15883996 -2.06228002 1.15818002 -2.06681998 0 P 0 ;0
L 1.15818002 -2.06681998 1.15751004 -2.07006998 0 P 0 ;0
L 1.15751004 -2.07006998 1.15661004 -2.07328996 0 P 0 ;0
L 1.15661004 -2.07328996 1.15616004 -2.07453996 0 P 0 ;0
L 1.15616004 -2.07453996 1.15563002 -2.07576998 0 P 0 ;0
L 1.15563002 -2.07576998 1.15501998 -2.07696004 0 P 0 ;0
L 1.15501998 -2.07696004 1.15433002 -2.0781 0 P 0 ;0
L 1.15433002 -2.0781 1.1534 -2.07941998 0 P 0 ;0
L 1.1534 -2.07941998 1.15236004 -2.08066004 0 P 0 ;0
L 1.15236004 -2.08066004 1.15123002 -2.08181998 0 P 0 ;0
L 1.15123002 -2.08181998 1.15001004 -2.08286998 0 P 0 ;0
L 1.15001004 -2.08286998 1.14871004 -2.08383002 0 P 0 ;0
L 1.14871004 -2.08383002 1.14733002 -2.08468002 0 P 0 ;0
L 1.14733002 -2.08468002 1.14591004 -2.0854 0 P 0 ;0
L 1.14591004 -2.0854 1.14443996 -2.086 0 P 0 ;0
L 1.14443996 -2.086 1.14291004 -2.08648002 0 P 0 ;0
L 1.14291004 -2.08648002 1.14136004 -2.08683002 0 P 0 ;0
L 1.14136004 -2.08683002 1.13976998 -2.08703996 0 P 0 ;0
L 1.13976998 -2.08703996 1.13816004 -2.08713002 0 P 0 ;0
L 1.13816004 -2.08713002 1.13656998 -2.08708002 0 P 0 ;0
L 1.13656998 -2.08708002 1.13498996 -2.0869 0 P 0 ;0
L 1.13498996 -2.0869 1.13341998 -2.08658996 0 P 0 ;0
L 1.13341998 -2.08658996 1.13188996 -2.08615 0 P 0 ;0
L 1.13188996 -2.08615 1.1304 -2.08558996 0 P 0 ;0
L 1.1304 -2.08558996 1.12895 -2.08488996 0 P 0 ;0
L 1.12895 -2.08488996 1.12756998 -2.08408002 0 P 0 ;0
L 1.12756998 -2.08408002 1.12625 -2.08315 0 P 0 ;0
L 1.12625 -2.08315 1.12501004 -2.08211998 0 P 0 ;0
L 1.12501004 -2.08211998 1.12386004 -2.081 0 P 0 ;0
L 1.12386004 -2.081 1.12281004 -2.07978002 0 P 0 ;0
L 1.12281004 -2.07978002 1.12183996 -2.07846998 0 P 0 ;0
L 1.12183996 -2.07846998 1.1211 -2.07726004 0 P 0 ;0
L 1.1211 -2.07726004 1.12046998 -2.07598996 0 P 0 ;0
L 1.12046998 -2.07598996 1.11996004 -2.07466998 0 P 0 ;0
L 1.11996004 -2.07466998 1.11955 -2.07331004 0 P 0 ;0
L 1.11955 -2.07331004 1.11926998 -2.07191004 0 P 0 ;0
L 1.11926998 -2.07191004 1.11868002 -2.06693996 0 P 0 ;0
L 1.11868002 -2.06693996 1.11848002 -2.06191004 0 P 0 ;0
L 1.11848002 -2.06191004 1.11871004 -2.05668002 0 P 0 ;0
L 1.11871004 -2.05668002 1.11936004 -2.05148002 0 P 0 ;0
L 1.11936004 -2.05148002 1.11978996 -2.04936998 0 P 0 ;0
L 1.11978996 -2.04936998 1.12036998 -2.0473 0 P 0 ;0
L 1.12036998 -2.0473 1.12108996 -2.04528002 0 P 0 ;0
L 1.12108996 -2.04528002 1.12196004 -2.04331998 0 P 0 ;0
L 1.12196004 -2.04331998 1.1229 -2.04153996 0 P 0 ;0
L 1.1229 -2.04153996 1.12396998 -2.03985 0 P 0 ;0
L 1.12396998 -2.03985 1.12516998 -2.03823002 0 P 0 ;0
L 1.12516998 -2.03823002 1.12735 -2.03573996 0 P 0 ;0
L 1.12735 -2.03573996 1.12973002 -2.03345 0 P 0 ;0
L 1.12973002 -2.03345 1.13223996 -2.03141998 0 P 0 ;0
L 1.13223996 -2.03141998 1.13491998 -2.02961004 0 P 0 ;0
L 1.13491998 -2.02961004 1.13611004 -2.02893002 0 P 0 ;0
L 1.13611004 -2.02893002 1.13735 -2.02833996 0 P 0 ;0
L 1.13735 -2.02833996 1.13861998 -2.02781998 0 P 0 ;0
L 1.13861998 -2.02781998 1.13993996 -2.0274 0 P 0 ;0
L 1.13993996 -2.0274 1.14191004 -2.02693002 0 P 0 ;0
L 1.14191004 -2.02693002 1.14391004 -2.02663002 0 P 0 ;0
L 1.14391004 -2.02663002 1.14935 -2.02626004 0 P 0 ;0
L 1.14935 -2.02626004 1.15471004 -2.0263 0 P 0 ;0
L 1.15471004 -2.0263 1.15591004 -2.02638996 0 P 0 ;0
L 1.15591004 -2.02638996 1.1571 -2.02656998 0 P 0 ;0
L 1.1571 -2.02656998 1.15828002 -2.02683996 0 P 0 ;0
L 1.15828002 -2.02683996 1.16085 -2.02753002 0 P 0 ;0
L 1.13876998 -2.14783002 1.20233002 -2.14783002 0 P 0 ;0
L 1.14236998 -2.14683002 1.20266004 -2.14683002 0 P 0 ;0
L 1.14481004 -2.14583002 1.20296004 -2.14583002 0 P 0 ;0
L 1.1467 -2.14483002 1.20325 -2.14483002 0 P 0 ;0
L 1.14826004 -2.14383002 1.20353002 -2.14383002 0 P 0 ;0
L 1.1496 -2.14283002 1.20373996 -2.14283002 0 P 0 ;0
L 1.15078996 -2.14183002 1.20395 -2.14183002 0 P 0 ;0
L 1.15186004 -2.14083002 1.20415 -2.14083002 0 P 0 ;0
L 1.15278996 -2.13983002 1.20431998 -2.13983002 0 P 0 ;0
L 1.15361998 -2.13883002 1.20446004 -2.13883002 0 P 0 ;0
L 1.15436004 -2.13783002 1.20458002 -2.13783002 0 P 0 ;0
L 1.155 -2.13683002 1.20466998 -2.13683002 0 P 0 ;0
L 1.15556998 -2.13583002 1.20475 -2.13583002 0 P 0 ;0
L 1.15608996 -2.13483002 1.20481998 -2.13483002 0 P 0 ;0
L 1.15653996 -2.13383002 1.20488996 -2.13383002 0 P 0 ;0
L 1.15691004 -2.13283002 1.20496004 -2.13283002 0 P 0 ;0
L 1.15723996 -2.13183002 1.20503002 -2.13183002 0 P 0 ;0
L 1.15751998 -2.13083002 1.2051 -2.13083002 0 P 0 ;0
L 1.15773002 -2.12983002 1.20516004 -2.12983002 0 P 0 ;0
L 1.15793002 -2.12883002 1.20523002 -2.12883002 0 P 0 ;0
L 1.15806004 -2.12783002 1.2053 -2.12783002 0 P 0 ;0
L 1.15816998 -2.12683002 1.20536998 -2.12683002 0 P 0 ;0
L 1.15821004 -2.12583002 1.20543996 -2.12583002 0 P 0 ;0
L 1.11716004 -2.12483002 1.12726004 -2.12483002 0 P 0 ;0
L 1.15823996 -2.12483002 1.20551004 -2.12483002 0 P 0 ;0
L 1.10911998 -2.12383002 1.1352 -2.12383002 0 P 0 ;0
L 1.15821998 -2.12383002 1.20556998 -2.12383002 0 P 0 ;0
L 1.10468996 -2.12283002 1.14018996 -2.12283002 0 P 0 ;0
L 1.1582 -2.12283002 1.20563996 -2.12283002 0 P 0 ;0
L 1.10131004 -2.12183002 1.14366998 -2.12183002 0 P 0 ;0
L 1.15818002 -2.12183002 1.2057 -2.12183002 0 P 0 ;0
L 1.15808996 -2.12083002 1.20576004 -2.12083002 0 P 0 ;0
L 1.15781004 -2.11983002 1.20583002 -2.11983002 0 P 0 ;0
L 1.15721004 -2.11883002 1.20588002 -2.11883002 0 P 0 ;0
L 1.14146004 -2.08883002 1.20758002 -2.08883002 0 P 0 ;0
L 1.14525 -2.08783002 1.20763002 -2.08783002 0 P 0 ;0
L 1.14751004 -2.08683002 1.20768002 -2.08683002 0 P 0 ;0
L 1.14928002 -2.08583002 1.20773002 -2.08583002 0 P 0 ;0
L 1.15073002 -2.08483002 1.20778996 -2.08483002 0 P 0 ;0
L 1.15196004 -2.08383002 1.20783996 -2.08383002 0 P 0 ;0
L 1.13818996 -2.08913002 1.13826998 -2.08913002 0 P 0 ;0
L 1.13826998 -2.08913002 1.13988002 -2.08903996 0 P 0 ;0
L 1.13988002 -2.08903996 1.13996004 -2.08903996 0 P 0 ;0
L 1.13996004 -2.08903996 1.14001004 -2.08903002 0 P 0 ;0
L 1.14001004 -2.08903002 1.14005 -2.08901998 0 P 0 ;0
L 1.14005 -2.08901998 1.14163002 -2.08881004 0 P 0 ;0
L 1.14163002 -2.08881004 1.14166998 -2.0888 0 P 0 ;0
L 1.14166998 -2.0888 1.14171004 -2.0888 0 P 0 ;0
L 1.14171004 -2.0888 1.14178996 -2.08878002 0 P 0 ;0
L 1.14178996 -2.08878002 1.14335 -2.08843002 0 P 0 ;0
L 1.14335 -2.08843002 1.14351004 -2.08838996 0 P 0 ;0
L 1.14351004 -2.08838996 1.14503002 -2.08791004 0 P 0 ;0
L 1.14503002 -2.08791004 1.14511004 -2.08788996 0 P 0 ;0
L 1.14511004 -2.08788996 1.14515 -2.08786998 0 P 0 ;0
L 1.14515 -2.08786998 1.14518996 -2.08786004 0 P 0 ;0
L 1.14518996 -2.08786004 1.14666004 -2.08725 0 P 0 ;0
L 1.14666004 -2.08725 1.14673996 -2.08721998 0 P 0 ;0
L 1.14673996 -2.08721998 1.14678002 -2.0872 0 P 0 ;0
L 1.14678002 -2.0872 1.14681998 -2.08718996 0 P 0 ;0
L 1.14681998 -2.08718996 1.14823996 -2.08646998 0 P 0 ;0
L 1.14823996 -2.08646998 1.14826998 -2.08645 0 P 0 ;0
L 1.14826998 -2.08645 1.14835 -2.08641004 0 P 0 ;0
L 1.14835 -2.08641004 1.14838002 -2.08638002 0 P 0 ;0
L 1.14838002 -2.08638002 1.14976004 -2.08553002 0 P 0 ;0
L 1.14976004 -2.08553002 1.14978996 -2.08551004 0 P 0 ;0
L 1.14978996 -2.08551004 1.14983002 -2.08548996 0 P 0 ;0
L 1.14983002 -2.08548996 1.14988996 -2.08543996 0 P 0 ;0
L 1.14988996 -2.08543996 1.1512 -2.08448996 0 P 0 ;0
L 1.1512 -2.08448996 1.15126004 -2.08443996 0 P 0 ;0
L 1.15126004 -2.08443996 1.15128996 -2.08441004 0 P 0 ;0
L 1.15128996 -2.08441004 1.15131998 -2.08438996 0 P 0 ;0
L 1.15131998 -2.08438996 1.15253996 -2.08333002 0 P 0 ;0
L 1.15253996 -2.08333002 1.15256998 -2.0833 0 P 0 ;0
L 1.15256998 -2.0833 1.1526 -2.08328002 0 P 0 ;0
L 1.1526 -2.08328002 1.15263002 -2.08323996 0 P 0 ;0
L 1.15263002 -2.08323996 1.15266004 -2.08321998 0 P 0 ;0
L 1.15266004 -2.08321998 1.15378996 -2.08206004 0 P 0 ;0
L 1.15378996 -2.08206004 1.15376004 -2.08203996 0 P 0 ;0
L 1.15376004 -2.08203996 1.15381998 -2.08203996 0 P 0 ;0
L 1.15381998 -2.08203996 1.15383996 -2.082 0 P 0 ;0
L 1.15383996 -2.082 1.15386998 -2.08196998 0 P 0 ;0
L 1.15386998 -2.08196998 1.1539 -2.08195 0 P 0 ;0
L 1.1539 -2.08195 1.15493002 -2.08071004 0 P 0 ;0
L 1.15493002 -2.08071004 1.15493002 -2.0807 0 P 0 ;0
L 1.15493002 -2.0807 1.15496004 -2.08066998 0 P 0 ;0
L 1.15496004 -2.08066998 1.15498002 -2.08063996 0 P 0 ;0
L 1.15498002 -2.08063996 1.15501004 -2.08061004 0 P 0 ;0
L 1.15501004 -2.08061004 1.15503002 -2.08058002 0 P 0 ;0
L 1.15503002 -2.08058002 1.15596004 -2.07926004 0 P 0 ;0
L 1.15596004 -2.07926004 1.15603996 -2.07913996 0 P 0 ;0
L 1.15603996 -2.07913996 1.15673002 -2.07798996 0 P 0 ;0
L 1.15673002 -2.07798996 1.15676998 -2.07793002 0 P 0 ;0
L 1.15676998 -2.07793002 1.15678996 -2.07786998 0 P 0 ;0
L 1.15678996 -2.07786998 1.15741004 -2.07668996 0 P 0 ;0
L 1.15741004 -2.07668996 1.15743996 -2.07663002 0 P 0 ;0
L 1.15743996 -2.07663002 1.15746004 -2.07656998 0 P 0 ;0
L 1.15746004 -2.07656998 1.15746998 -2.07656998 0 P 0 ;0
L 1.15746998 -2.07656998 1.158 -2.07533996 0 P 0 ;0
L 1.158 -2.07533996 1.15801004 -2.07531004 0 P 0 ;0
L 1.15801004 -2.07531004 1.15803002 -2.07528002 0 P 0 ;0
L 1.15803002 -2.07528002 1.15805 -2.07521998 0 P 0 ;0
L 1.15805 -2.07521998 1.15848996 -2.07396004 0 P 0 ;0
L 1.15848996 -2.07396004 1.15841004 -2.07393002 0 P 0 ;0
L 1.15841004 -2.07393002 1.15851004 -2.07393002 0 P 0 ;0
L 1.15851004 -2.07393002 1.15851998 -2.0739 0 P 0 ;0
L 1.15851998 -2.0739 1.15853002 -2.07386004 0 P 0 ;0
L 1.15853002 -2.07386004 1.15853996 -2.07383002 0 P 0 ;0
L 1.15853996 -2.07383002 1.15943996 -2.07061004 0 P 0 ;0
L 1.15943996 -2.07061004 1.15945 -2.07058002 0 P 0 ;0
L 1.15945 -2.07058002 1.15946004 -2.07053996 0 P 0 ;0
L 1.15946004 -2.07053996 1.15946998 -2.07051004 0 P 0 ;0
L 1.15946998 -2.07051004 1.15946998 -2.07046998 0 P 0 ;0
L 1.15946998 -2.07046998 1.16013996 -2.06723002 0 P 0 ;0
L 1.16013996 -2.06723002 1.16013996 -2.0672 0 P 0 ;0
L 1.16013996 -2.0672 1.16016004 -2.06713996 0 P 0 ;0
L 1.16016004 -2.06713996 1.16016004 -2.06711004 0 P 0 ;0
L 1.16016004 -2.06711004 1.16081998 -2.06256004 0 P 0 ;0
L 1.16081998 -2.06256004 1.16081998 -2.06253996 0 P 0 ;0
L 1.16081998 -2.06253996 1.16083002 -2.0625 0 P 0 ;0
L 1.16083002 -2.0625 1.16083002 -2.06246998 0 P 0 ;0
L 1.16083002 -2.06246998 1.16126998 -2.05791004 0 P 0 ;0
L 1.16126998 -2.05791004 1.16128002 -2.0579 0 P 0 ;0
L 1.16128002 -2.0579 1.16128002 -2.05783996 0 P 0 ;0
L 1.16128002 -2.05783996 1.1621 -2.04405 0 P 0 ;0
L 1.1621 -2.04405 1.1621 -2.04401998 0 P 0 ;0
L 1.1621 -2.04401998 1.16285 -2.02761998 0 P 0 ;0
L 1.16285 -2.02761998 1.16136998 -2.0256 0 P 0 ;0
L 1.16136998 -2.0256 1.15878996 -2.02491004 0 P 0 ;0
L 1.15878996 -2.02491004 1.15878002 -2.0249 0 P 0 ;0
L 1.15878002 -2.0249 1.15871998 -2.02488996 0 P 0 ;0
L 1.15871998 -2.02488996 1.15755 -2.02461998 0 P 0 ;0
L 1.15755 -2.02461998 1.15746998 -2.0246 0 P 0 ;0
L 1.15746998 -2.0246 1.1574 -2.0246 0 P 0 ;0
L 1.1574 -2.0246 1.15621004 -2.02441004 0 P 0 ;0
L 1.15621004 -2.02441004 1.15616998 -2.02441004 0 P 0 ;0
L 1.15616998 -2.02441004 1.1561 -2.0244 0 P 0 ;0
L 1.1561 -2.0244 1.15606004 -2.02438996 0 P 0 ;0
L 1.15606004 -2.02438996 1.15486004 -2.0243 0 P 0 ;0
L 1.15486004 -2.0243 1.15471998 -2.0243 0 P 0 ;0
L 1.15471998 -2.0243 1.14936004 -2.02426004 0 P 0 ;0
L 1.14936004 -2.02426004 1.14928996 -2.02426004 0 P 0 ;0
L 1.14928996 -2.02426004 1.14925 -2.02426998 0 P 0 ;0
L 1.14925 -2.02426998 1.14921004 -2.02426998 0 P 0 ;0
L 1.14921004 -2.02426998 1.14376998 -2.02463996 0 P 0 ;0
L 1.14376998 -2.02463996 1.1437 -2.02463996 0 P 0 ;0
L 1.1437 -2.02463996 1.14365 -2.02465 0 P 0 ;0
L 1.14365 -2.02465 1.14361004 -2.02465 0 P 0 ;0
L 1.14361004 -2.02465 1.14161998 -2.02495 0 P 0 ;0
L 1.14161998 -2.02495 1.14161004 -2.02495 0 P 0 ;0
L 1.14161004 -2.02495 1.14153002 -2.02496998 0 P 0 ;0
L 1.14153002 -2.02496998 1.14148996 -2.02496998 0 P 0 ;0
L 1.14148996 -2.02496998 1.14143996 -2.02498996 0 P 0 ;0
L 1.14143996 -2.02498996 1.13946998 -2.02545 0 P 0 ;0
L 1.13946998 -2.02545 1.13943996 -2.02546998 0 P 0 ;0
L 1.13943996 -2.02546998 1.1394 -2.02546998 0 P 0 ;0
L 1.1394 -2.02546998 1.13933002 -2.0255 0 P 0 ;0
L 1.13933002 -2.0255 1.13801004 -2.02591998 0 P 0 ;0
L 1.13801004 -2.02591998 1.13798002 -2.02593002 0 P 0 ;0
L 1.13798002 -2.02593002 1.13793996 -2.02593996 0 P 0 ;0
L 1.13793996 -2.02593996 1.13788002 -2.02596998 0 P 0 ;0
L 1.13788002 -2.02596998 1.1366 -2.02648002 0 P 0 ;0
L 1.1366 -2.02648002 1.13653996 -2.0265 0 P 0 ;0
L 1.13653996 -2.0265 1.13648002 -2.02653002 0 P 0 ;0
L 1.13648002 -2.02653002 1.13523996 -2.02713002 0 P 0 ;0
L 1.13523996 -2.02713002 1.13518002 -2.02716004 0 P 0 ;0
L 1.13518002 -2.02716004 1.13515 -2.02716998 0 P 0 ;0
L 1.13515 -2.02716998 1.13511998 -2.02718996 0 P 0 ;0
L 1.13511998 -2.02718996 1.13393002 -2.02786998 0 P 0 ;0
L 1.13393002 -2.02786998 1.13388996 -2.02788996 0 P 0 ;0
L 1.13388996 -2.02788996 1.1338 -2.02795 0 P 0 ;0
L 1.1338 -2.02795 1.13111998 -2.02976004 0 P 0 ;0
L 1.13111998 -2.02976004 1.13105 -2.02981004 0 P 0 ;0
L 1.13105 -2.02981004 1.13101004 -2.02983996 0 P 0 ;0
L 1.13101004 -2.02983996 1.13098002 -2.02986004 0 P 0 ;0
L 1.13098002 -2.02986004 1.12846998 -2.03188996 0 P 0 ;0
L 1.12846998 -2.03188996 1.12838002 -2.03198002 0 P 0 ;0
L 1.12838002 -2.03198002 1.12833996 -2.03201004 0 P 0 ;0
L 1.12833996 -2.03201004 1.12596004 -2.0343 0 P 0 ;0
L 1.12596004 -2.0343 1.12593996 -2.03433002 0 P 0 ;0
L 1.12593996 -2.03433002 1.1259 -2.03436004 0 P 0 ;0
L 1.1259 -2.03436004 1.12588002 -2.03438996 0 P 0 ;0
L 1.12588002 -2.03438996 1.12585 -2.03443002 0 P 0 ;0
L 1.12585 -2.03443002 1.12366998 -2.03691004 0 P 0 ;0
L 1.12366998 -2.03691004 1.12363996 -2.03695 0 P 0 ;0
L 1.12363996 -2.03695 1.12361998 -2.03698002 0 P 0 ;0
L 1.12361998 -2.03698002 1.12358996 -2.03701004 0 P 0 ;0
L 1.12358996 -2.03701004 1.12356998 -2.03703996 0 P 0 ;0
L 1.12356998 -2.03703996 1.12236998 -2.03865 0 P 0 ;0
L 1.12236998 -2.03865 1.12233996 -2.03868996 0 P 0 ;0
L 1.12233996 -2.03868996 1.12233002 -2.03871004 0 P 0 ;0
L 1.12233002 -2.03871004 1.12228996 -2.03878002 0 P 0 ;0
L 1.12228996 -2.03878002 1.12121004 -2.04046998 0 P 0 ;0
L 1.12121004 -2.04046998 1.12118996 -2.0405 0 P 0 ;0
L 1.12118996 -2.0405 1.12116998 -2.04053996 0 P 0 ;0
L 1.12116998 -2.04053996 1.12115 -2.04056998 0 P 0 ;0
L 1.12115 -2.04056998 1.12113996 -2.04061004 0 P 0 ;0
L 1.12113996 -2.04061004 1.12018996 -2.04238002 0 P 0 ;0
L 1.12018996 -2.04238002 1.12016004 -2.04245 0 P 0 ;0
L 1.12016004 -2.04245 1.12013996 -2.04248002 0 P 0 ;0
L 1.12013996 -2.04248002 1.12013002 -2.04251004 0 P 0 ;0
L 1.12013002 -2.04251004 1.11926004 -2.04446998 0 P 0 ;0
L 1.11926004 -2.04446998 1.11925 -2.0445 0 P 0 ;0
L 1.11925 -2.0445 1.11923002 -2.04453996 0 P 0 ;0
L 1.11923002 -2.04453996 1.11921998 -2.04458002 0 P 0 ;0
L 1.11921998 -2.04458002 1.11921004 -2.04461004 0 P 0 ;0
L 1.11921004 -2.04461004 1.11848002 -2.04663002 0 P 0 ;0
L 1.11848002 -2.04663002 1.11846998 -2.04666004 0 P 0 ;0
L 1.11846998 -2.04666004 1.11846004 -2.0467 0 P 0 ;0
L 1.11846004 -2.0467 1.11843996 -2.04676998 0 P 0 ;0
L 1.11843996 -2.04676998 1.11786004 -2.04883996 0 P 0 ;0
L 1.11786004 -2.04883996 1.11785 -2.04886998 0 P 0 ;0
L 1.11785 -2.04886998 1.11783996 -2.04891004 0 P 0 ;0
L 1.11783996 -2.04891004 1.11783996 -2.04893996 0 P 0 ;0
L 1.11783996 -2.04893996 1.11783002 -2.04896998 0 P 0 ;0
L 1.11783002 -2.04896998 1.11783002 -2.04898002 0 P 0 ;0
L 1.11783002 -2.04898002 1.1174 -2.05108002 0 P 0 ;0
L 1.1174 -2.05108002 1.1174 -2.05111998 0 P 0 ;0
L 1.1174 -2.05111998 1.11738996 -2.05116004 0 P 0 ;0
L 1.11738996 -2.05116004 1.11738002 -2.05118996 0 P 0 ;0
L 1.11738002 -2.05118996 1.11738002 -2.05123002 0 P 0 ;0
L 1.11738002 -2.05123002 1.11673002 -2.05643002 0 P 0 ;0
L 1.11673002 -2.05643002 1.11671998 -2.05646998 0 P 0 ;0
L 1.11671998 -2.05646998 1.11671998 -2.05655 0 P 0 ;0
L 1.11671998 -2.05655 1.11671004 -2.05658996 0 P 0 ;0
L 1.11671004 -2.05658996 1.11648996 -2.06181998 0 P 0 ;0
L 1.11648996 -2.06181998 1.11648002 -2.06186998 0 P 0 ;0
L 1.11648002 -2.06186998 1.11648002 -2.06195 0 P 0 ;0
L 1.11648002 -2.06195 1.11648996 -2.06198996 0 P 0 ;0
L 1.11648996 -2.06198996 1.11668002 -2.06696998 0 P 0 ;0
L 1.11668002 -2.06696998 1.11768002 -2.06696998 0 P 0 ;0
L 1.11768002 -2.06696998 1.11668002 -2.06701004 0 P 0 ;0
L 1.11668002 -2.06701004 1.11668002 -2.06713002 0 P 0 ;0
L 1.11668002 -2.06713002 1.11668996 -2.06716998 0 P 0 ;0
L 1.11668996 -2.06716998 1.11728002 -2.07215 0 P 0 ;0
L 1.11728002 -2.07215 1.11728996 -2.07218996 0 P 0 ;0
L 1.11728996 -2.07218996 1.11728996 -2.07223002 0 P 0 ;0
L 1.11728996 -2.07223002 1.11731004 -2.07231004 0 P 0 ;0
L 1.11731004 -2.07231004 1.11758996 -2.07371004 0 P 0 ;0
L 1.11758996 -2.07371004 1.1176 -2.07375 0 P 0 ;0
L 1.1176 -2.07375 1.11761004 -2.0738 0 P 0 ;0
L 1.11761004 -2.0738 1.11761998 -2.07383996 0 P 0 ;0
L 1.11761998 -2.07383996 1.11763996 -2.07388002 0 P 0 ;0
L 1.11763996 -2.07388002 1.11803996 -2.07523996 0 P 0 ;0
L 1.11803996 -2.07523996 1.11806004 -2.07531998 0 P 0 ;0
L 1.11806004 -2.07531998 1.11808002 -2.07536004 0 P 0 ;0
L 1.11808002 -2.07536004 1.11808996 -2.07541004 0 P 0 ;0
L 1.11808996 -2.07541004 1.11861004 -2.07673002 0 P 0 ;0
L 1.11861004 -2.07673002 1.11863996 -2.07681004 0 P 0 ;0
L 1.11863996 -2.07681004 1.11866004 -2.07683996 0 P 0 ;0
L 1.11866004 -2.07683996 1.11868002 -2.07688002 0 P 0 ;0
L 1.11868002 -2.07688002 1.11931004 -2.07815 0 P 0 ;0
L 1.11931004 -2.07815 1.11935 -2.07823002 0 P 0 ;0
L 1.11935 -2.07823002 1.1194 -2.0783 0 P 0 ;0
L 1.1194 -2.0783 1.12013996 -2.07951998 0 P 0 ;0
L 1.12013996 -2.07951998 1.12021004 -2.07961998 0 P 0 ;0
L 1.12021004 -2.07961998 1.12023002 -2.07965 0 P 0 ;0
L 1.12023002 -2.07965 1.12023002 -2.07966004 0 P 0 ;0
L 1.12023002 -2.07966004 1.1212 -2.08096998 0 P 0 ;0
L 1.1212 -2.08096998 1.12123996 -2.08103002 0 P 0 ;0
L 1.12123996 -2.08103002 1.12126998 -2.08106004 0 P 0 ;0
L 1.12126998 -2.08106004 1.12128996 -2.08108996 0 P 0 ;0
L 1.12128996 -2.08108996 1.12235 -2.08231004 0 P 0 ;0
L 1.12235 -2.08231004 1.12238002 -2.08233996 0 P 0 ;0
L 1.12238002 -2.08233996 1.1224 -2.08236998 0 P 0 ;0
L 1.1224 -2.08236998 1.12246004 -2.08243002 0 P 0 ;0
L 1.12246004 -2.08243002 1.12361004 -2.08355 0 P 0 ;0
L 1.12361004 -2.08355 1.12366998 -2.08361004 0 P 0 ;0
L 1.12366998 -2.08361004 1.1237 -2.08363002 0 P 0 ;0
L 1.1237 -2.08363002 1.12373002 -2.08366004 0 P 0 ;0
L 1.12373002 -2.08366004 1.12496998 -2.08468996 0 P 0 ;0
L 1.12496998 -2.08468996 1.125 -2.08471004 0 P 0 ;0
L 1.125 -2.08471004 1.12503002 -2.08473996 0 P 0 ;0
L 1.12503002 -2.08473996 1.12506998 -2.08476004 0 P 0 ;0
L 1.12506998 -2.08476004 1.1251 -2.08478996 0 P 0 ;0
L 1.1251 -2.08478996 1.12641998 -2.08571004 0 P 0 ;0
L 1.12641998 -2.08571004 1.12645 -2.08573002 0 P 0 ;0
L 1.12645 -2.08573002 1.12648002 -2.08576004 0 P 0 ;0
L 1.12648002 -2.08576004 1.12651004 -2.08578002 0 P 0 ;0
L 1.12651004 -2.08578002 1.12655 -2.0858 0 P 0 ;0
L 1.12655 -2.0858 1.12793996 -2.08661004 0 P 0 ;0
L 1.12793996 -2.08661004 1.12801004 -2.08665 0 P 0 ;0
L 1.12801004 -2.08665 1.12805 -2.08666998 0 P 0 ;0
L 1.12805 -2.08666998 1.12808002 -2.08668996 0 P 0 ;0
L 1.12808002 -2.08668996 1.12808996 -2.08668996 0 P 0 ;0
L 1.12808996 -2.08668996 1.12953996 -2.08738996 0 P 0 ;0
L 1.12953996 -2.08738996 1.12961998 -2.08743002 0 P 0 ;0
L 1.12961998 -2.08743002 1.12965 -2.08743996 0 P 0 ;0
L 1.12965 -2.08743996 1.1297 -2.08746004 0 P 0 ;0
L 1.1297 -2.08746004 1.13118002 -2.08801998 0 P 0 ;0
L 1.13118002 -2.08801998 1.13133996 -2.08808002 0 P 0 ;0
L 1.13133996 -2.08808002 1.13286998 -2.08851004 0 P 0 ;0
L 1.13286998 -2.08851004 1.13295 -2.08853996 0 P 0 ;0
L 1.13295 -2.08853996 1.13303996 -2.08855 0 P 0 ;0
L 1.13303996 -2.08855 1.1346 -2.08886004 0 P 0 ;0
L 1.1346 -2.08886004 1.13471998 -2.08888996 0 P 0 ;0
L 1.13471998 -2.08888996 1.13476004 -2.08888996 0 P 0 ;0
L 1.13476004 -2.08888996 1.13633996 -2.08906998 0 P 0 ;0
L 1.13633996 -2.08906998 1.13638996 -2.08908002 0 P 0 ;0
L 1.13638996 -2.08908002 1.13651004 -2.08908002 0 P 0 ;0
L 1.13651004 -2.08908002 1.1381 -2.08913002 0 P 0 ;0
L 1.1381 -2.08913002 1.13818996 -2.08913002 0 P 0 ;0
L 1.31623996 -1.98923996 1.3135 -1.98988002 0 P 0 ;0
L 1.3135 -1.98988002 1.31078996 -1.99071004 0 P 0 ;0
L 1.31078996 -1.99071004 1.30813002 -1.99175 0 P 0 ;0
L 1.30813002 -1.99175 1.30553996 -1.99296998 0 P 0 ;0
L 1.30553996 -1.99296998 1.30308996 -1.99431998 0 P 0 ;0
L 1.30308996 -1.99431998 1.30073996 -1.99585 0 P 0 ;0
L 1.30073996 -1.99585 1.29863996 -1.99746004 0 P 0 ;0
L 1.29863996 -1.99746004 1.29666004 -1.99923996 0 P 0 ;0
L 1.29666004 -1.99923996 1.29205 -2.00375 0 P 0 ;0
L 1.29205 -2.00375 1.29205 -1.99243996 0 P 0 ;0
L 1.29205 -1.99243996 1.24316004 -1.99243996 0 P 0 ;0
L 1.24316004 -1.99243996 1.24313996 -2.00521004 0 P 0 ;0
L 1.24313996 -2.00521004 1.24261004 -2.03151004 0 P 0 ;0
L 1.24261004 -2.03151004 1.24086998 -2.07046004 0 P 0 ;0
L 1.24086998 -2.07046004 1.23873996 -2.10921004 0 P 0 ;0
L 1.23873996 -2.10921004 1.23811998 -2.11641998 0 P 0 ;0
L 1.23811998 -2.11641998 1.23711998 -2.12361998 0 P 0 ;0
L 1.23711998 -2.12361998 1.23655 -2.12716004 0 P 0 ;0
L 1.23655 -2.12716004 1.29205 -2.12716004 0 P 0 ;0
L 1.29205 -2.12716004 1.29206998 -2.11766004 0 P 0 ;0
L 1.29206998 -2.11766004 1.29238996 -2.10283996 0 P 0 ;0
L 1.29238996 -2.10283996 1.29336004 -2.08431004 0 P 0 ;0
L 1.29336004 -2.08431004 1.29463996 -2.06673002 0 P 0 ;0
L 1.29463996 -2.06673002 1.29511004 -2.06253002 0 P 0 ;0
L 1.29511004 -2.06253002 1.29583996 -2.05836004 0 P 0 ;0
L 1.29583996 -2.05836004 1.29683002 -2.05446998 0 P 0 ;0
L 1.29683002 -2.05446998 1.29813996 -2.05068996 0 P 0 ;0
L 1.29813996 -2.05068996 1.29978002 -2.04701998 0 P 0 ;0
L 1.29978002 -2.04701998 1.30056998 -2.04556998 0 P 0 ;0
L 1.30056998 -2.04556998 1.30146998 -2.04418996 0 P 0 ;0
L 1.30146998 -2.04418996 1.30246998 -2.04288002 0 P 0 ;0
L 1.30246998 -2.04288002 1.30356998 -2.04165 0 P 0 ;0
L 1.30356998 -2.04165 1.30475 -2.0405 0 P 0 ;0
L 1.30475 -2.0405 1.30603996 -2.03945 0 P 0 ;0
L 1.30603996 -2.03945 1.30773996 -2.03826004 0 P 0 ;0
L 1.30773996 -2.03826004 1.30953002 -2.03723002 0 P 0 ;0
L 1.30953002 -2.03723002 1.31141004 -2.03635 0 P 0 ;0
L 1.31141004 -2.03635 1.31335 -2.03563002 0 P 0 ;0
L 1.31335 -2.03563002 1.31535 -2.03508002 0 P 0 ;0
L 1.31535 -2.03508002 1.31973996 -2.03423002 0 P 0 ;0
L 1.31973996 -2.03423002 1.32416004 -2.03366998 0 P 0 ;0
L 1.32416004 -2.03366998 1.32863002 -2.0334 0 P 0 ;0
L 1.32863002 -2.0334 1.33688002 -2.03318002 0 P 0 ;0
L 1.33688002 -2.03318002 1.33613002 -2.01151004 0 P 0 ;0
L 1.33613002 -2.01151004 1.33581004 -2.00315 0 P 0 ;0
L 1.33581004 -2.00315 1.33543996 -1.99596004 0 P 0 ;0
L 1.33543996 -1.99596004 1.33508002 -1.98971004 0 P 0 ;0
L 1.33508002 -1.98971004 1.33503996 -1.98945 0 P 0 ;0
L 1.33503996 -1.98945 1.335 -1.98931998 0 P 0 ;0
L 1.335 -1.98931998 1.33496004 -1.9892 0 P 0 ;0
L 1.33496004 -1.9892 1.3349 -1.98908002 0 P 0 ;0
L 1.3349 -1.98908002 1.33483996 -1.98896998 0 P 0 ;0
L 1.33483996 -1.98896998 1.33476998 -1.98886004 0 P 0 ;0
L 1.33476998 -1.98886004 1.33468996 -1.98876004 0 P 0 ;0
L 1.33468996 -1.98876004 1.3346 -1.98866998 0 P 0 ;0
L 1.3346 -1.98866998 1.33451004 -1.98858996 0 P 0 ;0
L 1.33451004 -1.98858996 1.3344 -1.98851998 0 P 0 ;0
L 1.3344 -1.98851998 1.3343 -1.98845 0 P 0 ;0
L 1.3343 -1.98845 1.33418002 -1.98838996 0 P 0 ;0
L 1.33418002 -1.98838996 1.33406998 -1.98833996 0 P 0 ;0
L 1.33406998 -1.98833996 1.33395 -1.9883 0 P 0 ;0
L 1.33395 -1.9883 1.33383002 -1.98828002 0 P 0 ;0
L 1.33383002 -1.98828002 1.3337 -1.98826004 0 P 0 ;0
L 1.3337 -1.98826004 1.33356998 -1.98825 0 P 0 ;0
L 1.33356998 -1.98825 1.32756998 -1.98823002 0 P 0 ;0
L 1.32756998 -1.98823002 1.32135 -1.98853996 0 P 0 ;0
L 1.32135 -1.98853996 1.31878996 -1.98881998 0 P 0 ;0
L 1.31878996 -1.98881998 1.31623996 -1.98923996 0 P 0 ;0
L 1.2389 -2.12516004 1.29006004 -2.12516004 0 P 0 ;0
L 1.23906998 -2.12416004 1.29006004 -2.12416004 0 P 0 ;0
L 1.23921004 -2.12316004 1.29006004 -2.12316004 0 P 0 ;0
L 1.23933996 -2.12216004 1.29006004 -2.12216004 0 P 0 ;0
L 1.23948996 -2.12116004 1.29006004 -2.12116004 0 P 0 ;0
L 1.23961998 -2.12016004 1.29006998 -2.12016004 0 P 0 ;0
L 1.23976004 -2.11916004 1.29006998 -2.11916004 0 P 0 ;0
L 1.2399 -2.11816004 1.29006998 -2.11816004 0 P 0 ;0
L 1.24003996 -2.11716004 1.29008002 -2.11716004 0 P 0 ;0
L 1.24015 -2.11616004 1.2901 -2.11616004 0 P 0 ;0
L 1.24023996 -2.11516004 1.29011998 -2.11516004 0 P 0 ;0
L 1.24033002 -2.11416004 1.29013996 -2.11416004 0 P 0 ;0
L 1.24041004 -2.11316004 1.29016004 -2.11316004 0 P 0 ;0
L 1.24048996 -2.11216004 1.29018996 -2.11216004 0 P 0 ;0
L 1.24058002 -2.11116004 1.29021004 -2.11116004 0 P 0 ;0
L 1.24066998 -2.11016004 1.29023002 -2.11016004 0 P 0 ;0
L 1.24075 -2.10916004 1.29025 -2.10916004 0 P 0 ;0
L 1.2408 -2.10816004 1.29026998 -2.10816004 0 P 0 ;0
L 1.24086004 -2.10716004 1.29028996 -2.10716004 0 P 0 ;0
L 1.24091004 -2.10616004 1.29031998 -2.10616004 0 P 0 ;0
L 1.24096998 -2.10516004 1.29033996 -2.10516004 0 P 0 ;0
L 1.24101998 -2.10416004 1.29036004 -2.10416004 0 P 0 ;0
L 1.24108002 -2.10316004 1.29038002 -2.10316004 0 P 0 ;0
L 1.24113002 -2.10216004 1.29041998 -2.10216004 0 P 0 ;0
L 1.24118002 -2.10116004 1.29046998 -2.10116004 0 P 0 ;0
L 1.24123996 -2.10016004 1.29053002 -2.10016004 0 P 0 ;0
L 1.24128996 -2.09916004 1.29058002 -2.09916004 0 P 0 ;0
L 1.24135 -2.09816004 1.29063002 -2.09816004 0 P 0 ;0
L 1.2414 -2.09716004 1.29068002 -2.09716004 0 P 0 ;0
L 1.24146004 -2.09616004 1.29073996 -2.09616004 0 P 0 ;0
L 1.24151004 -2.09516004 1.29078996 -2.09516004 0 P 0 ;0
L 1.24156998 -2.09416004 1.29083996 -2.09416004 0 P 0 ;0
L 1.24161998 -2.09316004 1.2909 -2.09316004 0 P 0 ;0
L 1.24168002 -2.09216004 1.29095 -2.09216004 0 P 0 ;0
L 1.24173002 -2.09116004 1.291 -2.09116004 0 P 0 ;0
L 1.24178996 -2.09016004 1.29105 -2.09016004 0 P 0 ;0
L 1.24183996 -2.08916004 1.2911 -2.08916004 0 P 0 ;0
L 1.2419 -2.08816004 1.29116004 -2.08816004 0 P 0 ;0
L 1.24196004 -2.08716004 1.29121004 -2.08716004 0 P 0 ;0
L 1.24201004 -2.08616004 1.29126998 -2.08616004 0 P 0 ;0
L 1.24206998 -2.08516004 1.29131998 -2.08516004 0 P 0 ;0
L 1.24211998 -2.08416004 1.29136998 -2.08416004 0 P 0 ;0
L 1.2389 -2.12516004 1.2391 -2.12393002 0 P 0 ;0
L 1.2391 -2.12393002 1.2391 -2.1239 0 P 0 ;0
L 1.2391 -2.1239 1.24011004 -2.11665 0 P 0 ;0
L 1.24011004 -2.11665 1.24073002 -2.10935 0 P 0 ;0
L 1.24073002 -2.10935 1.24073996 -2.10931998 0 P 0 ;0
L 1.24073996 -2.10931998 1.24286004 -2.07056004 0 P 0 ;0
L 1.24286004 -2.07056004 1.24461004 -2.03158002 0 P 0 ;0
L 1.24461004 -2.03158002 1.24513996 -2.00523002 0 P 0 ;0
L 1.24513996 -2.00523002 1.24515 -1.99443996 0 P 0 ;0
L 1.24515 -1.99443996 1.29005 -1.99443996 0 P 0 ;0
L 1.29005 -1.99443996 1.29005 -2.00375 0 P 0 ;0
L 1.29005 -2.00375 1.29128002 -2.0056 0 P 0 ;0
L 1.29128002 -2.0056 1.29345 -2.00518002 0 P 0 ;0
L 1.29345 -2.00518002 1.29803002 -2.0007 0 P 0 ;0
L 1.29803002 -2.0007 1.29991998 -1.999 0 P 0 ;0
L 1.29991998 -1.999 1.30188996 -1.99748996 0 P 0 ;0
L 1.30188996 -1.99748996 1.30411998 -1.99603996 0 P 0 ;0
L 1.30411998 -1.99603996 1.30645 -1.99475 0 P 0 ;0
L 1.30645 -1.99475 1.30891998 -1.99358996 0 P 0 ;0
L 1.30891998 -1.99358996 1.31145 -1.9926 0 P 0 ;0
L 1.31145 -1.9926 1.31401998 -1.99181004 0 P 0 ;0
L 1.31401998 -1.99181004 1.31663996 -1.9912 0 P 0 ;0
L 1.31663996 -1.9912 1.31906004 -1.9908 0 P 0 ;0
L 1.31906004 -1.9908 1.32151004 -1.99053002 0 P 0 ;0
L 1.32151004 -1.99053002 1.32761998 -1.99023002 0 P 0 ;0
L 1.32761998 -1.99023002 1.3331 -1.99025 0 P 0 ;0
L 1.3331 -1.99025 1.33345 -1.99608002 0 P 0 ;0
L 1.33345 -1.99608002 1.33381004 -2.00323002 0 P 0 ;0
L 1.33381004 -2.00323002 1.33413002 -2.01158996 0 P 0 ;0
L 1.33413002 -2.01158996 1.33413002 -2.0116 0 P 0 ;0
L 1.33413002 -2.0116 1.33481998 -2.03123002 0 P 0 ;0
L 1.33481998 -2.03123002 1.32853996 -2.0314 0 P 0 ;0
L 1.32853996 -2.0314 1.32398002 -2.03166998 0 P 0 ;0
L 1.32398002 -2.03166998 1.31941998 -2.03225 0 P 0 ;0
L 1.31941998 -2.03225 1.31488996 -2.03313002 0 P 0 ;0
L 1.31488996 -2.03313002 1.31273996 -2.03373002 0 P 0 ;0
L 1.31273996 -2.03373002 1.31063996 -2.0345 0 P 0 ;0
L 1.31063996 -2.0345 1.3086 -2.03545 0 P 0 ;0
L 1.3086 -2.03545 1.30666004 -2.03656998 0 P 0 ;0
L 1.30666004 -2.03656998 1.30658996 -2.03661998 0 P 0 ;0
L 1.30658996 -2.03661998 1.30483002 -2.03786004 0 P 0 ;0
L 1.30483002 -2.03786004 1.30341998 -2.03901004 0 P 0 ;0
L 1.30341998 -2.03901004 1.30336998 -2.03906004 0 P 0 ;0
L 1.30336998 -2.03906004 1.30211998 -2.04026004 0 P 0 ;0
L 1.30211998 -2.04026004 1.30093002 -2.0416 0 P 0 ;0
L 1.30093002 -2.0416 1.29983002 -2.04303996 0 P 0 ;0
L 1.29983002 -2.04303996 1.29978996 -2.0431 0 P 0 ;0
L 1.29978996 -2.0431 1.29885 -2.04453996 0 P 0 ;0
L 1.29885 -2.04453996 1.29798996 -2.04613002 0 P 0 ;0
L 1.29798996 -2.04613002 1.29631998 -2.04986998 0 P 0 ;0
L 1.29631998 -2.04986998 1.29628002 -2.04995 0 P 0 ;0
L 1.29628002 -2.04995 1.29625 -2.05003002 0 P 0 ;0
L 1.29625 -2.05003002 1.29491998 -2.0539 0 P 0 ;0
L 1.29491998 -2.0539 1.29388996 -2.05793996 0 P 0 ;0
L 1.29388996 -2.05793996 1.29386998 -2.05801998 0 P 0 ;0
L 1.29386998 -2.05801998 1.29313996 -2.06221004 0 P 0 ;0
L 1.29313996 -2.06221004 1.29313002 -2.06223996 0 P 0 ;0
L 1.29313002 -2.06223996 1.29311998 -2.0623 0 P 0 ;0
L 1.29311998 -2.0623 1.29265 -2.06655 0 P 0 ;0
L 1.29265 -2.06655 1.29136998 -2.08418996 0 P 0 ;0
L 1.29136998 -2.08418996 1.29038996 -2.10276998 0 P 0 ;0
L 1.29038996 -2.10276998 1.29006998 -2.11763002 0 P 0 ;0
L 1.29006998 -2.11763002 1.29006004 -2.12516004 0 P 0 ;0
L 1.29006004 -2.12516004 1.2389 -2.12516004 0 P 0 ;0
L 1.09846998 -2.00483002 1.21248002 -2.00483002 0 P 0 ;0
L 1.09838002 -2.12083002 1.14708002 -2.12083002 0 P 0 ;0
L 1.11933002 -2.18283002 1.15161998 -2.18283002 0 P 0 ;0
L 1.11001998 -2.18183002 1.15838002 -2.18183002 0 P 0 ;0
L 1.10246998 -2.18083002 1.16333996 -2.18083002 0 P 0 ;0
L 1.04061004 -1.89731004 1.09978002 -1.89731004 0 P 0 ;0
L 1.03565 -1.89631004 1.09821004 -1.89631004 0 P 0 ;0
L 1.03068996 -1.89531004 1.09661004 -1.89531004 0 P 0 ;0
L 1.02573002 -1.89431004 1.09475 -1.89431004 0 P 0 ;0
L 1.019 -1.89331004 1.09288002 -1.89331004 0 P 0 ;0
L 1.01163996 -1.89231004 1.09101998 -1.89231004 0 P 0 ;0
L 0.99518996 -1.89131004 1.08916004 -1.89131004 0 P 0 ;0
L 0.87011998 -1.88331004 1.07278996 -1.88331004 0 P 0 ;0
L 0.86963996 -1.88231004 1.07053002 -1.88231004 0 P 0 ;0
L 0.86916004 -1.88131004 1.06828002 -1.88131004 0 P 0 ;0
L 0.86863002 -1.88031004 1.06603002 -1.88031004 0 P 0 ;0
L 0.86806998 -1.87931004 1.06351004 -1.87931004 0 P 0 ;0
L 0.8675 -1.87831004 1.06076998 -1.87831004 0 P 0 ;0
L 0.86693002 -1.87731004 1.05803996 -1.87731004 0 P 0 ;0
L 0.86631004 -1.87631004 1.05531004 -1.87631004 0 P 0 ;0
L 0.86563996 -1.87531004 1.05256998 -1.87531004 0 P 0 ;0
L 0.86498002 -1.87431004 1.04983996 -1.87431004 0 P 0 ;0
L 0.86431998 -1.87331004 1.0471 -1.87331004 0 P 0 ;0
L 0.86356004 -1.87231004 1.04376004 -1.87231004 0 P 0 ;0
L 0.86278996 -1.87131004 1.04041998 -1.87131004 0 P 0 ;0
L 0.86203002 -1.87031004 1.03708002 -1.87031004 0 P 0 ;0
L 0.86118996 -1.86931004 1.03373996 -1.86931004 0 P 0 ;0
L 0.8603 -1.86831004 1.0304 -1.86831004 0 P 0 ;0
L 0.85941004 -1.86731004 1.02656998 -1.86731004 0 P 0 ;0
L 0.8585 -1.86631004 1.02231998 -1.86631004 0 P 0 ;0
L 0.85756998 -1.86531004 1.01806998 -1.86531004 0 P 0 ;0
L 0.85663002 -1.86431004 1.01381998 -1.86431004 0 P 0 ;0
L 0.85568996 -1.86331004 1.00931998 -1.86331004 0 P 0 ;0
L 0.85481004 -1.86231004 1.00335 -1.86231004 0 P 0 ;0
L 0.85916998 -1.86131004 0.99738002 -1.86131004 0 P 0 ;0
L 0.86716998 -1.86031004 0.99141998 -1.86031004 0 P 0 ;0
L 0.87476998 -1.89731004 0.89943002 -1.89731004 0 P 0 ;0
L 0.87453996 -1.89631004 0.90426004 -1.89631004 0 P 0 ;0
L 0.87431004 -1.89531004 0.9097 -1.89531004 0 P 0 ;0
L 0.87406998 -1.89431004 0.91608002 -1.89431004 0 P 0 ;0
L 0.87383002 -1.89331004 0.92246004 -1.89331004 0 P 0 ;0
L 0.87355 -1.89231004 0.93086004 -1.89231004 0 P 0 ;0
L 0.87323002 -1.89131004 0.95553002 -1.89131004 0 P 0 ;0
L 0.87291004 -1.89031004 1.08728996 -1.89031004 0 P 0 ;0
L 0.87258996 -1.88931004 1.08543002 -1.88931004 0 P 0 ;0
L 0.87223002 -1.88831004 1.08356998 -1.88831004 0 P 0 ;0
L 0.87183002 -1.88731004 1.0817 -1.88731004 0 P 0 ;0
L 0.87143002 -1.88631004 1.07955 -1.88631004 0 P 0 ;0
L 0.87103002 -1.88531004 1.07728996 -1.88531004 0 P 0 ;0
L 0.8706 -1.88431004 1.07503996 -1.88431004 0 P 0 ;0
L 0.87525 -1.85931004 0.98545 -1.85931004 0 P 0 ;0
L 0.88421004 -1.85831004 0.97621004 -1.85831004 0 P 0 ;0
L 0.89393002 -1.85731004 0.96606998 -1.85731004 0 P 0 ;0
L 0.9106 -1.85631004 0.95203002 -1.85631004 0 P 0 ;0
L 1.08716004 -1.91231004 1.12151004 -1.91231004 0 P 0 ;0
L 1.08486004 -1.91131004 1.12018996 -1.91131004 0 P 0 ;0
L 1.08256004 -1.91031004 1.11886004 -1.91031004 0 P 0 ;0
L 1.08023002 -1.90931004 1.11753996 -1.90931004 0 P 0 ;0
L 1.07738002 -1.90831004 1.11621004 -1.90831004 0 P 0 ;0
L 1.07453002 -1.90731004 1.11488996 -1.90731004 0 P 0 ;0
L 1.07168996 -1.90631004 1.11356998 -1.90631004 0 P 0 ;0
L 1.06883996 -1.90531004 1.11223996 -1.90531004 0 P 0 ;0
L 1.066 -1.90431004 1.11076998 -1.90431004 0 P 0 ;0
L 1.06315 -1.90331004 1.1092 -1.90331004 0 P 0 ;0
L 1.0599 -1.90231004 1.10763002 -1.90231004 0 P 0 ;0
L 1.05611998 -1.90131004 1.10606004 -1.90131004 0 P 0 ;0
L 1.05235 -1.90031004 1.10448996 -1.90031004 0 P 0 ;0
L 1.04856998 -1.89931004 1.10291998 -1.89931004 0 P 0 ;0
L 1.04478996 -1.89831004 1.10135 -1.89831004 0 P 0 ;0
L 0.98815 -2.08316004 1.03726998 -2.08316004 0 P 0 ;0
L 0.98818002 -2.08216004 1.03731004 -2.08216004 0 P 0 ;0
L 0.98821998 -2.08116004 1.03735 -2.08116004 0 P 0 ;0
L 0.98825 -2.08016004 1.03738996 -2.08016004 0 P 0 ;0
L 0.98828002 -2.07916004 1.03743002 -2.07916004 0 P 0 ;0
L 0.98831998 -2.07816004 1.03746998 -2.07816004 0 P 0 ;0
L 0.98835 -2.07716004 1.03751004 -2.07716004 0 P 0 ;0
L 0.98838002 -2.07616004 1.03755 -2.07616004 0 P 0 ;0
L 0.98841998 -2.07516004 1.03758002 -2.07516004 0 P 0 ;0
L 0.98845 -2.07416004 1.03761004 -2.07416004 0 P 0 ;0
L 0.98848002 -2.07316004 1.03763996 -2.07316004 0 P 0 ;0
L 0.98851004 -2.07216004 1.03768002 -2.07216004 0 P 0 ;0
L 0.98855 -2.07116004 1.03771004 -2.07116004 0 P 0 ;0
L 0.98858002 -2.07016004 1.03773996 -2.07016004 0 P 0 ;0
L 0.98858996 -2.06916004 1.03776998 -2.06916004 0 P 0 ;0
L 0.98858996 -2.06816004 1.0378 -2.06816004 0 P 0 ;0
L 0.98858996 -2.06716004 1.03783002 -2.06716004 0 P 0 ;0
L 0.98858002 -2.06616004 1.03786004 -2.06616004 0 P 0 ;0
L 0.98856998 -2.06516004 1.0379 -2.06516004 0 P 0 ;0
L 0.98856998 -2.06416004 1.03793002 -2.06416004 0 P 0 ;0
L 0.98856998 -2.06316004 1.03796004 -2.06316004 0 P 0 ;0
L 0.98856004 -2.06216004 1.03798996 -2.06216004 0 P 0 ;0
L 0.98855 -2.06116004 1.03801998 -2.06116004 0 P 0 ;0
L 0.98855 -2.06016004 1.03805 -2.06016004 0 P 0 ;0
L 0.98853996 -2.05916004 1.03808002 -2.05916004 0 P 0 ;0
L 0.98853996 -2.05816004 1.0381 -2.05816004 0 P 0 ;0
L 0.98853002 -2.05716004 1.03811998 -2.05716004 0 P 0 ;0
L 0.98848002 -2.05616004 1.03815 -2.05616004 0 P 0 ;0
L 0.98841004 -2.05516004 1.03818002 -2.05516004 0 P 0 ;0
L 0.98835 -2.05416004 1.0382 -2.05416004 0 P 0 ;0
L 0.98828002 -2.05316004 1.03821998 -2.05316004 0 P 0 ;0
L 0.98821004 -2.05216004 1.03825 -2.05216004 0 P 0 ;0
L 0.98815 -2.05116004 1.03826998 -2.05116004 0 P 0 ;0
L 0.98808996 -2.05016004 1.03828996 -2.05016004 0 P 0 ;0
L 0.98801998 -2.04916004 1.03831998 -2.04916004 0 P 0 ;0
L 0.98796004 -2.04816004 1.03833996 -2.04816004 0 P 0 ;0
L 0.98788996 -2.04716004 1.03836004 -2.04716004 0 P 0 ;0
L 0.98783002 -2.04616004 1.03838996 -2.04616004 0 P 0 ;0
L 0.98768996 -2.04516004 1.0384 -2.04516004 0 P 0 ;0
L 0.98756004 -2.04416004 1.03841004 -2.04416004 0 P 0 ;0
L 0.98738002 -2.04316004 1.03841998 -2.04316004 0 P 0 ;0
L 0.98716004 -2.04216004 1.03843002 -2.04216004 0 P 0 ;0
L 0.98691998 -2.04116004 1.03843996 -2.04116004 0 P 0 ;0
L 0.98661998 -2.04016004 1.03845 -2.04016004 0 P 0 ;0
L 0.98631998 -2.03916004 1.03846004 -2.03916004 0 P 0 ;0
L 0.98593996 -2.03816004 1.03846998 -2.03816004 0 P 0 ;0
L 0.98546998 -2.03716004 1.03848002 -2.03716004 0 P 0 ;0
L 0.98491004 -2.03616004 1.03846998 -2.03616004 0 P 0 ;0
L 0.98425 -2.03516004 1.03846004 -2.03516004 0 P 0 ;0
L 0.98346004 -2.03416004 1.03846004 -2.03416004 0 P 0 ;0
L 0.98251998 -2.03316004 1.03843996 -2.03316004 0 P 0 ;0
L 0.98138002 -2.03216004 1.03843002 -2.03216004 0 P 0 ;0
L 0.97998996 -2.03116004 1.03841998 -2.03116004 0 P 0 ;0
L 0.97813996 -2.03016004 1.03841004 -2.03016004 0 P 0 ;0
L 0.97491004 -2.02916004 1.0384 -2.02916004 0 P 0 ;0
L 0.94763996 -2.00716004 1.03293996 -2.00716004 0 P 0 ;0
L 0.94978996 -2.00616004 1.03231998 -2.00616004 0 P 0 ;0
L 0.95081004 -2.00516004 1.0317 -2.00516004 0 P 0 ;0
L 0.95183002 -2.00416004 1.03098002 -2.00416004 0 P 0 ;0
L 0.95285 -2.00316004 1.03023002 -2.00316004 0 P 0 ;0
L 0.95388996 -2.00216004 1.02936004 -2.00216004 0 P 0 ;0
L 0.95498002 -2.00116004 1.02841998 -2.00116004 0 P 0 ;0
L 0.95621998 -2.00016004 1.02738996 -2.00016004 0 P 0 ;0
L 0.95761998 -1.99916004 1.0262 -1.99916004 0 P 0 ;0
L 0.9592 -1.99816004 1.02486004 -1.99816004 0 P 0 ;0
L 0.96083996 -1.99716004 1.02335 -1.99716004 0 P 0 ;0
L 0.9627 -1.99616004 1.02161004 -1.99616004 0 P 0 ;0
L 0.96468996 -1.99516004 1.01951998 -1.99516004 0 P 0 ;0
L 0.96685 -1.99416004 1.01683002 -1.99416004 0 P 0 ;0
L 0.96936998 -1.99316004 1.01378002 -1.99316004 0 P 0 ;0
L 0.97236998 -1.99216004 1.00981004 -1.99216004 0 P 0 ;0
L 0.97676004 -1.99116004 1.00456998 -1.99116004 0 P 0 ;0
L 1.06713996 -2.08283002 1.12288002 -2.08283002 0 P 0 ;0
L 1.06698996 -2.08183002 1.12193996 -2.08183002 0 P 0 ;0
L 1.06686004 -2.08083002 1.12108996 -2.08083002 0 P 0 ;0
L 1.06673996 -2.07983002 1.12036004 -2.07983002 0 P 0 ;0
L 1.06661998 -2.07883002 1.11971998 -2.07883002 0 P 0 ;0
L 1.06653002 -2.07783002 1.11916004 -2.07783002 0 P 0 ;0
L 1.06648002 -2.07683002 1.11866004 -2.07683002 0 P 0 ;0
L 1.06641998 -2.07583002 1.11826004 -2.07583002 0 P 0 ;0
L 1.06636998 -2.07483002 1.11791998 -2.07483002 0 P 0 ;0
L 1.06631998 -2.07383002 1.11761998 -2.07383002 0 P 0 ;0
L 1.06626004 -2.07283002 1.11741998 -2.07283002 0 P 0 ;0
L 1.06621004 -2.07183002 1.11723996 -2.07183002 0 P 0 ;0
L 1.06616004 -2.07083002 1.11711998 -2.07083002 0 P 0 ;0
L 1.06616004 -2.06983002 1.11701004 -2.06983002 0 P 0 ;0
L 1.06616004 -2.06883002 1.11688996 -2.06883002 0 P 0 ;0
L 1.06616998 -2.06783002 1.11676998 -2.06783002 0 P 0 ;0
L 1.06618002 -2.06683002 1.11666998 -2.06683002 0 P 0 ;0
L 1.06618996 -2.06583002 1.11663002 -2.06583002 0 P 0 ;0
L 1.0662 -2.06483002 1.11658996 -2.06483002 0 P 0 ;0
L 1.06621004 -2.06383002 1.11656004 -2.06383002 0 P 0 ;0
L 1.06623002 -2.06283002 1.11651998 -2.06283002 0 P 0 ;0
L 1.06631004 -2.06183002 1.11648996 -2.06183002 0 P 0 ;0
L 1.06638002 -2.06083002 1.11653002 -2.06083002 0 P 0 ;0
L 1.06645 -2.05983002 1.11656998 -2.05983002 0 P 0 ;0
L 1.06651998 -2.05883002 1.11661998 -2.05883002 0 P 0 ;0
L 1.06658996 -2.05783002 1.11666004 -2.05783002 0 P 0 ;0
L 1.06666998 -2.05683002 1.11671004 -2.05683002 0 P 0 ;0
L 1.06673996 -2.05583002 1.11681004 -2.05583002 0 P 0 ;0
L 1.06686004 -2.05483002 1.11693002 -2.05483002 0 P 0 ;0
L 1.067 -2.05383002 1.11705 -2.05383002 0 P 0 ;0
L 1.06713996 -2.05283002 1.11718002 -2.05283002 0 P 0 ;0
L 1.06728002 -2.05183002 1.11731004 -2.05183002 0 P 0 ;0
L 1.06741998 -2.05083002 1.11746004 -2.05083002 0 P 0 ;0
L 1.06756004 -2.04983002 1.11766004 -2.04983002 0 P 0 ;0
L 1.0677 -2.04883002 1.11786004 -2.04883002 0 P 0 ;0
L 1.06786004 -2.04783002 1.11813996 -2.04783002 0 P 0 ;0
L 1.06806998 -2.04683002 1.11841998 -2.04683002 0 P 0 ;0
L 1.06828002 -2.04583002 1.11876998 -2.04583002 0 P 0 ;0
L 1.06848996 -2.04483002 1.11913002 -2.04483002 0 P 0 ;0
L 1.06871004 -2.04383002 1.11955 -2.04383002 0 P 0 ;0
L 1.06898996 -2.04283002 1.11998996 -2.04283002 0 P 0 ;0
L 1.06928002 -2.04183002 1.12048002 -2.04183002 0 P 0 ;0
L 1.06956004 -2.04083002 1.12101004 -2.04083002 0 P 0 ;0
L 1.06985 -2.03983002 1.12161998 -2.03983002 0 P 0 ;0
L 1.07021004 -2.03883002 1.12225 -2.03883002 0 P 0 ;0
L 1.07056998 -2.03783002 1.12298002 -2.03783002 0 P 0 ;0
L 1.07093002 -2.03683002 1.12373996 -2.03683002 0 P 0 ;0
L 1.07128996 -2.03583002 1.12461998 -2.03583002 0 P 0 ;0
L 1.07173002 -2.03483002 1.12548996 -2.03483002 0 P 0 ;0
L 1.07216998 -2.03383002 1.12646004 -2.03383002 0 P 0 ;0
L 1.07261998 -2.03283002 1.12748996 -2.03283002 0 P 0 ;0
L 1.07308002 -2.03183002 1.12855 -2.03183002 0 P 0 ;0
L 1.07361998 -2.03083002 1.12978996 -2.03083002 0 P 0 ;0
L 1.09761004 -1.91731004 1.12756998 -1.91731004 0 P 0 ;0
L 1.09566004 -1.91631004 1.12645 -1.91631004 0 P 0 ;0
L 1.09371004 -1.91531004 1.12533002 -1.91531004 0 P 0 ;0
L 1.09176004 -1.91431004 1.12416004 -1.91431004 0 P 0 ;0
L 1.08946004 -1.91331004 1.12283996 -1.91331004 0 P 0 ;0
L 1.07415 -2.02983002 1.13101998 -2.02983002 0 P 0 ;0
L 1.07468996 -2.02883002 1.13248996 -2.02883002 0 P 0 ;0
L 1.07528996 -2.02783002 1.134 -2.02783002 0 P 0 ;0
L 1.07591998 -2.02683002 1.13586004 -2.02683002 0 P 0 ;0
L 1.07656004 -2.02583002 1.13828996 -2.02583002 0 P 0 ;0
L 1.07721004 -2.02483002 1.14243002 -2.02483002 0 P 0 ;0
L 1.07795 -2.02383002 1.21126998 -2.02383002 0 P 0 ;0
L 1.07868002 -2.02283002 1.21133002 -2.02283002 0 P 0 ;0
L 1.07941998 -2.02183002 1.2114 -2.02183002 0 P 0 ;0
L 1.08021004 -2.02083002 1.21146004 -2.02083002 0 P 0 ;0
L 1.08103996 -2.01983002 1.21153002 -2.01983002 0 P 0 ;0
L 1.08186998 -2.01883002 1.2116 -2.01883002 0 P 0 ;0
L 1.08273002 -2.01783002 1.21166004 -2.01783002 0 P 0 ;0
L 1.08366998 -2.01683002 1.21173002 -2.01683002 0 P 0 ;0
L 1.0846 -2.01583002 1.2118 -2.01583002 0 P 0 ;0
L 1.08555 -2.01483002 1.21186004 -2.01483002 0 P 0 ;0
L 1.08661004 -2.01383002 1.21193002 -2.01383002 0 P 0 ;0
L 1.08766998 -2.01283002 1.21198996 -2.01283002 0 P 0 ;0
L 1.08873002 -2.01183002 1.21205 -2.01183002 0 P 0 ;0
L 1.0898 -2.01083002 1.21211998 -2.01083002 0 P 0 ;0
L 1.09098996 -2.00983002 1.21218002 -2.00983002 0 P 0 ;0
L 1.09225 -2.00883002 1.21223996 -2.00883002 0 P 0 ;0
L 1.09358996 -2.00783002 1.2123 -2.00783002 0 P 0 ;0
L 1.09506998 -2.00683002 1.21236004 -2.00683002 0 P 0 ;0
L 1.09668996 -2.00583002 1.21241998 -2.00583002 0 P 0 ;0
L 0.98546998 -2.12516004 1.03548996 -2.12516004 0 P 0 ;0
L 0.98558996 -2.12416004 1.03553996 -2.12416004 0 P 0 ;0
L 0.9857 -2.12316004 1.03558002 -2.12316004 0 P 0 ;0
L 0.98581004 -2.12216004 1.03561998 -2.12216004 0 P 0 ;0
L 0.98591004 -2.12116004 1.03566998 -2.12116004 0 P 0 ;0
L 0.98598996 -2.12016004 1.03571004 -2.12016004 0 P 0 ;0
L 0.98608002 -2.11916004 1.03575 -2.11916004 0 P 0 ;0
L 0.98616998 -2.11816004 1.0358 -2.11816004 0 P 0 ;0
L 0.98625 -2.11716004 1.03583996 -2.11716004 0 P 0 ;0
L 0.98633996 -2.11616004 1.03588002 -2.11616004 0 P 0 ;0
L 0.98641998 -2.11516004 1.03593002 -2.11516004 0 P 0 ;0
L 0.98651004 -2.11416004 1.03596998 -2.11416004 0 P 0 ;0
L 0.9866 -2.11316004 1.03601004 -2.11316004 0 P 0 ;0
L 0.98668002 -2.11216004 1.03605 -2.11216004 0 P 0 ;0
L 0.98676998 -2.11116004 1.0361 -2.11116004 0 P 0 ;0
L 0.98685 -2.11016004 1.03613996 -2.11016004 0 P 0 ;0
L 0.98693996 -2.10916004 1.03618002 -2.10916004 0 P 0 ;0
L 0.987 -2.10816004 1.03623002 -2.10816004 0 P 0 ;0
L 0.98705 -2.10716004 1.03626998 -2.10716004 0 P 0 ;0
L 0.9871 -2.10616004 1.03631004 -2.10616004 0 P 0 ;0
L 0.98716004 -2.10516004 1.03636004 -2.10516004 0 P 0 ;0
L 0.9872 -2.10416004 1.0364 -2.10416004 0 P 0 ;0
L 0.98725 -2.10316004 1.03643996 -2.10316004 0 P 0 ;0
L 0.98731004 -2.10216004 1.03648002 -2.10216004 0 P 0 ;0
L 0.98735 -2.10116004 1.03653002 -2.10116004 0 P 0 ;0
L 0.9874 -2.10016004 1.03656998 -2.10016004 0 P 0 ;0
L 0.98746004 -2.09916004 1.03661004 -2.09916004 0 P 0 ;0
L 0.98751004 -2.09816004 1.03666004 -2.09816004 0 P 0 ;0
L 0.98755 -2.09716004 1.0367 -2.09716004 0 P 0 ;0
L 0.9876 -2.09616004 1.03673996 -2.09616004 0 P 0 ;0
L 0.98766004 -2.09516004 1.03678996 -2.09516004 0 P 0 ;0
L 0.9877 -2.09416004 1.03683002 -2.09416004 0 P 0 ;0
L 0.98775 -2.09316004 1.03686998 -2.09316004 0 P 0 ;0
L 0.98781004 -2.09216004 1.03691998 -2.09216004 0 P 0 ;0
L 0.98785 -2.09116004 1.03696004 -2.09116004 0 P 0 ;0
L 0.9879 -2.09016004 1.037 -2.09016004 0 P 0 ;0
L 0.98796004 -2.08916004 1.03703996 -2.08916004 0 P 0 ;0
L 0.98798996 -2.08816004 1.03706998 -2.08816004 0 P 0 ;0
L 0.98801998 -2.08716004 1.03711004 -2.08716004 0 P 0 ;0
L 0.98805 -2.08616004 1.03715 -2.08616004 0 P 0 ;0
L 0.98808996 -2.08516004 1.03718996 -2.08516004 0 P 0 ;0
L 0.98811998 -2.08416004 1.03723002 -2.08416004 0 P 0 ;0
L 1.08216998 -2.15683002 1.19803996 -2.15683002 0 P 0 ;0
L 1.0821 -2.15583002 1.19861004 -2.15583002 0 P 0 ;0
L 1.08201998 -2.15483002 1.19918002 -2.15483002 0 P 0 ;0
L 1.08195 -2.15383002 1.1997 -2.15383002 0 P 0 ;0
L 1.08188996 -2.15283002 1.20018002 -2.15283002 0 P 0 ;0
L 1.08183002 -2.15183002 1.20066004 -2.15183002 0 P 0 ;0
L 1.08176998 -2.15083002 1.20113996 -2.15083002 0 P 0 ;0
L 1.08171998 -2.14983002 1.20153996 -2.14983002 0 P 0 ;0
L 1.08166004 -2.14883002 1.20193002 -2.14883002 0 P 0 ;0
L 1.0816 -2.14783002 1.11538996 -2.14783002 0 P 0 ;0
L 1.08155 -2.14683002 1.10903002 -2.14683002 0 P 0 ;0
L 1.0815 -2.14583002 1.10415 -2.14583002 0 P 0 ;0
L 1.08146004 -2.14483002 1.09953002 -2.14483002 0 P 0 ;0
L 1.08141004 -2.14383002 1.09563996 -2.14383002 0 P 0 ;0
L 1.08136004 -2.14283002 1.09183996 -2.14283002 0 P 0 ;0
L 1.08131004 -2.14183002 1.08821004 -2.14183002 0 P 0 ;0
L 1.08133002 -2.14083002 1.08471998 -2.14083002 0 P 0 ;0
L 1.09586998 -2.11983002 1.14965 -2.11983002 0 P 0 ;0
L 1.09361998 -2.11883002 1.15221998 -2.11883002 0 P 0 ;0
L 1.09158996 -2.11783002 1.20595 -2.11783002 0 P 0 ;0
L 1.08988002 -2.11683002 1.20601004 -2.11683002 0 P 0 ;0
L 1.08823996 -2.11583002 1.20606998 -2.11583002 0 P 0 ;0
L 1.08678996 -2.11483002 1.20613002 -2.11483002 0 P 0 ;0
L 1.08541004 -2.11383002 1.20618996 -2.11383002 0 P 0 ;0
L 1.08416998 -2.11283002 1.20625 -2.11283002 0 P 0 ;0
L 1.08295 -2.11183002 1.20631004 -2.11183002 0 P 0 ;0
L 1.08188002 -2.11083002 1.20638002 -2.11083002 0 P 0 ;0
L 1.08081998 -2.10983002 1.20643996 -2.10983002 0 P 0 ;0
L 1.07986004 -2.10883002 1.2065 -2.10883002 0 P 0 ;0
L 1.07895 -2.10783002 1.20656004 -2.10783002 0 P 0 ;0
L 1.07803002 -2.10683002 1.20661998 -2.10683002 0 P 0 ;0
L 1.07723996 -2.10583002 1.20666998 -2.10583002 0 P 0 ;0
L 1.07646004 -2.10483002 1.20671998 -2.10483002 0 P 0 ;0
L 1.07568002 -2.10383002 1.20678002 -2.10383002 0 P 0 ;0
L 1.075 -2.10283002 1.20683002 -2.10283002 0 P 0 ;0
L 1.07433002 -2.10183002 1.20688002 -2.10183002 0 P 0 ;0
L 1.07366998 -2.10083002 1.20693996 -2.10083002 0 P 0 ;0
L 1.07308996 -2.09983002 1.20698996 -2.09983002 0 P 0 ;0
L 1.07253002 -2.09883002 1.20705 -2.09883002 0 P 0 ;0
L 1.07198002 -2.09783002 1.2071 -2.09783002 0 P 0 ;0
L 1.07146998 -2.09683002 1.20715 -2.09683002 0 P 0 ;0
L 1.07101998 -2.09583002 1.2072 -2.09583002 0 P 0 ;0
L 1.07056998 -2.09483002 1.20726004 -2.09483002 0 P 0 ;0
L 1.07013002 -2.09383002 1.20731004 -2.09383002 0 P 0 ;0
L 1.06976998 -2.09283002 1.20736004 -2.09283002 0 P 0 ;0
L 1.06941998 -2.09183002 1.20741998 -2.09183002 0 P 0 ;0
L 1.06906004 -2.09083002 1.20746998 -2.09083002 0 P 0 ;0
L 1.06876004 -2.08983002 1.20753002 -2.08983002 0 P 0 ;0
L 1.06848996 -2.08883002 1.13443002 -2.08883002 0 P 0 ;0
L 1.06821998 -2.08783002 1.13068002 -2.08783002 0 P 0 ;0
L 1.06795 -2.08683002 1.12836998 -2.08683002 0 P 0 ;0
L 1.06771998 -2.08583002 1.1266 -2.08583002 0 P 0 ;0
L 1.06753002 -2.08483002 1.12516004 -2.08483002 0 P 0 ;0
L 1.06733002 -2.08383002 1.12393996 -2.08383002 0 P 0 ;0
L 0.90273996 -1.85456998 0.89068996 -1.85558002 0 P 0 ;0
L 0.89068996 -1.85558002 0.87421004 -1.85741998 0 P 0 ;0
L 0.87421004 -1.85741998 0.85783002 -1.85946998 0 P 0 ;0
L 0.85783002 -1.85946998 0.85526998 -1.8599 0 P 0 ;0
L 0.85526998 -1.8599 0.85276004 -1.86055 0 P 0 ;0
L 0.85276004 -1.86055 0.85255 -1.86063996 0 P 0 ;0
L 0.85255 -1.86063996 0.85248996 -1.86068996 0 P 0 ;0
L 0.85248996 -1.86068996 0.85243002 -1.86073002 0 P 0 ;0
L 0.85243002 -1.86073002 0.85238002 -1.86078002 0 P 0 ;0
L 0.85238002 -1.86078002 0.85233002 -1.86083996 0 P 0 ;0
L 0.85233002 -1.86083996 0.85225 -1.86096004 0 P 0 ;0
L 0.85225 -1.86096004 0.85218002 -1.8611 0 P 0 ;0
L 0.85218002 -1.8611 0.85216004 -1.86116998 0 P 0 ;0
L 0.85216004 -1.86116998 0.85215 -1.86123996 0 P 0 ;0
L 0.85215 -1.86123996 0.85213996 -1.86136998 0 P 0 ;0
L 0.85213996 -1.86136998 0.85213002 -1.86148996 0 P 0 ;0
L 0.85213002 -1.86148996 0.85213996 -1.86161998 0 P 0 ;0
L 0.85213996 -1.86161998 0.85215 -1.86173996 0 P 0 ;0
L 0.85215 -1.86173996 0.85218002 -1.86186998 0 P 0 ;0
L 0.85218002 -1.86186998 0.85221004 -1.86198996 0 P 0 ;0
L 0.85221004 -1.86198996 0.85225 -1.8621 0 P 0 ;0
L 0.85225 -1.8621 0.85231004 -1.86221998 0 P 0 ;0
L 0.85231004 -1.86221998 0.85236998 -1.86233002 0 P 0 ;0
L 0.85236998 -1.86233002 0.85281998 -1.863 0 P 0 ;0
L 0.85281998 -1.863 0.8533 -1.86363996 0 P 0 ;0
L 0.8533 -1.86363996 0.85383002 -1.86425 0 P 0 ;0
L 0.85383002 -1.86425 0.85736004 -1.86801998 0 P 0 ;0
L 0.85736004 -1.86801998 0.86013002 -1.87113002 0 P 0 ;0
L 0.86013002 -1.87113002 0.86266004 -1.87443002 0 P 0 ;0
L 0.86266004 -1.87443002 0.86501004 -1.87798996 0 P 0 ;0
L 0.86501004 -1.87798996 0.86711998 -1.88171004 0 P 0 ;0
L 0.86711998 -1.88171004 0.86896998 -1.88553996 0 P 0 ;0
L 0.86896998 -1.88553996 0.87055 -1.8895 0 P 0 ;0
L 0.87055 -1.8895 0.8718 -1.89343002 0 P 0 ;0
L 0.8718 -1.89343002 0.87276004 -1.89745 0 P 0 ;0
L 0.87276004 -1.89745 0.87371004 -1.90195 0 P 0 ;0
L 0.87371004 -1.90195 0.87383002 -1.90236004 0 P 0 ;0
L 0.87383002 -1.90236004 0.87396998 -1.90276004 0 P 0 ;0
L 0.87396998 -1.90276004 0.87416004 -1.90313996 0 P 0 ;0
L 0.87416004 -1.90313996 0.87436998 -1.90351004 0 P 0 ;0
L 0.87436998 -1.90351004 0.87443002 -1.9036 0 P 0 ;0
L 0.87443002 -1.9036 0.87456998 -1.90376004 0 P 0 ;0
L 0.87456998 -1.90376004 0.87465 -1.90381998 0 P 0 ;0
L 0.87465 -1.90381998 0.87473002 -1.90388996 0 P 0 ;0
L 0.87473002 -1.90388996 0.87481998 -1.90393996 0 P 0 ;0
L 0.87481998 -1.90393996 0.87491998 -1.90398996 0 P 0 ;0
L 0.87491998 -1.90398996 0.87501004 -1.90403002 0 P 0 ;0
L 0.87501004 -1.90403002 0.87521004 -1.90408996 0 P 0 ;0
L 0.87521004 -1.90408996 0.87531998 -1.9041 0 P 0 ;0
L 0.87531998 -1.9041 0.87573002 -1.90413002 0 P 0 ;0
L 0.87573002 -1.90413002 0.87613996 -1.90411998 0 P 0 ;0
L 0.87613996 -1.90411998 0.87653996 -1.90408002 0 P 0 ;0
L 0.87653996 -1.90408002 0.87695 -1.90401004 0 P 0 ;0
L 0.87695 -1.90401004 0.90756004 -1.89766998 0 P 0 ;0
L 0.90756004 -1.89766998 0.92603996 -1.89478002 0 P 0 ;0
L 0.92603996 -1.89478002 0.93486004 -1.89393996 0 P 0 ;0
L 0.93486004 -1.89393996 0.94371004 -1.8935 0 P 0 ;0
L 0.94371004 -1.8935 0.97045 -1.89308002 0 P 0 ;0
L 0.97045 -1.89308002 0.99468996 -1.89328996 0 P 0 ;0
L 0.99468996 -1.89328996 1.01021004 -1.89413996 0 P 0 ;0
L 1.01021004 -1.89413996 1.0241 -1.89601998 0 P 0 ;0
L 1.0241 -1.89601998 1.04188002 -1.89961004 0 P 0 ;0
L 1.04188002 -1.89961004 1.06095 -1.90466004 0 P 0 ;0
L 1.06095 -1.90466004 1.07963996 -1.91123002 0 P 0 ;0
L 1.07963996 -1.91123002 1.09093996 -1.91613002 0 P 0 ;0
L 1.09093996 -1.91613002 1.10186998 -1.92175 0 P 0 ;0
L 1.10186998 -1.92175 1.11243996 -1.92806998 0 P 0 ;0
L 1.11243996 -1.92806998 1.12163002 -1.93446998 0 P 0 ;0
L 1.12163002 -1.93446998 1.13033002 -1.94148996 0 P 0 ;0
L 1.13033002 -1.94148996 1.1385 -1.94911004 0 P 0 ;0
L 1.1385 -1.94911004 1.14358996 -1.9546 0 P 0 ;0
L 1.14358996 -1.9546 1.14825 -1.96045 0 P 0 ;0
L 1.14825 -1.96045 1.15246998 -1.96663002 0 P 0 ;0
L 1.15246998 -1.96663002 1.15623002 -1.97316004 0 P 0 ;0
L 1.15623002 -1.97316004 1.15895 -1.97831004 0 P 0 ;0
L 1.15895 -1.97831004 1.17358996 -1.97831004 0 P 0 ;0
L 1.17358996 -1.97831004 1.17135 -1.9726 0 P 0 ;0
L 1.17135 -1.9726 1.16696004 -1.96266998 0 P 0 ;0
L 1.16696004 -1.96266998 1.16171998 -1.95313002 0 P 0 ;0
L 1.16171998 -1.95313002 1.1557 -1.94406998 0 P 0 ;0
L 1.1557 -1.94406998 1.14885 -1.93548002 0 P 0 ;0
L 1.14885 -1.93548002 1.13778996 -1.92378002 0 P 0 ;0
L 1.13778996 -1.92378002 1.12576998 -1.91301998 0 P 0 ;0
L 1.12576998 -1.91301998 1.11283996 -1.90326004 0 P 0 ;0
L 1.11283996 -1.90326004 1.09783002 -1.89368996 0 P 0 ;0
L 1.09783002 -1.89368996 1.08213002 -1.88526998 0 P 0 ;0
L 1.08213002 -1.88526998 1.06576998 -1.87801004 0 P 0 ;0
L 1.06576998 -1.87801004 1.04776004 -1.87141998 0 P 0 ;0
L 1.04776004 -1.87141998 1.02938002 -1.86591998 0 P 0 ;0
L 1.02938002 -1.86591998 1.01058002 -1.8615 0 P 0 ;0
L 1.01058002 -1.8615 0.98441998 -1.85711004 0 P 0 ;0
L 0.98441998 -1.85711004 0.95781004 -1.85448996 0 P 0 ;0
L 0.95781004 -1.85448996 0.93061004 -1.85366004 0 P 0 ;0
L 0.93061004 -1.85366004 0.90273996 -1.85456998 0 P 0 ;0
L 1.16015 -1.97631004 1.15798002 -1.97218996 0 P 0 ;0
L 1.15798002 -1.97218996 1.15796004 -1.97216004 0 P 0 ;0
L 1.15796004 -1.97216004 1.15416004 -1.96556998 0 P 0 ;0
L 1.15416004 -1.96556998 1.15411998 -1.96551004 0 P 0 ;0
L 1.15411998 -1.96551004 1.14986004 -1.95926004 0 P 0 ;0
L 1.14986004 -1.95926004 1.14981998 -1.95921004 0 P 0 ;0
L 1.14981998 -1.95921004 1.14511004 -1.9533 0 P 0 ;0
L 1.14511004 -1.9533 1.13991998 -1.9477 0 P 0 ;0
L 1.13991998 -1.9477 1.13986004 -1.94765 0 P 0 ;0
L 1.13986004 -1.94765 1.13163996 -1.93998002 0 P 0 ;0
L 1.13163996 -1.93998002 1.12283002 -1.93286004 0 P 0 ;0
L 1.12283002 -1.93286004 1.11351998 -1.92638996 0 P 0 ;0
L 1.11351998 -1.92638996 1.10283996 -1.92 0 P 0 ;0
L 1.10283996 -1.92 1.0918 -1.91433002 0 P 0 ;0
L 1.0918 -1.91433002 1.08036998 -1.90936004 0 P 0 ;0
L 1.08036998 -1.90936004 1.06153002 -1.90273996 0 P 0 ;0
L 1.06153002 -1.90273996 1.06146004 -1.90273002 0 P 0 ;0
L 1.06146004 -1.90273002 1.04233002 -1.89766004 0 P 0 ;0
L 1.04233002 -1.89766004 1.02443002 -1.89405 0 P 0 ;0
L 1.02443002 -1.89405 1.0104 -1.89213996 0 P 0 ;0
L 1.0104 -1.89213996 0.99475 -1.89128996 0 P 0 ;0
L 0.99475 -1.89128996 0.97045 -1.89108002 0 P 0 ;0
L 0.97045 -1.89108002 0.94365 -1.8915 0 P 0 ;0
L 0.94365 -1.8915 0.94361998 -1.8915 0 P 0 ;0
L 0.94361998 -1.8915 0.93471998 -1.89195 0 P 0 ;0
L 0.93471998 -1.89195 0.92578996 -1.89278996 0 P 0 ;0
L 0.92578996 -1.89278996 0.9072 -1.89571004 0 P 0 ;0
L 0.9072 -1.89571004 0.87656998 -1.90203996 0 P 0 ;0
L 0.87656998 -1.90203996 0.87626998 -1.9021 0 P 0 ;0
L 0.87626998 -1.9021 0.87601998 -1.90211998 0 P 0 ;0
L 0.87601998 -1.90211998 0.87588996 -1.90213002 0 P 0 ;0
L 0.87588996 -1.90213002 0.87583002 -1.90198996 0 P 0 ;0
L 0.87583002 -1.90198996 0.87573002 -1.90175 0 P 0 ;0
L 0.87573002 -1.90175 0.87566004 -1.90146998 0 P 0 ;0
L 0.87566004 -1.90146998 0.87471004 -1.89701004 0 P 0 ;0
L 0.87471004 -1.89701004 0.8747 -1.89698996 0 P 0 ;0
L 0.8747 -1.89698996 0.87373002 -1.89288996 0 P 0 ;0
L 0.87373002 -1.89288996 0.87243002 -1.88881998 0 P 0 ;0
L 0.87243002 -1.88881998 0.8724 -1.88876004 0 P 0 ;0
L 0.8724 -1.88876004 0.8708 -1.88473996 0 P 0 ;0
L 0.8708 -1.88473996 0.8689 -1.88078002 0 P 0 ;0
L 0.8689 -1.88078002 0.86671998 -1.87693996 0 P 0 ;0
L 0.86671998 -1.87693996 0.86428996 -1.87326004 0 P 0 ;0
L 0.86428996 -1.87326004 0.86166998 -1.86985 0 P 0 ;0
L 0.86166998 -1.86985 0.85883996 -1.86668002 0 P 0 ;0
L 0.85883996 -1.86668002 0.85883002 -1.86666004 0 P 0 ;0
L 0.85883002 -1.86666004 0.85531998 -1.86291004 0 P 0 ;0
L 0.85531998 -1.86291004 0.85486004 -1.86238002 0 P 0 ;0
L 0.85486004 -1.86238002 0.85466004 -1.86211998 0 P 0 ;0
L 0.85466004 -1.86211998 0.8557 -1.86186004 0 P 0 ;0
L 0.8557 -1.86186004 0.85811998 -1.86145 0 P 0 ;0
L 0.85811998 -1.86145 0.87443996 -1.85941004 0 P 0 ;0
L 0.87443996 -1.85941004 0.89088996 -1.85756998 0 P 0 ;0
L 0.89088996 -1.85756998 0.90286004 -1.85656998 0 P 0 ;0
L 0.90286004 -1.85656998 0.93061004 -1.85566004 0 P 0 ;0
L 0.93061004 -1.85566004 0.95768002 -1.85648996 0 P 0 ;0
L 0.95768002 -1.85648996 0.98416004 -1.8591 0 P 0 ;0
L 0.98416004 -1.8591 1.01018996 -1.86346004 0 P 0 ;0
L 1.01018996 -1.86346004 1.02886004 -1.86785 0 P 0 ;0
L 1.02886004 -1.86785 1.04711998 -1.87331998 0 P 0 ;0
L 1.04711998 -1.87331998 1.06501004 -1.87986004 0 P 0 ;0
L 1.06501004 -1.87986004 1.08125 -1.88706998 0 P 0 ;0
L 1.08125 -1.88706998 1.09681004 -1.89541998 0 P 0 ;0
L 1.09681004 -1.89541998 1.1117 -1.9049 0 P 0 ;0
L 1.1117 -1.9049 1.1245 -1.91456998 0 P 0 ;0
L 1.1245 -1.91456998 1.13638996 -1.92521004 0 P 0 ;0
L 1.13638996 -1.92521004 1.14733996 -1.93678996 0 P 0 ;0
L 1.14733996 -1.93678996 1.15408002 -1.94525 0 P 0 ;0
L 1.15408002 -1.94525 1.16001004 -1.95416998 0 P 0 ;0
L 1.16001004 -1.95416998 1.16516004 -1.96355 0 P 0 ;0
L 1.16516004 -1.96355 1.1695 -1.97336998 0 P 0 ;0
L 1.1695 -1.97336998 1.17066004 -1.97631004 0 P 0 ;0
L 1.17066004 -1.97631004 1.16015 -1.97631004 0 P 0 ;0
L 0.87563002 -1.90131004 0.8801 -1.90131004 0 P 0 ;0
L 0.87541004 -1.90031004 0.88493996 -1.90031004 0 P 0 ;0
L 0.8752 -1.89931004 0.88976998 -1.89931004 0 P 0 ;0
L 0.87498996 -1.89831004 0.8946 -1.89831004 0 P 0 ;0
L 0.89423002 -2.08316004 0.94355 -2.08316004 0 P 0 ;0
L 0.89428996 -2.08216004 0.9436 -2.08216004 0 P 0 ;0
L 0.89435 -2.08116004 0.94365 -2.08116004 0 P 0 ;0
L 0.89441004 -2.08016004 0.9437 -2.08016004 0 P 0 ;0
L 0.89446004 -2.07916004 0.94375 -2.07916004 0 P 0 ;0
L 0.89451998 -2.07816004 0.94378996 -2.07816004 0 P 0 ;0
L 0.89458002 -2.07716004 0.94383996 -2.07716004 0 P 0 ;0
L 0.89463996 -2.07616004 0.94388996 -2.07616004 0 P 0 ;0
L 0.8947 -2.07516004 0.94393996 -2.07516004 0 P 0 ;0
L 0.89475 -2.07416004 0.94398002 -2.07416004 0 P 0 ;0
L 0.89481004 -2.07316004 0.94403002 -2.07316004 0 P 0 ;0
L 0.89486998 -2.07216004 0.94408002 -2.07216004 0 P 0 ;0
L 0.89493002 -2.07116004 0.94415 -2.07116004 0 P 0 ;0
L 0.89498996 -2.07016004 0.94426004 -2.07016004 0 P 0 ;0
L 0.89505 -2.06916004 0.94436998 -2.06916004 0 P 0 ;0
L 0.8951 -2.06816004 0.94448002 -2.06816004 0 P 0 ;0
L 0.89516004 -2.06716004 0.94458996 -2.06716004 0 P 0 ;0
L 0.89521998 -2.06616004 0.9447 -2.06616004 0 P 0 ;0
L 0.89526998 -2.06516004 0.94481004 -2.06516004 0 P 0 ;0
L 0.89531004 -2.06416004 0.94491998 -2.06416004 0 P 0 ;0
L 0.89535 -2.06316004 0.94503002 -2.06316004 0 P 0 ;0
L 0.8954 -2.06216004 0.94513996 -2.06216004 0 P 0 ;0
L 0.89543996 -2.06116004 0.94531998 -2.06116004 0 P 0 ;0
L 0.89548996 -2.06016004 0.94551004 -2.06016004 0 P 0 ;0
L 0.89553002 -2.05916004 0.9457 -2.05916004 0 P 0 ;0
L 0.89558002 -2.05816004 0.94588996 -2.05816004 0 P 0 ;0
L 0.89561998 -2.05716004 0.94608002 -2.05716004 0 P 0 ;0
L 0.89566998 -2.05616004 0.94626998 -2.05616004 0 P 0 ;0
L 0.89571004 -2.05516004 0.94646998 -2.05516004 0 P 0 ;0
L 0.89575 -2.05416004 0.94666004 -2.05416004 0 P 0 ;0
L 0.8958 -2.05316004 0.94685 -2.05316004 0 P 0 ;0
L 0.89583996 -2.05216004 0.94708002 -2.05216004 0 P 0 ;0
L 0.89588996 -2.05116004 0.94735 -2.05116004 0 P 0 ;0
L 0.89593996 -2.05016004 0.94761998 -2.05016004 0 P 0 ;0
L 0.89598002 -2.04916004 0.9479 -2.04916004 0 P 0 ;0
L 0.89601998 -2.04816004 0.94825 -2.04816004 0 P 0 ;0
L 0.89606998 -2.04716004 0.94858996 -2.04716004 0 P 0 ;0
L 0.89611004 -2.04616004 0.94893002 -2.04616004 0 P 0 ;0
L 0.89616004 -2.04516004 0.94935 -2.04516004 0 P 0 ;0
L 0.8962 -2.04416004 0.94976998 -2.04416004 0 P 0 ;0
L 0.89625 -2.04316004 0.9502 -2.04316004 0 P 0 ;0
L 0.89628002 -2.04216004 0.95068996 -2.04216004 0 P 0 ;0
L 0.89631004 -2.04116004 0.95118996 -2.04116004 0 P 0 ;0
L 0.89633996 -2.04016004 0.95168996 -2.04016004 0 P 0 ;0
L 0.89638002 -2.03916004 0.95228002 -2.03916004 0 P 0 ;0
L 0.89641004 -2.03816004 0.95291004 -2.03816004 0 P 0 ;0
L 0.89643996 -2.03716004 0.95363002 -2.03716004 0 P 0 ;0
L 0.89646998 -2.03616004 0.95445 -2.03616004 0 P 0 ;0
L 0.89651004 -2.03516004 0.95535 -2.03516004 0 P 0 ;0
L 0.89653996 -2.03416004 0.95636998 -2.03416004 0 P 0 ;0
L 0.89656998 -2.03316004 0.95756998 -2.03316004 0 P 0 ;0
L 0.8966 -2.03216004 0.95893996 -2.03216004 0 P 0 ;0
L 0.89663996 -2.03116004 0.96055 -2.03116004 0 P 0 ;0
L 0.89666998 -2.03016004 0.96278002 -2.03016004 0 P 0 ;0
L 0.8967 -2.02916004 0.96676004 -2.02916004 0 P 0 ;0
L 0.89673996 -2.02816004 1.03838996 -2.02816004 0 P 0 ;0
L 0.89676998 -2.02716004 1.03838002 -2.02716004 0 P 0 ;0
L 0.8968 -2.02616004 1.03833996 -2.02616004 0 P 0 ;0
L 0.89683996 -2.02516004 1.03828996 -2.02516004 0 P 0 ;0
L 0.89686998 -2.02416004 1.03823002 -2.02416004 0 P 0 ;0
L 0.8969 -2.02316004 1.03816004 -2.02316004 0 P 0 ;0
L 0.89693996 -2.02216004 1.0381 -2.02216004 0 P 0 ;0
L 0.89696998 -2.02116004 1.03803996 -2.02116004 0 P 0 ;0
L 0.897 -2.02016004 1.0379 -2.02016004 0 P 0 ;0
L 0.89703002 -2.01916004 1.03773996 -2.01916004 0 P 0 ;0
L 0.89706004 -2.01816004 1.03751998 -2.01816004 0 P 0 ;0
L 0.89708996 -2.01716004 1.03728002 -2.01716004 0 P 0 ;0
L 0.89711998 -2.01616004 1.03698996 -2.01616004 0 P 0 ;0
L 0.89713996 -2.01516004 1.03668002 -2.01516004 0 P 0 ;0
L 0.89716998 -2.01416004 1.03631004 -2.01416004 0 P 0 ;0
L 0.8972 -2.01316004 1.03591998 -2.01316004 0 P 0 ;0
L 0.89721998 -2.01216004 1.03548996 -2.01216004 0 P 0 ;0
L 0.89725 -2.01116004 1.03505 -2.01116004 0 P 0 ;0
L 0.89726998 -2.01016004 1.03458002 -2.01016004 0 P 0 ;0
L 0.8973 -2.00916004 1.03405 -2.00916004 0 P 0 ;0
L 0.89733002 -2.00816004 1.03351998 -2.00816004 0 P 0 ;0
L 0.89736004 -2.00716004 0.94676004 -2.00716004 0 P 0 ;0
L 0.89738002 -2.00616004 0.9461 -2.00616004 0 P 0 ;0
L 0.89741004 -2.00516004 0.94563996 -2.00516004 0 P 0 ;0
L 0.89743996 -2.00416004 0.94563996 -2.00416004 0 P 0 ;0
L 0.89746004 -2.00316004 0.94563996 -2.00316004 0 P 0 ;0
L 0.89748996 -2.00216004 0.94563996 -2.00216004 0 P 0 ;0
L 0.89751004 -2.00116004 0.94563996 -2.00116004 0 P 0 ;0
L 0.89753996 -2.00016004 0.94563996 -2.00016004 0 P 0 ;0
L 0.89756998 -1.99916004 0.94563996 -1.99916004 0 P 0 ;0
L 0.8976 -1.99816004 0.94563996 -1.99816004 0 P 0 ;0
L 0.89761998 -1.99716004 0.94563996 -1.99716004 0 P 0 ;0
L 0.89765 -1.99616004 0.94563996 -1.99616004 0 P 0 ;0
L 0.89768002 -1.99516004 0.94563996 -1.99516004 0 P 0 ;0
L 0.97546998 -1.98933996 0.97236998 -1.99006004 0 P 0 ;0
L 0.97236998 -1.99006004 0.96931998 -1.99103002 0 P 0 ;0
L 0.96931998 -1.99103002 0.96603002 -1.99233002 0 P 0 ;0
L 0.96603002 -1.99233002 0.96281004 -1.99383002 0 P 0 ;0
L 0.96281004 -1.99383002 0.95976004 -1.99546998 0 P 0 ;0
L 0.95976004 -1.99546998 0.95681004 -1.99728996 0 P 0 ;0
L 0.95681004 -1.99728996 0.95521004 -1.99841004 0 P 0 ;0
L 0.95521004 -1.99841004 0.95368996 -1.99963002 0 P 0 ;0
L 0.95368996 -1.99963002 0.95223996 -2.00095 0 P 0 ;0
L 0.95223996 -2.00095 0.94763996 -2.00546998 0 P 0 ;0
L 0.94763996 -2.00546998 0.94763996 -1.99243996 0 P 0 ;0
L 0.94763996 -1.99243996 0.89575 -1.99243996 0 P 0 ;0
L 0.89575 -1.99243996 0.89505 -2.01878002 0 P 0 ;0
L 0.89505 -2.01878002 0.89423996 -2.04316004 0 P 0 ;0
L 0.89423996 -2.04316004 0.89321998 -2.0661 0 P 0 ;0
L 0.89321998 -2.0661 0.89198996 -2.08728996 0 P 0 ;0
L 0.89198996 -2.08728996 0.89055 -2.1063 0 P 0 ;0
L 0.89055 -2.1063 0.88993996 -2.11358002 0 P 0 ;0
L 0.88993996 -2.11358002 0.88943002 -2.11988002 0 P 0 ;0
L 0.88943002 -2.11988002 0.88898996 -2.12533996 0 P 0 ;0
L 0.88898996 -2.12533996 0.88896004 -2.12613002 0 P 0 ;0
L 0.88896004 -2.12613002 0.88896998 -2.12621004 0 P 0 ;0
L 0.88896998 -2.12621004 0.88898002 -2.12625 0 P 0 ;0
L 0.88898002 -2.12625 0.88898996 -2.12628002 0 P 0 ;0
L 0.88898996 -2.12628002 0.88901998 -2.12636004 0 P 0 ;0
L 0.88901998 -2.12636004 0.88903996 -2.12638996 0 P 0 ;0
L 0.88903996 -2.12638996 0.88906998 -2.12641998 0 P 0 ;0
L 0.88906998 -2.12641998 0.88908996 -2.12645 0 P 0 ;0
L 0.88908996 -2.12645 0.88911998 -2.12646998 0 P 0 ;0
L 0.88911998 -2.12646998 0.88915 -2.1265 0 P 0 ;0
L 0.88915 -2.1265 0.88921004 -2.12653996 0 P 0 ;0
L 0.88921004 -2.12653996 0.88925 -2.12655 0 P 0 ;0
L 0.88925 -2.12655 0.88928002 -2.12656004 0 P 0 ;0
L 0.88928002 -2.12656004 0.88931998 -2.12658002 0 P 0 ;0
L 0.88931998 -2.12658002 0.8894 -2.12658002 0 P 0 ;0
L 0.8894 -2.12658002 0.89648002 -2.12686998 0 P 0 ;0
L 0.89648002 -2.12686998 0.90518996 -2.1271 0 P 0 ;0
L 0.90518996 -2.1271 0.9165 -2.12716004 0 P 0 ;0
L 0.9165 -2.12716004 0.94403996 -2.12716004 0 P 0 ;0
L 0.94403996 -2.12716004 0.94468996 -2.10135 0 P 0 ;0
L 0.94468996 -2.10135 0.9461 -2.07171998 0 P 0 ;0
L 0.9461 -2.07171998 0.94713002 -2.06233002 0 P 0 ;0
L 0.94713002 -2.06233002 0.9489 -2.05308002 0 P 0 ;0
L 0.9489 -2.05308002 0.94975 -2.04995 0 P 0 ;0
L 0.94975 -2.04995 0.9508 -2.04688996 0 P 0 ;0
L 0.9508 -2.04688996 0.95205 -2.0439 0 P 0 ;0
L 0.95205 -2.0439 0.95351004 -2.041 0 P 0 ;0
L 0.95351004 -2.041 0.9544 -2.03951004 0 P 0 ;0
L 0.9544 -2.03951004 0.95541998 -2.03811004 0 P 0 ;0
L 0.95541998 -2.03811004 0.95655 -2.03678996 0 P 0 ;0
L 0.95655 -2.03678996 0.95778996 -2.03556998 0 P 0 ;0
L 0.95778996 -2.03556998 0.95911998 -2.03446998 0 P 0 ;0
L 0.95911998 -2.03446998 0.96056998 -2.03346998 0 P 0 ;0
L 0.96056998 -2.03346998 0.96151004 -2.03291004 0 P 0 ;0
L 0.96151004 -2.03291004 0.96248996 -2.03243002 0 P 0 ;0
L 0.96248996 -2.03243002 0.96351004 -2.03201998 0 P 0 ;0
L 0.96351004 -2.03201998 0.96455 -2.03168996 0 P 0 ;0
L 0.96455 -2.03168996 0.96613002 -2.0313 0 P 0 ;0
L 0.96613002 -2.0313 0.96773002 -2.03101998 0 P 0 ;0
L 0.96773002 -2.03101998 0.96935 -2.03086004 0 P 0 ;0
L 0.96935 -2.03086004 0.97095 -2.03081004 0 P 0 ;0
L 0.97095 -2.03081004 0.97255 -2.03086998 0 P 0 ;0
L 0.97255 -2.03086998 0.97413002 -2.03105 0 P 0 ;0
L 0.97413002 -2.03105 0.97513002 -2.03123996 0 P 0 ;0
L 0.97513002 -2.03123996 0.9761 -2.03151004 0 P 0 ;0
L 0.9761 -2.03151004 0.97706004 -2.03186004 0 P 0 ;0
L 0.97706004 -2.03186004 0.97796998 -2.0323 0 P 0 ;0
L 0.97796998 -2.0323 0.97885 -2.0328 0 P 0 ;0
L 0.97885 -2.0328 0.97968002 -2.03336998 0 P 0 ;0
L 0.97968002 -2.03336998 0.98046998 -2.03398996 0 P 0 ;0
L 0.98046998 -2.03398996 0.98121998 -2.03468002 0 P 0 ;0
L 0.98121998 -2.03468002 0.98191004 -2.03541998 0 P 0 ;0
L 0.98191004 -2.03541998 0.98253996 -2.0362 0 P 0 ;0
L 0.98253996 -2.0362 0.9831 -2.03703002 0 P 0 ;0
L 0.9831 -2.03703002 0.9836 -2.03788996 0 P 0 ;0
L 0.9836 -2.03788996 0.98403996 -2.0388 0 P 0 ;0
L 0.98403996 -2.0388 0.9844 -2.03973996 0 P 0 ;0
L 0.9844 -2.03973996 0.98505 -2.04188996 0 P 0 ;0
L 0.98505 -2.04188996 0.98553002 -2.04408002 0 P 0 ;0
L 0.98553002 -2.04408002 0.98583002 -2.0463 0 P 0 ;0
L 0.98583002 -2.0463 0.98653002 -2.05705 0 P 0 ;0
L 0.98653002 -2.05705 0.9866 -2.06961004 0 P 0 ;0
L 0.9866 -2.06961004 0.98596004 -2.08908002 0 P 0 ;0
L 0.98596004 -2.08908002 0.98498002 -2.10858002 0 P 0 ;0
L 0.98498002 -2.10858002 0.98388002 -2.12146998 0 P 0 ;0
L 0.98388002 -2.12146998 0.98323002 -2.12716004 0 P 0 ;0
L 0.98323002 -2.12716004 1.03741004 -2.12716004 0 P 0 ;0
L 1.03741004 -2.12716004 1.03896004 -2.09103002 0 P 0 ;0
L 1.03896004 -2.09103002 1.03956004 -2.0759 0 P 0 ;0
L 1.03956004 -2.0759 1.04005 -2.06025 0 P 0 ;0
L 1.04005 -2.06025 1.04038996 -2.04626004 0 P 0 ;0
L 1.04038996 -2.04626004 1.04048002 -2.03698996 0 P 0 ;0
L 1.04048002 -2.03698996 1.04036998 -2.02651998 0 P 0 ;0
L 1.04036998 -2.02651998 1.04003996 -2.02096998 0 P 0 ;0
L 1.04003996 -2.02096998 1.03975 -2.01895 0 P 0 ;0
L 1.03975 -2.01895 1.0393 -2.01693996 0 P 0 ;0
L 1.0393 -2.01693996 1.03868996 -2.01483996 0 P 0 ;0
L 1.03868996 -2.01483996 1.03793996 -2.01278002 0 P 0 ;0
L 1.03793996 -2.01278002 1.03658996 -2.00968002 0 P 0 ;0
L 1.03658996 -2.00968002 1.03501004 -2.00668996 0 P 0 ;0
L 1.03501004 -2.00668996 1.0332 -2.0038 0 P 0 ;0
L 1.0332 -2.0038 1.03186998 -2.002 0 P 0 ;0
L 1.03186998 -2.002 1.0304 -2.0003 0 P 0 ;0
L 1.0304 -2.0003 1.0288 -1.99873002 0 P 0 ;0
L 1.0288 -1.99873002 1.02708002 -1.99728996 0 P 0 ;0
L 1.02708002 -1.99728996 1.02518002 -1.99593002 0 P 0 ;0
L 1.02518002 -1.99593002 1.02318002 -1.99471998 0 P 0 ;0
L 1.02318002 -1.99471998 1.0211 -1.99365 0 P 0 ;0
L 1.0211 -1.99365 1.01893002 -1.99273996 0 P 0 ;0
L 1.01893002 -1.99273996 1.01358996 -1.99098996 0 P 0 ;0
L 1.01358996 -1.99098996 1.0081 -1.98971004 0 P 0 ;0
L 1.0081 -1.98971004 1.00428996 -1.98908996 0 P 0 ;0
L 1.00428996 -1.98908996 1.00043996 -1.98868002 0 P 0 ;0
L 1.00043996 -1.98868002 0.99138002 -1.98826004 0 P 0 ;0
L 0.99138002 -1.98826004 0.98251998 -1.98846998 0 P 0 ;0
L 0.98251998 -1.98846998 0.97898996 -1.98878996 0 P 0 ;0
L 0.97898996 -1.98878996 0.97546998 -1.98933996 0 P 0 ;0
L 0.91651004 -2.12516004 0.94208996 -2.12516004 0 P 0 ;0
L 0.8911 -2.12416004 0.94211004 -2.12416004 0 P 0 ;0
L 0.89118002 -2.12316004 0.94213996 -2.12316004 0 P 0 ;0
L 0.89125 -2.12216004 0.94216004 -2.12216004 0 P 0 ;0
L 0.89133002 -2.12116004 0.94218996 -2.12116004 0 P 0 ;0
L 0.89141004 -2.12016004 0.94221004 -2.12016004 0 P 0 ;0
L 0.89148996 -2.11916004 0.94223996 -2.11916004 0 P 0 ;0
L 0.89156998 -2.11816004 0.94226998 -2.11816004 0 P 0 ;0
L 0.89166004 -2.11716004 0.94228996 -2.11716004 0 P 0 ;0
L 0.89173996 -2.11616004 0.94231004 -2.11616004 0 P 0 ;0
L 0.89181998 -2.11516004 0.94233996 -2.11516004 0 P 0 ;0
L 0.8919 -2.11416004 0.94236004 -2.11416004 0 P 0 ;0
L 0.89198002 -2.11316004 0.94238996 -2.11316004 0 P 0 ;0
L 0.89206998 -2.11216004 0.94241998 -2.11216004 0 P 0 ;0
L 0.89215 -2.11116004 0.94243996 -2.11116004 0 P 0 ;0
L 0.89223002 -2.11016004 0.94246998 -2.11016004 0 P 0 ;0
L 0.89231998 -2.10916004 0.94248996 -2.10916004 0 P 0 ;0
L 0.8924 -2.10816004 0.94251998 -2.10816004 0 P 0 ;0
L 0.89248002 -2.10716004 0.94255 -2.10716004 0 P 0 ;0
L 0.89256998 -2.10616004 0.94256998 -2.10616004 0 P 0 ;0
L 0.89263996 -2.10516004 0.94258996 -2.10516004 0 P 0 ;0
L 0.89271004 -2.10416004 0.94261998 -2.10416004 0 P 0 ;0
L 0.89278996 -2.10316004 0.94263996 -2.10316004 0 P 0 ;0
L 0.89286998 -2.10216004 0.94266998 -2.10216004 0 P 0 ;0
L 0.89293996 -2.10116004 0.9427 -2.10116004 0 P 0 ;0
L 0.89301998 -2.10016004 0.94275 -2.10016004 0 P 0 ;0
L 0.89308996 -2.09916004 0.94278996 -2.09916004 0 P 0 ;0
L 0.89316998 -2.09816004 0.94283996 -2.09816004 0 P 0 ;0
L 0.89325 -2.09716004 0.94288996 -2.09716004 0 P 0 ;0
L 0.89331998 -2.09616004 0.94293996 -2.09616004 0 P 0 ;0
L 0.8934 -2.09516004 0.94298002 -2.09516004 0 P 0 ;0
L 0.89346998 -2.09416004 0.94303002 -2.09416004 0 P 0 ;0
L 0.89355 -2.09316004 0.94308002 -2.09316004 0 P 0 ;0
L 0.89361998 -2.09216004 0.94313002 -2.09216004 0 P 0 ;0
L 0.8937 -2.09116004 0.94318002 -2.09116004 0 P 0 ;0
L 0.89378002 -2.09016004 0.94321998 -2.09016004 0 P 0 ;0
L 0.89385 -2.08916004 0.94326998 -2.08916004 0 P 0 ;0
L 0.89393002 -2.08816004 0.94331998 -2.08816004 0 P 0 ;0
L 0.894 -2.08716004 0.94336004 -2.08716004 0 P 0 ;0
L 0.89406004 -2.08616004 0.94341004 -2.08616004 0 P 0 ;0
L 0.89411998 -2.08516004 0.94346004 -2.08516004 0 P 0 ;0
L 0.89418002 -2.08416004 0.94351004 -2.08416004 0 P 0 ;0
L 0.91651004 -2.12516004 0.90521998 -2.1251 0 P 0 ;0
L 0.90521998 -2.1251 0.89655 -2.12486998 0 P 0 ;0
L 0.89655 -2.12486998 0.89106004 -2.12465 0 P 0 ;0
L 0.89106004 -2.12465 0.89141998 -2.12003996 0 P 0 ;0
L 0.89141998 -2.12003996 0.89193996 -2.11373996 0 P 0 ;0
L 0.89193996 -2.11373996 0.89253996 -2.10645 0 P 0 ;0
L 0.89253996 -2.10645 0.89398002 -2.08741998 0 P 0 ;0
L 0.89398002 -2.08741998 0.89521998 -2.06621998 0 P 0 ;0
L 0.89521998 -2.06621998 0.89521998 -2.06618996 0 P 0 ;0
L 0.89521998 -2.06618996 0.89623996 -2.04323002 0 P 0 ;0
L 0.89623996 -2.04323002 0.89703996 -2.01883002 0 P 0 ;0
L 0.89703996 -2.01883002 0.8977 -1.99443996 0 P 0 ;0
L 0.8977 -1.99443996 0.94563996 -1.99443996 0 P 0 ;0
L 0.94563996 -1.99443996 0.94563996 -2.00546998 0 P 0 ;0
L 0.94563996 -2.00546998 0.94686004 -2.00731004 0 P 0 ;0
L 0.94686004 -2.00731004 0.94903002 -2.00688996 0 P 0 ;0
L 0.94903002 -2.00688996 0.95361998 -2.00241004 0 P 0 ;0
L 0.95361998 -2.00241004 0.95498996 -2.00115 0 P 0 ;0
L 0.95498996 -2.00115 0.95641998 -2.00001004 0 P 0 ;0
L 0.95641998 -2.00001004 0.9579 -1.99896004 0 P 0 ;0
L 0.9579 -1.99896004 0.96076004 -1.9972 0 P 0 ;0
L 0.96076004 -1.9972 0.9637 -1.99561998 0 P 0 ;0
L 0.9637 -1.99561998 0.96683002 -1.99416998 0 P 0 ;0
L 0.96683002 -1.99416998 0.96998996 -1.99291998 0 P 0 ;0
L 0.96998996 -1.99291998 0.9729 -1.99198996 0 P 0 ;0
L 0.9729 -1.99198996 0.97586004 -1.9913 0 P 0 ;0
L 0.97586004 -1.9913 0.97923002 -1.99076998 0 P 0 ;0
L 0.97923002 -1.99076998 0.98263002 -1.99046998 0 P 0 ;0
L 0.98263002 -1.99046998 0.99136004 -1.99026004 0 P 0 ;0
L 0.99136004 -1.99026004 1.00028996 -1.99066998 0 P 0 ;0
L 1.00028996 -1.99066998 1.00403002 -1.99108002 0 P 0 ;0
L 1.00403002 -1.99108002 1.00771004 -1.99166998 0 P 0 ;0
L 1.00771004 -1.99166998 1.01305 -1.99291998 0 P 0 ;0
L 1.01305 -1.99291998 1.01823002 -1.99461998 0 P 0 ;0
L 1.01823002 -1.99461998 1.02026004 -1.99546998 0 P 0 ;0
L 1.02026004 -1.99546998 1.02221004 -1.99646998 0 P 0 ;0
L 1.02221004 -1.99646998 1.02408002 -1.9976 0 P 0 ;0
L 1.02408002 -1.9976 1.02585 -1.99886998 0 P 0 ;0
L 1.02585 -1.99886998 1.02746004 -2.00021004 0 P 0 ;0
L 1.02746004 -2.00021004 1.02893996 -2.00166998 0 P 0 ;0
L 1.02893996 -2.00166998 1.03031004 -2.00325 0 P 0 ;0
L 1.03031004 -2.00325 1.03155 -2.00493002 0 P 0 ;0
L 1.03155 -2.00493002 1.03326998 -2.00768002 0 P 0 ;0
L 1.03326998 -2.00768002 1.03478002 -2.01055 0 P 0 ;0
L 1.03478002 -2.01055 1.03608002 -2.01351998 0 P 0 ;0
L 1.03608002 -2.01351998 1.03678996 -2.01546998 0 P 0 ;0
L 1.03678996 -2.01546998 1.03736004 -2.01743002 0 P 0 ;0
L 1.03736004 -2.01743002 1.03778002 -2.0193 0 P 0 ;0
L 1.03778002 -2.0193 1.03805 -2.02116998 0 P 0 ;0
L 1.03805 -2.02116998 1.03836998 -2.02658996 0 P 0 ;0
L 1.03836998 -2.02658996 1.03848002 -2.03698996 0 P 0 ;0
L 1.03848002 -2.03698996 1.03838996 -2.04623002 0 P 0 ;0
L 1.03838996 -2.04623002 1.03805 -2.06018996 0 P 0 ;0
L 1.03805 -2.06018996 1.03756004 -2.07583002 0 P 0 ;0
L 1.03756004 -2.07583002 1.03696998 -2.09095 0 P 0 ;0
L 1.03696998 -2.09095 1.03548996 -2.12516004 0 P 0 ;0
L 1.03548996 -2.12516004 0.98546998 -2.12516004 0 P 0 ;0
L 0.98546998 -2.12516004 0.98586998 -2.12166004 0 P 0 ;0
L 0.98586998 -2.12166004 0.98696998 -2.10871998 0 P 0 ;0
L 0.98696998 -2.10871998 0.98796004 -2.08916004 0 P 0 ;0
L 0.98796004 -2.08916004 0.9886 -2.06963002 0 P 0 ;0
L 0.9886 -2.06963002 0.98853002 -2.05698002 0 P 0 ;0
L 0.98853002 -2.05698002 0.98781998 -2.0461 0 P 0 ;0
L 0.98781998 -2.0461 0.9875 -2.04373002 0 P 0 ;0
L 0.9875 -2.04373002 0.98748002 -2.04365 0 P 0 ;0
L 0.98748002 -2.04365 0.98698996 -2.04138996 0 P 0 ;0
L 0.98698996 -2.04138996 0.9863 -2.03908002 0 P 0 ;0
L 0.9863 -2.03908002 0.98588002 -2.038 0 P 0 ;0
L 0.98588002 -2.038 0.98538002 -2.03696004 0 P 0 ;0
L 0.98538002 -2.03696004 0.9848 -2.03596004 0 P 0 ;0
L 0.9848 -2.03596004 0.98413996 -2.03501004 0 P 0 ;0
L 0.98413996 -2.03501004 0.98341998 -2.03411004 0 P 0 ;0
L 0.98341998 -2.03411004 0.98336998 -2.03405 0 P 0 ;0
L 0.98336998 -2.03405 0.98263002 -2.03326004 0 P 0 ;0
L 0.98263002 -2.03326004 0.98176998 -2.03246998 0 P 0 ;0
L 0.98176998 -2.03246998 0.98086998 -2.03175 0 P 0 ;0
L 0.98086998 -2.03175 0.97991004 -2.0311 0 P 0 ;0
L 0.97991004 -2.0311 0.9789 -2.03051998 0 P 0 ;0
L 0.9789 -2.03051998 0.97783002 -2.03001998 0 P 0 ;0
L 0.97783002 -2.03001998 0.97673002 -2.02961004 0 P 0 ;0
L 0.97673002 -2.02961004 0.97663996 -2.02958002 0 P 0 ;0
L 0.97663996 -2.02958002 0.97558996 -2.02928996 0 P 0 ;0
L 0.97558996 -2.02928996 0.97443002 -2.02906998 0 P 0 ;0
L 0.97443002 -2.02906998 0.9727 -2.02888002 0 P 0 ;0
L 0.9727 -2.02888002 0.97261998 -2.02886998 0 P 0 ;0
L 0.97261998 -2.02886998 0.97096004 -2.02881004 0 P 0 ;0
L 0.97096004 -2.02881004 0.96921004 -2.02886004 0 P 0 ;0
L 0.96921004 -2.02886004 0.96745 -2.02903996 0 P 0 ;0
L 0.96745 -2.02903996 0.96571004 -2.02933996 0 P 0 ;0
L 0.96571004 -2.02933996 0.964 -2.02976004 0 P 0 ;0
L 0.964 -2.02976004 0.96283002 -2.03013996 0 P 0 ;0
L 0.96283002 -2.03013996 0.96168002 -2.0306 0 P 0 ;0
L 0.96168002 -2.0306 0.96056998 -2.03115 0 P 0 ;0
L 0.96056998 -2.03115 0.95948996 -2.03178002 0 P 0 ;0
L 0.95948996 -2.03178002 0.95791004 -2.03286998 0 P 0 ;0
L 0.95791004 -2.03286998 0.95645 -2.03408996 0 P 0 ;0
L 0.95645 -2.03408996 0.95508996 -2.03541998 0 P 0 ;0
L 0.95508996 -2.03541998 0.95383996 -2.03686998 0 P 0 ;0
L 0.95383996 -2.03686998 0.9538 -2.03693002 0 P 0 ;0
L 0.9538 -2.03693002 0.95273002 -2.03841004 0 P 0 ;0
L 0.95273002 -2.03841004 0.95175 -2.04003996 0 P 0 ;0
L 0.95175 -2.04003996 0.95023002 -2.04306004 0 P 0 ;0
L 0.95023002 -2.04306004 0.94896004 -2.04611004 0 P 0 ;0
L 0.94896004 -2.04611004 0.94893002 -2.04616998 0 P 0 ;0
L 0.94893002 -2.04616998 0.94783002 -2.04936004 0 P 0 ;0
L 0.94783002 -2.04936004 0.94695 -2.05263002 0 P 0 ;0
L 0.94695 -2.05263002 0.94515 -2.06203002 0 P 0 ;0
L 0.94515 -2.06203002 0.9441 -2.07156004 0 P 0 ;0
L 0.9441 -2.07156004 0.9427 -2.10128002 0 P 0 ;0
L 0.9427 -2.10128002 0.94208996 -2.12516004 0 P 0 ;0
L 0.94208996 -2.12516004 0.91651004 -2.12516004 0 P 0 ;0
L 0.93143002 -2.21261998 1.00578996 -2.21261998 0 P 0 ;0
L 0.94051004 -2.21161998 1.00803002 -2.21161998 0 P 0 ;0
L 0.94941998 -2.21061998 1.01026004 -2.21061998 0 P 0 ;0
L 0.9555 -2.20961998 1.0125 -2.20961998 0 P 0 ;0
L 0.96158002 -2.20861998 1.01473996 -2.20861998 0 P 0 ;0
L 0.96766004 -2.20761998 1.01696998 -2.20761998 0 P 0 ;0
L 0.97373002 -2.20661998 1.01921004 -2.20661998 0 P 0 ;0
L 0.97981004 -2.20561998 1.02145 -2.20561998 0 P 0 ;0
L 0.98498996 -2.20461998 1.02368996 -2.20461998 0 P 0 ;0
L 0.98973996 -2.20361998 1.02591998 -2.20361998 0 P 0 ;0
L 0.99448996 -2.20261998 1.02816004 -2.20261998 0 P 0 ;0
L 0.99923996 -2.20161998 1.0304 -2.20161998 0 P 0 ;0
L 1.00398996 -2.20061998 1.03243996 -2.20061998 0 P 0 ;0
L 1.00875 -2.19961998 1.0344 -2.19961998 0 P 0 ;0
L 1.01348996 -2.19861998 1.03636998 -2.19861998 0 P 0 ;0
L 1.0178 -2.19761998 1.03833996 -2.19761998 0 P 0 ;0
L 1.02168996 -2.19661998 1.04031004 -2.19661998 0 P 0 ;0
L 1.02558002 -2.19561998 1.04228002 -2.19561998 0 P 0 ;0
L 1.02946998 -2.19461998 1.04415 -2.19461998 0 P 0 ;0
L 1.03336004 -2.19361998 1.04596998 -2.19361998 0 P 0 ;0
L 1.03725 -2.19261998 1.04778996 -2.19261998 0 P 0 ;0
L 1.04113996 -2.19161998 1.0496 -2.19161998 0 P 0 ;0
L 1.14356998 -1.98926998 1.13261004 -1.99086004 0 P 0 ;0
L 1.13261004 -1.99086004 1.12165 -1.9934 0 P 0 ;0
L 1.12165 -1.9934 1.11125 -1.99673002 0 P 0 ;0
L 1.11125 -1.99673002 1.10658002 -1.99858996 0 P 0 ;0
L 1.10658002 -1.99858996 1.10198996 -2.00071004 0 P 0 ;0
L 1.10198996 -2.00071004 1.09653002 -2.00358996 0 P 0 ;0
L 1.09653002 -2.00358996 1.09436998 -2.00488996 0 P 0 ;0
L 1.09436998 -2.00488996 1.09226004 -2.00631004 0 P 0 ;0
L 1.09226004 -2.00631004 1.09028002 -2.00781004 0 P 0 ;0
L 1.09028002 -2.00781004 1.08836998 -2.00941998 0 P 0 ;0
L 1.08836998 -2.00941998 1.08405 -2.0135 0 P 0 ;0
L 1.08405 -2.0135 1.08096998 -2.01678996 0 P 0 ;0
L 1.08096998 -2.01678996 1.07808002 -2.02026998 0 P 0 ;0
L 1.07808002 -2.02026998 1.0754 -2.02393002 0 P 0 ;0
L 1.0754 -2.02393002 1.07313996 -2.02748002 0 P 0 ;0
L 1.07313996 -2.02748002 1.07116004 -2.03118996 0 P 0 ;0
L 1.07116004 -2.03118996 1.06943996 -2.03505 0 P 0 ;0
L 1.06943996 -2.03505 1.06795 -2.03918996 0 P 0 ;0
L 1.06795 -2.03918996 1.06673996 -2.04343996 0 P 0 ;0
L 1.06673996 -2.04343996 1.06583002 -2.04778002 0 P 0 ;0
L 1.06583002 -2.04778002 1.06476998 -2.05538996 0 P 0 ;0
L 1.06476998 -2.05538996 1.06421004 -2.06306004 0 P 0 ;0
L 1.06421004 -2.06306004 1.06415 -2.07076004 0 P 0 ;0
L 1.06415 -2.07076004 1.06456998 -2.0785 0 P 0 ;0
L 1.06456998 -2.0785 1.06508996 -2.08276004 0 P 0 ;0
L 1.06508996 -2.08276004 1.06591004 -2.08696004 0 P 0 ;0
L 1.06591004 -2.08696004 1.06703002 -2.09108002 0 P 0 ;0
L 1.06703002 -2.09108002 1.06833002 -2.09473002 0 P 0 ;0
L 1.06833002 -2.09473002 1.06991998 -2.09823996 0 P 0 ;0
L 1.06991998 -2.09823996 1.0718 -2.10161998 0 P 0 ;0
L 1.0718 -2.10161998 1.07398002 -2.10491998 0 P 0 ;0
L 1.07398002 -2.10491998 1.07641998 -2.10803002 0 P 0 ;0
L 1.07641998 -2.10803002 1.07908996 -2.11095 0 P 0 ;0
L 1.07908996 -2.11095 1.08175 -2.11345 0 P 0 ;0
L 1.08175 -2.11345 1.08458996 -2.11573996 0 P 0 ;0
L 1.08458996 -2.11573996 1.08758996 -2.1178 0 P 0 ;0
L 1.08758996 -2.1178 1.09073002 -2.11963996 0 P 0 ;0
L 1.09073002 -2.11963996 1.094 -2.12123996 0 P 0 ;0
L 1.094 -2.12123996 1.0986 -2.12306998 0 P 0 ;0
L 1.0986 -2.12306998 1.10331004 -2.12456004 0 P 0 ;0
L 1.10331004 -2.12456004 1.10811004 -2.12568996 0 P 0 ;0
L 1.10811004 -2.12568996 1.11298002 -2.12646998 0 P 0 ;0
L 1.11298002 -2.12646998 1.1182 -2.12693002 0 P 0 ;0
L 1.1182 -2.12693002 1.12343996 -2.12703002 0 P 0 ;0
L 1.12343996 -2.12703002 1.12866998 -2.12676004 0 P 0 ;0
L 1.12866998 -2.12676004 1.13388002 -2.12613002 0 P 0 ;0
L 1.13388002 -2.12613002 1.14086004 -2.12473996 0 P 0 ;0
L 1.14086004 -2.12473996 1.1477 -2.12273996 0 P 0 ;0
L 1.1477 -2.12273996 1.15433996 -2.12015 0 P 0 ;0
L 1.15433996 -2.12015 1.1545 -2.12008996 0 P 0 ;0
L 1.1545 -2.12008996 1.15466004 -2.12003996 0 P 0 ;0
L 1.15466004 -2.12003996 1.15483002 -2.12001004 0 P 0 ;0
L 1.15483002 -2.12001004 1.15498996 -2.11998996 0 P 0 ;0
L 1.15498996 -2.11998996 1.15533002 -2.11998996 0 P 0 ;0
L 1.15533002 -2.11998996 1.15538996 -2.12 0 P 0 ;0
L 1.15538996 -2.12 1.15545 -2.12001998 0 P 0 ;0
L 1.15545 -2.12001998 1.15551004 -2.12003002 0 P 0 ;0
L 1.15551004 -2.12003002 1.15556004 -2.12006004 0 P 0 ;0
L 1.15556004 -2.12006004 1.15561004 -2.12008002 0 P 0 ;0
L 1.15561004 -2.12008002 1.15566004 -2.12011004 0 P 0 ;0
L 1.15566004 -2.12011004 1.15571004 -2.12015 0 P 0 ;0
L 1.15571004 -2.12015 1.15575 -2.12018996 0 P 0 ;0
L 1.15575 -2.12018996 1.15578996 -2.12023996 0 P 0 ;0
L 1.15578996 -2.12023996 1.15583002 -2.12028002 0 P 0 ;0
L 1.15583002 -2.12028002 1.15586004 -2.12033996 0 P 0 ;0
L 1.15586004 -2.12033996 1.15588002 -2.12038996 0 P 0 ;0
L 1.15588002 -2.12038996 1.15591004 -2.12043996 0 P 0 ;0
L 1.15591004 -2.12043996 1.15601998 -2.12076004 0 P 0 ;0
L 1.15601998 -2.12076004 1.1561 -2.12108002 0 P 0 ;0
L 1.1561 -2.12108002 1.15616004 -2.12141998 0 P 0 ;0
L 1.15616004 -2.12141998 1.15618002 -2.12175 0 P 0 ;0
L 1.15618002 -2.12175 1.15623996 -2.12505 0 P 0 ;0
L 1.15623996 -2.12505 1.15616004 -2.12688002 0 P 0 ;0
L 1.15616004 -2.12688002 1.15593002 -2.12871004 0 P 0 ;0
L 1.15593002 -2.12871004 1.15553996 -2.13051998 0 P 0 ;0
L 1.15553996 -2.13051998 1.15516004 -2.1318 0 P 0 ;0
L 1.15516004 -2.1318 1.1547 -2.13305 0 P 0 ;0
L 1.1547 -2.13305 1.15415 -2.13426004 0 P 0 ;0
L 1.15415 -2.13426004 1.15351004 -2.13545 0 P 0 ;0
L 1.15351004 -2.13545 1.15278996 -2.1366 0 P 0 ;0
L 1.15278996 -2.1366 1.15198002 -2.13768996 0 P 0 ;0
L 1.15198002 -2.13768996 1.15111004 -2.13873002 0 P 0 ;0
L 1.15111004 -2.13873002 1.15016004 -2.13971004 0 P 0 ;0
L 1.15016004 -2.13971004 1.14876004 -2.14096004 0 P 0 ;0
L 1.14876004 -2.14096004 1.14726004 -2.1421 0 P 0 ;0
L 1.14726004 -2.1421 1.14566998 -2.14311004 0 P 0 ;0
L 1.14566998 -2.14311004 1.144 -2.144 0 P 0 ;0
L 1.144 -2.144 1.14226004 -2.14476004 0 P 0 ;0
L 1.14226004 -2.14476004 1.14046004 -2.14536998 0 P 0 ;0
L 1.14046004 -2.14536998 1.13863002 -2.14583002 0 P 0 ;0
L 1.13863002 -2.14583002 1.13676004 -2.14613996 0 P 0 ;0
L 1.13676004 -2.14613996 1.13041998 -2.14663996 0 P 0 ;0
L 1.13041998 -2.14663996 1.12403996 -2.1466 0 P 0 ;0
L 1.12403996 -2.1466 1.11621998 -2.14593996 0 P 0 ;0
L 1.11621998 -2.14593996 1.10843996 -2.14471004 0 P 0 ;0
L 1.10843996 -2.14471004 1.09946998 -2.14276998 0 P 0 ;0
L 1.09946998 -2.14276998 1.0905 -2.14041004 0 P 0 ;0
L 1.0905 -2.14041004 1.07963996 -2.13728996 0 P 0 ;0
L 1.07963996 -2.13728996 1.07936004 -2.1401 0 P 0 ;0
L 1.07936004 -2.1401 1.07931004 -2.14103996 0 P 0 ;0
L 1.07931004 -2.14103996 1.07931998 -2.14198002 0 P 0 ;0
L 1.07931998 -2.14198002 1.07956998 -2.14735 0 P 0 ;0
L 1.07956998 -2.14735 1.07993996 -2.15375 0 P 0 ;0
L 1.07993996 -2.15375 1.08045 -2.16081998 0 P 0 ;0
L 1.08045 -2.16081998 1.08181004 -2.17873002 0 P 0 ;0
L 1.08181004 -2.17873002 1.08996004 -2.18061004 0 P 0 ;0
L 1.08996004 -2.18061004 1.09951004 -2.18246004 0 P 0 ;0
L 1.09951004 -2.18246004 1.11243996 -2.18416998 0 P 0 ;0
L 1.11243996 -2.18416998 1.1254 -2.18543002 0 P 0 ;0
L 1.1254 -2.18543002 1.13508002 -2.18583002 0 P 0 ;0
L 1.13508002 -2.18583002 1.14765 -2.18528996 0 P 0 ;0
L 1.14765 -2.18528996 1.15368002 -2.18461004 0 P 0 ;0
L 1.15368002 -2.18461004 1.15971004 -2.18363996 0 P 0 ;0
L 1.15971004 -2.18363996 1.16521004 -2.18248002 0 P 0 ;0
L 1.16521004 -2.18248002 1.17063996 -2.18103002 0 P 0 ;0
L 1.17063996 -2.18103002 1.17528996 -2.17946998 0 P 0 ;0
L 1.17528996 -2.17946998 1.17978002 -2.17753996 0 P 0 ;0
L 1.17978002 -2.17753996 1.18216998 -2.1763 0 P 0 ;0
L 1.18216998 -2.1763 1.18446004 -2.17488996 0 P 0 ;0
L 1.18446004 -2.17488996 1.18663996 -2.17331004 0 P 0 ;0
L 1.18663996 -2.17331004 1.18871004 -2.17156004 0 P 0 ;0
L 1.18871004 -2.17156004 1.19161004 -2.16871998 0 P 0 ;0
L 1.19161004 -2.16871998 1.19431004 -2.16568996 0 P 0 ;0
L 1.19431004 -2.16568996 1.19678996 -2.16246998 0 P 0 ;0
L 1.19678996 -2.16246998 1.19908996 -2.15901998 0 P 0 ;0
L 1.19908996 -2.15901998 1.20113996 -2.15543996 0 P 0 ;0
L 1.20113996 -2.15543996 1.20295 -2.15171004 0 P 0 ;0
L 1.20295 -2.15171004 1.20435 -2.14815 0 P 0 ;0
L 1.20435 -2.14815 1.20543996 -2.14448996 0 P 0 ;0
L 1.20543996 -2.14448996 1.20621004 -2.14073996 0 P 0 ;0
L 1.20621004 -2.14073996 1.20651998 -2.13855 0 P 0 ;0
L 1.20651998 -2.13855 1.20671998 -2.13633996 0 P 0 ;0
L 1.20671998 -2.13633996 1.20761998 -2.12321004 0 P 0 ;0
L 1.20761998 -2.12321004 1.20858002 -2.10753996 0 P 0 ;0
L 1.20858002 -2.10753996 1.20951004 -2.09021998 0 P 0 ;0
L 1.20951004 -2.09021998 1.21048002 -2.07166004 0 P 0 ;0
L 1.21048002 -2.07166004 1.21156004 -2.05228002 0 P 0 ;0
L 1.21156004 -2.05228002 1.21258002 -2.03478996 0 P 0 ;0
L 1.21258002 -2.03478996 1.21333002 -2.02286004 0 P 0 ;0
L 1.21333002 -2.02286004 1.21393996 -2.01373996 0 P 0 ;0
L 1.21393996 -2.01373996 1.21443996 -2.00568996 0 P 0 ;0
L 1.21443996 -2.00568996 1.21485 -1.99883996 0 P 0 ;0
L 1.21485 -1.99883996 1.2149 -1.99721004 0 P 0 ;0
L 1.2149 -1.99721004 1.21488996 -1.99703996 0 P 0 ;0
L 1.21488996 -1.99703996 1.21486998 -1.99686004 0 P 0 ;0
L 1.21486998 -1.99686004 1.21483996 -1.99668996 0 P 0 ;0
L 1.21483996 -1.99668996 1.21478996 -1.99653002 0 P 0 ;0
L 1.21478996 -1.99653002 1.21473002 -1.99636998 0 P 0 ;0
L 1.21473002 -1.99636998 1.21466004 -1.99621004 0 P 0 ;0
L 1.21466004 -1.99621004 1.21458002 -1.99606004 0 P 0 ;0
L 1.21458002 -1.99606004 1.21448002 -1.99591004 0 P 0 ;0
L 1.21448002 -1.99591004 1.21433002 -1.99571998 0 P 0 ;0
L 1.21433002 -1.99571998 1.21416998 -1.99553996 0 P 0 ;0
L 1.21416998 -1.99553996 1.21398996 -1.99538002 0 P 0 ;0
L 1.21398996 -1.99538002 1.21378996 -1.99523996 0 P 0 ;0
L 1.21378996 -1.99523996 1.21358002 -1.99511004 0 P 0 ;0
L 1.21358002 -1.99511004 1.21336004 -1.995 0 P 0 ;0
L 1.21336004 -1.995 1.21261004 -1.99468996 0 P 0 ;0
L 1.21261004 -1.99468996 1.21183996 -1.99443996 0 P 0 ;0
L 1.21183996 -1.99443996 1.21105 -1.99423002 0 P 0 ;0
L 1.21105 -1.99423002 1.20593996 -1.99318002 0 P 0 ;0
L 1.20593996 -1.99318002 1.18996998 -1.99065 0 P 0 ;0
L 1.18996998 -1.99065 1.17318996 -1.98908002 0 P 0 ;0
L 1.17318996 -1.98908002 1.15718996 -1.98858002 0 P 0 ;0
L 1.15718996 -1.98858002 1.1504 -1.98876004 0 P 0 ;0
L 1.1504 -1.98876004 1.14356998 -1.98926998 0 P 0 ;0
L 1.04503996 -2.19061998 1.05141998 -2.19061998 0 P 0 ;0
L 1.04893002 -2.18961998 1.05323002 -2.18961998 0 P 0 ;0
L 1.05263002 -2.18861998 1.05503996 -2.18861998 0 P 0 ;0
L 1.05628996 -2.18761998 1.05676004 -2.18761998 0 P 0 ;0
L 1.09645 -2.17983002 1.16738002 -2.17983002 0 P 0 ;0
L 1.09126004 -2.17883002 1.17091004 -2.17883002 0 P 0 ;0
L 1.0868 -2.17783002 1.17386998 -2.17783002 0 P 0 ;0
L 1.08368002 -2.17683002 1.17636004 -2.17683002 0 P 0 ;0
L 1.0836 -2.17583002 1.1787 -2.17583002 0 P 0 ;0
L 1.08351998 -2.17483002 1.18066998 -2.17483002 0 P 0 ;0
L 1.08345 -2.17383002 1.18236998 -2.17383002 0 P 0 ;0
L 1.08336998 -2.17283002 1.1839 -2.17283002 0 P 0 ;0
L 1.08328996 -2.17183002 1.18526998 -2.17183002 0 P 0 ;0
L 1.08321998 -2.17083002 1.18646998 -2.17083002 0 P 0 ;0
L 1.08313996 -2.16983002 1.18761998 -2.16983002 0 P 0 ;0
L 1.08306998 -2.16883002 1.18863996 -2.16883002 0 P 0 ;0
L 1.08298996 -2.16783002 1.18966004 -2.16783002 0 P 0 ;0
L 1.08291998 -2.16683002 1.19061004 -2.16683002 0 P 0 ;0
L 1.08283996 -2.16583002 1.1915 -2.16583002 0 P 0 ;0
L 1.08276004 -2.16483002 1.19238996 -2.16483002 0 P 0 ;0
L 1.08268996 -2.16383002 1.19321004 -2.16383002 0 P 0 ;0
L 1.08261004 -2.16283002 1.19398002 -2.16283002 0 P 0 ;0
L 1.08253002 -2.16183002 1.19476004 -2.16183002 0 P 0 ;0
L 1.08246004 -2.16083002 1.19548002 -2.16083002 0 P 0 ;0
L 1.08238002 -2.15983002 1.19613996 -2.15983002 0 P 0 ;0
L 1.08231004 -2.15883002 1.19681004 -2.15883002 0 P 0 ;0
L 1.08223996 -2.15783002 1.19746004 -2.15783002 0 P 0 ;0
L 1.13506998 -2.18383002 1.12553002 -2.18343996 0 P 0 ;0
L 1.12553002 -2.18343996 1.11266004 -2.18218002 0 P 0 ;0
L 1.11266004 -2.18218002 1.09983002 -2.18048002 0 P 0 ;0
L 1.09983002 -2.18048002 1.09036998 -2.17866004 0 P 0 ;0
L 1.09036998 -2.17866004 1.0837 -2.17711004 0 P 0 ;0
L 1.0837 -2.17711004 1.08245 -2.16066998 0 P 0 ;0
L 1.08245 -2.16066998 1.08193996 -2.15361998 0 P 0 ;0
L 1.08193996 -2.15361998 1.08156998 -2.14726004 0 P 0 ;0
L 1.08156998 -2.14726004 1.08131998 -2.14191004 0 P 0 ;0
L 1.08131998 -2.14191004 1.08131004 -2.14108996 0 P 0 ;0
L 1.08131004 -2.14108996 1.08136004 -2.14026004 0 P 0 ;0
L 1.08136004 -2.14026004 1.0814 -2.13986998 0 P 0 ;0
L 1.0814 -2.13986998 1.08996004 -2.14233002 0 P 0 ;0
L 1.08996004 -2.14233002 1.08996998 -2.14233996 0 P 0 ;0
L 1.08996998 -2.14233996 1.08998996 -2.14233996 0 P 0 ;0
L 1.08998996 -2.14233996 1.099 -2.14471998 0 P 0 ;0
L 1.099 -2.14471998 1.10806998 -2.14668002 0 P 0 ;0
L 1.10806998 -2.14668002 1.11598002 -2.14791998 0 P 0 ;0
L 1.11598002 -2.14791998 1.12395 -2.1486 0 P 0 ;0
L 1.12395 -2.1486 1.13048996 -2.14863996 0 P 0 ;0
L 1.13048996 -2.14863996 1.137 -2.14811998 0 P 0 ;0
L 1.137 -2.14811998 1.13903002 -2.14778996 0 P 0 ;0
L 1.13903002 -2.14778996 1.14103002 -2.14728996 0 P 0 ;0
L 1.14103002 -2.14728996 1.14298002 -2.14661998 0 P 0 ;0
L 1.14298002 -2.14661998 1.14486998 -2.14581004 0 P 0 ;0
L 1.14486998 -2.14581004 1.14668002 -2.14483996 0 P 0 ;0
L 1.14668002 -2.14483996 1.1484 -2.14373996 0 P 0 ;0
L 1.1484 -2.14373996 1.15003002 -2.1425 0 P 0 ;0
L 1.15003002 -2.1425 1.15155 -2.14115 0 P 0 ;0
L 1.15155 -2.14115 1.1526 -2.14006998 0 P 0 ;0
L 1.1526 -2.14006998 1.15263996 -2.14001998 0 P 0 ;0
L 1.15263996 -2.14001998 1.15356004 -2.13893002 0 P 0 ;0
L 1.15356004 -2.13893002 1.15443996 -2.13771998 0 P 0 ;0
L 1.15443996 -2.13771998 1.15523002 -2.13646004 0 P 0 ;0
L 1.15523002 -2.13646004 1.15593996 -2.13515 0 P 0 ;0
L 1.15593996 -2.13515 1.15655 -2.13381004 0 P 0 ;0
L 1.15655 -2.13381004 1.15706004 -2.13243002 0 P 0 ;0
L 1.15706004 -2.13243002 1.15748002 -2.13101004 0 P 0 ;0
L 1.15748002 -2.13101004 1.1579 -2.12905 0 P 0 ;0
L 1.1579 -2.12905 1.15816004 -2.12706004 0 P 0 ;0
L 1.15816004 -2.12706004 1.15825 -2.12506998 0 P 0 ;0
L 1.15825 -2.12506998 1.15818002 -2.12165 0 P 0 ;0
L 1.15818002 -2.12165 1.15813996 -2.12118002 0 P 0 ;0
L 1.15813996 -2.12118002 1.15813002 -2.1211 0 P 0 ;0
L 1.15813002 -2.1211 1.15806004 -2.12068002 0 P 0 ;0
L 1.15806004 -2.12068002 1.15793996 -2.12018996 0 P 0 ;0
L 1.15793996 -2.12018996 1.15778002 -2.11973002 0 P 0 ;0
L 1.15778002 -2.11973002 1.1577 -2.11953002 0 P 0 ;0
L 1.1577 -2.11953002 1.15758996 -2.11933002 0 P 0 ;0
L 1.15758996 -2.11933002 1.15746998 -2.11913996 0 P 0 ;0
L 1.15746998 -2.11913996 1.15733002 -2.11895 0 P 0 ;0
L 1.15733002 -2.11895 1.15716998 -2.11878002 0 P 0 ;0
L 1.15716998 -2.11878002 1.157 -2.11863002 0 P 0 ;0
L 1.157 -2.11863002 1.15681998 -2.11848996 0 P 0 ;0
L 1.15681998 -2.11848996 1.15663002 -2.11836004 0 P 0 ;0
L 1.15663002 -2.11836004 1.15641998 -2.11825 0 P 0 ;0
L 1.15641998 -2.11825 1.15621004 -2.11816004 0 P 0 ;0
L 1.15621004 -2.11816004 1.15598996 -2.11808996 0 P 0 ;0
L 1.15598996 -2.11808996 1.15576998 -2.11803996 0 P 0 ;0
L 1.15576998 -2.11803996 1.15553002 -2.118 0 P 0 ;0
L 1.15553002 -2.118 1.15518002 -2.11798002 0 P 0 ;0
L 1.15518002 -2.11798002 1.15483996 -2.11798996 0 P 0 ;0
L 1.15483996 -2.11798996 1.15451004 -2.11803002 0 P 0 ;0
L 1.15451004 -2.11803002 1.15418002 -2.1181 0 P 0 ;0
L 1.15418002 -2.1181 1.15386004 -2.1182 0 P 0 ;0
L 1.15386004 -2.1182 1.15361004 -2.11828996 0 P 0 ;0
L 1.15361004 -2.11828996 1.14705 -2.12083996 0 P 0 ;0
L 1.14705 -2.12083996 1.14038996 -2.12278996 0 P 0 ;0
L 1.14038996 -2.12278996 1.13356004 -2.12416004 0 P 0 ;0
L 1.13356004 -2.12416004 1.1285 -2.12476998 0 P 0 ;0
L 1.1285 -2.12476998 1.12341004 -2.12501998 0 P 0 ;0
L 1.12341004 -2.12501998 1.11831004 -2.12493002 0 P 0 ;0
L 1.11831004 -2.12493002 1.11323002 -2.12448996 0 P 0 ;0
L 1.11323002 -2.12448996 1.10848996 -2.12373002 0 P 0 ;0
L 1.10848996 -2.12373002 1.10383996 -2.12263002 0 P 0 ;0
L 1.10383996 -2.12263002 1.09926998 -2.12118996 0 P 0 ;0
L 1.09926998 -2.12118996 1.09481004 -2.11941004 0 P 0 ;0
L 1.09481004 -2.11941004 1.09168002 -2.11788002 0 P 0 ;0
L 1.09168002 -2.11788002 1.08866004 -2.11611998 0 P 0 ;0
L 1.08866004 -2.11611998 1.08578002 -2.11413002 0 P 0 ;0
L 1.08578002 -2.11413002 1.08306998 -2.11193996 0 P 0 ;0
L 1.08306998 -2.11193996 1.08051998 -2.10955 0 P 0 ;0
L 1.08051998 -2.10955 1.07793996 -2.10673002 0 P 0 ;0
L 1.07793996 -2.10673002 1.07561004 -2.10373996 0 P 0 ;0
L 1.07561004 -2.10373996 1.07351004 -2.10058002 0 P 0 ;0
L 1.07351004 -2.10058002 1.07171004 -2.09733996 0 P 0 ;0
L 1.07171004 -2.09733996 1.07018002 -2.09396998 0 P 0 ;0
L 1.07018002 -2.09396998 1.06893996 -2.09048002 0 P 0 ;0
L 1.06893996 -2.09048002 1.06786004 -2.0865 0 P 0 ;0
L 1.06786004 -2.0865 1.06706004 -2.08243996 0 P 0 ;0
L 1.06706004 -2.08243996 1.06656004 -2.07833002 0 P 0 ;0
L 1.06656004 -2.07833002 1.06615 -2.07071004 0 P 0 ;0
L 1.06615 -2.07071004 1.06621004 -2.06313996 0 P 0 ;0
L 1.06621004 -2.06313996 1.06675 -2.0556 0 P 0 ;0
L 1.06675 -2.0556 1.0678 -2.04813002 0 P 0 ;0
L 1.0678 -2.04813002 1.06868996 -2.04391998 0 P 0 ;0
L 1.06868996 -2.04391998 1.06985 -2.03981004 0 P 0 ;0
L 1.06985 -2.03981004 1.0713 -2.03578996 0 P 0 ;0
L 1.0713 -2.03578996 1.07296004 -2.03206998 0 P 0 ;0
L 1.07296004 -2.03206998 1.07486998 -2.02848996 0 P 0 ;0
L 1.07486998 -2.02848996 1.07705 -2.02506004 0 P 0 ;0
L 1.07705 -2.02506004 1.07966004 -2.0215 0 P 0 ;0
L 1.07966004 -2.0215 1.08246998 -2.01811004 0 P 0 ;0
L 1.08246998 -2.01811004 1.08546998 -2.01491004 0 P 0 ;0
L 1.08546998 -2.01491004 1.0897 -2.01091004 0 P 0 ;0
L 1.0897 -2.01091004 1.09153002 -2.00936998 0 P 0 ;0
L 1.09153002 -2.00936998 1.09341998 -2.00793996 0 P 0 ;0
L 1.09341998 -2.00793996 1.09545 -2.00658002 0 P 0 ;0
L 1.09545 -2.00658002 1.09751004 -2.00533996 0 P 0 ;0
L 1.09751004 -2.00533996 1.10288002 -2.0025 0 P 0 ;0
L 1.10288002 -2.0025 1.10736998 -2.00043002 0 P 0 ;0
L 1.10736998 -2.00043002 1.11193002 -1.99861004 0 P 0 ;0
L 1.11193002 -1.99861004 1.12218002 -1.99533002 0 P 0 ;0
L 1.12218002 -1.99533002 1.13298002 -1.99281998 0 P 0 ;0
L 1.13298002 -1.99281998 1.14378996 -1.99126004 0 P 0 ;0
L 1.14378996 -1.99126004 1.1505 -1.99075 0 P 0 ;0
L 1.1505 -1.99075 1.15718002 -1.99058996 0 P 0 ;0
L 1.15718002 -1.99058996 1.17306998 -1.99108002 0 P 0 ;0
L 1.17306998 -1.99108002 1.18971998 -1.99263002 0 P 0 ;0
L 1.18971998 -1.99263002 1.20558002 -1.99515 0 P 0 ;0
L 1.20558002 -1.99515 1.21058996 -1.99618002 0 P 0 ;0
L 1.21058996 -1.99618002 1.21126998 -1.99636004 0 P 0 ;0
L 1.21126998 -1.99636004 1.21191998 -1.99656998 0 P 0 ;0
L 1.21191998 -1.99656998 1.21253002 -1.99681998 0 P 0 ;0
L 1.21253002 -1.99681998 1.21261004 -1.99686004 0 P 0 ;0
L 1.21261004 -1.99686004 1.21266004 -1.99688996 0 P 0 ;0
L 1.21266004 -1.99688996 1.21271998 -1.99693002 0 P 0 ;0
L 1.21271998 -1.99693002 1.21281998 -1.99703002 0 P 0 ;0
L 1.21281998 -1.99703002 1.21286004 -1.99708996 0 P 0 ;0
L 1.21286004 -1.99708996 1.21288002 -1.99711004 0 P 0 ;0
L 1.21288002 -1.99711004 1.21288002 -1.99711998 0 P 0 ;0
L 1.21288002 -1.99711998 1.21288996 -1.99715 0 P 0 ;0
L 1.21288996 -1.99715 1.2129 -1.99716998 0 P 0 ;0
L 1.2129 -1.99716998 1.2129 -1.99721998 0 P 0 ;0
L 1.2129 -1.99721998 1.21285 -1.99875 0 P 0 ;0
L 1.21285 -1.99875 1.21243996 -2.00556998 0 P 0 ;0
L 1.21243996 -2.00556998 1.21193996 -2.01361004 0 P 0 ;0
L 1.21193996 -2.01361004 1.21133996 -2.02273002 0 P 0 ;0
L 1.21133996 -2.02273002 1.21133996 -2.02273996 0 P 0 ;0
L 1.21133996 -2.02273996 1.21058996 -2.03468002 0 P 0 ;0
L 1.21058996 -2.03468002 1.20956004 -2.05216998 0 P 0 ;0
L 1.20956004 -2.05216998 1.20848996 -2.07156004 0 P 0 ;0
L 1.20848996 -2.07156004 1.20848996 -2.07156998 0 P 0 ;0
L 1.20848996 -2.07156998 1.20751004 -2.09011004 0 P 0 ;0
L 1.20751004 -2.09011004 1.20658996 -2.10743996 0 P 0 ;0
L 1.20658996 -2.10743996 1.20561998 -2.12308996 0 P 0 ;0
L 1.20561998 -2.12308996 1.20473002 -2.13618996 0 P 0 ;0
L 1.20473002 -2.13618996 1.20453002 -2.13831998 0 P 0 ;0
L 1.20453002 -2.13831998 1.20423996 -2.14041004 0 P 0 ;0
L 1.20423996 -2.14041004 1.2035 -2.144 0 P 0 ;0
L 1.2035 -2.144 1.20246004 -2.1475 0 P 0 ;0
L 1.20246004 -2.1475 1.20111998 -2.1509 0 P 0 ;0
L 1.20111998 -2.1509 1.19936998 -2.1545 0 P 0 ;0
L 1.19936998 -2.1545 1.19738002 -2.15796998 0 P 0 ;0
L 1.19738002 -2.15796998 1.19516004 -2.1613 0 P 0 ;0
L 1.19516004 -2.1613 1.19276998 -2.16441004 0 P 0 ;0
L 1.19276998 -2.16441004 1.19016004 -2.16733996 0 P 0 ;0
L 1.19016004 -2.16733996 1.18736004 -2.17008002 0 P 0 ;0
L 1.18736004 -2.17008002 1.1854 -2.17173996 0 P 0 ;0
L 1.1854 -2.17173996 1.18335 -2.17323002 0 P 0 ;0
L 1.18335 -2.17323002 1.18118002 -2.17456004 0 P 0 ;0
L 1.18118002 -2.17456004 1.17893002 -2.17573002 0 P 0 ;0
L 1.17893002 -2.17573002 1.17456998 -2.1776 0 P 0 ;0
L 1.17456998 -2.1776 1.17006998 -2.17911998 0 P 0 ;0
L 1.17006998 -2.17911998 1.16473996 -2.18053002 0 P 0 ;0
L 1.16473996 -2.18053002 1.15935 -2.18166998 0 P 0 ;0
L 1.15935 -2.18166998 1.15341998 -2.18263002 0 P 0 ;0
L 1.15341998 -2.18263002 1.1475 -2.18328996 0 P 0 ;0
L 1.1475 -2.18328996 1.13506998 -2.18383002 0 P 0 ;0
L 0.90491998 -2.21461998 1.00131004 -2.21461998 0 P 0 ;0
L 0.92235 -2.21361998 1.00355 -2.21361998 0 P 0 ;0
L 0.76925 -1.8965 0.85586998 -1.8965 0 P 0 ;0
L 0.76958996 -1.8955 0.85556004 -1.8955 0 P 0 ;0
L 0.76995 -1.8945 0.85521004 -1.8945 0 P 0 ;0
L 0.77031004 -1.8935 0.85486004 -1.8935 0 P 0 ;0
L 0.77071004 -1.8925 0.85443996 -1.8925 0 P 0 ;0
L 0.77115 -1.8915 0.85401004 -1.8915 0 P 0 ;0
L 0.7716 -1.8905 0.85355 -1.8905 0 P 0 ;0
L 0.77206004 -1.8895 0.85303002 -1.8895 0 P 0 ;0
L 0.7726 -1.8885 0.85251004 -1.8885 0 P 0 ;0
L 0.77313996 -1.8875 0.85198996 -1.8875 0 P 0 ;0
L 0.77368996 -1.8865 0.85138002 -1.8865 0 P 0 ;0
L 0.77433002 -1.8855 0.85073996 -1.8855 0 P 0 ;0
L 0.77496004 -1.8845 0.85011004 -1.8845 0 P 0 ;0
L 0.77561998 -1.8835 0.84943002 -1.8835 0 P 0 ;0
L 0.77636004 -1.8825 0.84866998 -1.8825 0 P 0 ;0
L 0.77711004 -1.8815 0.84791004 -1.8815 0 P 0 ;0
L 0.7779 -1.8805 0.84713002 -1.8805 0 P 0 ;0
L 0.77876998 -1.8795 0.84623002 -1.8795 0 P 0 ;0
L 0.77963996 -1.8785 0.84533002 -1.8785 0 P 0 ;0
L 0.7806 -1.8775 0.8444 -1.8775 0 P 0 ;0
L 0.78161004 -1.8765 0.84335 -1.8765 0 P 0 ;0
L 0.78265 -1.8755 0.84228996 -1.8755 0 P 0 ;0
L 0.78381998 -1.8745 0.84108996 -1.8745 0 P 0 ;0
L 0.78498996 -1.8735 0.83986998 -1.8735 0 P 0 ;0
L 0.78635 -1.8725 0.83848002 -1.8725 0 P 0 ;0
L 0.78773002 -1.8715 0.83706004 -1.8715 0 P 0 ;0
L 0.78933002 -1.8705 0.83541998 -1.8705 0 P 0 ;0
L 0.791 -1.8695 0.83366004 -1.8695 0 P 0 ;0
L 0.793 -1.8685 0.83171998 -1.8685 0 P 0 ;0
L 0.79525 -1.8675 0.82941998 -1.8675 0 P 0 ;0
L 0.79791998 -1.8665 0.82671004 -1.8665 0 P 0 ;0
L 0.80143996 -1.8655 0.82328996 -1.8655 0 P 0 ;0
L 0.80705 -1.8645 0.81776004 -1.8645 0 P 0 ;0
L 0.74543002 -1.89661998 0.75033002 -1.89661998 0 P 0 ;0
L 0.74751004 -1.89561998 0.75058996 -1.89561998 0 P 0 ;0
L 0.74958996 -1.89461998 0.75086004 -1.89461998 0 P 0 ;0
L 0.76733996 -1.9125 0.85751998 -1.9125 0 P 0 ;0
L 0.76728996 -1.9115 0.85756004 -1.9115 0 P 0 ;0
L 0.76723996 -1.9105 0.85758996 -1.9105 0 P 0 ;0
L 0.76721998 -1.9095 0.85763002 -1.9095 0 P 0 ;0
L 0.76725 -1.9085 0.85761004 -1.9085 0 P 0 ;0
L 0.76728002 -1.9075 0.85756998 -1.9075 0 P 0 ;0
L 0.76731004 -1.9065 0.85753002 -1.9065 0 P 0 ;0
L 0.76741998 -1.9055 0.85748996 -1.9055 0 P 0 ;0
L 0.76753996 -1.9045 0.85738002 -1.9045 0 P 0 ;0
L 0.76766004 -1.9035 0.85726004 -1.9035 0 P 0 ;0
L 0.76781998 -1.9025 0.85713996 -1.9025 0 P 0 ;0
L 0.76801998 -1.9015 0.85701004 -1.9015 0 P 0 ;0
L 0.76821004 -1.9005 0.85683002 -1.9005 0 P 0 ;0
L 0.76841998 -1.8995 0.85661998 -1.8995 0 P 0 ;0
L 0.7687 -1.8985 0.85641004 -1.8985 0 P 0 ;0
L 0.76896998 -1.8975 0.85613996 -1.8975 0 P 0 ;0
L 0.76751004 -2.08325 0.8416 -2.08325 0 P 0 ;0
L 0.76761998 -2.08225 0.84161998 -2.08225 0 P 0 ;0
L 0.76773996 -2.08125 0.84166998 -2.08125 0 P 0 ;0
L 0.76786004 -2.08025 0.84171998 -2.08025 0 P 0 ;0
L 0.76796998 -2.07925 0.84176998 -2.07925 0 P 0 ;0
L 0.76808002 -2.07825 0.84181004 -2.07825 0 P 0 ;0
L 0.76818002 -2.07725 0.84186004 -2.07725 0 P 0 ;0
L 0.76828996 -2.07625 0.8419 -2.07625 0 P 0 ;0
L 0.76838996 -2.07525 0.84195 -2.07525 0 P 0 ;0
L 0.76848996 -2.07425 0.842 -2.07425 0 P 0 ;0
L 0.7686 -2.07325 0.84205 -2.07325 0 P 0 ;0
L 0.7687 -2.07225 0.84208996 -2.07225 0 P 0 ;0
L 0.7688 -2.07125 0.84213996 -2.07125 0 P 0 ;0
L 0.7689 -2.07025 0.84218002 -2.07025 0 P 0 ;0
L 0.76901004 -2.06925 0.84223002 -2.06925 0 P 0 ;0
L 0.76911004 -2.06825 0.84228002 -2.06825 0 P 0 ;0
L 0.76921004 -2.06725 0.84233002 -2.06725 0 P 0 ;0
L 0.76931998 -2.06625 0.84236998 -2.06625 0 P 0 ;0
L 0.76941998 -2.06525 0.84241998 -2.06525 0 P 0 ;0
L 0.76948996 -2.06425 0.84246004 -2.06425 0 P 0 ;0
L 0.76956004 -2.06325 0.84251004 -2.06325 0 P 0 ;0
L 0.76963002 -2.06225 0.84256004 -2.06225 0 P 0 ;0
L 0.7697 -2.06125 0.8426 -2.06125 0 P 0 ;0
L 0.76976998 -2.06025 0.84265 -2.06025 0 P 0 ;0
L 0.76983996 -2.05925 0.8427 -2.05925 0 P 0 ;0
L 0.76991004 -2.05825 0.84273996 -2.05825 0 P 0 ;0
L 0.76996998 -2.05725 0.84278996 -2.05725 0 P 0 ;0
L 0.77001004 -2.05625 0.84283996 -2.05625 0 P 0 ;0
L 0.77003996 -2.05525 0.84288002 -2.05525 0 P 0 ;0
L 0.77008002 -2.05425 0.84295 -2.05425 0 P 0 ;0
L 0.77011998 -2.05325 0.84303996 -2.05325 0 P 0 ;0
L 0.77016004 -2.05225 0.84311998 -2.05225 0 P 0 ;0
L 0.77018996 -2.05125 0.84321004 -2.05125 0 P 0 ;0
L 0.77023002 -2.05025 0.8433 -2.05025 0 P 0 ;0
L 0.77026998 -2.04925 0.84338002 -2.04925 0 P 0 ;0
L 0.77031004 -2.04825 0.84346998 -2.04825 0 P 0 ;0
L 0.77033996 -2.04725 0.84356004 -2.04725 0 P 0 ;0
L 0.77038002 -2.04625 0.84363996 -2.04625 0 P 0 ;0
L 0.77041004 -2.04525 0.84373002 -2.04525 0 P 0 ;0
L 0.77043996 -2.04425 0.84381004 -2.04425 0 P 0 ;0
L 0.77046004 -2.04325 0.8439 -2.04325 0 P 0 ;0
L 0.77048002 -2.04225 0.84398996 -2.04225 0 P 0 ;0
L 0.77051004 -2.04125 0.84406998 -2.04125 0 P 0 ;0
L 0.77053002 -2.04025 0.84416004 -2.04025 0 P 0 ;0
L 0.77055 -2.03925 0.84425 -2.03925 0 P 0 ;0
L 0.77058002 -2.03825 0.84433002 -2.03825 0 P 0 ;0
L 0.7706 -2.03725 0.84441998 -2.03725 0 P 0 ;0
L 0.77061998 -2.03625 0.84451004 -2.03625 0 P 0 ;0
L 0.77065 -2.03525 0.84458996 -2.03525 0 P 0 ;0
L 0.77066998 -2.03425 0.84468002 -2.03425 0 P 0 ;0
L 0.7707 -2.03325 0.84476998 -2.03325 0 P 0 ;0
L 0.77071998 -2.03225 0.84485 -2.03225 0 P 0 ;0
L 0.77073002 -2.03125 0.84493996 -2.03125 0 P 0 ;0
L 0.77073996 -2.03025 0.84503002 -2.03025 0 P 0 ;0
L 0.79986004 -1.8638 0.79643996 -1.86486998 0 P 0 ;0
L 0.79643996 -1.86486998 0.79311998 -1.86621004 0 P 0 ;0
L 0.79311998 -1.86621004 0.78991004 -1.86781004 0 P 0 ;0
L 0.78991004 -1.86781004 0.78683996 -1.86966998 0 P 0 ;0
L 0.78683996 -1.86966998 0.78391998 -1.87178002 0 P 0 ;0
L 0.78391998 -1.87178002 0.78111998 -1.87416998 0 P 0 ;0
L 0.78111998 -1.87416998 0.7785 -1.87676004 0 P 0 ;0
L 0.7785 -1.87676004 0.77608002 -1.87953996 0 P 0 ;0
L 0.77608002 -1.87953996 0.77386998 -1.8825 0 P 0 ;0
L 0.77386998 -1.8825 0.77188002 -1.88561998 0 P 0 ;0
L 0.77188002 -1.88561998 0.77013996 -1.88886004 0 P 0 ;0
L 0.77013996 -1.88886004 0.76863996 -1.89221004 0 P 0 ;0
L 0.76863996 -1.89221004 0.7674 -1.89566998 0 P 0 ;0
L 0.7674 -1.89566998 0.76643002 -1.89921004 0 P 0 ;0
L 0.76643002 -1.89921004 0.76571004 -1.90283996 0 P 0 ;0
L 0.76571004 -1.90283996 0.76531004 -1.90636004 0 P 0 ;0
L 0.76531004 -1.90636004 0.7652 -1.90991004 0 P 0 ;0
L 0.7652 -1.90991004 0.76538996 -1.91345 0 P 0 ;0
L 0.76538996 -1.91345 0.76586998 -1.91696998 0 P 0 ;0
L 0.76586998 -1.91696998 0.76663996 -1.92046004 0 P 0 ;0
L 0.76663996 -1.92046004 0.76803002 -1.92493996 0 P 0 ;0
L 0.76803002 -1.92493996 0.76978002 -1.9293 0 P 0 ;0
L 0.76978002 -1.9293 0.77106998 -1.93193996 0 P 0 ;0
L 0.77106998 -1.93193996 0.77253002 -1.93448002 0 P 0 ;0
L 0.77253002 -1.93448002 0.77416004 -1.93693996 0 P 0 ;0
L 0.77416004 -1.93693996 0.77593002 -1.93923002 0 P 0 ;0
L 0.77593002 -1.93923002 0.77783996 -1.94141004 0 P 0 ;0
L 0.77783996 -1.94141004 0.77988996 -1.94345 0 P 0 ;0
L 0.77988996 -1.94345 0.78216004 -1.94545 0 P 0 ;0
L 0.78216004 -1.94545 0.78453996 -1.9473 0 P 0 ;0
L 0.78453996 -1.9473 0.78703002 -1.94901998 0 P 0 ;0
L 0.78703002 -1.94901998 0.79016998 -1.95088002 0 P 0 ;0
L 0.79016998 -1.95088002 0.79343996 -1.95248996 0 P 0 ;0
L 0.79343996 -1.95248996 0.79683002 -1.95383996 0 P 0 ;0
L 0.79683002 -1.95383996 0.80031998 -1.95491998 0 P 0 ;0
L 0.80031998 -1.95491998 0.80391004 -1.95573996 0 P 0 ;0
L 0.80391004 -1.95573996 0.80751998 -1.95626004 0 P 0 ;0
L 0.80751998 -1.95626004 0.81116004 -1.9565 0 P 0 ;0
L 0.81116004 -1.9565 0.81481004 -1.95646004 0 P 0 ;0
L 0.81481004 -1.95646004 0.81843996 -1.95613002 0 P 0 ;0
L 0.81843996 -1.95613002 0.82205 -1.95551004 0 P 0 ;0
L 0.82205 -1.95551004 0.82561998 -1.95461004 0 P 0 ;0
L 0.82561998 -1.95461004 0.82911004 -1.95345 0 P 0 ;0
L 0.82911004 -1.95345 0.83248996 -1.95201004 0 P 0 ;0
L 0.83248996 -1.95201004 0.83576004 -1.95031998 0 P 0 ;0
L 0.83576004 -1.95031998 0.83891998 -1.94836004 0 P 0 ;0
L 0.83891998 -1.94836004 0.84191998 -1.94616998 0 P 0 ;0
L 0.84191998 -1.94616998 0.84475 -1.94375 0 P 0 ;0
L 0.84475 -1.94375 0.84738996 -1.94113996 0 P 0 ;0
L 0.84738996 -1.94113996 0.84983002 -1.93833996 0 P 0 ;0
L 0.84983002 -1.93833996 0.85206998 -1.93533996 0 P 0 ;0
L 0.85206998 -1.93533996 0.8536 -1.93291998 0 P 0 ;0
L 0.8536 -1.93291998 0.85496004 -1.93041004 0 P 0 ;0
L 0.85496004 -1.93041004 0.85613996 -1.9278 0 P 0 ;0
L 0.85613996 -1.9278 0.85711998 -1.92511004 0 P 0 ;0
L 0.85711998 -1.92511004 0.85823002 -1.92123002 0 P 0 ;0
L 0.85823002 -1.92123002 0.85901998 -1.91726998 0 P 0 ;0
L 0.85901998 -1.91726998 0.85948996 -1.91323996 0 P 0 ;0
L 0.85948996 -1.91323996 0.85963996 -1.90918002 0 P 0 ;0
L 0.85963996 -1.90918002 0.85946998 -1.90513002 0 P 0 ;0
L 0.85946998 -1.90513002 0.85898002 -1.9011 0 P 0 ;0
L 0.85898002 -1.9011 0.85841998 -1.89826004 0 P 0 ;0
L 0.85841998 -1.89826004 0.85766004 -1.89546004 0 P 0 ;0
L 0.85766004 -1.89546004 0.85671004 -1.89273002 0 P 0 ;0
L 0.85671004 -1.89273002 0.85556998 -1.89006004 0 P 0 ;0
L 0.85556998 -1.89006004 0.85361998 -1.88631004 0 P 0 ;0
L 0.85361998 -1.88631004 0.85136004 -1.88273996 0 P 0 ;0
L 0.85136004 -1.88273996 0.84881004 -1.87938002 0 P 0 ;0
L 0.84881004 -1.87938002 0.84596998 -1.87623002 0 P 0 ;0
L 0.84596998 -1.87623002 0.84355 -1.87393996 0 P 0 ;0
L 0.84355 -1.87393996 0.84096998 -1.87181998 0 P 0 ;0
L 0.84096998 -1.87181998 0.83826004 -1.86988996 0 P 0 ;0
L 0.83826004 -1.86988996 0.83541004 -1.86815 0 P 0 ;0
L 0.83541004 -1.86815 0.83243996 -1.86661004 0 P 0 ;0
L 0.83243996 -1.86661004 0.82938996 -1.86531004 0 P 0 ;0
L 0.82938996 -1.86531004 0.82625 -1.86423002 0 P 0 ;0
L 0.82625 -1.86423002 0.82303996 -1.86336004 0 P 0 ;0
L 0.82303996 -1.86336004 0.81978002 -1.86273002 0 P 0 ;0
L 0.81978002 -1.86273002 0.81646998 -1.86233002 0 P 0 ;0
L 0.81646998 -1.86233002 0.81228996 -1.86215 0 P 0 ;0
L 0.81228996 -1.86215 0.80811004 -1.86233996 0 P 0 ;0
L 0.80811004 -1.86233996 0.80396004 -1.86288996 0 P 0 ;0
L 0.80396004 -1.86288996 0.79986004 -1.8638 0 P 0 ;0
L 0.80308996 -1.9535 0.82186004 -1.9535 0 P 0 ;0
L 0.79926004 -1.9525 0.82563996 -1.9525 0 P 0 ;0
L 0.79636004 -1.9515 0.82856998 -1.9515 0 P 0 ;0
L 0.79393002 -1.9505 0.83093996 -1.9505 0 P 0 ;0
L 0.7919 -1.9495 0.83298996 -1.9495 0 P 0 ;0
L 0.79008002 -1.9485 0.8349 -1.9485 0 P 0 ;0
L 0.78838996 -1.9475 0.83651004 -1.9475 0 P 0 ;0
L 0.7869 -1.9465 0.83806998 -1.9465 0 P 0 ;0
L 0.78548002 -1.9455 0.83943996 -1.9455 0 P 0 ;0
L 0.7842 -1.9445 0.84078996 -1.9445 0 P 0 ;0
L 0.78298002 -1.9435 0.84196998 -1.9435 0 P 0 ;0
L 0.78183996 -1.9425 0.84313996 -1.9425 0 P 0 ;0
L 0.78076998 -1.9415 0.84418996 -1.9415 0 P 0 ;0
L 0.77976004 -1.9405 0.8452 -1.9405 0 P 0 ;0
L 0.77883002 -1.9395 0.84616998 -1.9395 0 P 0 ;0
L 0.77793996 -1.9385 0.84703996 -1.9385 0 P 0 ;0
L 0.77711998 -1.9375 0.84791004 -1.9375 0 P 0 ;0
L 0.77635 -1.9365 0.84871004 -1.9365 0 P 0 ;0
L 0.77561004 -1.9355 0.84945 -1.9355 0 P 0 ;0
L 0.77493996 -1.9345 0.8502 -1.9345 0 P 0 ;0
L 0.77428002 -1.9335 0.85086998 -1.9335 0 P 0 ;0
L 0.7737 -1.9325 0.8515 -1.9325 0 P 0 ;0
L 0.77311998 -1.9315 0.8521 -1.9315 0 P 0 ;0
L 0.77258996 -1.9305 0.85263996 -1.9305 0 P 0 ;0
L 0.7721 -1.9295 0.85318002 -1.9295 0 P 0 ;0
L 0.77161004 -1.9285 0.85363002 -1.9285 0 P 0 ;0
L 0.77121004 -1.9275 0.85408002 -1.9275 0 P 0 ;0
L 0.77081004 -1.9265 0.85448002 -1.9265 0 P 0 ;0
L 0.77041004 -1.9255 0.85485 -1.9255 0 P 0 ;0
L 0.77001004 -1.9245 0.85521998 -1.9245 0 P 0 ;0
L 0.76968002 -1.9235 0.8555 -1.9235 0 P 0 ;0
L 0.76936998 -1.9225 0.85578996 -1.9225 0 P 0 ;0
L 0.76906004 -1.9215 0.85606998 -1.9215 0 P 0 ;0
L 0.76875 -1.9205 0.85633002 -1.9205 0 P 0 ;0
L 0.76848002 -1.9195 0.85653002 -1.9195 0 P 0 ;0
L 0.76826004 -1.9185 0.85673002 -1.9185 0 P 0 ;0
L 0.76803002 -1.9175 0.85693002 -1.9175 0 P 0 ;0
L 0.76783002 -1.9165 0.85708996 -1.9165 0 P 0 ;0
L 0.76768996 -1.9155 0.85721004 -1.9155 0 P 0 ;0
L 0.76755 -1.9145 0.85733002 -1.9145 0 P 0 ;0
L 0.76741998 -1.9135 0.85745 -1.9135 0 P 0 ;0
L 0.81121004 -1.9545 0.80773002 -1.95426998 0 P 0 ;0
L 0.80773002 -1.95426998 0.80426998 -1.95376998 0 P 0 ;0
L 0.80426998 -1.95376998 0.80083996 -1.95298996 0 P 0 ;0
L 0.80083996 -1.95298996 0.7975 -1.95195 0 P 0 ;0
L 0.7975 -1.95195 0.79426004 -1.95066004 0 P 0 ;0
L 0.79426004 -1.95066004 0.79111998 -1.94911998 0 P 0 ;0
L 0.79111998 -1.94911998 0.78811004 -1.94733002 0 P 0 ;0
L 0.78811004 -1.94733002 0.78573002 -1.94568996 0 P 0 ;0
L 0.78573002 -1.94568996 0.78343996 -1.9439 0 P 0 ;0
L 0.78343996 -1.9439 0.78126004 -1.94198996 0 P 0 ;0
L 0.78126004 -1.94198996 0.7793 -1.94003996 0 P 0 ;0
L 0.7793 -1.94003996 0.77746998 -1.93796004 0 P 0 ;0
L 0.77746998 -1.93796004 0.77578996 -1.93576998 0 P 0 ;0
L 0.77578996 -1.93576998 0.77423002 -1.93343002 0 P 0 ;0
L 0.77423002 -1.93343002 0.77283996 -1.931 0 P 0 ;0
L 0.77283996 -1.931 0.77161004 -1.92848996 0 P 0 ;0
L 0.77161004 -1.92848996 0.76991998 -1.92426998 0 P 0 ;0
L 0.76991998 -1.92426998 0.76858002 -1.91993996 0 P 0 ;0
L 0.76858002 -1.91993996 0.76783996 -1.91661998 0 P 0 ;0
L 0.76783996 -1.91661998 0.76738002 -1.91326998 0 P 0 ;0
L 0.76738002 -1.91326998 0.76721004 -1.90988996 0 P 0 ;0
L 0.76721004 -1.90988996 0.76731004 -1.90651004 0 P 0 ;0
L 0.76731004 -1.90651004 0.7677 -1.90315 0 P 0 ;0
L 0.7677 -1.90315 0.76838002 -1.89966998 0 P 0 ;0
L 0.76838002 -1.89966998 0.76931004 -1.89626998 0 P 0 ;0
L 0.76931004 -1.89626998 0.7705 -1.89296004 0 P 0 ;0
L 0.7705 -1.89296004 0.77193996 -1.88973996 0 P 0 ;0
L 0.77193996 -1.88973996 0.7736 -1.88663996 0 P 0 ;0
L 0.7736 -1.88663996 0.77551004 -1.88363996 0 P 0 ;0
L 0.77551004 -1.88363996 0.77763002 -1.8808 0 P 0 ;0
L 0.77763002 -1.8808 0.77996004 -1.87813002 0 P 0 ;0
L 0.77996004 -1.87813002 0.78246998 -1.87565 0 P 0 ;0
L 0.78246998 -1.87565 0.78516004 -1.87336004 0 P 0 ;0
L 0.78516004 -1.87336004 0.78795 -1.87133996 0 P 0 ;0
L 0.78795 -1.87133996 0.79088002 -1.86956004 0 P 0 ;0
L 0.79088002 -1.86956004 0.79393996 -1.86803002 0 P 0 ;0
L 0.79393996 -1.86803002 0.79711004 -1.86675 0 P 0 ;0
L 0.79711004 -1.86675 0.80038002 -1.86573002 0 P 0 ;0
L 0.80038002 -1.86573002 0.80431004 -1.86486004 0 P 0 ;0
L 0.80431004 -1.86486004 0.80828996 -1.86433996 0 P 0 ;0
L 0.80828996 -1.86433996 0.8123 -1.86416004 0 P 0 ;0
L 0.8123 -1.86416004 0.81631004 -1.86431998 0 P 0 ;0
L 0.81631004 -1.86431998 0.81946998 -1.86471004 0 P 0 ;0
L 0.81946998 -1.86471004 0.82258996 -1.86531004 0 P 0 ;0
L 0.82258996 -1.86531004 0.82566004 -1.86613996 0 P 0 ;0
L 0.82566004 -1.86613996 0.82866998 -1.86718002 0 P 0 ;0
L 0.82866998 -1.86718002 0.83158996 -1.86843002 0 P 0 ;0
L 0.83158996 -1.86843002 0.83443002 -1.86988996 0 P 0 ;0
L 0.83443002 -1.86988996 0.83716004 -1.87156004 0 P 0 ;0
L 0.83716004 -1.87156004 0.83976004 -1.87341004 0 P 0 ;0
L 0.83976004 -1.87341004 0.84223002 -1.87543996 0 P 0 ;0
L 0.84223002 -1.87543996 0.84453996 -1.87763002 0 P 0 ;0
L 0.84453996 -1.87763002 0.84726998 -1.88065 0 P 0 ;0
L 0.84726998 -1.88065 0.84971998 -1.88388002 0 P 0 ;0
L 0.84971998 -1.88388002 0.85188996 -1.88731004 0 P 0 ;0
L 0.85188996 -1.88731004 0.85376004 -1.89091004 0 P 0 ;0
L 0.85376004 -1.89091004 0.85483996 -1.89345 0 P 0 ;0
L 0.85483996 -1.89345 0.85575 -1.89605 0 P 0 ;0
L 0.85575 -1.89605 0.85646998 -1.89871004 0 P 0 ;0
L 0.85646998 -1.89871004 0.857 -1.90141004 0 P 0 ;0
L 0.857 -1.90141004 0.85748002 -1.9053 0 P 0 ;0
L 0.85748002 -1.9053 0.85763996 -1.90918996 0 P 0 ;0
L 0.85763996 -1.90918996 0.8575 -1.91308002 0 P 0 ;0
L 0.8575 -1.91308002 0.85703996 -1.91696004 0 P 0 ;0
L 0.85703996 -1.91696004 0.85628002 -1.92076004 0 P 0 ;0
L 0.85628002 -1.92076004 0.85521998 -1.92448996 0 P 0 ;0
L 0.85521998 -1.92448996 0.85428002 -1.92705 0 P 0 ;0
L 0.85428002 -1.92705 0.85316998 -1.92951998 0 P 0 ;0
L 0.85316998 -1.92951998 0.85188002 -1.93191004 0 P 0 ;0
L 0.85188002 -1.93191004 0.85041998 -1.9342 0 P 0 ;0
L 0.85041998 -1.9342 0.84826998 -1.93708002 0 P 0 ;0
L 0.84826998 -1.93708002 0.84593002 -1.93976998 0 P 0 ;0
L 0.84593002 -1.93976998 0.8434 -1.94228002 0 P 0 ;0
L 0.8434 -1.94228002 0.84068002 -1.9446 0 P 0 ;0
L 0.84068002 -1.9446 0.8378 -1.9467 0 P 0 ;0
L 0.8378 -1.9467 0.83476998 -1.94858002 0 P 0 ;0
L 0.83476998 -1.94858002 0.83163996 -1.9502 0 P 0 ;0
L 0.83163996 -1.9502 0.8284 -1.95158002 0 P 0 ;0
L 0.8284 -1.95158002 0.82506004 -1.95268996 0 P 0 ;0
L 0.82506004 -1.95268996 0.82163996 -1.95356004 0 P 0 ;0
L 0.82163996 -1.95356004 0.81818002 -1.95413996 0 P 0 ;0
L 0.81818002 -1.95413996 0.8147 -1.95446004 0 P 0 ;0
L 0.8147 -1.95446004 0.81121004 -1.9545 0 P 0 ;0
L 0.77075 -2.02925 0.84511004 -2.02925 0 P 0 ;0
L 0.77076004 -2.02825 0.8452 -2.02825 0 P 0 ;0
L 0.77076998 -2.02725 0.84528996 -2.02725 0 P 0 ;0
L 0.77078002 -2.02625 0.84536998 -2.02625 0 P 0 ;0
L 0.77078996 -2.02525 0.84548996 -2.02525 0 P 0 ;0
L 0.7708 -2.02425 0.84561998 -2.02425 0 P 0 ;0
L 0.77081004 -2.02325 0.84575 -2.02325 0 P 0 ;0
L 0.77081998 -2.02225 0.84588002 -2.02225 0 P 0 ;0
L 0.77083002 -2.02125 0.84601004 -2.02125 0 P 0 ;0
L 0.77083996 -2.02025 0.84613996 -2.02025 0 P 0 ;0
L 0.77085 -2.01925 0.84626004 -2.01925 0 P 0 ;0
L 0.77085 -2.01825 0.84638996 -2.01825 0 P 0 ;0
L 0.77085 -2.01725 0.84651998 -2.01725 0 P 0 ;0
L 0.77086004 -2.01625 0.84663996 -2.01625 0 P 0 ;0
L 0.77086004 -2.01525 0.84676998 -2.01525 0 P 0 ;0
L 0.77086004 -2.01425 0.8469 -2.01425 0 P 0 ;0
L 0.77086004 -2.01325 0.84703002 -2.01325 0 P 0 ;0
L 0.77086004 -2.01225 0.84716004 -2.01225 0 P 0 ;0
L 0.77086004 -2.01125 0.84728996 -2.01125 0 P 0 ;0
L 0.77086004 -2.01025 0.84741004 -2.01025 0 P 0 ;0
L 0.77086998 -2.00925 0.84753996 -2.00925 0 P 0 ;0
L 0.77086998 -2.00825 0.84766998 -2.00825 0 P 0 ;0
L 0.77086998 -2.00725 0.84778996 -2.00725 0 P 0 ;0
L 0.77086998 -2.00625 0.84791998 -2.00625 0 P 0 ;0
L 0.77086998 -2.00525 0.84805 -2.00525 0 P 0 ;0
L 0.77086998 -2.00425 0.84818002 -2.00425 0 P 0 ;0
L 0.77088002 -2.00325 0.84831004 -2.00325 0 P 0 ;0
L 0.77088002 -2.00225 0.84843996 -2.00225 0 P 0 ;0
L 0.77088002 -2.00125 0.84856004 -2.00125 0 P 0 ;0
L 0.77088002 -2.00025 0.84868996 -2.00025 0 P 0 ;0
L 0.77088002 -1.99925 0.84881998 -1.99925 0 P 0 ;0
L 0.77088002 -1.99825 0.84896004 -1.99825 0 P 0 ;0
L 0.77088002 -1.99725 0.84911004 -1.99725 0 P 0 ;0
L 0.77088996 -1.99625 0.84926998 -1.99625 0 P 0 ;0
L 0.77088996 -1.99525 0.84941998 -1.99525 0 P 0 ;0
L 0.77088996 -1.99425 0.84956998 -1.99425 0 P 0 ;0
L 0.77088996 -1.99325 0.84971998 -1.99325 0 P 0 ;0
L 0.77088996 -1.99225 0.84986998 -1.99225 0 P 0 ;0
L 0.77088996 -1.99125 0.85003002 -1.99125 0 P 0 ;0
L 0.7709 -1.99025 0.85018002 -1.99025 0 P 0 ;0
L 0.7709 -1.98925 0.85033002 -1.98925 0 P 0 ;0
L 0.76885 -2.01878002 0.76871998 -2.03201998 0 P 0 ;0
L 0.76871998 -2.03201998 0.7684 -2.04553996 0 P 0 ;0
L 0.7684 -2.04553996 0.76796004 -2.05751004 0 P 0 ;0
L 0.76796004 -2.05751004 0.76741004 -2.06523002 0 P 0 ;0
L 0.76741004 -2.06523002 0.76596004 -2.07933996 0 P 0 ;0
L 0.76596004 -2.07933996 0.7636 -2.09918002 0 P 0 ;0
L 0.7636 -2.09918002 0.76116004 -2.119 0 P 0 ;0
L 0.76116004 -2.119 0.76011998 -2.12526004 0 P 0 ;0
L 0.76011998 -2.12526004 0.75948996 -2.12825 0 P 0 ;0
L 0.75948996 -2.12825 0.84418002 -2.12825 0 P 0 ;0
L 0.84418002 -2.12825 0.84361998 -2.10788002 0 P 0 ;0
L 0.84361998 -2.10788002 0.8436 -2.08276004 0 P 0 ;0
L 0.8436 -2.08276004 0.8449 -2.05491998 0 P 0 ;0
L 0.8449 -2.05491998 0.84736004 -2.02641004 0 P 0 ;0
L 0.84736004 -2.02641004 0.85083996 -1.99923002 0 P 0 ;0
L 0.85083996 -1.99923002 0.85268996 -1.987 0 P 0 ;0
L 0.85268996 -1.987 0.7689 -1.987 0 P 0 ;0
L 0.7689 -1.987 0.76885 -2.01878002 0 P 0 ;0
L 0.76195 -2.12625 0.84211998 -2.12625 0 P 0 ;0
L 0.76213996 -2.12525 0.8421 -2.12525 0 P 0 ;0
L 0.76231004 -2.12425 0.84206998 -2.12425 0 P 0 ;0
L 0.76248002 -2.12325 0.84203996 -2.12325 0 P 0 ;0
L 0.76263996 -2.12225 0.84201004 -2.12225 0 P 0 ;0
L 0.76281004 -2.12125 0.84198996 -2.12125 0 P 0 ;0
L 0.76296998 -2.12025 0.84196004 -2.12025 0 P 0 ;0
L 0.76313996 -2.11925 0.84193002 -2.11925 0 P 0 ;0
L 0.76326998 -2.11825 0.8419 -2.11825 0 P 0 ;0
L 0.76338996 -2.11725 0.84188002 -2.11725 0 P 0 ;0
L 0.76351004 -2.11625 0.84185 -2.11625 0 P 0 ;0
L 0.76363996 -2.11525 0.84181998 -2.11525 0 P 0 ;0
L 0.76376004 -2.11425 0.84178996 -2.11425 0 P 0 ;0
L 0.76388002 -2.11325 0.84176998 -2.11325 0 P 0 ;0
L 0.76401004 -2.11225 0.84173996 -2.11225 0 P 0 ;0
L 0.76413002 -2.11125 0.84171004 -2.11125 0 P 0 ;0
L 0.76425 -2.11025 0.84168002 -2.11025 0 P 0 ;0
L 0.76438002 -2.10925 0.84166004 -2.10925 0 P 0 ;0
L 0.7645 -2.10825 0.84163002 -2.10825 0 P 0 ;0
L 0.76461998 -2.10725 0.84161998 -2.10725 0 P 0 ;0
L 0.76475 -2.10625 0.84161998 -2.10625 0 P 0 ;0
L 0.76486998 -2.10525 0.84161998 -2.10525 0 P 0 ;0
L 0.76498996 -2.10425 0.84161998 -2.10425 0 P 0 ;0
L 0.76511998 -2.10325 0.84161998 -2.10325 0 P 0 ;0
L 0.76523996 -2.10225 0.84161998 -2.10225 0 P 0 ;0
L 0.76536004 -2.10125 0.84161998 -2.10125 0 P 0 ;0
L 0.76548996 -2.10025 0.84161998 -2.10025 0 P 0 ;0
L 0.76561004 -2.09925 0.84161998 -2.09925 0 P 0 ;0
L 0.76573002 -2.09825 0.84161004 -2.09825 0 P 0 ;0
L 0.76583996 -2.09725 0.84161004 -2.09725 0 P 0 ;0
L 0.76596998 -2.09625 0.84161004 -2.09625 0 P 0 ;0
L 0.76608996 -2.09525 0.84161004 -2.09525 0 P 0 ;0
L 0.7662 -2.09425 0.84161004 -2.09425 0 P 0 ;0
L 0.76631998 -2.09325 0.84161004 -2.09325 0 P 0 ;0
L 0.76643996 -2.09225 0.84161004 -2.09225 0 P 0 ;0
L 0.76656004 -2.09125 0.84161004 -2.09125 0 P 0 ;0
L 0.76668002 -2.09025 0.84161004 -2.09025 0 P 0 ;0
L 0.76678996 -2.08925 0.84161004 -2.08925 0 P 0 ;0
L 0.76691998 -2.08825 0.84161004 -2.08825 0 P 0 ;0
L 0.76703002 -2.08725 0.84161004 -2.08725 0 P 0 ;0
L 0.76715 -2.08625 0.8416 -2.08625 0 P 0 ;0
L 0.76726998 -2.08525 0.8416 -2.08525 0 P 0 ;0
L 0.76738996 -2.08425 0.8416 -2.08425 0 P 0 ;0
L 0.76195 -2.12625 0.76208002 -2.12561998 0 P 0 ;0
L 0.76208002 -2.12561998 0.76313996 -2.11928996 0 P 0 ;0
L 0.76313996 -2.11928996 0.76558996 -2.09941998 0 P 0 ;0
L 0.76558996 -2.09941998 0.76558996 -2.09941004 0 P 0 ;0
L 0.76558996 -2.09941004 0.76793996 -2.07956004 0 P 0 ;0
L 0.76793996 -2.07956004 0.7694 -2.0654 0 P 0 ;0
L 0.7694 -2.0654 0.76941004 -2.06536004 0 P 0 ;0
L 0.76941004 -2.06536004 0.76996004 -2.05761998 0 P 0 ;0
L 0.76996004 -2.05761998 0.76996004 -2.05758996 0 P 0 ;0
L 0.76996004 -2.05758996 0.7704 -2.0456 0 P 0 ;0
L 0.7704 -2.0456 0.77071998 -2.03206004 0 P 0 ;0
L 0.77071998 -2.03206004 0.77085 -2.01878002 0 P 0 ;0
L 0.77085 -2.01878002 0.7709 -1.989 0 P 0 ;0
L 0.7709 -1.989 0.85036004 -1.989 0 P 0 ;0
L 0.85036004 -1.989 0.84886004 -1.99895 0 P 0 ;0
L 0.84886004 -1.99895 0.84538002 -2.02618996 0 P 0 ;0
L 0.84538002 -2.02618996 0.8429 -2.05478996 0 P 0 ;0
L 0.8429 -2.05478996 0.8416 -2.08271004 0 P 0 ;0
L 0.8416 -2.08271004 0.84161998 -2.10791004 0 P 0 ;0
L 0.84161998 -2.10791004 0.84211998 -2.12625 0 P 0 ;0
L 0.84211998 -2.12625 0.76195 -2.12625 0 P 0 ;0
L 0.71628996 -1.91261998 0.74938002 -1.91261998 0 P 0 ;0
L 0.71783002 -1.91161998 0.74933002 -1.91161998 0 P 0 ;0
L 0.71953002 -1.91061998 0.74931004 -1.91061998 0 P 0 ;0
L 0.72133002 -1.90961998 0.74928996 -1.90961998 0 P 0 ;0
L 0.72313996 -1.90861998 0.74926998 -1.90861998 0 P 0 ;0
L 0.72493996 -1.90761998 0.74928996 -1.90761998 0 P 0 ;0
L 0.72673996 -1.90661998 0.74931998 -1.90661998 0 P 0 ;0
L 0.72855 -1.90561998 0.74935 -1.90561998 0 P 0 ;0
L 0.73035 -1.90461998 0.74938996 -1.90461998 0 P 0 ;0
L 0.73215 -1.90361998 0.74946998 -1.90361998 0 P 0 ;0
L 0.73396004 -1.90261998 0.74953996 -1.90261998 0 P 0 ;0
L 0.73576004 -1.90161998 0.74961998 -1.90161998 0 P 0 ;0
L 0.73756998 -1.90061998 0.74973996 -1.90061998 0 P 0 ;0
L 0.73943002 -1.89961998 0.74986004 -1.89961998 0 P 0 ;0
L 0.74141998 -1.89861998 0.74998996 -1.89861998 0 P 0 ;0
L 0.74341004 -1.89761998 0.75015 -1.89761998 0 P 0 ;0
L 0.59843002 -2.08361998 0.6754 -2.08361998 0 P 0 ;0
L 0.59846004 -2.08261998 0.67538996 -2.08261998 0 P 0 ;0
L 0.59848002 -2.08161998 0.67538002 -2.08161998 0 P 0 ;0
L 0.59851004 -2.08061998 0.67538002 -2.08061998 0 P 0 ;0
L 0.59853002 -2.07961998 0.67546004 -2.07961998 0 P 0 ;0
L 0.59856004 -2.07861998 0.67553996 -2.07861998 0 P 0 ;0
L 0.59861998 -2.07761998 0.67561004 -2.07761998 0 P 0 ;0
L 0.5987 -2.07661998 0.67568996 -2.07661998 0 P 0 ;0
L 0.59878002 -2.07561998 0.67576004 -2.07561998 0 P 0 ;0
L 0.59885 -2.07461998 0.67583996 -2.07461998 0 P 0 ;0
L 0.59893002 -2.07361998 0.67591998 -2.07361998 0 P 0 ;0
L 0.59901004 -2.07261998 0.67598996 -2.07261998 0 P 0 ;0
L 0.59908002 -2.07161998 0.67606998 -2.07161998 0 P 0 ;0
L 0.59916004 -2.07061998 0.67613996 -2.07061998 0 P 0 ;0
L 0.59923002 -2.06961998 0.67621004 -2.06961998 0 P 0 ;0
L 0.59936004 -2.06861998 0.6763 -2.06861998 0 P 0 ;0
L 0.59948996 -2.06761998 0.67645 -2.06761998 0 P 0 ;0
L 0.59963002 -2.06661998 0.6766 -2.06661998 0 P 0 ;0
L 0.59976998 -2.06561998 0.67676004 -2.06561998 0 P 0 ;0
L 0.5999 -2.06461998 0.67691998 -2.06461998 0 P 0 ;0
L 0.60003002 -2.06361998 0.67706998 -2.06361998 0 P 0 ;0
L 0.60016998 -2.06261998 0.6773 -2.06261998 0 P 0 ;0
L 0.60031004 -2.06161998 0.67753002 -2.06161998 0 P 0 ;0
L 0.60051004 -2.06061998 0.67776004 -2.06061998 0 P 0 ;0
L 0.60071004 -2.05961998 0.67798996 -2.05961998 0 P 0 ;0
L 0.60091998 -2.05861998 0.67823002 -2.05861998 0 P 0 ;0
L 0.60111998 -2.05761998 0.67853002 -2.05761998 0 P 0 ;0
L 0.60133002 -2.05661998 0.67883996 -2.05661998 0 P 0 ;0
L 0.60153996 -2.05561998 0.67913996 -2.05561998 0 P 0 ;0
L 0.60173996 -2.05461998 0.67945 -2.05461998 0 P 0 ;0
L 0.60195 -2.05361998 0.67975 -2.05361998 0 P 0 ;0
L 0.60223002 -2.05261998 0.68006004 -2.05261998 0 P 0 ;0
L 0.60251004 -2.05161998 0.68036004 -2.05161998 0 P 0 ;0
L 0.60278996 -2.05061998 0.68066998 -2.05061998 0 P 0 ;0
L 0.60306004 -2.04961998 0.68096998 -2.04961998 0 P 0 ;0
L 0.60333996 -2.04861998 0.68135 -2.04861998 0 P 0 ;0
L 0.60361998 -2.04761998 0.68173002 -2.04761998 0 P 0 ;0
L 0.6039 -2.04661998 0.68211004 -2.04661998 0 P 0 ;0
L 0.60418002 -2.04561998 0.68248996 -2.04561998 0 P 0 ;0
L 0.60453002 -2.04461998 0.68288002 -2.04461998 0 P 0 ;0
L 0.60488002 -2.04361998 0.68326004 -2.04361998 0 P 0 ;0
L 0.60523002 -2.04261998 0.68363996 -2.04261998 0 P 0 ;0
L 0.60556998 -2.04161998 0.68401998 -2.04161998 0 P 0 ;0
L 0.60591998 -2.04061998 0.6844 -2.04061998 0 P 0 ;0
L 0.60626998 -2.03961998 0.68486004 -2.03961998 0 P 0 ;0
L 0.60661998 -2.03861998 0.68531998 -2.03861998 0 P 0 ;0
L 0.60698996 -2.03761998 0.68578002 -2.03761998 0 P 0 ;0
L 0.60743002 -2.03661998 0.68623996 -2.03661998 0 P 0 ;0
L 0.60786004 -2.03561998 0.6867 -2.03561998 0 P 0 ;0
L 0.60828996 -2.03461998 0.68716004 -2.03461998 0 P 0 ;0
L 0.60873002 -2.03361998 0.68761998 -2.03361998 0 P 0 ;0
L 0.60916004 -2.03261998 0.68808996 -2.03261998 0 P 0 ;0
L 0.60958996 -2.03161998 0.68856998 -2.03161998 0 P 0 ;0
L 0.61003002 -2.03061998 0.68911004 -2.03061998 0 P 0 ;0
L 0.61046004 -2.02961998 0.68965 -2.02961998 0 P 0 ;0
L 0.61088996 -2.02861998 0.69018996 -2.02861998 0 P 0 ;0
L 0.61133002 -2.02761998 0.69073002 -2.02761998 0 P 0 ;0
L 0.61176004 -2.02661998 0.69126998 -2.02661998 0 P 0 ;0
L 0.6122 -2.02561998 0.69181004 -2.02561998 0 P 0 ;0
L 0.61263002 -2.02461998 0.69235 -2.02461998 0 P 0 ;0
L 0.61306004 -2.02361998 0.69288002 -2.02361998 0 P 0 ;0
L 0.61348996 -2.02261998 0.69346998 -2.02261998 0 P 0 ;0
L 0.61393002 -2.02161998 0.69408996 -2.02161998 0 P 0 ;0
L 0.61436004 -2.02061998 0.6947 -2.02061998 0 P 0 ;0
L 0.61478996 -2.01961998 0.69531998 -2.01961998 0 P 0 ;0
L 0.61531004 -2.01861998 0.69593996 -2.01861998 0 P 0 ;0
L 0.61583996 -2.01761998 0.69656004 -2.01761998 0 P 0 ;0
L 0.61636004 -2.01661998 0.69718002 -2.01661998 0 P 0 ;0
L 0.61688002 -2.01561998 0.69778996 -2.01561998 0 P 0 ;0
L 0.6174 -2.01461998 0.69841998 -2.01461998 0 P 0 ;0
L 0.61791998 -2.01361998 0.69911998 -2.01361998 0 P 0 ;0
L 0.61843996 -2.01261998 0.69981998 -2.01261998 0 P 0 ;0
L 0.61896004 -2.01161998 0.70051998 -2.01161998 0 P 0 ;0
L 0.61948002 -2.01061998 0.70123002 -2.01061998 0 P 0 ;0
L 0.62 -2.00961998 0.70193002 -2.00961998 0 P 0 ;0
L 0.62051998 -2.00861998 0.70263002 -2.00861998 0 P 0 ;0
L 0.62103996 -2.00761998 0.70333002 -2.00761998 0 P 0 ;0
L 0.62163996 -2.00661998 0.70403996 -2.00661998 0 P 0 ;0
L 0.62225 -2.00561998 0.70483002 -2.00561998 0 P 0 ;0
L 0.62285 -2.00461998 0.70565 -2.00461998 0 P 0 ;0
L 0.62346004 -2.00361998 0.70646004 -2.00361998 0 P 0 ;0
L 0.62406004 -2.00261998 0.70726998 -2.00261998 0 P 0 ;0
L 0.62466004 -2.00161998 0.70808996 -2.00161998 0 P 0 ;0
L 0.62526998 -2.00061998 0.7089 -2.00061998 0 P 0 ;0
L 0.62586998 -1.99961998 0.70971004 -1.99961998 0 P 0 ;0
L 0.62648002 -1.99861998 0.71053002 -1.99861998 0 P 0 ;0
L 0.62708002 -1.99761998 0.71133996 -1.99761998 0 P 0 ;0
L 0.62768996 -1.99661998 0.71216004 -1.99661998 0 P 0 ;0
L 0.62831998 -1.99561998 0.71296998 -1.99561998 0 P 0 ;0
L 0.62901004 -1.99461998 0.71378996 -1.99461998 0 P 0 ;0
L 0.62971004 -1.99361998 0.71466004 -1.99361998 0 P 0 ;0
L 0.6304 -1.99261998 0.71561004 -1.99261998 0 P 0 ;0
L 0.6311 -1.99161998 0.71656998 -1.99161998 0 P 0 ;0
L 0.63178996 -1.99061998 0.71753002 -1.99061998 0 P 0 ;0
L 0.63248996 -1.98961998 0.71848996 -1.98961998 0 P 0 ;0
L 0.63318002 -1.98861998 0.71945 -1.98861998 0 P 0 ;0
L 0.63388002 -1.98761998 0.72041004 -1.98761998 0 P 0 ;0
L 0.63456998 -1.98661998 0.72136998 -1.98661998 0 P 0 ;0
L 0.63526998 -1.98561998 0.72233002 -1.98561998 0 P 0 ;0
L 0.63598002 -1.98461998 0.72328996 -1.98461998 0 P 0 ;0
L 0.63678996 -1.98361998 0.72425 -1.98361998 0 P 0 ;0
L 0.6376 -1.98261998 0.72521004 -1.98261998 0 P 0 ;0
L 0.63841004 -1.98161998 0.72628002 -1.98161998 0 P 0 ;0
L 0.63921998 -1.98061998 0.72738996 -1.98061998 0 P 0 ;0
L 0.64003002 -1.97961998 0.7285 -1.97961998 0 P 0 ;0
L 0.64083996 -1.97861998 0.72961004 -1.97861998 0 P 0 ;0
L 0.64165 -1.97761998 0.73071004 -1.97761998 0 P 0 ;0
L 0.64246004 -1.97661998 0.73181998 -1.97661998 0 P 0 ;0
L 0.64326998 -1.97561998 0.73293002 -1.97561998 0 P 0 ;0
L 0.64406998 -1.97461998 0.73403996 -1.97461998 0 P 0 ;0
L 0.64488002 -1.97361998 0.73515 -1.97361998 0 P 0 ;0
L 0.64568996 -1.97261998 0.73625 -1.97261998 0 P 0 ;0
L 0.6465 -1.97161998 0.73736004 -1.97161998 0 P 0 ;0
L 0.64731004 -1.97061998 0.73848002 -1.97061998 0 P 0 ;0
L 0.64811998 -1.96961998 0.73973002 -1.96961998 0 P 0 ;0
L 0.64893002 -1.96861998 0.74098996 -1.96861998 0 P 0 ;0
L 0.64981004 -1.96761998 0.74225 -1.96761998 0 P 0 ;0
L 0.65076004 -1.96661998 0.74351004 -1.96661998 0 P 0 ;0
L 0.65171004 -1.96561998 0.74476998 -1.96561998 0 P 0 ;0
L 0.65266998 -1.96461998 0.74603002 -1.96461998 0 P 0 ;0
L 0.65361998 -1.96361998 0.74728996 -1.96361998 0 P 0 ;0
L 0.65458002 -1.96261998 0.74855 -1.96261998 0 P 0 ;0
L 0.65553002 -1.96161998 0.74981004 -1.96161998 0 P 0 ;0
L 0.65648996 -1.96061998 0.75106004 -1.96061998 0 P 0 ;0
L 0.65743996 -1.95961998 0.75233996 -1.95961998 0 P 0 ;0
L 0.6584 -1.95861998 0.7537 -1.95861998 0 P 0 ;0
L 0.65935 -1.95761998 0.75506004 -1.95761998 0 P 0 ;0
L 0.66031004 -1.95661998 0.75641998 -1.95661998 0 P 0 ;0
L 0.66126004 -1.95561998 0.75778996 -1.95561998 0 P 0 ;0
L 0.66221004 -1.95461998 0.75916004 -1.95461998 0 P 0 ;0
L 0.66316998 -1.95361998 0.76053996 -1.95361998 0 P 0 ;0
L 0.66411998 -1.95261998 0.76193996 -1.95261998 0 P 0 ;0
L 0.66523002 -1.95161998 0.76333996 -1.95161998 0 P 0 ;0
L 0.66636004 -1.95061998 0.76406998 -1.95061998 0 P 0 ;0
L 0.66746998 -1.94961998 0.76355 -1.94961998 0 P 0 ;0
L 0.6686 -1.94861998 0.76291998 -1.94861998 0 P 0 ;0
L 0.66971004 -1.94761998 0.76226998 -1.94761998 0 P 0 ;0
L 0.67083996 -1.94661998 0.76161998 -1.94661998 0 P 0 ;0
L 0.67196004 -1.94561998 0.76096998 -1.94561998 0 P 0 ;0
L 0.67306998 -1.94461998 0.76033002 -1.94461998 0 P 0 ;0
L 0.6742 -1.94361998 0.75968996 -1.94361998 0 P 0 ;0
L 0.67531004 -1.94261998 0.75905 -1.94261998 0 P 0 ;0
L 0.67643996 -1.94161998 0.75846004 -1.94161998 0 P 0 ;0
L 0.67755 -1.94061998 0.75788996 -1.94061998 0 P 0 ;0
L 0.67868002 -1.93961998 0.75731998 -1.93961998 0 P 0 ;0
L 0.67978996 -1.93861998 0.75676998 -1.93861998 0 P 0 ;0
L 0.68091998 -1.93761998 0.75626998 -1.93761998 0 P 0 ;0
L 0.68221004 -1.93661998 0.75576998 -1.93661998 0 P 0 ;0
L 0.68353002 -1.93561998 0.75528002 -1.93561998 0 P 0 ;0
L 0.68483996 -1.93461998 0.75483996 -1.93461998 0 P 0 ;0
L 0.68616004 -1.93361998 0.75441004 -1.93361998 0 P 0 ;0
L 0.68746998 -1.93261998 0.75398002 -1.93261998 0 P 0 ;0
L 0.68878002 -1.93161998 0.7536 -1.93161998 0 P 0 ;0
L 0.6901 -1.93061998 0.75323996 -1.93061998 0 P 0 ;0
L 0.69141004 -1.92961998 0.75286998 -1.92961998 0 P 0 ;0
L 0.69271998 -1.92861998 0.75253996 -1.92861998 0 P 0 ;0
L 0.69403002 -1.92761998 0.75223002 -1.92761998 0 P 0 ;0
L 0.69535 -1.92661998 0.75193002 -1.92661998 0 P 0 ;0
L 0.69666004 -1.92561998 0.75163002 -1.92561998 0 P 0 ;0
L 0.69796998 -1.92461998 0.75138002 -1.92461998 0 P 0 ;0
L 0.69936998 -1.92361998 0.75113996 -1.92361998 0 P 0 ;0
L 0.70091004 -1.92261998 0.75088996 -1.92261998 0 P 0 ;0
L 0.70243996 -1.92161998 0.75066004 -1.92161998 0 P 0 ;0
L 0.70398002 -1.92061998 0.75046004 -1.92061998 0 P 0 ;0
L 0.70551998 -1.91961998 0.75026004 -1.91961998 0 P 0 ;0
L 0.70706004 -1.91861998 0.75006998 -1.91861998 0 P 0 ;0
L 0.7086 -1.91761998 0.7499 -1.91761998 0 P 0 ;0
L 0.71013996 -1.91661998 0.74976998 -1.91661998 0 P 0 ;0
L 0.71166998 -1.91561998 0.74961998 -1.91561998 0 P 0 ;0
L 0.71321004 -1.91461998 0.74951998 -1.91461998 0 P 0 ;0
L 0.71475 -1.91361998 0.74945 -1.91361998 0 P 0 ;0
L 0.61556998 -2.15661998 0.70655 -2.15661998 0 P 0 ;0
L 0.61503002 -2.15561998 0.7056 -2.15561998 0 P 0 ;0
L 0.61448996 -2.15461998 0.70465 -2.15461998 0 P 0 ;0
L 0.61395 -2.15361998 0.7037 -2.15361998 0 P 0 ;0
L 0.61341004 -2.15261998 0.70273996 -2.15261998 0 P 0 ;0
L 0.61286998 -2.15161998 0.70178996 -2.15161998 0 P 0 ;0
L 0.61233002 -2.15061998 0.70095 -2.15061998 0 P 0 ;0
L 0.61188002 -2.14961998 0.70015 -2.14961998 0 P 0 ;0
L 0.61143002 -2.14861998 0.69935 -2.14861998 0 P 0 ;0
L 0.61098002 -2.14761998 0.69855 -2.14761998 0 P 0 ;0
L 0.61053002 -2.14661998 0.69775 -2.14661998 0 P 0 ;0
L 0.61008002 -2.14561998 0.69695 -2.14561998 0 P 0 ;0
L 0.60963002 -2.14461998 0.69615 -2.14461998 0 P 0 ;0
L 0.60918002 -2.14361998 0.69535 -2.14361998 0 P 0 ;0
L 0.60873002 -2.14261998 0.69455 -2.14261998 0 P 0 ;0
L 0.60831004 -2.14161998 0.69381998 -2.14161998 0 P 0 ;0
L 0.60793996 -2.14061998 0.69315 -2.14061998 0 P 0 ;0
L 0.60756998 -2.13961998 0.69248002 -2.13961998 0 P 0 ;0
L 0.60721004 -2.13861998 0.69181004 -2.13861998 0 P 0 ;0
L 0.60683996 -2.13761998 0.69115 -2.13761998 0 P 0 ;0
L 0.60646998 -2.13661998 0.69048002 -2.13661998 0 P 0 ;0
L 0.60611004 -2.13561998 0.68981004 -2.13561998 0 P 0 ;0
L 0.60573996 -2.13461998 0.68918002 -2.13461998 0 P 0 ;0
L 0.60538002 -2.13361998 0.68863002 -2.13361998 0 P 0 ;0
L 0.60503996 -2.13261998 0.68808002 -2.13261998 0 P 0 ;0
L 0.60476004 -2.13161998 0.68753002 -2.13161998 0 P 0 ;0
L 0.60446998 -2.13061998 0.68698002 -2.13061998 0 P 0 ;0
L 0.60418002 -2.12961998 0.68643002 -2.12961998 0 P 0 ;0
L 0.6039 -2.12861998 0.68588002 -2.12861998 0 P 0 ;0
L 0.60361004 -2.12761998 0.68533002 -2.12761998 0 P 0 ;0
L 0.60331998 -2.12661998 0.68486004 -2.12661998 0 P 0 ;0
L 0.60303002 -2.12561998 0.68441998 -2.12561998 0 P 0 ;0
L 0.60275 -2.12461998 0.68396998 -2.12461998 0 P 0 ;0
L 0.60246004 -2.12361998 0.68353002 -2.12361998 0 P 0 ;0
L 0.60218002 -2.12261998 0.68308996 -2.12261998 0 P 0 ;0
L 0.60188996 -2.12161998 0.68263996 -2.12161998 0 P 0 ;0
L 0.60166998 -2.12061998 0.6822 -2.12061998 0 P 0 ;0
L 0.60145 -2.11961998 0.68176004 -2.11961998 0 P 0 ;0
L 0.60123002 -2.11861998 0.68138996 -2.11861998 0 P 0 ;0
L 0.60101004 -2.11761998 0.68105 -2.11761998 0 P 0 ;0
L 0.60078002 -2.11661998 0.68071004 -2.11661998 0 P 0 ;0
L 0.6006 -2.11561998 0.68036004 -2.11561998 0 P 0 ;0
L 0.60043002 -2.11461998 0.68001998 -2.11461998 0 P 0 ;0
L 0.60025 -2.11361998 0.67968002 -2.11361998 0 P 0 ;0
L 0.60008002 -2.11261998 0.67933002 -2.11261998 0 P 0 ;0
L 0.59991004 -2.11161998 0.67898996 -2.11161998 0 P 0 ;0
L 0.59976004 -2.11061998 0.6787 -2.11061998 0 P 0 ;0
L 0.59963996 -2.10961998 0.67845 -2.10961998 0 P 0 ;0
L 0.59951004 -2.10861998 0.6782 -2.10861998 0 P 0 ;0
L 0.59938002 -2.10761998 0.67795 -2.10761998 0 P 0 ;0
L 0.59925 -2.10661998 0.6777 -2.10661998 0 P 0 ;0
L 0.59913002 -2.10561998 0.67746004 -2.10561998 0 P 0 ;0
L 0.59905 -2.10461998 0.67721004 -2.10461998 0 P 0 ;0
L 0.59896998 -2.10361998 0.67696004 -2.10361998 0 P 0 ;0
L 0.59888002 -2.10261998 0.67671004 -2.10261998 0 P 0 ;0
L 0.5988 -2.10161998 0.67653996 -2.10161998 0 P 0 ;0
L 0.59871998 -2.10061998 0.67638002 -2.10061998 0 P 0 ;0
L 0.59866998 -2.09961998 0.67621004 -2.09961998 0 P 0 ;0
L 0.59863996 -2.09861998 0.67605 -2.09861998 0 P 0 ;0
L 0.59861004 -2.09761998 0.67588996 -2.09761998 0 P 0 ;0
L 0.59858996 -2.09661998 0.6758 -2.09661998 0 P 0 ;0
L 0.59856004 -2.09561998 0.67571004 -2.09561998 0 P 0 ;0
L 0.59853002 -2.09461998 0.67563002 -2.09461998 0 P 0 ;0
L 0.5985 -2.09361998 0.67553996 -2.09361998 0 P 0 ;0
L 0.59846998 -2.09261998 0.67546004 -2.09261998 0 P 0 ;0
L 0.59843996 -2.09161998 0.67546004 -2.09161998 0 P 0 ;0
L 0.59841998 -2.09061998 0.67545 -2.09061998 0 P 0 ;0
L 0.59838002 -2.08961998 0.67543996 -2.08961998 0 P 0 ;0
L 0.59836004 -2.08861998 0.67543002 -2.08861998 0 P 0 ;0
L 0.59833002 -2.08761998 0.67543002 -2.08761998 0 P 0 ;0
L 0.59835 -2.08661998 0.67541998 -2.08661998 0 P 0 ;0
L 0.59836998 -2.08561998 0.67541004 -2.08561998 0 P 0 ;0
L 0.5984 -2.08461998 0.67541004 -2.08461998 0 P 0 ;0
L 0.80005 -2.25161998 0.85543996 -2.25161998 0 P 0 ;0
L 0.78651998 -2.25061998 0.86596004 -2.25061998 0 P 0 ;0
L 0.77878996 -2.24961998 0.87636004 -2.24961998 0 P 0 ;0
L 0.77106004 -2.24861998 0.88285 -2.24861998 0 P 0 ;0
L 0.76398996 -2.24761998 0.88933996 -2.24761998 0 P 0 ;0
L 0.75891998 -2.24661998 0.89583996 -2.24661998 0 P 0 ;0
L 0.73781004 -1.8982 0.71738996 -1.90951998 0 P 0 ;0
L 0.71738996 -1.90951998 0.69766998 -1.92233996 0 P 0 ;0
L 0.69766998 -1.92233996 0.67971004 -1.93601998 0 P 0 ;0
L 0.67971004 -1.93601998 0.66278996 -1.95113002 0 P 0 ;0
L 0.66278996 -1.95113002 0.64786998 -1.96675 0 P 0 ;0
L 0.64786998 -1.96675 0.63423996 -1.98358996 0 P 0 ;0
L 0.63423996 -1.98358996 0.62643996 -1.99483002 0 P 0 ;0
L 0.62643996 -1.99483002 0.61933996 -2.00655 0 P 0 ;0
L 0.61933996 -2.00655 0.61298996 -2.01873996 0 P 0 ;0
L 0.61298996 -2.01873996 0.60503002 -2.03713002 0 P 0 ;0
L 0.60503002 -2.03713002 0.60225 -2.04506004 0 P 0 ;0
L 0.60225 -2.04506004 0.59998996 -2.05323002 0 P 0 ;0
L 0.59998996 -2.05323002 0.59833996 -2.0612 0 P 0 ;0
L 0.59833996 -2.0612 0.59725 -2.06928996 0 P 0 ;0
L 0.59725 -2.06928996 0.59656998 -2.07833996 0 P 0 ;0
L 0.59656998 -2.07833996 0.59633002 -2.0875 0 P 0 ;0
L 0.59633002 -2.0875 0.59668996 -2.10036998 0 P 0 ;0
L 0.59668996 -2.10036998 0.59715 -2.10596004 0 P 0 ;0
L 0.59715 -2.10596004 0.59786004 -2.11151004 0 P 0 ;0
L 0.59786004 -2.11151004 0.59878996 -2.11686998 0 P 0 ;0
L 0.59878996 -2.11686998 0.59996998 -2.1222 0 P 0 ;0
L 0.59996998 -2.1222 0.60326998 -2.13368996 0 P 0 ;0
L 0.60326998 -2.13368996 0.60656998 -2.1427 0 P 0 ;0
L 0.60656998 -2.1427 0.6105 -2.15143996 0 P 0 ;0
L 0.6105 -2.15143996 0.61505 -2.15988002 0 P 0 ;0
L 0.61505 -2.15988002 0.62023996 -2.16803996 0 P 0 ;0
L 0.62023996 -2.16803996 0.62828996 -2.17873002 0 P 0 ;0
L 0.62828996 -2.17873002 0.63718996 -2.18871004 0 P 0 ;0
L 0.63718996 -2.18871004 0.64693002 -2.19795 0 P 0 ;0
L 0.64693002 -2.19795 0.6582 -2.20701998 0 P 0 ;0
L 0.6582 -2.20701998 0.67011004 -2.21518996 0 P 0 ;0
L 0.67011004 -2.21518996 0.68261004 -2.22243002 0 P 0 ;0
L 0.68261004 -2.22243002 0.69673996 -2.22936004 0 P 0 ;0
L 0.69673996 -2.22936004 0.71123002 -2.23543996 0 P 0 ;0
L 0.71123002 -2.23543996 0.72611998 -2.24066998 0 P 0 ;0
L 0.72611998 -2.24066998 0.74536004 -2.24598996 0 P 0 ;0
L 0.74536004 -2.24598996 0.76493002 -2.24985 0 P 0 ;0
L 0.76493002 -2.24985 0.78671998 -2.25266998 0 P 0 ;0
L 0.78671998 -2.25266998 0.80863002 -2.25425 0 P 0 ;0
L 0.80863002 -2.25425 0.83146004 -2.25463002 0 P 0 ;0
L 0.83146004 -2.25463002 0.85418002 -2.25375 0 P 0 ;0
L 0.85418002 -2.25375 0.87641004 -2.25163996 0 P 0 ;0
L 0.87641004 -2.25163996 0.89853002 -2.24823002 0 P 0 ;0
L 0.89853002 -2.24823002 0.93045 -2.24101998 0 P 0 ;0
L 0.93045 -2.24101998 0.96466004 -2.23063002 0 P 0 ;0
L 0.96466004 -2.23063002 0.99911004 -2.2178 0 P 0 ;0
L 0.99911004 -2.2178 1.03183002 -2.20318002 0 P 0 ;0
L 1.03183002 -2.20318002 1.04391998 -2.19703002 0 P 0 ;0
L 1.04391998 -2.19703002 1.05581004 -2.19048996 0 P 0 ;0
L 1.05581004 -2.19048996 1.06676004 -2.18411998 0 P 0 ;0
L 1.06676004 -2.18411998 1.06681004 -2.18408996 0 P 0 ;0
L 1.06681004 -2.18408996 1.06685 -2.18405 0 P 0 ;0
L 1.06685 -2.18405 1.0669 -2.18401004 0 P 0 ;0
L 1.0669 -2.18401004 1.06693996 -2.18396998 0 P 0 ;0
L 1.06693996 -2.18396998 1.06696998 -2.18391998 0 P 0 ;0
L 1.06696998 -2.18391998 1.06701004 -2.18386998 0 P 0 ;0
L 1.06701004 -2.18386998 1.06703002 -2.18381998 0 P 0 ;0
L 1.06703002 -2.18381998 1.06706004 -2.18376004 0 P 0 ;0
L 1.06706004 -2.18376004 1.06706998 -2.18371004 0 P 0 ;0
L 1.06706998 -2.18371004 1.06708996 -2.18365 0 P 0 ;0
L 1.06708996 -2.18365 1.06708996 -2.18358996 0 P 0 ;0
L 1.06708996 -2.18358996 1.0671 -2.18353002 0 P 0 ;0
L 1.0671 -2.18353002 1.0671 -2.18346998 0 P 0 ;0
L 1.0671 -2.18346998 1.06708996 -2.18341004 0 P 0 ;0
L 1.06708996 -2.18341004 1.06706998 -2.18336004 0 P 0 ;0
L 1.06706998 -2.18336004 1.06706004 -2.1833 0 P 0 ;0
L 1.06706004 -2.1833 1.06703002 -2.18323996 0 P 0 ;0
L 1.06703002 -2.18323996 1.06701004 -2.18318996 0 P 0 ;0
L 1.06701004 -2.18318996 1.06696998 -2.18313996 0 P 0 ;0
L 1.06696998 -2.18313996 1.06693996 -2.18308996 0 P 0 ;0
L 1.06693996 -2.18308996 1.06688002 -2.18303002 0 P 0 ;0
L 1.06688002 -2.18303002 1.06678996 -2.18296998 0 P 0 ;0
L 1.06678996 -2.18296998 1.06673002 -2.18295 0 P 0 ;0
L 1.06673002 -2.18295 1.0667 -2.18295 0 P 0 ;0
L 1.0667 -2.18295 1.06666004 -2.18293996 0 P 0 ;0
L 1.06666004 -2.18293996 1.0666 -2.18293996 0 P 0 ;0
L 1.0666 -2.18293996 1.06656998 -2.18295 0 P 0 ;0
L 1.06656998 -2.18295 1.06653002 -2.18295 0 P 0 ;0
L 1.06653002 -2.18295 1.06153002 -2.1842 0 P 0 ;0
L 1.06153002 -2.1842 1.05583996 -2.18566998 0 P 0 ;0
L 1.05583996 -2.18566998 1.04916998 -2.1875 0 P 0 ;0
L 1.04916998 -2.1875 1.0153 -2.1962 0 P 0 ;0
L 1.0153 -2.1962 0.9814 -2.20333996 0 P 0 ;0
L 0.9814 -2.20333996 0.94881998 -2.2087 0 P 0 ;0
L 0.94881998 -2.2087 0.9189 -2.21198996 0 P 0 ;0
L 0.9189 -2.21198996 0.90113996 -2.21278996 0 P 0 ;0
L 0.90113996 -2.21278996 0.87738002 -2.21265 0 P 0 ;0
L 0.87738002 -2.21265 0.854 -2.21183002 0 P 0 ;0
L 0.854 -2.21183002 0.83788996 -2.21033996 0 P 0 ;0
L 0.83788996 -2.21033996 0.8174 -2.20693002 0 P 0 ;0
L 0.8174 -2.20693002 0.79708996 -2.2023 0 P 0 ;0
L 0.79708996 -2.2023 0.7769 -2.19641004 0 P 0 ;0
L 0.7769 -2.19641004 0.76433002 -2.19183996 0 P 0 ;0
L 0.76433002 -2.19183996 0.75208996 -2.18638002 0 P 0 ;0
L 0.75208996 -2.18638002 0.74026998 -2.18006998 0 P 0 ;0
L 0.74026998 -2.18006998 0.72886998 -2.17291004 0 P 0 ;0
L 0.72886998 -2.17291004 0.71961998 -2.16603002 0 P 0 ;0
L 0.71961998 -2.16603002 0.71098996 -2.15838996 0 P 0 ;0
L 0.71098996 -2.15838996 0.70303002 -2.15003002 0 P 0 ;0
L 0.70303002 -2.15003002 0.6958 -2.14098996 0 P 0 ;0
L 0.6958 -2.14098996 0.69106998 -2.1339 0 P 0 ;0
L 0.69106998 -2.1339 0.68696004 -2.12643002 0 P 0 ;0
L 0.68696004 -2.12643002 0.68351004 -2.11863002 0 P 0 ;0
L 0.68351004 -2.11863002 0.68073996 -2.11056004 0 P 0 ;0
L 0.68073996 -2.11056004 0.67866004 -2.10218996 0 P 0 ;0
L 0.67866004 -2.10218996 0.67788002 -2.09741998 0 P 0 ;0
L 0.67788002 -2.09741998 0.67746004 -2.0926 0 P 0 ;0
L 0.67746004 -2.0926 0.67738002 -2.08076004 0 P 0 ;0
L 0.67738002 -2.08076004 0.67828002 -2.06891004 0 P 0 ;0
L 0.67828002 -2.06891004 0.67903002 -2.06403996 0 P 0 ;0
L 0.67903002 -2.06403996 0.68013002 -2.05923996 0 P 0 ;0
L 0.68013002 -2.05923996 0.68288002 -2.05021998 0 P 0 ;0
L 0.68288002 -2.05021998 0.68623996 -2.04141004 0 P 0 ;0
L 0.68623996 -2.04141004 0.69018002 -2.03286004 0 P 0 ;0
L 0.69018002 -2.03286004 0.69486004 -2.02418002 0 P 0 ;0
L 0.69486004 -2.02418002 0.70003996 -2.0158 0 P 0 ;0
L 0.70003996 -2.0158 0.70573002 -2.00768996 0 P 0 ;0
L 0.70573002 -2.00768996 0.7158 -1.99531998 0 P 0 ;0
L 0.7158 -1.99531998 0.72681004 -1.98385 0 P 0 ;0
L 0.72681004 -1.98385 0.73971004 -1.9722 0 P 0 ;0
L 0.73971004 -1.9722 0.7533 -1.9614 0 P 0 ;0
L 0.7533 -1.9614 0.75753996 -1.95828002 0 P 0 ;0
L 0.75753996 -1.95828002 0.76138002 -1.95548002 0 P 0 ;0
L 0.76138002 -1.95548002 0.76463002 -1.95316004 0 P 0 ;0
L 0.76463002 -1.95316004 0.76516004 -1.95281004 0 P 0 ;0
L 0.76516004 -1.95281004 0.7657 -1.95248996 0 P 0 ;0
L 0.7657 -1.95248996 0.76578002 -1.95243996 0 P 0 ;0
L 0.76578002 -1.95243996 0.76586004 -1.95238002 0 P 0 ;0
L 0.76586004 -1.95238002 0.76593002 -1.95231998 0 P 0 ;0
L 0.76593002 -1.95231998 0.766 -1.95223996 0 P 0 ;0
L 0.766 -1.95223996 0.76606004 -1.95216998 0 P 0 ;0
L 0.76606004 -1.95216998 0.76616004 -1.95201004 0 P 0 ;0
L 0.76616004 -1.95201004 0.7662 -1.95191998 0 P 0 ;0
L 0.7662 -1.95191998 0.76626004 -1.95173996 0 P 0 ;0
L 0.76626004 -1.95173996 0.76628002 -1.95163996 0 P 0 ;0
L 0.76628002 -1.95163996 0.7663 -1.95143002 0 P 0 ;0
L 0.7663 -1.95143002 0.7663 -1.95121004 0 P 0 ;0
L 0.7663 -1.95121004 0.76628996 -1.951 0 P 0 ;0
L 0.76628996 -1.951 0.76625 -1.95078996 0 P 0 ;0
L 0.76625 -1.95078996 0.7662 -1.95058002 0 P 0 ;0
L 0.7662 -1.95058002 0.76613002 -1.95036998 0 P 0 ;0
L 0.76613002 -1.95036998 0.76583002 -1.94966998 0 P 0 ;0
L 0.76583002 -1.94966998 0.76548996 -1.94896998 0 P 0 ;0
L 0.76548996 -1.94896998 0.76508996 -1.9483 0 P 0 ;0
L 0.76508996 -1.9483 0.76253002 -1.94436004 0 P 0 ;0
L 0.76253002 -1.94436004 0.76056998 -1.94126998 0 P 0 ;0
L 0.76056998 -1.94126998 0.75871998 -1.93806004 0 P 0 ;0
L 0.75871998 -1.93806004 0.75716998 -1.93496998 0 P 0 ;0
L 0.75716998 -1.93496998 0.7558 -1.93178002 0 P 0 ;0
L 0.7558 -1.93178002 0.7546 -1.92853996 0 P 0 ;0
L 0.7546 -1.92853996 0.75358996 -1.92521004 0 P 0 ;0
L 0.75358996 -1.92521004 0.7527 -1.92161998 0 P 0 ;0
L 0.7527 -1.92161998 0.75196998 -1.91796004 0 P 0 ;0
L 0.75196998 -1.91796004 0.75155 -1.91496004 0 P 0 ;0
L 0.75155 -1.91496004 0.75133002 -1.91193002 0 P 0 ;0
L 0.75133002 -1.91193002 0.75126998 -1.9085 0 P 0 ;0
L 0.75126998 -1.9085 0.75136004 -1.90506004 0 P 0 ;0
L 0.75136004 -1.90506004 0.75161004 -1.90181998 0 P 0 ;0
L 0.75161004 -1.90181998 0.752 -1.8986 0 P 0 ;0
L 0.752 -1.8986 0.75228996 -1.89701998 0 P 0 ;0
L 0.75228996 -1.89701998 0.75268996 -1.89546998 0 P 0 ;0
L 0.75268996 -1.89546998 0.7532 -1.89395 0 P 0 ;0
L 0.7532 -1.89395 0.75358996 -1.89281998 0 P 0 ;0
L 0.75358996 -1.89281998 0.75373002 -1.89231998 0 P 0 ;0
L 0.75373002 -1.89231998 0.75383996 -1.8918 0 P 0 ;0
L 0.75383996 -1.8918 0.75391998 -1.89138996 0 P 0 ;0
L 0.75391998 -1.89138996 0.75396998 -1.89098996 0 P 0 ;0
L 0.75396998 -1.89098996 0.75396998 -1.89086004 0 P 0 ;0
L 0.75396998 -1.89086004 0.75393996 -1.89076998 0 P 0 ;0
L 0.75393996 -1.89076998 0.7539 -1.89071004 0 P 0 ;0
L 0.7539 -1.89071004 0.75386004 -1.89066998 0 P 0 ;0
L 0.75386004 -1.89066998 0.75381004 -1.89063002 0 P 0 ;0
L 0.75381004 -1.89063002 0.75378996 -1.89061004 0 P 0 ;0
L 0.75378996 -1.89061004 0.75373002 -1.89058996 0 P 0 ;0
L 0.75373002 -1.89058996 0.75368002 -1.89056998 0 P 0 ;0
L 0.75368002 -1.89056998 0.75356004 -1.89056998 0 P 0 ;0
L 0.75356004 -1.89056998 0.75346998 -1.8906 0 P 0 ;0
L 0.75346998 -1.8906 0.74898002 -1.8927 0 P 0 ;0
L 0.74898002 -1.8927 0.74383002 -1.89518002 0 P 0 ;0
L 0.74383002 -1.89518002 0.73781004 -1.8982 0 P 0 ;0
L 0.69776998 -2.22761998 0.96701004 -2.22761998 0 P 0 ;0
L 0.6957 -2.22661998 0.96968996 -2.22661998 0 P 0 ;0
L 0.69366998 -2.22561998 0.97238002 -2.22561998 0 P 0 ;0
L 0.69163002 -2.22461998 0.97506004 -2.22461998 0 P 0 ;0
L 0.68958996 -2.22361998 0.97775 -2.22361998 0 P 0 ;0
L 0.68756004 -2.22261998 0.98043002 -2.22261998 0 P 0 ;0
L 0.68551998 -2.22161998 0.98311004 -2.22161998 0 P 0 ;0
L 0.68348996 -2.22061998 0.9858 -2.22061998 0 P 0 ;0
L 0.68176998 -2.21961998 0.98848002 -2.21961998 0 P 0 ;0
L 0.68003996 -2.21861998 0.99116998 -2.21861998 0 P 0 ;0
L 0.67831004 -2.21761998 0.99385 -2.21761998 0 P 0 ;0
L 0.67658002 -2.21661998 0.99653996 -2.21661998 0 P 0 ;0
L 0.67485 -2.21561998 0.99908002 -2.21561998 0 P 0 ;0
L 0.67311998 -2.21461998 0.87665 -2.21461998 0 P 0 ;0
L 0.6714 -2.21361998 0.85166004 -2.21361998 0 P 0 ;0
L 0.6699 -2.21261998 0.84083002 -2.21261998 0 P 0 ;0
L 0.66845 -2.21161998 0.8334 -2.21161998 0 P 0 ;0
L 0.66698996 -2.21061998 0.8274 -2.21061998 0 P 0 ;0
L 0.66553002 -2.20961998 0.82138996 -2.20961998 0 P 0 ;0
L 0.66406998 -2.20861998 0.81583002 -2.20861998 0 P 0 ;0
L 0.66261998 -2.20761998 0.81143996 -2.20761998 0 P 0 ;0
L 0.66116004 -2.20661998 0.80706004 -2.20661998 0 P 0 ;0
L 0.6597 -2.20561998 0.80266998 -2.20561998 0 P 0 ;0
L 0.65841004 -2.20461998 0.79828996 -2.20461998 0 P 0 ;0
L 0.65716998 -2.20361998 0.79448996 -2.20361998 0 P 0 ;0
L 0.65593002 -2.20261998 0.79106004 -2.20261998 0 P 0 ;0
L 0.65468996 -2.20161998 0.78763996 -2.20161998 0 P 0 ;0
L 0.83143002 -2.25261998 0.80871998 -2.25225 0 P 0 ;0
L 0.80871998 -2.25225 0.78691998 -2.25066998 0 P 0 ;0
L 0.78691998 -2.25066998 0.76525 -2.24786998 0 P 0 ;0
L 0.76525 -2.24786998 0.74581998 -2.24403996 0 P 0 ;0
L 0.74581998 -2.24403996 0.72671004 -2.23876004 0 P 0 ;0
L 0.72671004 -2.23876004 0.71196004 -2.23356998 0 P 0 ;0
L 0.71196004 -2.23356998 0.69756998 -2.22753996 0 P 0 ;0
L 0.69756998 -2.22753996 0.68355 -2.22066004 0 P 0 ;0
L 0.68355 -2.22066004 0.67118002 -2.2135 0 P 0 ;0
L 0.67118002 -2.2135 0.65938996 -2.20541004 0 P 0 ;0
L 0.65938996 -2.20541004 0.64825 -2.19643996 0 P 0 ;0
L 0.64825 -2.19643996 0.63861998 -2.18731998 0 P 0 ;0
L 0.63861998 -2.18731998 0.62983002 -2.17746998 0 P 0 ;0
L 0.62983002 -2.17746998 0.62188996 -2.1669 0 P 0 ;0
L 0.62188996 -2.1669 0.61678002 -2.15886998 0 P 0 ;0
L 0.61678002 -2.15886998 0.6123 -2.15056004 0 P 0 ;0
L 0.6123 -2.15056004 0.60841998 -2.14193996 0 P 0 ;0
L 0.60841998 -2.14193996 0.60516998 -2.13306998 0 P 0 ;0
L 0.60516998 -2.13306998 0.60191004 -2.12171004 0 P 0 ;0
L 0.60191004 -2.12171004 0.60075 -2.11648002 0 P 0 ;0
L 0.60075 -2.11648002 0.59983996 -2.11121004 0 P 0 ;0
L 0.59983996 -2.11121004 0.59913996 -2.10576004 0 P 0 ;0
L 0.59913996 -2.10576004 0.59868996 -2.10026004 0 P 0 ;0
L 0.59868996 -2.10026004 0.59833002 -2.0875 0 P 0 ;0
L 0.59833002 -2.0875 0.59856998 -2.07843996 0 P 0 ;0
L 0.59856998 -2.07843996 0.59923996 -2.0695 0 P 0 ;0
L 0.59923996 -2.0695 0.60031998 -2.06153996 0 P 0 ;0
L 0.60031998 -2.06153996 0.60193002 -2.05368996 0 P 0 ;0
L 0.60193002 -2.05368996 0.60416004 -2.04566004 0 P 0 ;0
L 0.60416004 -2.04566004 0.60688996 -2.03786004 0 P 0 ;0
L 0.60688996 -2.03786004 0.6148 -2.01961004 0 P 0 ;0
L 0.6148 -2.01961004 0.62108996 -2.00753002 0 P 0 ;0
L 0.62108996 -2.00753002 0.62811998 -1.99591998 0 P 0 ;0
L 0.62811998 -1.99591998 0.63583996 -1.98478996 0 P 0 ;0
L 0.63583996 -1.98478996 0.64936998 -1.96808002 0 P 0 ;0
L 0.64936998 -1.96808002 0.66418002 -1.95256998 0 P 0 ;0
L 0.66418002 -1.95256998 0.68098002 -1.93756004 0 P 0 ;0
L 0.68098002 -1.93756004 0.69881998 -1.92398002 0 P 0 ;0
L 0.69881998 -1.92398002 0.71841998 -1.91123996 0 P 0 ;0
L 0.71841998 -1.91123996 0.73875 -1.89996998 0 P 0 ;0
L 0.73875 -1.89996998 0.74471004 -1.89696998 0 P 0 ;0
L 0.74471004 -1.89696998 0.74983002 -1.89451004 0 P 0 ;0
L 0.74983002 -1.89451004 0.7511 -1.89391004 0 P 0 ;0
L 0.7511 -1.89391004 0.75076998 -1.89488996 0 P 0 ;0
L 0.75076998 -1.89488996 0.75033996 -1.89658996 0 P 0 ;0
L 0.75033996 -1.89658996 0.75003002 -1.8983 0 P 0 ;0
L 0.75003002 -1.8983 0.74961998 -1.90161998 0 P 0 ;0
L 0.74961998 -1.90161998 0.74936004 -1.90496004 0 P 0 ;0
L 0.74936004 -1.90496004 0.74926998 -1.9085 0 P 0 ;0
L 0.74926998 -1.9085 0.74933002 -1.91201998 0 P 0 ;0
L 0.74933002 -1.91201998 0.74956004 -1.91516998 0 P 0 ;0
L 0.74956004 -1.91516998 0.75 -1.91828996 0 P 0 ;0
L 0.75 -1.91828996 0.75075 -1.92205 0 P 0 ;0
L 0.75075 -1.92205 0.75166004 -1.92573996 0 P 0 ;0
L 0.75166004 -1.92573996 0.7527 -1.92916998 0 P 0 ;0
L 0.7527 -1.92916998 0.75393996 -1.93253002 0 P 0 ;0
L 0.75393996 -1.93253002 0.75536004 -1.93581998 0 P 0 ;0
L 0.75536004 -1.93581998 0.75696004 -1.939 0 P 0 ;0
L 0.75696004 -1.939 0.75885 -1.94231004 0 P 0 ;0
L 0.75885 -1.94231004 0.76083996 -1.94543996 0 P 0 ;0
L 0.76083996 -1.94543996 0.76338996 -1.94933996 0 P 0 ;0
L 0.76338996 -1.94933996 0.76371998 -1.94991998 0 P 0 ;0
L 0.76371998 -1.94991998 0.76401004 -1.9505 0 P 0 ;0
L 0.76401004 -1.9505 0.76423996 -1.95103002 0 P 0 ;0
L 0.76423996 -1.95103002 0.76408996 -1.95111004 0 P 0 ;0
L 0.76408996 -1.95111004 0.76348996 -1.95151004 0 P 0 ;0
L 0.76348996 -1.95151004 0.76021004 -1.95386004 0 P 0 ;0
L 0.76021004 -1.95386004 0.7602 -1.95386998 0 P 0 ;0
L 0.7602 -1.95386998 0.75636998 -1.95666004 0 P 0 ;0
L 0.75636998 -1.95666004 0.75636004 -1.95666998 0 P 0 ;0
L 0.75636004 -1.95666998 0.75635 -1.95666998 0 P 0 ;0
L 0.75635 -1.95666998 0.75208996 -1.95981004 0 P 0 ;0
L 0.75208996 -1.95981004 0.73841004 -1.97066998 0 P 0 ;0
L 0.73841004 -1.97066998 0.72541004 -1.98241004 0 P 0 ;0
L 0.72541004 -1.98241004 0.7143 -1.994 0 P 0 ;0
L 0.7143 -1.994 0.71425 -1.99406004 0 P 0 ;0
L 0.71425 -1.99406004 0.70413996 -2.00648002 0 P 0 ;0
L 0.70413996 -2.00648002 0.69836998 -2.01468996 0 P 0 ;0
L 0.69836998 -2.01468996 0.69313002 -2.02318002 0 P 0 ;0
L 0.69313002 -2.02318002 0.68838996 -2.03196004 0 P 0 ;0
L 0.68838996 -2.03196004 0.68438996 -2.04063996 0 P 0 ;0
L 0.68438996 -2.04063996 0.68098996 -2.04958002 0 P 0 ;0
L 0.68098996 -2.04958002 0.6782 -2.05873002 0 P 0 ;0
L 0.6782 -2.05873002 0.67706004 -2.06366004 0 P 0 ;0
L 0.67706004 -2.06366004 0.67628996 -2.06866998 0 P 0 ;0
L 0.67628996 -2.06866998 0.67538002 -2.08068996 0 P 0 ;0
L 0.67538002 -2.08068996 0.67546004 -2.09268996 0 P 0 ;0
L 0.67546004 -2.09268996 0.67588996 -2.09766998 0 P 0 ;0
L 0.67588996 -2.09766998 0.6767 -2.10258996 0 P 0 ;0
L 0.6767 -2.10258996 0.67881998 -2.11111998 0 P 0 ;0
L 0.67881998 -2.11111998 0.68163996 -2.11936004 0 P 0 ;0
L 0.68163996 -2.11936004 0.68516004 -2.12731998 0 P 0 ;0
L 0.68516004 -2.12731998 0.68935 -2.13493996 0 P 0 ;0
L 0.68935 -2.13493996 0.69418002 -2.14216998 0 P 0 ;0
L 0.69418002 -2.14216998 0.70153002 -2.15135 0 P 0 ;0
L 0.70153002 -2.15135 0.7096 -2.15983002 0 P 0 ;0
L 0.7096 -2.15983002 0.71836004 -2.16758996 0 P 0 ;0
L 0.71836004 -2.16758996 0.71843002 -2.16763996 0 P 0 ;0
L 0.71843002 -2.16763996 0.72773996 -2.17456004 0 P 0 ;0
L 0.72773996 -2.17456004 0.73926998 -2.1818 0 P 0 ;0
L 0.73926998 -2.1818 0.75121004 -2.18818002 0 P 0 ;0
L 0.75121004 -2.18818002 0.75128002 -2.18821004 0 P 0 ;0
L 0.75128002 -2.18821004 0.76358002 -2.19368996 0 P 0 ;0
L 0.76358002 -2.19368996 0.77628002 -2.19831004 0 P 0 ;0
L 0.77628002 -2.19831004 0.79658996 -2.20423996 0 P 0 ;0
L 0.79658996 -2.20423996 0.81701004 -2.20888996 0 P 0 ;0
L 0.81701004 -2.20888996 0.83763996 -2.21233002 0 P 0 ;0
L 0.83763996 -2.21233002 0.85388002 -2.21383002 0 P 0 ;0
L 0.85388002 -2.21383002 0.87733996 -2.21465 0 P 0 ;0
L 0.87733996 -2.21465 0.90118002 -2.21478996 0 P 0 ;0
L 0.90118002 -2.21478996 0.91906004 -2.21398996 0 P 0 ;0
L 0.91906004 -2.21398996 0.94908996 -2.21068002 0 P 0 ;0
L 0.94908996 -2.21068002 0.98176998 -2.2053 0 P 0 ;0
L 0.98176998 -2.2053 1.01575 -2.19815 0 P 0 ;0
L 1.01575 -2.19815 1.04968002 -2.18943002 0 P 0 ;0
L 1.04968002 -2.18943002 1.05633996 -2.18761004 0 P 0 ;0
L 1.05633996 -2.18761004 1.05713996 -2.1874 0 P 0 ;0
L 1.05713996 -2.1874 1.05483002 -2.18875 0 P 0 ;0
L 1.05483002 -2.18875 1.04298996 -2.19526004 0 P 0 ;0
L 1.04298996 -2.19526004 1.03096998 -2.20136998 0 P 0 ;0
L 1.03096998 -2.20136998 0.99835 -2.21595 0 P 0 ;0
L 0.99835 -2.21595 0.96401998 -2.22873996 0 P 0 ;0
L 0.96401998 -2.22873996 0.92993996 -2.23908002 0 P 0 ;0
L 0.92993996 -2.23908002 0.89816004 -2.24626004 0 P 0 ;0
L 0.89816004 -2.24626004 0.87616004 -2.24965 0 P 0 ;0
L 0.87616004 -2.24965 0.85405 -2.25176004 0 P 0 ;0
L 0.85405 -2.25176004 0.83143002 -2.25261998 0 P 0 ;0
L 0.65345 -2.20061998 0.78421004 -2.20061998 0 P 0 ;0
L 0.65221004 -2.19961998 0.78078002 -2.19961998 0 P 0 ;0
L 0.65096004 -2.19861998 0.77735 -2.19861998 0 P 0 ;0
L 0.64971998 -2.19761998 0.77438996 -2.19761998 0 P 0 ;0
L 0.64848002 -2.19661998 0.77163996 -2.19661998 0 P 0 ;0
L 0.64738996 -2.19561998 0.76888996 -2.19561998 0 P 0 ;0
L 0.64633996 -2.19461998 0.76613996 -2.19461998 0 P 0 ;0
L 0.64528002 -2.19361998 0.76343002 -2.19361998 0 P 0 ;0
L 0.64421998 -2.19261998 0.76118996 -2.19261998 0 P 0 ;0
L 0.64316998 -2.19161998 0.75893996 -2.19161998 0 P 0 ;0
L 0.64211004 -2.19061998 0.7567 -2.19061998 0 P 0 ;0
L 0.64106004 -2.18961998 0.75446004 -2.18961998 0 P 0 ;0
L 0.64 -2.18861998 0.75221004 -2.18861998 0 P 0 ;0
L 0.63895 -2.18761998 0.75018002 -2.18761998 0 P 0 ;0
L 0.63801004 -2.18661998 0.74831004 -2.18661998 0 P 0 ;0
L 0.63711004 -2.18561998 0.74643002 -2.18561998 0 P 0 ;0
L 0.63621998 -2.18461998 0.74456004 -2.18461998 0 P 0 ;0
L 0.63533002 -2.18361998 0.74268002 -2.18361998 0 P 0 ;0
L 0.63443996 -2.18261998 0.74081004 -2.18261998 0 P 0 ;0
L 0.63353996 -2.18161998 0.73898996 -2.18161998 0 P 0 ;0
L 0.63265 -2.18061998 0.73738996 -2.18061998 0 P 0 ;0
L 0.63176004 -2.17961998 0.7358 -2.17961998 0 P 0 ;0
L 0.63086998 -2.17861998 0.73421004 -2.17861998 0 P 0 ;0
L 0.62996998 -2.17761998 0.73261998 -2.17761998 0 P 0 ;0
L 0.6292 -2.17661998 0.73103002 -2.17661998 0 P 0 ;0
L 0.62845 -2.17561998 0.72943996 -2.17561998 0 P 0 ;0
L 0.6277 -2.17461998 0.72783996 -2.17461998 0 P 0 ;0
L 0.62693996 -2.17361998 0.72648002 -2.17361998 0 P 0 ;0
L 0.62618996 -2.17261998 0.72513996 -2.17261998 0 P 0 ;0
L 0.62543996 -2.17161998 0.72378996 -2.17161998 0 P 0 ;0
L 0.62468996 -2.17061998 0.72245 -2.17061998 0 P 0 ;0
L 0.62393996 -2.16961998 0.7211 -2.16961998 0 P 0 ;0
L 0.62318002 -2.16861998 0.71976004 -2.16861998 0 P 0 ;0
L 0.62243996 -2.16761998 0.71841004 -2.16761998 0 P 0 ;0
L 0.62171004 -2.16661998 0.71726998 -2.16661998 0 P 0 ;0
L 0.62108002 -2.16561998 0.71613996 -2.16561998 0 P 0 ;0
L 0.62043996 -2.16461998 0.71501004 -2.16461998 0 P 0 ;0
L 0.61981004 -2.16361998 0.71388002 -2.16361998 0 P 0 ;0
L 0.61916998 -2.16261998 0.71276004 -2.16261998 0 P 0 ;0
L 0.61853002 -2.16161998 0.71163002 -2.16161998 0 P 0 ;0
L 0.6179 -2.16061998 0.7105 -2.16061998 0 P 0 ;0
L 0.61726004 -2.15961998 0.7094 -2.15961998 0 P 0 ;0
L 0.61665 -2.15861998 0.70845 -2.15861998 0 P 0 ;0
L 0.61611004 -2.15761998 0.7075 -2.15761998 0 P 0 ;0
L 0.75383996 -2.24561998 0.901 -2.24561998 0 P 0 ;0
L 0.74876998 -2.24461998 0.90541998 -2.24461998 0 P 0 ;0
L 0.74431004 -2.24361998 0.90985 -2.24361998 0 P 0 ;0
L 0.7407 -2.24261998 0.91426998 -2.24261998 0 P 0 ;0
L 0.73708002 -2.24161998 0.9187 -2.24161998 0 P 0 ;0
L 0.73346998 -2.24061998 0.92311998 -2.24061998 0 P 0 ;0
L 0.72986004 -2.23961998 0.92753996 -2.23961998 0 P 0 ;0
L 0.72633996 -2.23861998 0.93145 -2.23861998 0 P 0 ;0
L 0.72348996 -2.23761998 0.93473996 -2.23761998 0 P 0 ;0
L 0.72063996 -2.23661998 0.93803996 -2.23661998 0 P 0 ;0
L 0.7178 -2.23561998 0.94133002 -2.23561998 0 P 0 ;0
L 0.71495 -2.23461998 0.94461998 -2.23461998 0 P 0 ;0
L 0.7121 -2.23361998 0.94791998 -2.23361998 0 P 0 ;0
L 0.70968996 -2.23261998 0.95121004 -2.23261998 0 P 0 ;0
L 0.70731004 -2.23161998 0.95451004 -2.23161998 0 P 0 ;0
L 0.70491998 -2.23061998 0.9578 -2.23061998 0 P 0 ;0
L 0.70253996 -2.22961998 0.9611 -2.22961998 0 P 0 ;0
L 0.70015 -2.22861998 0.96431998 -2.22861998 0 P 0 ;0
L 8.45 3.66615 8.45 3.71615 6 P 0 
L 8.5 3.76615 8.5 3.81615 6 P 0 
L 8.45 3.81615 8.45 3.86615 6 P 0 
L 8.5 3.46615 8.5 3.51615 6 P 0 
L 8.45 3.41615 8.45 3.46615 6 P 0 
L 8.5 3.61615 8.5 3.66615 6 P 0 
L 8.45 3.26615 8.45 3.31615 6 P 0 
L 8.5 3.31615 8.5 3.36615 6 P 0 
L 8.2 3.66615 8.2 3.71615 6 P 0 
L 8.35 3.66615 8.35 3.71615 6 P 0 
L 8.4 3.76615 8.4 3.81615 6 P 0 
L 8.35 3.81615 8.35 3.86615 6 P 0 
L 8.2 3.81615 8.2 3.86615 6 P 0 
L 8.4 3.46615 8.4 3.51615 6 P 0 
L 8.35 3.41615 8.35 3.46615 6 P 0 
L 8.2 3.41615 8.2 3.46615 6 P 0 
L 8.4 3.61615 8.4 3.66615 6 P 0 
L 8.35 3.26615 8.35 3.31615 6 P 0 
L 8.4 3.31615 8.4 3.36615 6 P 0 
L 8.2 3.26615 8.2 3.31615 6 P 0 
L 8.25 2.86615 8.3 2.86615 6 P 0 
L 8.1 3.66615 8.1 3.71615 6 P 0 
L 8.15 3.76615 8.15 3.81615 6 P 0 
L 8.1 3.81615 8.1 3.86615 6 P 0 
L 8.05 3.76615 8.05 3.81615 6 P 0 
L 8.1 3.41615 8.1 3.46615 6 P 0 
L 8.15 3.46615 8.15 3.51615 6 P 0 
L 8 3.46615 8 3.51615 6 P 0 
L 8.05 3.61615 8.05 3.66615 6 P 0 
L 8.15 3.61615 8.15 3.66615 6 P 0 
L 8.1 3.26615 8.1 3.31615 6 P 0 
L 8.15 3.31615 8.15 3.36615 6 P 0 
L 8.05 3.31615 8.05 3.36615 6 P 0 
L 5.42048002 1.91835 5.42048002 1.87835 6 P 0 
L 5.57531004 1.8508 5.57531004 1.8108 6 P 0 
L 2.34606004 3.26615 2.34606004 3.31615 6 P 0 
L 2.39606004 3.31615 2.39606004 3.36615 6 P 0 
L 2.44606004 3.26615 2.44606004 3.31615 6 P 0 
L 2.49606004 3.31615 2.49606004 3.36615 6 P 0 
L 2.49606004 3.46615 2.49606004 3.51615 6 P 0 
L 2.44606004 3.41615 2.44606004 3.46615 6 P 0 
L 2.39606004 3.46615 2.39606004 3.51615 6 P 0 
L 2.34606004 3.41615 2.34606004 3.46615 6 P 0 
L 2.19606004 3.26615 2.19606004 3.31615 6 P 0 
L 2.09606004 3.26615 2.09606004 3.31615 6 P 0 
L 2.14606004 3.31615 2.14606004 3.36615 6 P 0 
L 2.19606004 3.41615 2.19606004 3.46615 6 P 0 
L 2.09606004 3.41615 2.09606004 3.46615 6 P 0 
L 2.04606004 3.31615 2.04606004 3.36615 6 P 0 
L 2.14606004 3.46615 2.14606004 3.51615 6 P 0 
L 1.99606004 3.46615 1.99606004 3.51615 6 P 0 
L 2.04606004 3.61615 2.04606004 3.66615 6 P 0 
L 2.09606004 3.66615 2.09606004 3.71615 6 P 0 
L 2.14606004 3.61615 2.14606004 3.66615 6 P 0 
L 2.19606004 3.66615 2.19606004 3.71615 6 P 0 
L 2.49606004 3.61615 2.49606004 3.66615 6 P 0 
L 2.34606004 3.66615 2.34606004 3.71615 6 P 0 
L 2.39606004 3.61615 2.39606004 3.66615 6 P 0 
L 2.44606004 3.66615 2.44606004 3.71615 6 P 0 
L 2.49606004 3.76615 2.49606004 3.81615 6 P 0 
L 2.44606004 3.81615 2.44606004 3.86615 6 P 0 
L 2.39606004 3.76615 2.39606004 3.81615 6 P 0 
L 2.34606004 3.81615 2.34606004 3.86615 6 P 0 
L 2.14606004 3.76615 2.14606004 3.81615 6 P 0 
L 2.19606004 3.81615 2.19606004 3.86615 6 P 0 
L 2.09606004 3.81615 2.09606004 3.86615 6 P 0 
L 2.04606004 3.76615 2.04606004 3.81615 6 P 0 
L 2.24606004 2.86615 2.29606004 2.86615 6 P 0 
L 5.42048002 1.6433 5.42048002 1.6033 6 P 0 
L 5.57531004 1.7118 5.57531004 1.6718 6 P 0 
L 5.42048002 1.7796 5.42048002 1.7396 6 P 0 
L 5.57531004 1.9869 5.57531004 1.9469 6 P 0 
L 5.42048002 2.0547 5.42048002 2.0147 6 P 0 
L 5.57531004 2.1278 5.57531004 2.0878 6 P 0 
L 5.42048002 2.1954 5.42048002 2.1554 6 P 0 
L 5.57531004 2.2632 5.57531004 2.2232 6 P 0 
L 5.42048002 2.3308 5.42048002 2.2908 6 P 0 
L 5.57531004 2.3986 5.57531004 2.3586 6 P 0 
L 5.42048002 2.4662 5.42048002 2.4262 6 P 0 
L 5.57531004 2.5378 5.57531004 2.4978 6 P 0 
L 5.57531004 2.673 5.57531004 2.633 6 P 0 
L 5.42048002 2.6054 5.42048002 2.5654 6 P 0 
L 10.09 2.73655 10.09 2.69655 6 P 0 
L 9.975 2.66445 9.975 2.62445 6 P 0 
L 9.975 2.5109 9.975 2.4709 6 P 0 
L 10.09 2.57845 10.09 2.53845 6 P 0 
L 10.09 2.44335 10.09 2.40335 6 P 0 
L 9.975 2.3758 9.975 2.3358 6 P 0 
L 10.09 2.30825 10.09 2.26825 6 P 0 
L 9.975 2.23955 9.975 2.19955 6 P 0 
L 10.09 2.17095 10.09 2.13095 6 P 0 
L 10.09 2.05655 10.09 2.01655 6 P 0 
L 10.225 1.96645 10.225 1.92645 6 P 0 
L 10.26025 1.86845 10.26025 1.82845 6 P 0 
L 10.26 1.70445 10.26 1.66445 6 P 0 
L 10.35543996 1.52156004 10.38371998 1.49328002 7 P 0 
L 10.46445 1.395 10.42445 1.395 6 P 0 
L 10.395 1.28555 10.395 1.32555 6 P 0 
L 11.53316004 1.412 11.53316004 1.452 6 P 0 
L 11.73316004 1.492 11.73316004 1.532 6 P 0 
L 11.53316004 1.572 11.53316004 1.612 6 P 0 
L 11.78316004 1.652 11.78316004 1.692 6 P 0 
L 11.53316004 1.732 11.53316004 1.772 6 P 0 
L 11.73316004 1.812 11.73316004 1.852 6 P 0 
L 11.53316004 1.892 11.53316004 1.932 6 P 0 
L 11.53316004 2.052 11.53316004 2.092 6 P 0 
L 11.73316004 1.972 11.73316004 2.012 6 P 0 
L 11.73316004 2.132 11.73316004 2.172 6 P 0 
L 11.83316004 2.212 11.83316004 2.252 6 P 0 
L 11.73316004 2.292 11.73316004 2.332 6 P 0 
L 11.53316004 2.372 11.53316004 2.412 6 P 0 
L 11.53316004 2.532 11.53316004 2.572 6 P 0 
L 11.73316004 2.452 11.73316004 2.492 6 P 0 
L 11.73316004 2.612 11.73316004 2.652 6 P 0 
L 8.98115 2.825 8.98115 2.865 6 P 0 
L 2.97721004 2.825 2.97721004 2.865 6 P 0 
L 11.03661004 2.46615 11.03661004 2.51615 6 P 0 
L 11.08661004 2.21615 11.08661004 2.26615 6 P 0 
L 10.98661004 2.21615 10.98661004 2.26615 6 P 0 
L 11.03661004 2.26615 11.03661004 2.31615 6 P 0 
L 10.93661004 2.26615 10.93661004 2.31615 6 P 0 
L 10.98661004 2.36615 10.98661004 2.41615 6 P 0 
L 10.93661004 2.41615 10.93661004 2.46615 6 P 0 
L 11.08661004 2.36615 11.08661004 2.41615 6 P 0 
L 10.93661004 2.01615 10.93661004 2.06615 6 P 0 
L 10.98661004 2.06615 10.98661004 2.11615 6 P 0 
L 11.03661004 2.01615 11.03661004 2.06615 6 P 0 
L 11.08661004 2.06615 11.08661004 2.11615 6 P 0 
L 10.93661004 1.86615 10.93661004 1.91615 6 P 0 
L 11.03661004 1.86615 11.03661004 1.91615 6 P 0 
L 10.98661004 1.91615 10.98661004 1.96615 6 P 0 
L 11.08661004 1.91615 11.08661004 1.96615 6 P 0 
L 10.73661004 2.46615 10.73661004 2.41615 6 P 0 
L 10.68661004 2.41615 10.68661004 2.36615 6 P 0 
L 10.68661004 2.26615 10.68661004 2.21615 6 P 0 
L 10.73661004 2.31615 10.73661004 2.26615 6 P 0 
L 10.68661004 2.11615 10.68661004 2.06615 6 P 0 
L 10.83661004 2.16615 10.88661004 2.16615 6 P 0 
L 10.73661004 2.01615 10.73661004 2.06615 6 P 0 
L 10.68661004 1.91615 10.68661004 1.96615 6 P 0 
L 10.73661004 1.86615 10.73661004 1.91615 6 P 0 
L 10.63661004 2.46615 10.63661004 2.41615 6 P 0 
L 10.58661004 2.41615 10.58661004 2.36615 6 P 0 
L 10.63661004 2.31615 10.63661004 2.26615 6 P 0 
L 10.58661004 2.26615 10.58661004 2.21615 6 P 0 
L 10.58661004 2.11615 10.58661004 2.06615 6 P 0 
L 10.63661004 2.01615 10.63661004 2.06615 6 P 0 
L 10.58661004 1.91615 10.58661004 1.96615 6 P 0 
L 10.63661004 1.86615 10.63661004 1.91615 6 P 0 
L 0.69348996 1.86611998 0.69348996 1.90611998 6 P 0 
L 5.03268002 2.46615 5.03268002 2.51615 6 P 0 
L 5.08268002 2.36615 5.08268002 2.41615 6 P 0 
L 4.93268002 2.41615 4.93268002 2.46615 6 P 0 
L 4.98268002 2.36615 4.98268002 2.41615 6 P 0 
L 4.93268002 2.26615 4.93268002 2.31615 6 P 0 
L 5.03268002 2.26615 5.03268002 2.31615 6 P 0 
L 4.98268002 2.21615 4.98268002 2.26615 6 P 0 
L 5.08268002 2.21615 5.08268002 2.26615 6 P 0 
L 5.08268002 2.06615 5.08268002 2.11615 6 P 0 
L 5.03268002 2.01615 5.03268002 2.06615 6 P 0 
L 4.98268002 2.06615 4.98268002 2.11615 6 P 0 
L 4.93268002 2.01615 4.93268002 2.06615 6 P 0 
L 5.08268002 1.91615 5.08268002 1.96615 6 P 0 
L 4.98268002 1.91615 4.98268002 1.96615 6 P 0 
L 5.03268002 1.86615 5.03268002 1.91615 6 P 0 
L 4.93268002 1.86615 4.93268002 1.91615 6 P 0 
L 4.73268002 1.86615 4.73268002 1.91615 6 P 0 
L 4.63268002 1.86615 4.63268002 1.91615 6 P 0 
L 4.68268002 1.91615 4.68268002 1.96615 6 P 0 
L 4.58268002 1.91615 4.58268002 1.96615 6 P 0 
L 4.63268002 2.01615 4.63268002 2.06615 6 P 0 
L 4.73268002 2.01615 4.73268002 2.06615 6 P 0 
L 4.83268002 2.16615 4.88268002 2.16615 6 P 0 
L 4.58268002 2.11615 4.58268002 2.06615 6 P 0 
L 4.68268002 2.11615 4.68268002 2.06615 6 P 0 
L 4.73268002 2.31615 4.73268002 2.26615 6 P 0 
L 4.68268002 2.26615 4.68268002 2.21615 6 P 0 
L 4.58268002 2.26615 4.58268002 2.21615 6 P 0 
L 4.63268002 2.31615 4.63268002 2.26615 6 P 0 
L 4.58268002 2.41615 4.58268002 2.36615 6 P 0 
L 4.68268002 2.41615 4.68268002 2.36615 6 P 0 
L 4.63268002 2.46615 4.63268002 2.41615 6 P 0 
L 4.73268002 2.46615 4.73268002 2.41615 6 P 0 
A 12.75476004 4.52361998 12.75476004 4.52361998 12.73621004 4.52361998 3 P 0 N
A 12.8335 4.48425 12.8335 4.48425 12.81495 4.48425 3 P 0 N
L 12.73621004 4.52361998 12.81495 4.48425 9 P 0 
L 12.73621004 4.36613996 12.81495 4.32676998 9 P 0 
A 12.8335 4.32676998 12.8335 4.32676998 12.81495 4.32676998 3 P 0 N
A 12.75476004 4.36613996 12.75476004 4.36613996 12.73621004 4.36613996 3 P 0 N
L 12.73621004 4.20866004 12.81495 4.16928996 9 P 0 
A 12.8335 4.16928996 12.8335 4.16928996 12.81495 4.16928996 3 P 0 N
A 12.75476004 4.20866004 12.75476004 4.20866004 12.73621004 4.20866004 3 P 0 N
L 12.73621004 4.05118002 12.81495 4.01181004 9 P 0 
A 12.8335 4.01181004 12.8335 4.01181004 12.81495 4.01181004 3 P 0 N
A 12.75476004 4.05118002 12.75476004 4.05118002 12.73621004 4.05118002 3 P 0 N
L 12.73621004 3.8937 12.81495 3.85433002 9 P 0 
A 12.8335 3.85433002 12.8335 3.85433002 12.81495 3.85433002 3 P 0 N
A 12.75476004 3.8937 12.75476004 3.8937 12.73621004 3.8937 3 P 0 N
A 12.75476004 3.73621998 12.75476004 3.73621998 12.73621004 3.73621998 3 P 0 N
L 12.73621004 3.73621998 12.81495 3.69685 9 P 0 
A 12.8335 3.69685 12.8335 3.69685 12.81495 3.69685 3 P 0 N
L 12.73621004 3.57873996 12.81495 3.53936998 9 P 0 
A 12.8335 3.53936998 12.8335 3.53936998 12.81495 3.53936998 3 P 0 N
A 12.75476004 3.57873996 12.75476004 3.57873996 12.73621004 3.57873996 3 P 0 N
L 12.73621004 3.42126004 12.81495 3.38188996 9 P 0 
A 12.8335 3.38188996 12.8335 3.38188996 12.81495 3.38188996 3 P 0 N
A 12.75476004 3.42126004 12.75476004 3.42126004 12.73621004 3.42126004 3 P 0 N
A 12.8335 3.22441004 12.8335 3.22441004 12.81495 3.22441004 3 P 0 N
L 12.73621004 3.02756004 12.81495 3.06693002 9 P 0 
A 12.8335 3.06693002 12.8335 3.06693002 12.81495 3.06693002 3 P 0 N
A 12.75476004 3.02756004 12.75476004 3.02756004 12.73621004 3.02756004 3 P 0 N
L 12.73621004 3.18503996 12.81495 3.22441004 9 P 0 
A 12.75476004 3.18503996 12.75476004 3.18503996 12.73621004 3.18503996 3 P 0 N
A 12.8335 2.75196998 12.8335 2.75196998 12.81495 2.75196998 3 P 0 N
L 12.73621004 2.87008002 12.81495 2.90945 9 P 0 
A 12.8335 2.90945 12.8335 2.90945 12.81495 2.90945 3 P 0 N
A 12.75476004 2.87008002 12.75476004 2.87008002 12.73621004 2.87008002 3 P 0 N
A 12.8335 2.51575 12.8335 2.51575 12.81495 2.51575 3 P 0 N
A 12.75476004 2.47638002 12.75476004 2.47638002 12.73621004 2.47638002 3 P 0 N
L 12.73621004 2.7126 12.81495 2.75196998 9 P 0 
A 12.75476004 2.7126 12.75476004 2.7126 12.73621004 2.7126 3 P 0 N
L 12.73621004 2.3189 12.81495 2.35826998 9 P 0 
A 12.8335 2.35826998 12.8335 2.35826998 12.81495 2.35826998 3 P 0 N
A 12.75476004 2.3189 12.75476004 2.3189 12.73621004 2.3189 3 P 0 N
L 12.73621004 2.47638002 12.81495 2.51575 9 P 0 
A 12.75476004 2.00393996 12.75476004 2.00393996 12.73621004 2.00393996 3 P 0 N
L 12.73621004 2.16141998 12.81495 2.20078996 9 P 0 
A 12.8335 2.20078996 12.8335 2.20078996 12.81495 2.20078996 3 P 0 N
A 12.75476004 2.16141998 12.75476004 2.16141998 12.73621004 2.16141998 3 P 0 N
L 12.73621004 2.00393996 12.81495 1.96456998 9 P 0 
A 12.8335 1.96456998 12.8335 1.96456998 12.81495 1.96456998 3 P 0 N
L 12.55905 4.563 12.63778996 4.60236998 9 P 0 
A 12.65633996 4.60236998 12.65633996 4.60236998 12.63778996 4.60236998 3 P 0 N
A 12.5776 4.563 12.5776 4.563 12.55905 4.563 3 P 0 N
L 12.55905 4.24803002 12.63778996 4.2874 9 P 0 
A 12.65633996 4.2874 12.65633996 4.2874 12.63778996 4.2874 3 P 0 N
A 12.5776 4.24803002 12.5776 4.24803002 12.55905 4.24803002 3 P 0 N
L 12.55905 4.40551004 12.63778996 4.44488002 9 P 0 
A 12.65633996 4.44488002 12.65633996 4.44488002 12.63778996 4.44488002 3 P 0 N
A 12.5776 4.40551004 12.5776 4.40551004 12.55905 4.40551004 3 P 0 N
A 12.65633996 3.97243996 12.65633996 3.97243996 12.63778996 3.97243996 3 P 0 N
L 12.55905 4.09055 12.63778996 4.12991998 9 P 0 
A 12.65633996 4.12991998 12.65633996 4.12991998 12.63778996 4.12991998 3 P 0 N
A 12.5776 4.09055 12.5776 4.09055 12.55905 4.09055 3 P 0 N
L 12.55905 3.77558996 12.63778996 3.81496004 9 P 0 
A 12.65633996 3.81496004 12.65633996 3.81496004 12.63778996 3.81496004 3 P 0 N
A 12.5776 3.77558996 12.5776 3.77558996 12.55905 3.77558996 3 P 0 N
L 12.55905 3.93306998 12.63778996 3.97243996 9 P 0 
A 12.5776 3.93306998 12.5776 3.93306998 12.55905 3.93306998 3 P 0 N
A 12.65633996 3.5 12.65633996 3.5 12.63778996 3.5 3 P 0 N
L 12.55905 3.61811004 12.63778996 3.65748002 9 P 0 
A 12.65633996 3.65748002 12.65633996 3.65748002 12.63778996 3.65748002 3 P 0 N
A 12.5776 3.61811004 12.5776 3.61811004 12.55905 3.61811004 3 P 0 N
L 12.55905 3.30315 12.63778996 3.26378002 9 P 0 
A 12.65633996 3.26378002 12.65633996 3.26378002 12.63778996 3.26378002 3 P 0 N
A 12.5776 3.30315 12.5776 3.30315 12.55905 3.30315 3 P 0 N
L 12.55905 3.46063002 12.63778996 3.5 9 P 0 
A 12.5776 3.46063002 12.5776 3.46063002 12.55905 3.46063002 3 P 0 N
L 12.55905 3.14566998 12.63778996 3.1063 9 P 0 
A 12.65633996 3.1063 12.65633996 3.1063 12.63778996 3.1063 3 P 0 N
A 12.5776 3.14566998 12.5776 3.14566998 12.55905 3.14566998 3 P 0 N
A 12.5776 2.98818996 12.5776 2.98818996 12.55905 2.98818996 3 P 0 N
L 12.55905 2.98818996 12.63778996 2.94881998 9 P 0 
A 12.65633996 2.94881998 12.65633996 2.94881998 12.63778996 2.94881998 3 P 0 N
L 12.55905 2.83071004 12.63778996 2.79133996 9 P 0 
A 12.65633996 2.79133996 12.65633996 2.79133996 12.63778996 2.79133996 3 P 0 N
A 12.5776 2.83071004 12.5776 2.83071004 12.55905 2.83071004 3 P 0 N
L 12.55905 2.59448996 12.63778996 2.55511998 9 P 0 
A 12.65633996 2.55511998 12.65633996 2.55511998 12.63778996 2.55511998 3 P 0 N
A 12.5776 2.59448996 12.5776 2.59448996 12.55905 2.59448996 3 P 0 N
L 12.55905 2.43701004 12.63778996 2.39763996 9 P 0 
A 12.65633996 2.39763996 12.65633996 2.39763996 12.63778996 2.39763996 3 P 0 N
A 12.5776 2.43701004 12.5776 2.43701004 12.55905 2.43701004 3 P 0 N
L 12.55905 2.27953002 12.63778996 2.24016004 9 P 0 
A 12.65633996 2.24016004 12.65633996 2.24016004 12.63778996 2.24016004 3 P 0 N
A 12.5776 2.27953002 12.5776 2.27953002 12.55905 2.27953002 3 P 0 N
A 12.5776 2.04331004 12.5776 2.04331004 12.55905 2.04331004 3 P 0 N
A 12.65633996 2.08268002 12.65633996 2.08268002 12.63778996 2.08268002 3 P 0 N
L 12.55905 2.04331004 12.63778996 2.08268002 9 P 0 
L 12.55905 1.96456998 12.63778996 1.9252 9 P 0 
A 12.65633996 1.9252 12.65633996 1.9252 12.63778996 1.9252 3 P 0 N
A 12.5776 1.96456998 12.5776 1.96456998 12.55905 1.96456998 3 P 0 N
A 0.11303996 4.52363002 0.11303996 4.52363002 0.09448996 4.52363002 3 P 0 N
A 0.19178002 4.563 0.19178002 4.563 0.17323002 4.563 3 P 0 N
L 0.09448996 4.52363002 0.17323002 4.563 9 P 0 
A 0.11303996 4.36613996 0.11303996 4.36613996 0.09448996 4.36613996 3 P 0 N
A 0.19178002 4.40551004 0.19178002 4.40551004 0.17323002 4.40551004 3 P 0 N
L 0.09448996 4.36613996 0.17323002 4.40551004 9 P 0 
A 0.11303996 4.20866004 0.11303996 4.20866004 0.09448996 4.20866004 3 P 0 N
A 0.19178002 4.24803002 0.19178002 4.24803002 0.17323002 4.24803002 3 P 0 N
L 0.09448996 4.20866004 0.17323002 4.24803002 9 P 0 
A 0.11303996 4.05118002 0.11303996 4.05118002 0.09448996 4.05118002 3 P 0 N
A 0.19178002 4.09055 0.19178002 4.09055 0.17323002 4.09055 3 P 0 N
L 0.09448996 4.05118002 0.17323002 4.09055 9 P 0 
A 0.11303996 3.8937 0.11303996 3.8937 0.09448996 3.8937 3 P 0 N
A 0.19178002 3.93306998 0.19178002 3.93306998 0.17323002 3.93306998 3 P 0 N
L 0.09448996 3.8937 0.17323002 3.93306998 9 P 0 
A 0.11303996 3.73621998 0.11303996 3.73621998 0.09448996 3.73621998 3 P 0 N
A 0.19178002 3.77558996 0.19178002 3.77558996 0.17323002 3.77558996 3 P 0 N
L 0.09448996 3.73621998 0.17323002 3.77558996 9 P 0 
A 0.11303996 3.57873996 0.11303996 3.57873996 0.09448996 3.57873996 3 P 0 N
A 0.19178002 3.61811004 0.19178002 3.61811004 0.17323002 3.61811004 3 P 0 N
L 0.09448996 3.57873996 0.17323002 3.61811004 9 P 0 
A 0.11303996 3.42126004 0.11303996 3.42126004 0.09448996 3.42126004 3 P 0 N
A 0.19178002 3.46063002 0.19178002 3.46063002 0.17323002 3.46063002 3 P 0 N
L 0.09448996 3.42126004 0.17323002 3.46063002 9 P 0 
A 0.2902 3.14566998 0.2902 3.14566998 0.27165 3.14566998 3 P 0 N
A 0.36893996 3.18503996 0.36893996 3.18503996 0.35038996 3.18503996 3 P 0 N
L 0.27165 3.14566998 0.35038996 3.18503996 9 P 0 
A 0.2902 2.98818996 0.2902 2.98818996 0.27165 2.98818996 3 P 0 N
A 0.36893996 3.02756004 0.36893996 3.02756004 0.35038996 3.02756004 3 P 0 N
L 0.27165 2.98818996 0.35038996 3.02756004 9 P 0 
A 0.2902 2.83071004 0.2902 2.83071004 0.27165 2.83071004 3 P 0 N
A 0.36893996 2.87008002 0.36893996 2.87008002 0.35038996 2.87008002 3 P 0 N
L 0.27165 2.83071004 0.35038996 2.87008002 9 P 0 
A 0.2902 2.67323002 0.2902 2.67323002 0.27165 2.67323002 3 P 0 N
A 0.36893996 2.7126 0.36893996 2.7126 0.35038996 2.7126 3 P 0 N
L 0.27165 2.67323002 0.35038996 2.7126 9 P 0 
A 0.2902 2.43701004 0.2902 2.43701004 0.27165 2.43701004 3 P 0 N
A 0.36893996 2.47638002 0.36893996 2.47638002 0.35038996 2.47638002 3 P 0 N
L 0.27165 2.43701004 0.35038996 2.47638002 9 P 0 
A 0.2902 2.27953002 0.2902 2.27953002 0.27165 2.27953002 3 P 0 N
A 0.36893996 2.3189 0.36893996 2.3189 0.35038996 2.3189 3 P 0 N
L 0.27165 2.27953002 0.35038996 2.3189 9 P 0 
A 0.2902 2.12205 0.2902 2.12205 0.27165 2.12205 3 P 0 N
A 0.36893996 2.16141998 0.36893996 2.16141998 0.35038996 2.16141998 3 P 0 N
L 0.27165 2.12205 0.35038996 2.16141998 9 P 0 
L 0.09448996 2.00393996 0.17323002 2.04331004 9 P 0 
A 0.19178002 2.04331004 0.19178002 2.04331004 0.17323002 2.04331004 3 P 0 N
A 0.11303996 2.00393996 0.11303996 2.00393996 0.09448996 2.00393996 3 P 0 N
A 0.2902 1.96456998 0.2902 1.96456998 0.27165 1.96456998 3 P 0 N
A 0.36893996 1.9252 0.36893996 1.9252 0.35038996 1.9252 3 P 0 N
L 0.27165 1.96456998 0.35038996 1.9252 8 P 0 
A 0.11303996 1.9252 0.11303996 1.9252 0.09448996 1.9252 3 P 0 N
A 0.19178002 1.88583002 0.19178002 1.88583002 0.17323002 1.88583002 3 P 0 N
L 0.09448996 1.9252 0.17323002 1.88583002 9 P 0 
A 0.11303996 2.24016004 0.11303996 2.24016004 0.09448996 2.24016004 3 P 0 N
A 0.19178002 2.20078996 0.19178002 2.20078996 0.17323002 2.20078996 3 P 0 N
L 0.09448996 2.24016004 0.17323002 2.20078996 9 P 0 
A 0.11303996 2.39763996 0.11303996 2.39763996 0.09448996 2.39763996 3 P 0 N
A 0.19178002 2.35826998 0.19178002 2.35826998 0.17323002 2.35826998 3 P 0 N
L 0.09448996 2.39763996 0.17323002 2.35826998 9 P 0 
A 0.11303996 2.55511998 0.11303996 2.55511998 0.09448996 2.55511998 3 P 0 N
A 0.19178002 2.51575 0.19178002 2.51575 0.17323002 2.51575 3 P 0 N
L 0.09448996 2.55511998 0.17323002 2.51575 9 P 0 
A 0.11303996 2.79133996 0.11303996 2.79133996 0.09448996 2.79133996 3 P 0 N
A 0.19178002 2.75196998 0.19178002 2.75196998 0.17323002 2.75196998 3 P 0 N
L 0.09448996 2.79133996 0.17323002 2.75196998 9 P 0 
A 0.11303996 2.94881998 0.11303996 2.94881998 0.09448996 2.94881998 3 P 0 N
A 0.19178002 2.90945 0.19178002 2.90945 0.17323002 2.90945 3 P 0 N
L 0.09448996 2.94881998 0.17323002 2.90945 9 P 0 
A 0.11303996 3.1063 0.11303996 3.1063 0.09448996 3.1063 3 P 0 N
A 0.19178002 3.06693002 0.19178002 3.06693002 0.17323002 3.06693002 3 P 0 N
L 0.09448996 3.1063 0.17323002 3.06693002 9 P 0 
A 0.11303996 3.26378002 0.11303996 3.26378002 0.09448996 3.26378002 3 P 0 N
A 0.19178002 3.22441004 0.19178002 3.22441004 0.17323002 3.22441004 3 P 0 N
L 0.09448996 3.26378002 0.17323002 3.22441004 9 P 0 
A 0.2902 3.38188996 0.2902 3.38188996 0.27165 3.38188996 3 P 0 N
A 0.36893996 3.34251998 0.36893996 3.34251998 0.35038996 3.34251998 3 P 0 N
L 0.27165 3.38188996 0.35038996 3.34251998 9 P 0 
A 0.2902 3.53936998 0.2902 3.53936998 0.27165 3.53936998 3 P 0 N
A 0.36893996 3.5 0.36893996 3.5 0.35038996 3.5 3 P 0 N
L 0.27165 3.53936998 0.35038996 3.5 9 P 0 
A 0.2902 3.69685 0.2902 3.69685 0.27165 3.69685 3 P 0 N
A 0.36893996 3.65748002 0.36893996 3.65748002 0.35038996 3.65748002 3 P 0 N
L 0.27165 3.69685 0.35038996 3.65748002 9 P 0 
A 0.2902 3.85433002 0.2902 3.85433002 0.27165 3.85433002 3 P 0 N
A 0.36893996 3.81496004 0.36893996 3.81496004 0.35038996 3.81496004 3 P 0 N
L 0.27165 3.85433002 0.35038996 3.81496004 9 P 0 
A 0.2902 4.01181004 0.2902 4.01181004 0.27165 4.01181004 3 P 0 N
A 0.36893996 3.97243996 0.36893996 3.97243996 0.35038996 3.97243996 3 P 0 N
L 0.27165 4.01181004 0.35038996 3.97243996 9 P 0 
A 0.2902 4.16928996 0.2902 4.16928996 0.27165 4.16928996 3 P 0 N
A 0.36893996 4.12991998 0.36893996 4.12991998 0.35038996 4.12991998 3 P 0 N
L 0.27165 4.16928996 0.35038996 4.12991998 9 P 0 
A 0.2902 4.32676998 0.2902 4.32676998 0.27165 4.32676998 3 P 0 N
A 0.36893996 4.2874 0.36893996 4.2874 0.35038996 4.2874 3 P 0 N
L 0.27165 4.32676998 0.35038996 4.2874 9 P 0 
L 0.27165 4.48425 0.35038996 4.44488002 9 P 0 
A 0.36893996 4.44488002 0.36893996 4.44488002 0.35038996 4.44488002 3 P 0 N
A 0.2902 4.48425 0.2902 4.48425 0.27165 4.48425 3 P 0 N
L 4.87 0.025 6.565 0.025 15 P 0 
L 4.885 0.085 6.53 0.085 15 P 0 
L 4.895 0.15 6.54 0.15 15 P 0 
L 4.89 0.215 6.555 0.215 15 P 0 
L 4.89 0.3 6.535 0.3 15 P 0 
L 4.895 0.37 6.54 0.37 15 P 0 
A 12.84646004 6.02361998 12.9252 5.94488002 12.84646004 5.94488002 9 P 0 Y
A 12.9252 0.07873996 12.84646004 0 12.84646004 0.07873996 9 P 0 Y
L 12.9252 5.94488002 12.9252 0.07873996 9 P 0 
L 12.84646004 0 6.66536004 0 9 P 0 
A 6.58661998 0.35433002 6.50788002 0.43306998 6.50788002 0.35433002 9 P 0 N
A 6.66536004 0 6.58661998 0.07873996 6.66535994 0.07873996 9 P 0 Y
L 6.58661998 0.07873996 6.58661998 0.35433002 9 P 0 
A 4.93308002 0.43306998 4.85433996 0.35433002 4.93307992 0.35433002 9 P 0 N
L 6.50788002 0.43306998 4.93308002 0.43306998 9 P 0 
L 4.85433996 0.35433002 4.85433996 0.07873996 9 P 0 
A 4.85433996 0.07873996 4.77558996 0 4.7755999 0.07873996 9 P 0 Y
A 0.07873996 0 0 0.07873996 0.07873996 0.07873996 9 P 0 Y
L 4.77558996 0 0.07873996 0 9 P 0 
L 0.07873996 6.02361998 12.84646004 6.02361998 9 P 0 
A 0 5.94488002 0.07873996 6.02361998 0.07873996 5.94488002 9 P 0 Y
L 0 0.07873996 0 5.94488002 9 P 0 
L 0 6.07011998 12.89 6.07011998 15 P 0 
L 0 -0.0465 12.89 -0.0465 15 P 0 
L 0.005 6.16 0.035 6.13 3 P 0 
L 12.91 6.15 12.88 6.12 3 P 0 
L 12.91 -0.13 12.88 -0.1 3 P 0 
L 0.005 -0.135 0.035 -0.105 3 P 0 
L 0 -0.41426004 0 -0.093 9 P 0 
A 0.07873996 -0.493 0 -0.41426004 0.07873996 -0.41426004 9 P 0 Y
L 12.84646004 -0.493 0.07873996 -0.493 9 P 0 
A 12.9252 -0.41426004 12.84646004 -0.493 12.84646004 -0.41426004 9 P 0 Y
L 12.9252 -0.093 12.9252 -0.41426004 9 P 0 
L 0 -0.093 12.9252 -0.093 9 P 0 
L 0 6.11661998 12.9252 6.11661998 9 P 0 
L 0 6.43788002 0 6.11661998 9 P 0 
A 0.07873996 6.51661998 0 6.43788002 0.07873996 6.43788002 9 P 0 N
L 12.84646004 6.51661998 0.07873996 6.51661998 9 P 0 
A 12.9252 6.43788002 12.84646004 6.51661998 12.84646004 6.43788002 9 P 0 N
L 12.9252 6.11661998 12.9252 6.43788002 9 P 0 
A 0 5.94488002 0.07873996 6.02361998 0.07873996 5.94488002 18 P 0 Y
L 0 0.07873996 0 5.94488002 18 P 0 
A 0.07873996 0 0 0.07873996 0.07873996 0.07873996 18 P 0 Y
L 4.77558996 0 0.07873996 0 18 P 0 
A 4.85433996 0.07873996 4.77558996 0 4.7755999 0.07873996 18 P 0 Y
L 4.85433996 0.35433002 4.85433996 0.07873996 18 P 0 
A 4.93308002 0.43306998 4.85433996 0.35433002 4.93307992 0.35433002 18 P 0 N
L 6.50788002 0.43306998 4.93308002 0.43306998 18 P 0 
A 6.58661998 0.35433002 6.50788002 0.43306998 6.50788002 0.35433002 18 P 0 N
L 6.58661998 0.07873996 6.58661998 0.35433002 18 P 0 
A 6.66536004 0 6.58661998 0.07873996 6.66535994 0.07873996 18 P 0 Y
L 12.84646004 0 6.66536004 0 18 P 0 
A 12.9252 0.07873996 12.84646004 0 12.84646004 0.07873996 18 P 0 Y
L 12.9252 5.94488002 12.9252 0.07873996 18 P 0 
A 12.84646004 6.02361998 12.9252 5.94488002 12.84646004 5.94488002 18 P 0 Y
L 0.07873996 6.02361998 12.84646004 6.02361998 18 P 0 
L 0.0349 -2.3038 0.0349 -1.0038 2 P 0 ;0
L 0.0349 -1.0038 4.5349 -1.0038 2 P 0 ;0
L 4.5349 -1.0038 4.5349 -2.3038 2 P 0 ;0
L 4.5349 -2.3038 0.0349 -2.3038 2 P 0 ;0
L 0.0349 -1.6038 4.5349 -1.6038 2 P 0 ;0
L 0.0349 -1.8038 4.5349 -1.8038 2 P 0 ;0
L 2.4349 -2.1038 4.0349 -2.1038 2 P 0 ;0
L 2.4349 -2.3038 2.4349 -1.8038 2 P 0 ;0
L 3.2349 -2.1038 3.2349 -1.8038 2 P 0 ;0
L 4.0349 -2.3038 4.0349 -1.8038 2 P 0 ;0
L 0.0723999 -1.6844687 0.07906663 -1.69030079 1 P 0 ;0
L 0.07906663 -1.69030079 0.08656654 -1.6938 1 P 0 ;0
L 0.08656654 -1.6938 0.09323337 -1.6938 1 P 0 ;0
L 0.09323337 -1.6938 0.0999001 -1.69030079 1 P 0 ;0
L 0.0999001 -1.69030079 0.10490059 -1.6844687 1 P 0 ;0
L 0.10490059 -1.6844687 0.1074 -1.67629951 1 P 0 ;0
L 0.1074 -1.67629951 0.10573376 -1.66813455 1 P 0 ;0
L 0.10573376 -1.66813455 0.10156644 -1.66113396 1 P 0 ;0
L 0.10156644 -1.66113396 0.09406654 -1.65646614 1 P 0 ;0
L 0.09406654 -1.65646614 0.08406713 -1.65413327 1 P 0 ;0
L 0.08406713 -1.65413327 0.07823346 -1.64946762 1 P 0 ;0
L 0.07823346 -1.64946762 0.07573248 -1.64130059 1 P 0 ;0
L 0.07573248 -1.64130059 0.0774003 -1.63313356 1 P 0 ;0
L 0.0774003 -1.63313356 0.08156614 -1.62730148 1 P 0 ;0
L 0.08156614 -1.62730148 0.0873997 -1.6238 1 P 0 ;0
L 0.0873997 -1.6238 0.09323337 -1.6238 1 P 8191 ;0
L 0.09323337 -1.6238 0.09906693 -1.62613287 1 P 0 ;0
L 0.09906693 -1.62613287 0.10406742 -1.63196713 1 P 0 ;0
L 0.1383999 -1.6938 0.1383999 -1.6238 1 P 0 ;0
L 0.1734 -1.6238 0.1734 -1.6938 1 P 0 ;0
L 0.1734 -1.65880108 0.1383999 -1.65880108 1 P 0 ;0
L 0.23856683 -1.6938 0.20523307 -1.6938 1 P 0 ;0
L 0.20523307 -1.6938 0.20523307 -1.6238 1 P 0 ;0
L 0.20523307 -1.6238 0.23856683 -1.6238 1 P 0 ;0
L 0.22523337 -1.65763258 0.20523307 -1.65763258 1 P 0 ;0
L 0.30456683 -1.6938 0.27123307 -1.6938 1 P 0 ;0
L 0.27123307 -1.6938 0.27123307 -1.6238 1 P 0 ;0
L 0.27123307 -1.6238 0.30456683 -1.6238 1 P 0 ;0
L 0.29123337 -1.65763258 0.27123307 -1.65763258 1 P 0 ;0
L 0.35389921 -1.6238 0.35389921 -1.6938 1 P 0 ;0
L 0.33473356 -1.6238 0.37306634 -1.6238 1 P 0 ;0
L 0.09489921 -1.7188 0.09489921 -1.7888 1 P 0 ;0
L 0.07573356 -1.7188 0.11406634 -1.7188 1 P 0 ;0
L 0.1508998 -1.7188 0.17089862 -1.7188 1 P 0 ;0
L 0.16089921 -1.7188 0.16089921 -1.7888 1 P 0 ;0
L 0.1508998 -1.7888 0.17089862 -1.7888 1 P 0 ;0
L 0.22689921 -1.7188 0.22689921 -1.7888 1 P 0 ;0
L 0.20773356 -1.7188 0.24606634 -1.7188 1 P 0 ;0
L 0.27623307 -1.7188 0.27623307 -1.7888 1 P 0 ;0
L 0.27623307 -1.7888 0.30956683 -1.7888 1 P 0 ;0
L 0.37556683 -1.7888 0.34223307 -1.7888 1 P 0 ;0
L 0.34223307 -1.7888 0.34223307 -1.7188 1 P 0 ;0
L 0.34223307 -1.7188 0.37556683 -1.7188 1 P 0 ;0
L 0.36223337 -1.75263258 0.34223307 -1.75263258 1 P 0 ;0
L 2.5438999 -1.96813563 2.5519 -1.97480089 1 P 0 ;0
L 2.5519 -1.97480089 2.5608999 -1.9788 1 P 0 ;0
L 2.5608999 -1.9788 2.5689 -1.9788 1 P 0 ;0
L 2.5689 -1.9788 2.5769001 -1.97480089 1 P 0 ;0
L 2.5769001 -1.97480089 2.58290069 -1.96813563 1 P 0 ;0
L 2.58290069 -1.96813563 2.5859 -1.95879941 1 P 0 ;0
L 2.5859 -1.95879941 2.58390049 -1.94946811 1 P 0 ;0
L 2.58390049 -1.94946811 2.5788997 -1.94146732 1 P 0 ;0
L 2.5788997 -1.94146732 2.5698998 -1.93613278 1 P 0 ;0
L 2.5698998 -1.93613278 2.55790049 -1.93346663 1 P 0 ;0
L 2.55790049 -1.93346663 2.5509002 -1.92813445 1 P 0 ;0
L 2.5509002 -1.92813445 2.54789902 -1.91880069 1 P 0 ;0
L 2.54789902 -1.91880069 2.54990039 -1.90946683 1 P 0 ;0
L 2.54990039 -1.90946683 2.55489931 -1.90280167 1 P 0 ;0
L 2.55489931 -1.90280167 2.5618997 -1.8988 1 P 0 ;0
L 2.5618997 -1.8988 2.5689 -1.8988 1 P 0 ;0
L 2.5689 -1.8988 2.57590039 -1.90146614 1 P 0 ;0
L 2.57590039 -1.90146614 2.58190089 -1.90813386 1 P 0 ;0
L 2.6648998 -1.90546772 2.65889931 -1.90146614 1 P 0 ;0
L 2.65889931 -1.90146614 2.65190079 -1.8988 1 P 0 ;0
L 2.65190079 -1.8988 2.64390069 -1.8988 1 P 0 ;0
L 2.64390069 -1.8988 2.63489892 -1.90280167 1 P 0 ;0
L 2.63489892 -1.90280167 2.62790039 -1.90946683 1 P 0 ;0
L 2.62790039 -1.90946683 2.62289961 -1.91746762 1 P 0 ;0
L 2.62289961 -1.91746762 2.61889862 -1.93080049 1 P 0 ;0
L 2.61889862 -1.93080049 2.61789892 -1.94280039 1 P 0 ;0
L 2.61789892 -1.94280039 2.6199003 -1.9548003 1 P 0 ;0
L 2.6199003 -1.9548003 2.62289961 -1.96280098 1 P 0 ;0
L 2.62289961 -1.96280098 2.6289002 -1.97080177 1 P 0 ;0
L 2.6289002 -1.97080177 2.63590049 -1.97613396 1 P 0 ;0
L 2.63590049 -1.97613396 2.64289902 -1.9788 1 P 0 ;0
L 2.64289902 -1.9788 2.64989941 -1.9788 1 P 0 ;0
L 2.64989941 -1.9788 2.6568997 -1.97613396 1 P 0 ;0
L 2.6568997 -1.97613396 2.6629003 -1.97213484 1 P 0 ;0
L 2.6629003 -1.97213484 2.66790098 -1.96680266 1 P 0 ;0
L 2.69589892 -1.9788 2.72089902 -1.8988 1 P 0 ;0
L 2.72089902 -1.8988 2.74590098 -1.9788 1 P 0 ;0
L 2.73689931 -1.95080118 2.70489882 -1.95080118 1 P 0 ;0
L 2.77889961 -1.8988 2.77889961 -1.9788 1 P 0 ;0
L 2.77889961 -1.9788 2.8189003 -1.9788 1 P 0 ;0
L 2.8969003 -1.9788 2.85689961 -1.9788 1 P 0 ;0
L 2.85689961 -1.9788 2.85689961 -1.8988 1 P 0 ;0
L 2.85689961 -1.8988 2.8969003 -1.8988 1 P 0 ;0
L 2.8809 -1.93746575 2.85689961 -1.93746575 1 P 0 ;0
L 3.03289902 -1.9788 3.03289902 -1.8988 1 P 0 ;0
L 3.03289902 -1.8988 3.0208998 -1.91479911 1 P 0 ;0
L 3.0208998 -1.9788 3.04489833 -1.9788 1 P 0 ;0
L 3.11089902 -1.98146604 3.10889951 -1.98013297 1 P 8191 ;0
L 3.10889951 -1.98013297 3.10889951 -1.97746703 1 P 8191 ;0
L 3.10889951 -1.97746703 3.11089902 -1.97613396 1 P 8191 ;0
L 3.11089902 -1.97613396 3.11290039 -1.97746703 1 P 8191 ;0
L 3.11290039 -1.97746703 3.11290039 -1.98013297 1 P 8191 ;0
L 3.11290039 -1.98013297 3.11089902 -1.98146604 1 P 8191 ;0
L 3.11089902 -1.945469 3.10889951 -1.94413346 1 P 8191 ;0
L 3.10889951 -1.94413346 3.10889951 -1.94146732 1 P 8191 ;0
L 3.10889951 -1.94146732 3.11089902 -1.94013435 1 P 8191 ;0
L 3.11089902 -1.94013435 3.11290039 -1.94146732 1 P 8191 ;0
L 3.11290039 -1.94146732 3.11290039 -1.94413346 1 P 8191 ;0
L 3.11290039 -1.94413346 3.11089902 -1.945469 1 P 8191 ;0
L 3.18889902 -1.9788 3.18889902 -1.8988 1 P 0 ;0
L 3.18889902 -1.8988 3.1768998 -1.91479911 1 P 0 ;0
L 3.1768998 -1.9788 3.20089833 -1.9788 1 P 0 ;0
L 2.5138999 -2.23313563 2.5219 -2.23980089 1 P 0 ;0
L 2.5219 -2.23980089 2.5308999 -2.2438 1 P 0 ;0
L 2.5308999 -2.2438 2.5389 -2.2438 1 P 0 ;0
L 2.5389 -2.2438 2.5469001 -2.23980089 1 P 0 ;0
L 2.5469001 -2.23980089 2.55290069 -2.23313563 1 P 0 ;0
L 2.55290069 -2.23313563 2.5559 -2.22379941 1 P 0 ;0
L 2.5559 -2.22379941 2.55390049 -2.21446811 1 P 0 ;0
L 2.55390049 -2.21446811 2.5488997 -2.20646732 1 P 0 ;0
L 2.5488997 -2.20646732 2.5398998 -2.20113278 1 P 0 ;0
L 2.5398998 -2.20113278 2.52790049 -2.19846663 1 P 0 ;0
L 2.52790049 -2.19846663 2.5209002 -2.19313445 1 P 0 ;0
L 2.5209002 -2.19313445 2.51789902 -2.18380069 1 P 0 ;0
L 2.51789902 -2.18380069 2.51990039 -2.17446683 1 P 0 ;0
L 2.51990039 -2.17446683 2.52489931 -2.16780167 1 P 0 ;0
L 2.52489931 -2.16780167 2.5318997 -2.1638 1 P 0 ;0
L 2.5318997 -2.1638 2.5389 -2.1638 1 P 0 ;0
L 2.5389 -2.1638 2.54590039 -2.16646614 1 P 0 ;0
L 2.54590039 -2.16646614 2.55190089 -2.17313386 1 P 0 ;0
L 2.5918999 -2.2438 2.5918999 -2.1638 1 P 0 ;0
L 2.6339 -2.1638 2.6339 -2.2438 1 P 0 ;0
L 2.6339 -2.20380128 2.5918999 -2.20380128 1 P 0 ;0
L 2.7109003 -2.2438 2.67089961 -2.2438 1 P 0 ;0
L 2.67089961 -2.2438 2.67089961 -2.1638 1 P 0 ;0
L 2.67089961 -2.1638 2.7109003 -2.1638 1 P 0 ;0
L 2.6949 -2.20246575 2.67089961 -2.20246575 1 P 0 ;0
L 2.7889003 -2.2438 2.74889961 -2.2438 1 P 0 ;0
L 2.74889961 -2.2438 2.74889961 -2.1638 1 P 0 ;0
L 2.74889961 -2.1638 2.7889003 -2.1638 1 P 0 ;0
L 2.7729 -2.20246575 2.74889961 -2.20246575 1 P 0 ;0
L 2.84689902 -2.1638 2.84689902 -2.2438 1 P 0 ;0
L 2.8239003 -2.1638 2.86989961 -2.1638 1 P 0 ;0
L 3.29489961 -1.9238 3.29489961 -2.0038 1 P 0 ;0
L 3.29489961 -2.0038 3.3349003 -2.0038 1 P 0 ;0
L 3.36789892 -2.0038 3.39289902 -1.9238 1 P 0 ;0
L 3.39289902 -1.9238 3.41790098 -2.0038 1 P 0 ;0
L 3.40889931 -1.97580118 3.37689882 -1.97580118 1 P 0 ;0
L 3.47089902 -2.0038 3.47089902 -1.96780039 1 P 0 ;0
L 3.47089902 -1.96780039 3.45089961 -1.9238 1 P 0 ;0
L 3.4909003 -1.9238 3.47089902 -1.96780039 1 P 0 ;0
L 3.5689003 -2.0038 3.52889961 -2.0038 1 P 0 ;0
L 3.52889961 -2.0038 3.52889961 -1.9238 1 P 0 ;0
L 3.52889961 -1.9238 3.5689003 -1.9238 1 P 0 ;0
L 3.5529 -1.96246575 3.52889961 -1.96246575 1 P 0 ;0
L 3.60689961 -2.0038 3.60689961 -1.9238 1 P 0 ;0
L 3.60689961 -1.9238 3.6318998 -1.9238 1 P 0 ;0
L 3.6318998 -1.9238 3.6398999 -1.92780167 1 P 0 ;0
L 3.6398999 -1.92780167 3.64490069 -1.93313386 1 P 0 ;0
L 3.64490069 -1.93313386 3.6469003 -1.94380069 1 P 0 ;0
L 3.6469003 -1.94380069 3.64490069 -1.95446752 1 P 0 ;0
L 3.64490069 -1.95446752 3.6389001 -1.96113278 1 P 0 ;0
L 3.6389001 -1.96113278 3.6318998 -1.96513435 1 P 0 ;0
L 3.6318998 -1.96513435 3.60689961 -1.96513435 1 P 0 ;0
L 3.6318998 -1.96513435 3.6469003 -2.0038 1 P 0 ;0
L 3.33989902 -2.2538 3.33189892 -2.25246703 1 P 0 ;0
L 3.33189892 -2.25246703 3.32490039 -2.24713484 1 P 0 ;0
L 3.32490039 -2.24713484 3.3188999 -2.23913406 1 P 0 ;0
L 3.3188999 -2.23913406 3.31489892 -2.2298003 1 P 0 ;0
L 3.31489892 -2.2298003 3.31289931 -2.21913346 1 P 0 ;0
L 3.31289931 -2.21913346 3.31289931 -2.20846663 1 P 0 ;0
L 3.31289931 -2.20846663 3.31489892 -2.1977998 1 P 0 ;0
L 3.31489892 -2.1977998 3.3188999 -2.18846604 1 P 0 ;0
L 3.3188999 -2.18846604 3.32490039 -2.18046772 1 P 0 ;0
L 3.32490039 -2.18046772 3.33189892 -2.17513307 1 P 0 ;0
L 3.33189892 -2.17513307 3.33989902 -2.1738 1 P 0 ;0
L 3.33989902 -2.1738 3.34789911 -2.17513307 1 P 0 ;0
L 3.34789911 -2.17513307 3.35489951 -2.18046772 1 P 0 ;0
L 3.35489951 -2.18046772 3.3609 -2.18846604 1 P 0 ;0
L 3.3609 -2.18846604 3.36490098 -2.1977998 1 P 0 ;0
L 3.36490098 -2.1977998 3.36690059 -2.20846663 1 P 0 ;0
L 3.36690059 -2.20846663 3.36690059 -2.21913346 1 P 0 ;0
L 3.36690059 -2.21913346 3.36490098 -2.2298003 1 P 0 ;0
L 3.36490098 -2.2298003 3.3609 -2.23913406 1 P 0 ;0
L 3.3609 -2.23913406 3.35489951 -2.24713484 1 P 0 ;0
L 3.35489951 -2.24713484 3.34789911 -2.25246703 1 P 0 ;0
L 3.34789911 -2.25246703 3.33989902 -2.2538 1 P 0 ;0
L 3.39889941 -2.2538 3.39889941 -2.1738 1 P 0 ;0
L 3.39889941 -2.1738 3.43690049 -2.1738 1 P 0 ;0
L 3.4228998 -2.21246575 3.39889941 -2.21246575 1 P 0 ;0
L 0.16489872 -1.0538 0.16489872 -1.1538 1 P 0 ;0
L 0.13423376 -1.0538 0.19556614 -1.0538 1 P 0 ;0
L 0.2588997 -1.0538 0.29089774 -1.0538 1 P 0 ;0
L 0.27489872 -1.0538 0.27489872 -1.1538 1 P 0 ;0
L 0.2588997 -1.1538 0.29089774 -1.1538 1 P 0 ;0
L 0.38489872 -1.0538 0.38489872 -1.1538 1 P 0 ;0
L 0.35423376 -1.0538 0.41556614 -1.0538 1 P 0 ;0
L 0.46823287 -1.0538 0.46823287 -1.1538 1 P 0 ;0
L 0.46823287 -1.1538 0.52156703 -1.1538 1 P 0 ;0
L 0.63156703 -1.1538 0.57823287 -1.1538 1 P 0 ;0
L 0.57823287 -1.1538 0.57823287 -1.0538 1 P 0 ;0
L 0.57823287 -1.0538 0.63156703 -1.0538 1 P 0 ;0
L 0.61023337 -1.10213219 0.57823287 -1.10213219 1 P 0 ;0
L 4.18989892 -1.9538 4.21489902 -1.8738 1 P 0 ;0
L 4.21489902 -1.8738 4.23990098 -1.9538 1 P 0 ;0
L 4.23089931 -1.92580118 4.19889882 -1.92580118 1 P 0 ;0
L 4.27289961 -1.9538 4.27289961 -1.8738 1 P 0 ;0
L 4.27289961 -1.8738 4.2978998 -1.8738 1 P 0 ;0
L 4.2978998 -1.8738 4.3058999 -1.87780167 1 P 0 ;0
L 4.3058999 -1.87780167 4.31090069 -1.88313386 1 P 0 ;0
L 4.31090069 -1.88313386 4.3129003 -1.89380069 1 P 0 ;0
L 4.3129003 -1.89380069 4.31090069 -1.90446752 1 P 0 ;0
L 4.31090069 -1.90446752 4.3049001 -1.91113278 1 P 0 ;0
L 4.3049001 -1.91113278 4.2978998 -1.91513435 1 P 0 ;0
L 4.2978998 -1.91513435 4.27289961 -1.91513435 1 P 0 ;0
L 4.2978998 -1.91513435 4.3129003 -1.9538 1 P 0 ;0
L 4.37089902 -1.8738 4.37089902 -1.9538 1 P 0 ;0
L 4.3479003 -1.8738 4.39389961 -1.8738 1 P 0 ;0
L 3.61989892 -2.2538 3.61989892 -2.1638 1 P 0 ;0
L 3.61989892 -2.1638 3.6058997 -2.18179892 1 P 0 ;0
L 3.6058997 -2.2538 3.63389803 -2.2538 1 P 0 ;0
L 3.68773268 -2.17879961 3.69473337 -2.16980148 1 P 0 ;0
L 3.69473337 -2.16980148 3.70290039 -2.1652997 1 P 0 ;0
L 3.70290039 -2.1652997 3.71223386 -2.1638 1 P 0 ;0
L 3.71223386 -2.1638 3.7239002 -2.16679941 1 P 0 ;0
L 3.7239002 -2.16679941 3.73206722 -2.17430059 1 P 0 ;0
L 3.73206722 -2.17430059 3.7344001 -2.18329862 1 P 0 ;0
L 3.7344001 -2.18329862 3.73323366 -2.19230217 1 P 0 ;0
L 3.73323366 -2.19230217 3.72856585 -2.19980059 1 P 0 ;0
L 3.72856585 -2.19980059 3.70523317 -2.2148001 1 P 0 ;0
L 3.70523317 -2.2148001 3.69473337 -2.22530069 1 P 0 ;0
L 3.69473337 -2.22530069 3.68773268 -2.24030295 1 P 0 ;0
L 3.68773268 -2.24030295 3.6853998 -2.2538 1 P 0 ;0
L 3.6853998 -2.2538 3.7344001 -2.2538 1 P 0 ;0
L 0.59099833 -1.36499882 0.5990003 -1.35750039 1 P 0 ;0
L 0.5990003 -1.35750039 0.60499902 -1.34500315 1 P 0 ;0
L 0.60499902 -1.34500315 0.60900187 -1.32749764 1 P 0 ;0
L 0.60900187 -1.32749764 0.60499902 -1.31250089 1 P 0 ;0
L 0.60499902 -1.31250089 0.59700079 -1.30250305 1 P 0 ;0
L 0.59700079 -1.30250305 0.5830001 -1.295 1 P 0 ;0
L 0.5830001 -1.295 0.52900059 -1.295 1 P 0 ;0
L 0.52900059 -1.295 0.52900059 -1.445 1 P 0 ;0
L 0.52900059 -1.445 0.59500118 -1.445 1 P 0 ;0
L 0.59500118 -1.445 0.60900187 -1.43500217 1 P 0 ;0
L 0.60900187 -1.43500217 0.6170001 -1.42000079 1 P 0 ;0
L 0.6170001 -1.42000079 0.62099931 -1.4025 1 P 0 ;0
L 0.62099931 -1.4025 0.6170001 -1.38500374 1 P 0 ;0
L 0.6170001 -1.38500374 0.60499902 -1.37000236 1 P 0 ;0
L 0.60499902 -1.37000236 0.59099833 -1.36499882 1 P 0 ;0
L 0.59099833 -1.36499882 0.52900059 -1.36499882 1 P 0 ;0
L 0.77100138 -1.445 0.77100138 -1.34500315 1 P 0 ;0
L 0.77100138 -1.36249941 0.76299951 -1.35250148 1 P 0 ;0
L 0.76299951 -1.35250148 0.75099833 -1.34750256 1 P 0 ;0
L 0.75099833 -1.34750256 0.73700138 -1.34500315 1 P 0 ;0
L 0.73700138 -1.34500315 0.72300069 -1.35000207 1 P 0 ;0
L 0.72300069 -1.35000207 0.71099961 -1.3599999 1 P 0 ;0
L 0.71099961 -1.3599999 0.70299764 -1.37500128 1 P 0 ;0
L 0.70299764 -1.37500128 0.69899852 -1.39500157 1 P 0 ;0
L 0.69899852 -1.39500157 0.70299764 -1.41500187 1 P 0 ;0
L 0.70299764 -1.41500187 0.71099961 -1.43000325 1 P 0 ;0
L 0.71099961 -1.43000325 0.72300069 -1.44000108 1 P 0 ;0
L 0.72300069 -1.44000108 0.73700138 -1.445 1 P 0 ;0
L 0.73700138 -1.445 0.75099833 -1.44250059 1 P 0 ;0
L 0.75099833 -1.44250059 0.76299951 -1.43500217 1 P 0 ;0
L 0.76299951 -1.43500217 0.77100138 -1.42500433 1 P 0 ;0
L 0.86700039 -1.445 0.86700039 -1.34500315 1 P 0 ;0
L 0.86700039 -1.36499882 0.87699833 -1.35500098 1 P 0 ;0
L 0.87699833 -1.35500098 0.8869998 -1.34750256 1 P 0 ;0
L 0.8869998 -1.34750256 0.90100049 -1.34500315 1 P 0 ;0
L 0.90100049 -1.34500315 0.91099833 -1.34750256 1 P 0 ;0
L 0.91099833 -1.34750256 0.92299951 -1.35500098 1 P 0 ;0
L 1.02700039 -1.445 1.02700039 -1.34500315 1 P 0 ;0
L 1.02700039 -1.36499882 1.03699833 -1.35500098 1 P 0 ;0
L 1.03699833 -1.35500098 1.0469998 -1.34750256 1 P 0 ;0
L 1.0469998 -1.34750256 1.06100049 -1.34500315 1 P 0 ;0
L 1.06100049 -1.34500315 1.07099833 -1.34750256 1 P 0 ;0
L 1.07099833 -1.34750256 1.08299951 -1.35500098 1 P 0 ;0
L 1.18500089 -1.37750069 1.24900187 -1.37750069 1 P 0 ;0
L 1.24900187 -1.37750069 1.24299951 -1.3599999 1 P 0 ;0
L 1.24299951 -1.3599999 1.23300157 -1.35000207 1 P 0 ;0
L 1.23300157 -1.35000207 1.21900089 -1.34500315 1 P 0 ;0
L 1.21900089 -1.34500315 1.2050003 -1.34750256 1 P 0 ;0
L 1.2050003 -1.34750256 1.19299911 -1.35500098 1 P 0 ;0
L 1.19299911 -1.35500098 1.18500089 -1.37250177 1 P 0 ;0
L 1.18500089 -1.37250177 1.18099803 -1.38750315 1 P 0 ;0
L 1.18099803 -1.38750315 1.18099803 -1.4025 1 P 0 ;0
L 1.18099803 -1.4025 1.18500089 -1.41750138 1 P 0 ;0
L 1.18500089 -1.41750138 1.19499872 -1.43250276 1 P 0 ;0
L 1.19499872 -1.43250276 1.2069998 -1.44250059 1 P 0 ;0
L 1.2069998 -1.44250059 1.22100049 -1.445 1 P 0 ;0
L 1.22100049 -1.445 1.23500118 -1.44000108 1 P 0 ;0
L 1.23500118 -1.44000108 1.24900187 -1.42500433 1 P 0 ;0
L 1.37499813 -1.445 1.37499813 -1.295 1 P 0 ;0
L 1.50500089 -1.37750069 1.56900187 -1.37750069 1 P 0 ;0
L 1.56900187 -1.37750069 1.56299951 -1.3599999 1 P 0 ;0
L 1.56299951 -1.3599999 1.55300157 -1.35000207 1 P 0 ;0
L 1.55300157 -1.35000207 1.53900089 -1.34500315 1 P 0 ;0
L 1.53900089 -1.34500315 1.5250003 -1.34750256 1 P 0 ;0
L 1.5250003 -1.34750256 1.51299911 -1.35500098 1 P 0 ;0
L 1.51299911 -1.35500098 1.50500089 -1.37250177 1 P 0 ;0
L 1.50500089 -1.37250177 1.50099803 -1.38750315 1 P 0 ;0
L 1.50099803 -1.38750315 1.50099803 -1.4025 1 P 0 ;0
L 1.50099803 -1.4025 1.50500089 -1.41750138 1 P 0 ;0
L 1.50500089 -1.41750138 1.51499872 -1.43250276 1 P 0 ;0
L 1.51499872 -1.43250276 1.5269998 -1.44250059 1 P 0 ;0
L 1.5269998 -1.44250059 1.54100049 -1.445 1 P 0 ;0
L 1.54100049 -1.445 1.55500118 -1.44000108 1 P 0 ;0
L 1.55500118 -1.44000108 1.56900187 -1.42500433 1 P 0 ;0
L 1.6529998 -1.48999951 1.66500089 -1.49499843 1 P 0 ;0
L 1.66500089 -1.49499843 1.68100108 -1.48999951 1 P 0 ;0
L 1.68100108 -1.48999951 1.69099902 -1.48000167 1 P 0 ;0
L 1.69099902 -1.48000167 1.69900089 -1.4674997 1 P 0 ;0
L 1.69900089 -1.4674997 1.71099833 -1.42750374 1 P 0 ;0
L 1.71099833 -1.42750374 1.7370001 -1.34500315 1 P 0 ;0
L 1.67299911 -1.34500315 1.71099833 -1.42750374 1 P 0 ;0
L 1.82500089 -1.37750069 1.88900187 -1.37750069 1 P 0 ;0
L 1.88900187 -1.37750069 1.88299951 -1.3599999 1 P 0 ;0
L 1.88299951 -1.3599999 1.87300157 -1.35000207 1 P 0 ;0
L 1.87300157 -1.35000207 1.85900089 -1.34500315 1 P 0 ;0
L 1.85900089 -1.34500315 1.8450003 -1.34750256 1 P 0 ;0
L 1.8450003 -1.34750256 1.83299911 -1.35500098 1 P 0 ;0
L 1.83299911 -1.35500098 1.82500089 -1.37250177 1 P 0 ;0
L 1.82500089 -1.37250177 1.82099803 -1.38750315 1 P 0 ;0
L 1.82099803 -1.38750315 1.82099803 -1.4025 1 P 0 ;0
L 1.82099803 -1.4025 1.82500089 -1.41750138 1 P 0 ;0
L 1.82500089 -1.41750138 1.83499872 -1.43250276 1 P 0 ;0
L 1.83499872 -1.43250276 1.8469998 -1.44250059 1 P 0 ;0
L 1.8469998 -1.44250059 1.86100049 -1.445 1 P 0 ;0
L 1.86100049 -1.445 1.87500118 -1.44000108 1 P 0 ;0
L 1.87500118 -1.44000108 1.88900187 -1.42500433 1 P 0 ;0
L 2.18699921 -1.37000236 2.22700167 -1.37000236 1 P 0 ;0
L 2.22700167 -1.37000236 2.22700167 -1.41500187 1 P 0 ;0
L 2.22700167 -1.41500187 2.21500059 -1.43000325 1 P 0 ;0
L 2.21500059 -1.43000325 2.2009999 -1.44000108 1 P 0 ;0
L 2.2009999 -1.44000108 2.18100049 -1.445 1 P 0 ;0
L 2.18100049 -1.445 2.16100108 -1.44000108 1 P 0 ;0
L 2.16100108 -1.44000108 2.14700039 -1.43000325 1 P 0 ;0
L 2.14700039 -1.43000325 2.13499931 -1.41500187 1 P 0 ;0
L 2.13499931 -1.41500187 2.12699734 -1.39750108 1 P 0 ;0
L 2.12699734 -1.39750108 2.12299823 -1.37750069 1 P 0 ;0
L 2.12299823 -1.37750069 2.12299823 -1.3599999 1 P 0 ;0
L 2.12299823 -1.3599999 2.12699734 -1.34500315 1 P 0 ;0
L 2.12699734 -1.34500315 2.13499931 -1.32749764 1 P 0 ;0
L 2.13499931 -1.32749764 2.14700039 -1.31250089 1 P 0 ;0
L 2.14700039 -1.31250089 2.15899783 -1.30250305 1 P 0 ;0
L 2.15899783 -1.30250305 2.17499813 -1.295 1 P 0 ;0
L 2.17499813 -1.295 2.18899882 -1.295 1 P 0 ;0
L 2.18899882 -1.295 2.20499902 -1.29999902 1 P 0 ;0
L 2.20499902 -1.29999902 2.2170001 -1.31000138 1 P 0 ;0
L 2.29699892 -1.31999931 2.309 -1.30500246 1 P 0 ;0
L 2.309 -1.30500246 2.32300069 -1.29749951 1 P 0 ;0
L 2.32300069 -1.29749951 2.33900089 -1.295 1 P 0 ;0
L 2.33900089 -1.295 2.3590003 -1.29999902 1 P 0 ;0
L 2.3590003 -1.29999902 2.37300098 -1.31250089 1 P 0 ;0
L 2.37300098 -1.31250089 2.3770001 -1.32749764 1 P 0 ;0
L 2.3770001 -1.32749764 2.37500059 -1.34250364 1 P 0 ;0
L 2.37500059 -1.34250364 2.36699862 -1.35500098 1 P 0 ;0
L 2.36699862 -1.35500098 2.3269998 -1.3800002 1 P 0 ;0
L 2.3269998 -1.3800002 2.309 -1.39750108 1 P 0 ;0
L 2.309 -1.39750108 2.29699892 -1.42250482 1 P 0 ;0
L 2.29699892 -1.42250482 2.2929998 -1.445 1 P 0 ;0
L 2.2929998 -1.445 2.3770001 -1.445 1 P 0 ;0
L 2.6129998 -1.42500433 2.629 -1.43750167 1 P 0 ;0
L 2.629 -1.43750167 2.6469998 -1.445 1 P 0 ;0
L 2.6469998 -1.445 2.6630001 -1.445 1 P 0 ;0
L 2.6630001 -1.445 2.6790003 -1.43750167 1 P 0 ;0
L 2.6790003 -1.43750167 2.69100138 -1.42500433 1 P 0 ;0
L 2.69100138 -1.42500433 2.6970001 -1.40749892 1 P 0 ;0
L 2.6970001 -1.40749892 2.69300098 -1.39000266 1 P 0 ;0
L 2.69300098 -1.39000266 2.68299951 -1.37500128 1 P 0 ;0
L 2.68299951 -1.37500128 2.66499961 -1.36499882 1 P 0 ;0
L 2.66499961 -1.36499882 2.64100108 -1.3599999 1 P 0 ;0
L 2.64100108 -1.3599999 2.62700039 -1.35000207 1 P 0 ;0
L 2.62700039 -1.35000207 2.62099803 -1.33250118 1 P 0 ;0
L 2.62099803 -1.33250118 2.62500089 -1.31500039 1 P 0 ;0
L 2.62500089 -1.31500039 2.63499872 -1.30250305 1 P 0 ;0
L 2.63499872 -1.30250305 2.64899941 -1.295 1 P 0 ;0
L 2.64899941 -1.295 2.6630001 -1.295 1 P 0 ;0
L 2.6630001 -1.295 2.67700079 -1.29999902 1 P 0 ;0
L 2.67700079 -1.29999902 2.68900187 -1.31250089 1 P 0 ;0
L 2.7729998 -1.445 2.8570001 -1.295 1 P 0 ;0
L 2.7729998 -1.295 2.8570001 -1.445 1 P 0 ;0
L 2.92299823 -1.445 2.92299823 -1.295 1 P 0 ;0
L 2.92299823 -1.295 2.97499813 -1.42000079 1 P 0 ;0
L 2.97499813 -1.42000079 3.02700167 -1.295 1 P 0 ;0
L 3.02700167 -1.295 3.02700167 -1.445 1 P 0 ;0
L 3.09699892 -1.31999931 3.109 -1.30500246 1 P 0 ;0
L 3.109 -1.30500246 3.12300069 -1.29749951 1 P 0 ;0
L 3.12300069 -1.29749951 3.13900089 -1.295 1 P 0 ;0
L 3.13900089 -1.295 3.1590003 -1.29999902 1 P 0 ;0
L 3.1590003 -1.29999902 3.17300098 -1.31250089 1 P 0 ;0
L 3.17300098 -1.31250089 3.1770001 -1.32749764 1 P 0 ;0
L 3.1770001 -1.32749764 3.17500059 -1.34250364 1 P 0 ;0
L 3.17500059 -1.34250364 3.16699862 -1.35500098 1 P 0 ;0
L 3.16699862 -1.35500098 3.1269998 -1.3800002 1 P 0 ;0
L 3.1269998 -1.3800002 3.109 -1.39750108 1 P 0 ;0
L 3.109 -1.39750108 3.09699892 -1.42250482 1 P 0 ;0
L 3.09699892 -1.42250482 3.0929998 -1.445 1 P 0 ;0
L 3.0929998 -1.445 3.1770001 -1.445 1 P 0 ;0
L 3.269 -1.39500157 3.3209999 -1.39500157 1 P 0 ;0
L 3.41499931 -1.445 3.41499931 -1.295 1 P 0 ;0
L 3.41499931 -1.295 3.46499961 -1.295 1 P 0 ;0
L 3.46499961 -1.295 3.4809999 -1.30250305 1 P 0 ;0
L 3.4809999 -1.30250305 3.49100138 -1.31250089 1 P 0 ;0
L 3.49100138 -1.31250089 3.49500059 -1.33250118 1 P 0 ;0
L 3.49500059 -1.33250118 3.49100138 -1.35250148 1 P 0 ;0
L 3.49100138 -1.35250148 3.4790003 -1.36499882 1 P 0 ;0
L 3.4790003 -1.36499882 3.46499961 -1.37250177 1 P 0 ;0
L 3.46499961 -1.37250177 3.41499931 -1.37250177 1 P 0 ;0
L 3.46499961 -1.37250177 3.49500059 -1.445 1 P 0 ;0
L 3.61499813 -1.34500315 3.61499813 -1.445 1 P 0 ;0
L 3.61499813 -1.30500246 3.61099902 -1.30250305 1 P 8191 ;0
L 3.61099902 -1.30250305 3.61099902 -1.29749951 1 P 8191 ;0
L 3.61099902 -1.29749951 3.61499813 -1.295 1 P 8191 ;0
L 3.61499813 -1.295 3.61900089 -1.29749951 1 P 8191 ;0
L 3.61900089 -1.29749951 3.61900089 -1.30250305 1 P 8191 ;0
L 3.61900089 -1.30250305 3.61499813 -1.30500246 1 P 8191 ;0
L 3.74500089 -1.42750374 3.75499872 -1.43750167 1 P 0 ;0
L 3.75499872 -1.43750167 3.76899941 -1.445 1 P 0 ;0
L 3.76899941 -1.445 3.78100049 -1.445 1 P 0 ;0
L 3.78100049 -1.445 3.79300157 -1.44000108 1 P 0 ;0
L 3.79300157 -1.44000108 3.8009999 -1.43250276 1 P 0 ;0
L 3.8009999 -1.43250276 3.80499902 -1.42250482 1 P 0 ;0
L 3.80499902 -1.42250482 3.80299951 -1.40749892 1 P 0 ;0
L 3.80299951 -1.40749892 3.79500118 -1.40000049 1 P 0 ;0
L 3.79500118 -1.40000049 3.75899783 -1.38500374 1 P 0 ;0
L 3.75899783 -1.38500374 3.75099961 -1.36749833 1 P 0 ;0
L 3.75099961 -1.36749833 3.75499872 -1.35500098 1 P 0 ;0
L 3.75499872 -1.35500098 3.76300069 -1.34750256 1 P 0 ;0
L 3.76300069 -1.34750256 3.77499813 -1.34500315 1 P 0 ;0
L 3.77499813 -1.34500315 3.78699921 -1.34750256 1 P 0 ;0
L 3.78699921 -1.34750256 3.7990003 -1.35500098 1 P 0 ;0
L 3.90500089 -1.37750069 3.96900187 -1.37750069 1 P 0 ;0
L 3.96900187 -1.37750069 3.96299951 -1.3599999 1 P 0 ;0
L 3.96299951 -1.3599999 3.95300157 -1.35000207 1 P 0 ;0
L 3.95300157 -1.35000207 3.93900089 -1.34500315 1 P 0 ;0
L 3.93900089 -1.34500315 3.9250003 -1.34750256 1 P 0 ;0
L 3.9250003 -1.34750256 3.91299911 -1.35500098 1 P 0 ;0
L 3.91299911 -1.35500098 3.90500089 -1.37250177 1 P 0 ;0
L 3.90500089 -1.37250177 3.90099803 -1.38750315 1 P 0 ;0
L 3.90099803 -1.38750315 3.90099803 -1.4025 1 P 0 ;0
L 3.90099803 -1.4025 3.90500089 -1.41750138 1 P 0 ;0
L 3.90500089 -1.41750138 3.91499872 -1.43250276 1 P 0 ;0
L 3.91499872 -1.43250276 3.9269998 -1.44250059 1 P 0 ;0
L 3.9269998 -1.44250059 3.94100049 -1.445 1 P 0 ;0
L 3.94100049 -1.445 3.95500118 -1.44000108 1 P 0 ;0
L 3.95500118 -1.44000108 3.96900187 -1.42500433 1 P 0 ;0
L 4.06700039 -1.445 4.06700039 -1.34500315 1 P 0 ;0
L 4.06700039 -1.36499882 4.07699833 -1.35500098 1 P 0 ;0
L 4.07699833 -1.35500098 4.0869998 -1.34750256 1 P 0 ;0
L 4.0869998 -1.34750256 4.10100049 -1.34500315 1 P 0 ;0
L 4.10100049 -1.34500315 4.11099833 -1.34750256 1 P 0 ;0
L 4.11099833 -1.34750256 4.12299951 -1.35500098 1 P 0 ;0
L 4.16964783 -2.2038 4.21839813 -2.0478 1 P 0 ;0
L 4.21839813 -2.0478 4.26715207 -2.2038 1 P 0 ;0
L 4.24959862 -2.14920217 4.18719774 -2.14920217 1 P 0 ;0
L 4.37939813 -2.2038 4.37939813 -2.0478 1 P 0 ;0
L 4.37939813 -2.0478 4.35599961 -2.07899813 1 P 0 ;0
L 4.35599961 -2.2038 4.40279675 -2.2038 1 P 0 ;0
L 2.0009002 -0.9538 2.0009002 -0.8038 1 P 0 ;0
L 2.0009002 -0.8038 2.04089902 -0.8038 1 P 0 ;0
L 2.04089902 -0.8038 2.05689921 -0.81130305 1 P 0 ;0
L 2.05689921 -0.81130305 2.0689003 -0.82130089 1 P 0 ;0
L 2.0689003 -0.82130089 2.07890187 -0.83629764 1 P 0 ;0
L 2.07890187 -0.83629764 2.0869001 -0.85380315 1 P 0 ;0
L 2.0869001 -0.85380315 2.0888997 -0.87880236 1 P 0 ;0
L 2.0888997 -0.87880236 2.0869001 -0.90380157 1 P 0 ;0
L 2.0869001 -0.90380157 2.07890187 -0.92130246 1 P 0 ;0
L 2.07890187 -0.92130246 2.0689003 -0.93630374 1 P 0 ;0
L 2.0689003 -0.93630374 2.05689921 -0.94630167 1 P 0 ;0
L 2.05689921 -0.94630167 2.04089902 -0.9538 1 P 0 ;0
L 2.04089902 -0.9538 2.0009002 -0.9538 1 P 0 ;0
L 2.15489783 -0.9538 2.20489813 -0.8038 1 P 0 ;0
L 2.20489813 -0.8038 2.25490207 -0.9538 1 P 0 ;0
L 2.23689862 -0.90130207 2.17289764 -0.90130207 1 P 0 ;0
L 2.36489813 -0.8038 2.36489813 -0.9538 1 P 0 ;0
L 2.31890059 -0.8038 2.41089931 -0.8038 1 P 0 ;0
L 2.56490059 -0.9538 2.48489931 -0.9538 1 P 0 ;0
L 2.48489931 -0.9538 2.48489931 -0.8038 1 P 0 ;0
L 2.48489931 -0.8038 2.56490059 -0.8038 1 P 0 ;0
L 2.5329001 -0.87629833 2.48489931 -0.87629833 1 P 0 ;0
L 2.84489813 -0.9538 2.82889783 -0.95130059 1 P 0 ;0
L 2.82889783 -0.95130059 2.81490089 -0.94130276 1 P 0 ;0
L 2.81490089 -0.94130276 2.8028998 -0.92630138 1 P 0 ;0
L 2.8028998 -0.92630138 2.79489783 -0.90880049 1 P 0 ;0
L 2.79489783 -0.90880049 2.79089862 -0.8888002 1 P 0 ;0
L 2.79089862 -0.8888002 2.79089862 -0.8687999 1 P 0 ;0
L 2.79089862 -0.8687999 2.79489783 -0.84879961 1 P 0 ;0
L 2.79489783 -0.84879961 2.8028998 -0.83129872 1 P 0 ;0
L 2.8028998 -0.83129872 2.81490089 -0.81630197 1 P 0 ;0
L 2.81490089 -0.81630197 2.82889783 -0.80629951 1 P 0 ;0
L 2.82889783 -0.80629951 2.84489813 -0.8038 1 P 0 ;0
L 2.84489813 -0.8038 2.86089833 -0.80629951 1 P 0 ;0
L 2.86089833 -0.80629951 2.87489902 -0.81630197 1 P 0 ;0
L 2.87489902 -0.81630197 2.8869001 -0.83129872 1 P 0 ;0
L 2.8869001 -0.83129872 2.89490207 -0.84879961 1 P 0 ;0
L 2.89490207 -0.84879961 2.89890128 -0.8687999 1 P 0 ;0
L 2.89890128 -0.8687999 2.89890128 -0.8888002 1 P 0 ;0
L 2.89890128 -0.8888002 2.89490207 -0.90880049 1 P 0 ;0
L 2.89490207 -0.90880049 2.8869001 -0.92630138 1 P 0 ;0
L 2.8869001 -0.92630138 2.87489902 -0.94130276 1 P 0 ;0
L 2.87489902 -0.94130276 2.86089833 -0.95130059 1 P 0 ;0
L 2.86089833 -0.95130059 2.84489813 -0.9538 1 P 0 ;0
L 3.0488997 -0.81630197 3.03689862 -0.80879902 1 P 0 ;0
L 3.03689862 -0.80879902 3.02290157 -0.8038 1 P 0 ;0
L 3.02290157 -0.8038 3.00690138 -0.8038 1 P 0 ;0
L 3.00690138 -0.8038 2.98889783 -0.81130305 1 P 0 ;0
L 2.98889783 -0.81130305 2.97490089 -0.82380039 1 P 0 ;0
L 2.97490089 -0.82380039 2.96489931 -0.83880177 1 P 0 ;0
L 2.96489931 -0.83880177 2.95689734 -0.86380098 1 P 0 ;0
L 2.95689734 -0.86380098 2.95489783 -0.88630069 1 P 0 ;0
L 2.95489783 -0.88630069 2.95890059 -0.90880049 1 P 0 ;0
L 2.95890059 -0.90880049 2.96489931 -0.92380187 1 P 0 ;0
L 2.96489931 -0.92380187 2.97690039 -0.93880325 1 P 0 ;0
L 2.97690039 -0.93880325 2.99090108 -0.94880108 1 P 0 ;0
L 2.99090108 -0.94880108 3.00489813 -0.9538 1 P 0 ;0
L 3.00489813 -0.9538 3.01889882 -0.9538 1 P 0 ;0
L 3.01889882 -0.9538 3.03289951 -0.94880108 1 P 0 ;0
L 3.03289951 -0.94880108 3.04490059 -0.94130276 1 P 0 ;0
L 3.04490059 -0.94130276 3.05490207 -0.93130482 1 P 0 ;0
L 3.16489813 -0.8038 3.16489813 -0.9538 1 P 0 ;0
L 3.11890059 -0.8038 3.21089931 -0.8038 1 P 0 ;0
L 3.28889852 -0.95879892 3.36090138 -0.8038 1 P 0 ;0
L 3.44689892 -0.82879931 3.4589 -0.81380246 1 P 0 ;0
L 3.4589 -0.81380246 3.47290069 -0.80629951 1 P 0 ;0
L 3.47290069 -0.80629951 3.48890089 -0.8038 1 P 0 ;0
L 3.48890089 -0.8038 3.5089003 -0.80879902 1 P 0 ;0
L 3.5089003 -0.80879902 3.52290098 -0.82130089 1 P 0 ;0
L 3.52290098 -0.82130089 3.5269001 -0.83629764 1 P 0 ;0
L 3.5269001 -0.83629764 3.52490059 -0.85130364 1 P 0 ;0
L 3.52490059 -0.85130364 3.51689862 -0.86380098 1 P 0 ;0
L 3.51689862 -0.86380098 3.4768998 -0.8888002 1 P 0 ;0
L 3.4768998 -0.8888002 3.4589 -0.90630108 1 P 0 ;0
L 3.4589 -0.90630108 3.44689892 -0.93130482 1 P 0 ;0
L 3.44689892 -0.93130482 3.4428998 -0.9538 1 P 0 ;0
L 3.4428998 -0.9538 3.5269001 -0.9538 1 P 0 ;0
L 3.64089902 -0.9538 3.64489813 -0.92130246 1 P 0 ;0
L 3.64489813 -0.92130246 3.65090049 -0.89380374 1 P 0 ;0
L 3.65090049 -0.89380374 3.65889882 -0.8687999 1 P 0 ;0
L 3.65889882 -0.8687999 3.6689003 -0.84130118 1 P 0 ;0
L 3.6689003 -0.84130118 3.68490059 -0.8038 1 P 0 ;0
L 3.68490059 -0.8038 3.60489931 -0.8038 1 P 0 ;0
L 3.76889852 -0.95879892 3.84090138 -0.8038 1 P 0 ;0
L 3.92689892 -0.82879931 3.9389 -0.81380246 1 P 0 ;0
L 3.9389 -0.81380246 3.95290069 -0.80629951 1 P 0 ;0
L 3.95290069 -0.80629951 3.96890089 -0.8038 1 P 0 ;0
L 3.96890089 -0.8038 3.9889003 -0.80879902 1 P 0 ;0
L 3.9889003 -0.80879902 4.00290098 -0.82130089 1 P 0 ;0
L 4.00290098 -0.82130089 4.0069001 -0.83629764 1 P 0 ;0
L 4.0069001 -0.83629764 4.00490059 -0.85130364 1 P 0 ;0
L 4.00490059 -0.85130364 3.99689862 -0.86380098 1 P 0 ;0
L 3.99689862 -0.86380098 3.9568998 -0.8888002 1 P 0 ;0
L 3.9568998 -0.8888002 3.9389 -0.90630108 1 P 0 ;0
L 3.9389 -0.90630108 3.92689892 -0.93130482 1 P 0 ;0
L 3.92689892 -0.93130482 3.9228998 -0.9538 1 P 0 ;0
L 3.9228998 -0.9538 4.0069001 -0.9538 1 P 0 ;0
L 4.12489813 -0.8038 4.10889783 -0.80879902 1 P 0 ;0
L 4.10889783 -0.80879902 4.09690039 -0.82130089 1 P 0 ;0
L 4.09690039 -0.82130089 4.08889852 -0.83629764 1 P 0 ;0
L 4.08889852 -0.83629764 4.0828998 -0.85630256 1 P 0 ;0
L 4.0828998 -0.85630256 4.0809002 -0.87880236 1 P 0 ;0
L 4.0809002 -0.87880236 4.0828998 -0.90130207 1 P 0 ;0
L 4.0828998 -0.90130207 4.08889852 -0.92130246 1 P 0 ;0
L 4.08889852 -0.92130246 4.09690039 -0.93630374 1 P 0 ;0
L 4.09690039 -0.93630374 4.10889783 -0.94880108 1 P 0 ;0
L 4.10889783 -0.94880108 4.12489813 -0.9538 1 P 0 ;0
L 4.12489813 -0.9538 4.14089833 -0.94880108 1 P 0 ;0
L 4.14089833 -0.94880108 4.15289951 -0.93630374 1 P 0 ;0
L 4.15289951 -0.93630374 4.16090138 -0.92130246 1 P 0 ;0
L 4.16090138 -0.92130246 4.1669001 -0.90130207 1 P 0 ;0
L 4.1669001 -0.90130207 4.1688997 -0.87880236 1 P 0 ;0
L 4.1688997 -0.87880236 4.1669001 -0.85630256 1 P 0 ;0
L 4.1669001 -0.85630256 4.16090138 -0.83629764 1 P 0 ;0
L 4.16090138 -0.83629764 4.15289951 -0.82130089 1 P 0 ;0
L 4.15289951 -0.82130089 4.14089833 -0.80879902 1 P 0 ;0
L 4.14089833 -0.80879902 4.12489813 -0.8038 1 P 0 ;0
L 4.28489813 -0.9538 4.28489813 -0.8038 1 P 0 ;0
L 4.28489813 -0.8038 4.26089961 -0.83379823 1 P 0 ;0
L 4.26089961 -0.9538 4.30889665 -0.9538 1 P 0 ;0
L 4.44089902 -0.9538 4.44489813 -0.92130246 1 P 0 ;0
L 4.44489813 -0.92130246 4.45090049 -0.89380374 1 P 0 ;0
L 4.45090049 -0.89380374 4.45889882 -0.8687999 1 P 0 ;0
L 4.45889882 -0.8687999 4.4689003 -0.84130118 1 P 0 ;0
L 4.4689003 -0.84130118 4.48490059 -0.8038 1 P 0 ;0
L 4.48490059 -0.8038 4.40489931 -0.8038 1 P 0 ;0
L 1.9639003 -1.6638 1.93590197 -1.6638 1 P 0 ;0
L 1.94990108 -1.6638 1.94990108 -1.7538 1 P 0 ;0
L 1.9639003 -1.7538 1.93590197 -1.7538 1 P 0 ;0
L 1.88673297 -1.7538 1.88673297 -1.6638 1 P 0 ;0
L 1.88673297 -1.6638 1.83306713 -1.7538 1 P 0 ;0
L 1.83306713 -1.7538 1.83306713 -1.6638 1 P 0 ;0
L 1.76990108 -1.6638 1.76990108 -1.7538 1 P 0 ;0
L 1.79673297 -1.6638 1.74306713 -1.6638 1 P 0 ;0
L 1.65656634 -1.7538 1.70323376 -1.7538 1 P 0 ;0
L 1.70323376 -1.7538 1.70323376 -1.6638 1 P 0 ;0
L 1.70323376 -1.6638 1.65656634 -1.6638 1 P 0 ;0
L 1.67523327 -1.70729902 1.70323376 -1.70729902 1 P 0 ;0
L 1.61323376 -1.7538 1.61323376 -1.6638 1 P 0 ;0
L 1.61323376 -1.6638 1.58406693 -1.6638 1 P 0 ;0
L 1.58406693 -1.6638 1.57473346 -1.66830187 1 P 0 ;0
L 1.57473346 -1.66830187 1.56889921 -1.67430059 1 P 0 ;0
L 1.56889921 -1.67430059 1.56656634 -1.68630069 1 P 0 ;0
L 1.56656634 -1.68630069 1.56889921 -1.69830089 1 P 0 ;0
L 1.56889921 -1.69830089 1.5758998 -1.70579931 1 P 0 ;0
L 1.5758998 -1.70579931 1.58406693 -1.71030108 1 P 0 ;0
L 1.58406693 -1.71030108 1.61323376 -1.71030108 1 P 0 ;0
L 1.58406693 -1.71030108 1.56656634 -1.7538 1 P 0 ;0
L 1.52673297 -1.7538 1.52673297 -1.6638 1 P 0 ;0
L 1.52673297 -1.6638 1.47306713 -1.7538 1 P 0 ;0
L 1.47306713 -1.7538 1.47306713 -1.6638 1 P 0 ;0
L 1.43906791 -1.7538 1.40990108 -1.6638 1 P 0 ;0
L 1.40990108 -1.6638 1.38073219 -1.7538 1 P 0 ;0
L 1.39123415 -1.72230128 1.42856811 -1.72230128 1 P 0 ;0
L 1.34323376 -1.6638 1.34323376 -1.7538 1 P 0 ;0
L 1.34323376 -1.7538 1.29656634 -1.7538 1 P 0 ;0
L 1.16323376 -1.6638 1.16323376 -1.7538 1 P 0 ;0
L 1.16323376 -1.7538 1.11656634 -1.7538 1 P 0 ;0
L 1.07906791 -1.7538 1.04990108 -1.6638 1 P 0 ;0
L 1.04990108 -1.6638 1.02073219 -1.7538 1 P 0 ;0
L 1.03123415 -1.72230128 1.06856811 -1.72230128 1 P 0 ;0
L 0.95990108 -1.7538 0.95990108 -1.71330049 1 P 0 ;0
L 0.95990108 -1.71330049 0.98323376 -1.6638 1 P 0 ;0
L 0.93656634 -1.6638 0.95990108 -1.71330049 1 P 0 ;0
L 0.84656634 -1.7538 0.89323376 -1.7538 1 P 0 ;0
L 0.89323376 -1.7538 0.89323376 -1.6638 1 P 0 ;0
L 0.89323376 -1.6638 0.84656634 -1.6638 1 P 0 ;0
L 0.86523327 -1.70729902 0.89323376 -1.70729902 1 P 0 ;0
L 0.80323376 -1.7538 0.80323376 -1.6638 1 P 0 ;0
L 0.80323376 -1.6638 0.77406693 -1.6638 1 P 0 ;0
L 0.77406693 -1.6638 0.76473346 -1.66830187 1 P 0 ;0
L 0.76473346 -1.66830187 0.75889921 -1.67430059 1 P 0 ;0
L 0.75889921 -1.67430059 0.75656634 -1.68630069 1 P 0 ;0
L 0.75656634 -1.68630069 0.75889921 -1.69830089 1 P 0 ;0
L 0.75889921 -1.69830089 0.7658998 -1.70579931 1 P 0 ;0
L 0.7658998 -1.70579931 0.77406693 -1.71030108 1 P 0 ;0
L 0.77406693 -1.71030108 0.80323376 -1.71030108 1 P 0 ;0
L 0.77406693 -1.71030108 0.75656634 -1.7538 1 P 0 ;0
L 0.59990108 -1.7538 0.59173406 -1.75230039 1 P 0 ;0
L 0.59173406 -1.75230039 0.58240059 -1.74780138 1 P 0 ;0
L 0.58240059 -1.74780138 0.57656634 -1.74030295 1 P 0 ;0
L 0.57656634 -1.74030295 0.57423356 -1.7297997 1 P 0 ;0
L 0.57423356 -1.7297997 0.57656634 -1.71930197 1 P 0 ;0
L 0.57656634 -1.71930197 0.58356703 -1.71030108 1 P 0 ;0
L 0.58356703 -1.71030108 0.59406693 -1.70579931 1 P 0 ;0
L 0.59406693 -1.70579931 0.60573317 -1.70579931 1 P 0 ;0
L 0.60573317 -1.70579931 0.61273386 -1.7028 1 P 0 ;0
L 0.61273386 -1.7028 0.61856811 -1.69530157 1 P 0 ;0
L 0.61856811 -1.69530157 0.62090089 -1.68480108 1 P 0 ;0
L 0.62090089 -1.68480108 0.61739951 -1.67430059 1 P 0 ;0
L 0.61739951 -1.67430059 0.60923455 -1.66679941 1 P 0 ;0
L 0.60923455 -1.66679941 0.59990108 -1.6638 1 P 0 ;0
L 0.59990108 -1.6638 0.59056762 -1.66679941 1 P 0 ;0
L 0.59056762 -1.66679941 0.58240059 -1.67430059 1 P 0 ;0
L 0.58240059 -1.67430059 0.57889921 -1.68480108 1 P 0 ;0
L 0.57889921 -1.68480108 0.58123415 -1.69530157 1 P 0 ;0
L 0.58123415 -1.69530157 0.58706624 -1.7028 1 P 0 ;0
L 0.58706624 -1.7028 0.59406693 -1.70579931 1 P 0 ;0
L 0.59406693 -1.70579931 0.60573317 -1.70579931 1 P 0 ;0
L 0.60573317 -1.70579931 0.61623307 -1.71030108 1 P 0 ;0
L 0.61623307 -1.71030108 0.62323376 -1.71930197 1 P 0 ;0
L 0.62323376 -1.71930197 0.62556654 -1.7297997 1 P 0 ;0
L 0.62556654 -1.7297997 0.62323376 -1.74030295 1 P 0 ;0
L 0.62323376 -1.74030295 0.61739951 -1.74780138 1 P 0 ;0
L 0.61739951 -1.74780138 0.60806604 -1.75230039 1 P 0 ;0
L 0.60806604 -1.75230039 0.59990108 -1.7538 1 P 0 ;0
L 3.06989892 -2.2538 3.07806594 -2.25230039 1 P 0 ;0
L 3.07806594 -2.25230039 3.08739941 -2.24780138 1 P 0 ;0
L 3.08739941 -2.24780138 3.09323366 -2.24030295 1 P 0 ;0
L 3.09323366 -2.24030295 3.09556644 -2.2297997 1 P 0 ;0
L 3.09556644 -2.2297997 3.09323366 -2.21930197 1 P 0 ;0
L 3.09323366 -2.21930197 3.08623297 -2.21030108 1 P 0 ;0
L 3.08623297 -2.21030108 3.07573307 -2.20579931 1 P 0 ;0
L 3.07573307 -2.20579931 3.06406683 -2.20579931 1 P 0 ;0
L 3.06406683 -2.20579931 3.05706614 -2.2028 1 P 0 ;0
L 3.05706614 -2.2028 3.05123189 -2.19530157 1 P 0 ;0
L 3.05123189 -2.19530157 3.04889911 -2.18480108 1 P 0 ;0
L 3.04889911 -2.18480108 3.05240049 -2.17430059 1 P 0 ;0
L 3.05240049 -2.17430059 3.06056545 -2.16679941 1 P 0 ;0
L 3.06056545 -2.16679941 3.06989892 -2.1638 1 P 0 ;0
L 3.06989892 -2.1638 3.07923238 -2.16679941 1 P 0 ;0
L 3.07923238 -2.16679941 3.08739941 -2.17430059 1 P 0 ;0
L 3.08739941 -2.17430059 3.09090079 -2.18480108 1 P 0 ;0
L 3.09090079 -2.18480108 3.08856585 -2.19530157 1 P 0 ;0
L 3.08856585 -2.19530157 3.08273376 -2.2028 1 P 0 ;0
L 3.08273376 -2.2028 3.07573307 -2.20579931 1 P 0 ;0
L 3.07573307 -2.20579931 3.06406683 -2.20579931 1 P 0 ;0
L 3.06406683 -2.20579931 3.05356693 -2.21030108 1 P 0 ;0
L 3.05356693 -2.21030108 3.04656624 -2.21930197 1 P 0 ;0
L 3.04656624 -2.21930197 3.04423346 -2.2297997 1 P 0 ;0
L 3.04423346 -2.2297997 3.04656624 -2.24030295 1 P 0 ;0
L 3.04656624 -2.24030295 3.05240049 -2.24780138 1 P 0 ;0
L 3.05240049 -2.24780138 3.06173396 -2.25230039 1 P 0 ;0
L 3.06173396 -2.25230039 3.06989892 -2.2538 1 P 0 ;0
L 3.81989892 -2.0038 3.82806594 -2.00230039 1 P 0 ;0
L 3.82806594 -2.00230039 3.83739941 -1.99780138 1 P 0 ;0
L 3.83739941 -1.99780138 3.84323366 -1.99030295 1 P 0 ;0
L 3.84323366 -1.99030295 3.84556644 -1.9797997 1 P 0 ;0
L 3.84556644 -1.9797997 3.84323366 -1.96930197 1 P 0 ;0
L 3.84323366 -1.96930197 3.83623297 -1.96030108 1 P 0 ;0
L 3.83623297 -1.96030108 3.82573307 -1.95579931 1 P 0 ;0
L 3.82573307 -1.95579931 3.81406683 -1.95579931 1 P 0 ;0
L 3.81406683 -1.95579931 3.80706614 -1.9528 1 P 0 ;0
L 3.80706614 -1.9528 3.80123189 -1.94530157 1 P 0 ;0
L 3.80123189 -1.94530157 3.79889911 -1.93480108 1 P 0 ;0
L 3.79889911 -1.93480108 3.80240049 -1.92430059 1 P 0 ;0
L 3.80240049 -1.92430059 3.81056545 -1.91679941 1 P 0 ;0
L 3.81056545 -1.91679941 3.81989892 -1.9138 1 P 0 ;0
L 3.81989892 -1.9138 3.82923238 -1.91679941 1 P 0 ;0
L 3.82923238 -1.91679941 3.83739941 -1.92430059 1 P 0 ;0
L 3.83739941 -1.92430059 3.84090079 -1.93480108 1 P 0 ;0
L 3.84090079 -1.93480108 3.83856585 -1.94530157 1 P 0 ;0
L 3.83856585 -1.94530157 3.83273376 -1.9528 1 P 0 ;0
L 3.83273376 -1.9528 3.82573307 -1.95579931 1 P 0 ;0
L 3.82573307 -1.95579931 3.81406683 -1.95579931 1 P 0 ;0
L 3.81406683 -1.95579931 3.80356693 -1.96030108 1 P 0 ;0
L 3.80356693 -1.96030108 3.79656624 -1.96930197 1 P 0 ;0
L 3.79656624 -1.96930197 3.79423346 -1.9797997 1 P 0 ;0
L 3.79423346 -1.9797997 3.79656624 -1.99030295 1 P 0 ;0
L 3.79656624 -1.99030295 3.80240049 -1.99780138 1 P 0 ;0
L 3.80240049 -1.99780138 3.81173396 -2.00230039 1 P 0 ;0
L 3.81173396 -2.00230039 3.81989892 -2.0038 1 P 0 ;0

### steps/drc/layers/l9/features
#
#Feature symbol names
#
$0 r2
$1 r6
$2 r15
$3 r20
$4 r28
$5 r30
$6 r32
$7 r33
$8 r40
$9 r50
$10 r57.09
$11 r78.74
$12 r86.61
$13 r90.55
$14 r100
$15 r131.89
$16 r137.8
$17 r161.42
$18 r168.31
$19 r173.23
$20 r181.1
$21 r204.72
$22 r224.41
$23 r440.94
$24 null
$25 oval236.22x177.17
$26 thr61.02x49.21x45x4x15.75
$27 thr96.46x76.77x45x4x19.69

#
#Feature attribute names
#
@0 .nomenclature
@1 .geometry

#
#Feature attribute text strings
#
&0 TPB30V20D10AT28BPM
&1 C1_11P0_7
&2 C1_11P0_7TP
&3 V17D8AT30SM11
&4 V20D10AT28SM14
&5 C2_5N
&6 S1_11P0_7TP
&7 S1_11P0_7
&8 V20D10AT28PG
&9 C1_17P0_76TPM
&10 C1_9P1_4
&11 S1_9P1_4
&12 SP-8C5_2P0_254
&13 SP-9C5_7P0_254
&14 C3_175N-A
&15 C10N
&16 C3_3N
&17 C4_5N-B
&18 C4N-B
&19 C3_5N
&20 O5X3_5N
&21 C3N
&22 C1_3N
&23 C2_35N
&24 C1N

#
#Layer features
#
P 7.785 4.45 4 P 0 0;1=0
P 7.835 4.45 4 P 0 0;1=0
P 1.8 4.485 4 P 0 0;1=0
P 1.86 4.485 4 P 0 0;1=0
P 0.27165 1.72835 10 P 0 0;1=1
P 0.17323002 2.12205 10 P 0 0;1=1
P 12.73621004 1.76771998 10 P 0 0;1=1
P 12.81495 2.59448996 10 P 0 0;1=1
P 12.63778996 2.16141998 10 P 0 0;1=1
P 0.725 -0.25 10 P 0 0;1=2
P 0.875 -0.25 10 P 0 0;1=2
P 1.065 6.26 10 P 0 0;1=2
P 1.065 6.36 10 P 0 0;1=2
P 1.29 6.26 10 P 0 0;1=2
P 1.29 6.36 10 P 0 0;1=2
P 1.515 6.26 10 P 0 0;1=2
P 1.515 6.36 10 P 0 0;1=2
P 0.84 6.26 10 P 0 0;1=2
P 0.84 6.36 10 P 0 0;1=2
P 1.74 6.26 10 P 0 0;1=2
P 1.74 6.36 10 P 0 0;1=2
P 2.09606004 3.56615 5 P 0 0;1=3
P 8.1 3.56615 5 P 0 0;1=3
P 12.55905 3.38188996 10 P 0 0;1=1
P 12.81495 4.64173996 10 P 0 0;1=1
P 12.81495 1.88583002 10 P 0 0;1=1
P 0.35038996 4.60236998 10 P 0 0;1=1
P 0.35038996 2.55511998 10 P 0 0;1=1
P 0.35038996 1.84646004 10 P 0 0;1=1
P 0.09448996 3.34251998 10 P 0 0;1=1
P 6.385 5.03 4 P 0 0;1=4
P 12.68701998 0.97243996 16 P 0 0;1=5
P 0.22245 0.93306998 16 P 0 0;1=5
P 12.68701004 4.91338002 16 P 0 0;1=5
P 3.94 4.545 4 P 0 0;1=0
P 4.91 5.375 4 P 0 0;1=4
P 1.08 5.85 4 P 0 0;1=0
P 3.6817 5.74 4 P 0 0;1=4
P 10.07 2.928 4 P 0 0;1=4
P 4.105 4.985 4 P 0 0;1=0
P 4.125 2.725 4 P 0 0;1=4
P 4.02 4.355 4 P 0 0;1=0
P 1.16 5.85 4 P 0 0;1=0
P 3.815 5.815 4 P 0 0;1=4
P 1.19 6.36 26 P 0 3;1=6
P 1.19 6.26 26 P 0 3;1=6
P 1.415 6.36 26 P 0 3;1=6
P 1.415 6.26 26 P 0 3;1=6
P 1.64 6.36 26 P 0 3;1=6
P 1.64 6.26 26 P 0 3;1=6
P 0.965 6.26 26 P 0 3;1=6
P 0.965 6.36 26 P 0 3;1=6
P 0.74 6.26 26 P 0 3;1=6
P 0.74 6.36 26 P 0 3;1=6
P 12.63778996 1.37401998 10 P 0 0;1=7
P 0.17323002 1.33465 10 P 0 0;1=7
P 6.501 5.017 4 P 0 0;1=0
P 7.425 3.43 4 P 0 0;1=0
P 7.445 1.705 4 P 0 0;1=4
P 11.03661004 3.81615 5 P 0 0;1=3
P 11.135 2.845 4 P 0 0;1=4
P 11.03661004 2.16615 5 P 0 0;1=3
P 3.8899 4.765 4 P 0 0;1=0
P 4.93268002 2.41615 5 P 0 0;1=3
P 4.93268002 2.46615 5 P 0 0;1=3
P 7.2926 5.04351004 4 P 0 0;1=0
P 7.2426 5.04351004 4 P 0 0;1=0
P 3.45646004 5.3 4 P 0 0;1=0
P 1.28906004 5.04351004 4 P 0 0;1=0
P 1.23906004 5.04351004 4 P 0 0;1=0
P 9.46 5.3 4 P 0 0;1=0
P 4.68268002 2.36615 5 P 0 0;1=3
P 0.27165 4.01181004 10 P 0 0;1=1
P 4.58268002 2.36615 5 P 0 0;1=3
P 0.27165 4.16928996 10 P 0 0;1=1
P 4.63268002 2.41615 5 P 0 0;1=3
P 0.27165 4.32676998 10 P 0 0;1=1
P 4.73268002 2.26615 5 P 0 0;1=3
P 0.27165 3.38188996 10 P 0 0;1=1
P 4.73268002 2.41615 5 P 0 0;1=3
P 0.27165 4.48425 10 P 0 0;1=1
P 4.68268002 2.21615 5 P 0 0;1=3
P 0.27165 3.53936998 10 P 0 0;1=1
P 4.63268002 2.26615 5 P 0 0;1=3
P 0.27165 3.85433002 10 P 0 0;1=1
P 4.58268002 2.06615 5 P 0 0;1=3
P 0.35038996 3.02756004 10 P 0 0;1=1
P 4.58268002 2.11615 5 P 0 0;1=3
P 0.27165 2.98818996 10 P 0 0;1=1
P 4.63268002 1.86615 5 P 0 0;1=3
P 0.35038996 2.3189 10 P 0 0;1=1
P 4.58268002 1.96615 5 P 0 0;1=3
P 0.27165 2.43701004 10 P 0 0;1=1
P 4.68268002 2.06615 5 P 0 0;1=3
P 0.35038996 3.18503996 10 P 0 0;1=1
P 4.58268002 1.91615 5 P 0 0;1=3
P 0.35038996 2.47638002 10 P 0 0;1=1
P 0.27165 2.27953002 10 P 0 0;1=1
P 4.63268002 1.91615 5 P 0 0;1=3
P 5.42048002 1.7396 5 P 0 0;1=3
P 0.09448996 2.55511998 10 P 0 0;1=1
P 4.68268002 2.11615 5 P 0 0;1=3
P 0.27165 3.14566998 10 P 0 0;1=1
P 5.42048002 1.7796 5 P 0 0;1=3
P 0.17323002 2.51575 10 P 0 0;1=1
P 4.68268002 1.91615 5 P 0 0;1=3
P 0.35038996 2.16141998 10 P 0 0;1=1
P 4.68268002 1.96615 5 P 0 0;1=3
P 0.27165 2.12205 10 P 0 0;1=1
P 5.57531004 2.0878 5 P 0 0;1=3
P 0.09448996 3.1063 10 P 0 0;1=1
P 5.57531004 2.1278 5 P 0 0;1=3
P 0.17323002 3.06693002 10 P 0 0;1=1
P 5.57531004 2.2232 5 P 0 0;1=3
P 0.17323002 3.46063002 10 P 0 0;1=1
P 5.57531004 2.2632 5 P 0 0;1=3
P 0.09448996 3.42126004 10 P 0 0;1=1
P 5.42048002 2.4662 5 P 0 0;1=3
P 0.09448996 4.05118002 10 P 0 0;1=1
P 5.57531004 2.3986 5 P 0 0;1=3
P 0.09448996 3.8937 10 P 0 0;1=1
P 5.57531004 2.673 5 P 0 0;1=3
P 0.09448996 4.36613996 10 P 0 0;1=1
P 5.57531004 1.9869 5 P 0 0;1=3
P 0.17323002 2.75196998 10 P 0 0;1=1
P 5.57531004 2.4978 5 P 0 0;1=3
P 0.17323002 4.24803002 10 P 0 0;1=1
P 5.57531004 1.6718 5 P 0 0;1=3
P 0.17323002 2.20078996 10 P 0 0;1=1
P 5.57531004 2.633 5 P 0 0;1=3
P 0.17323002 4.40551004 10 P 0 0;1=1
P 5.57531004 1.7118 5 P 0 0;1=3
P 0.09448996 2.24016004 10 P 0 0;1=1
P 5.57531004 2.5378 5 P 0 0;1=3
P 0.09448996 4.20866004 10 P 0 0;1=1
P 5.42048002 1.6433 5 P 0 0;1=3
P 0.09448996 2.39763996 10 P 0 0;1=1
P 5.42048002 2.6054 5 P 0 0;1=3
P 0.09448996 4.52361998 10 P 0 0;1=1
P 5.42048002 1.87835 5 P 0 0;1=3
P 0.09448996 2.94881998 10 P 0 0;1=1
P 5.57531004 2.3586 5 P 0 0;1=3
P 0.17323002 3.93306998 10 P 0 0;1=1
P 5.42048002 1.6033 5 P 0 0;1=3
P 0.17323002 2.35826998 10 P 0 0;1=1
P 5.42048002 2.4262 5 P 0 0;1=3
P 0.17323002 4.09055 10 P 0 0;1=1
P 5.42048002 1.91835 5 P 0 0;1=3
P 0.17323002 2.90945 10 P 0 0;1=1
P 5.42048002 2.0547 5 P 0 0;1=3
P 0.17323002 3.22441004 10 P 0 0;1=1
P 5.57531004 1.9469 5 P 0 0;1=3
P 0.09448996 2.79133996 10 P 0 0;1=1
P 5.42048002 2.0147 5 P 0 0;1=3
P 0.09448996 3.26378002 10 P 0 0;1=1
P 5.57531004 1.8508 5 P 0 0;1=3
P 0.09448996 2.00393996 10 P 0 0;1=1
P 5.57531004 1.8108 5 P 0 0;1=3
P 0.17323002 2.04331004 10 P 0 0;1=1
P 0.35038996 3.97243996 10 P 0 0;1=1
P 4.68268002 2.41615 5 P 0 0;1=3
P 4.73268002 2.46615 5 P 0 0;1=3
P 0.35038996 4.44488002 10 P 0 0;1=1
P 4.63268002 2.46615 5 P 0 0;1=3
P 0.35038996 4.2874 10 P 0 0;1=1
P 0.35038996 4.12991998 10 P 0 0;1=1
P 4.58268002 2.41615 5 P 0 0;1=3
P 4.68268002 2.26615 5 P 0 0;1=3
P 0.35038996 3.5 10 P 0 0;1=1
P 5.42048002 2.1554 5 P 0 0;1=3
P 0.17323002 3.77558996 10 P 0 0;1=1
P 4.73268002 2.31615 5 P 0 0;1=3
P 0.35038996 3.34251998 10 P 0 0;1=1
P 4.63268002 2.31615 5 P 0 0;1=3
P 0.35038996 3.81496004 10 P 0 0;1=1
P 4.58268002 2.26615 5 P 0 0;1=3
P 0.35038996 3.65748002 10 P 0 0;1=1
P 5.42048002 2.5654 5 P 0 0;1=3
P 0.17323002 4.563 10 P 0 0;1=1
P 5.42048002 2.1954 5 P 0 0;1=3
P 0.09448996 3.73621998 10 P 0 0;1=1
P 0.09448996 3.57873996 10 P 0 0;1=1
P 5.42048002 2.3308 5 P 0 0;1=3
P 0.17323002 3.61811004 10 P 0 0;1=1
P 5.42048002 2.2908 5 P 0 0;1=3
P 0.35038996 1.9252 10 P 0 0;1=1
P 4.73268002 1.91615 5 P 0 0;1=3
P 4.73268002 1.86615 5 P 0 0;1=3
P 0.27165 1.96456998 10 P 0 0;1=1
P 4.58268002 2.21615 5 P 0 0;1=3
P 0.27165 3.69685 10 P 0 0;1=1
P 4.73268002 2.06615 5 P 0 0;1=3
P 0.27165 2.67323002 10 P 0 0;1=1
P 4.73268002 2.01615 5 P 0 0;1=3
P 0.35038996 2.7126 10 P 0 0;1=1
P 4.63268002 2.01615 5 P 0 0;1=3
P 0.35038996 2.87008002 10 P 0 0;1=1
P 4.63268002 2.06615 5 P 0 0;1=3
P 0.27165 2.83071004 10 P 0 0;1=1
P 6.785 4.725 4 P 0 0;1=4
P 6.785 4.685 4 P 0 0;1=4
P 6.74018996 4.765 4 P 0 0;1=4
P 6.74 4.805 4 P 0 0;1=0
P 6.785 4.845 4 P 0 0;1=4
P 6.785 4.805 4 P 0 0;1=4
P 6.785 4.765 4 P 0 0;1=4
P 6.74 4.845 4 P 0 0;1=4
P 6.65 5.055 4 P 0 0;1=0
P 6.49205 5.09705 4 P 0 0;1=0
P 6.495 4.9328 4 P 0 0;1=0
P 6.55118996 5.04705 4 P 0 0;1=0
P 6.78 4.94705 4 P 0 0;1=0
P 6.755 4.89705 4 P 0 0;1=0
P 6.74 4.987 4 P 0 0;1=0
P 12.73621004 2.08268002 10 P 0 0;1=1
P 12.73621004 2.63386004 10 P 0 0;1=1
P 12.81495 3.30315 10 P 0 0;1=1
P 12.73621004 4.60236998 10 P 0 0;1=1
P 12.55905 1.96456998 10 P 0 0;1=1
P 12.63778996 1.9252 10 P 0 0;1=1
P 0.09448996 1.9252 10 P 0 0;1=1
P 0.17323002 1.88583002 10 P 0 0;1=1
P 0.27165 2.04331004 10 P 0 0;1=1
P 0.27165 4.563 10 P 0 0;1=1
P 0.35038996 3.26378002 10 P 0 0;1=1
P 0.27165 2.59448996 10 P 0 0;1=1
P 0.17323002 1.72835 10 P 0 0;1=1
P 5.03268002 1.91615 5 P 0 0;1=3
P 1.025 -0.25 10 P 0 0;1=2
P 1.175 -0.25 10 P 0 0;1=2
P 1.325 -0.25 10 P 0 0;1=2
P 5.03268002 2.06615 5 P 0 0;1=3
P 12.63778996 4.12991998 10 P 0 0;1=1
P 11.53316004 2.372 5 P 0 0;1=3
P 5.08268002 2.26615 5 P 0 0;1=3
P 11.53316004 1.892 5 P 0 0;1=3
P 12.55905 3.30315 10 P 0 0;1=1
P 12.81495 2.51575 10 P 0 0;1=1
P 10.58661004 1.91615 5 P 0 0;1=3
P 10.26 1.66445 5 P 0 0;1=3
P 11.03998996 4.8431 4 P 0 0;1=4
P 11.08498996 4.8431 4 P 0 0;1=4
P 11.13498996 4.8431 4 P 0 0;1=4
P 11.17998996 4.8431 4 P 0 0;1=4
P 11.17998996 4.8031 4 P 0 0;1=4
P 11.17998996 4.7581 4 P 0 0;1=4
P 11.17998996 4.7131 4 P 0 0;1=4
P 11.17998996 4.6731 4 P 0 0;1=4
P 11.03998996 4.6731 4 P 0 0;1=4
P 11.08498996 4.6731 4 P 0 0;1=4
P 11.13498996 4.6731 4 P 0 0;1=4
P 11.03998996 4.7131 4 P 0 0;1=4
P 11.03998996 4.8031 4 P 0 0;1=4
P 11.03998996 4.7581 4 P 0 0;1=4
P 10.81998996 4.6631 4 P 0 0;1=4
P 10.85998996 4.6631 4 P 0 0;1=4
P 10.65998996 4.6631 4 P 0 0;1=4
P 10.69998996 4.6631 4 P 0 0;1=4
P 10.81998996 4.7031 4 P 0 0;1=4
P 10.81998996 4.8381 4 P 0 0;1=4
P 10.81998996 4.7931 4 P 0 0;1=4
P 10.81998996 4.7481 4 P 0 0;1=4
P 10.85998996 4.7031 4 P 0 0;1=4
P 10.85998996 4.8381 4 P 0 0;1=4
P 10.85998996 4.7931 4 P 0 0;1=4
P 10.85998996 4.7481 4 P 0 0;1=4
P 10.65998996 4.7031 4 P 0 0;1=4
P 10.65998996 4.8381 4 P 0 0;1=4
P 10.65998996 4.7931 4 P 0 0;1=4
P 10.65998996 4.7481 4 P 0 0;1=4
P 10.69998996 4.7031 4 P 0 0;1=4
P 10.69998996 4.8381 4 P 0 0;1=4
P 10.69998996 4.7931 4 P 0 0;1=4
P 10.69998996 4.7481 4 P 0 0;1=4
P 10.77998996 4.6431 4 P 0 0;1=4
P 10.73498996 4.6431 4 P 0 0;1=4
P 10.73998996 4.8381 4 P 0 0;1=4
P 10.77998996 4.8381 4 P 0 0;1=4
P 10.30998996 4.6631 4 P 0 0;1=4
P 10.26998996 4.6631 4 P 0 0;1=4
P 10.34498996 4.6431 4 P 0 0;1=4
P 10.38998996 4.6431 4 P 0 0;1=4
P 10.42998996 4.6631 4 P 0 0;1=4
P 10.46998996 4.6631 4 P 0 0;1=4
P 10.30998996 4.7481 4 P 0 0;1=4
P 10.30998996 4.7931 4 P 0 0;1=4
P 10.30998996 4.7031 4 P 0 0;1=4
P 10.26998996 4.7481 4 P 0 0;1=4
P 10.26998996 4.7931 4 P 0 0;1=4
P 10.26998996 4.7031 4 P 0 0;1=4
P 10.26998996 4.8381 4 P 0 0;1=4
P 10.30998996 4.8381 4 P 0 0;1=4
P 10.38998996 4.8381 4 P 0 0;1=4
P 10.34998996 4.8381 4 P 0 0;1=4
P 10.46998996 4.8381 4 P 0 0;1=4
P 10.42998996 4.8381 4 P 0 0;1=4
P 10.42998996 4.7031 4 P 0 0;1=4
P 10.42998996 4.7931 4 P 0 0;1=4
P 10.42998996 4.7481 4 P 0 0;1=4
P 10.46998996 4.7031 4 P 0 0;1=4
P 10.46998996 4.7931 4 P 0 0;1=4
P 10.46998996 4.7481 4 P 0 0;1=4
P 10.58661004 3.16615 5 P 0 0;1=3
P 10.63661004 3.01615 5 P 0 0;1=3
P 10.58661004 3.11615 5 P 0 0;1=3
P 10.58661004 3.01615 5 P 0 0;1=3
P 10.63661004 3.11615 5 P 0 0;1=3
P 10.63661004 2.96615 5 P 0 0;1=3
P 10.58661004 2.96615 5 P 0 0;1=3
P 10.58661004 3.41615 5 P 0 0;1=3
P 10.63661004 3.16615 5 P 0 0;1=3
P 10.63661004 3.26615 5 P 0 0;1=3
P 10.58661004 3.31615 5 P 0 0;1=3
P 10.58661004 3.26615 5 P 0 0;1=3
P 10.63661004 3.31615 5 P 0 0;1=3
P 10.63661004 3.56615 5 P 0 0;1=3
P 10.63661004 3.61615 5 P 0 0;1=3
P 10.58661004 3.56615 5 P 0 0;1=3
P 10.58661004 3.61615 5 P 0 0;1=3
P 10.63661004 3.46615 5 P 0 0;1=3
P 10.63661004 3.41615 5 P 0 0;1=3
P 10.58661004 3.46615 5 P 0 0;1=3
P 10.63661004 3.86615 5 P 0 0;1=3
P 10.63661004 3.76615 5 P 0 0;1=3
P 10.58661004 3.86615 5 P 0 0;1=3
P 10.58661004 3.76615 5 P 0 0;1=3
P 10.63661004 3.71615 5 P 0 0;1=3
P 10.58661004 3.71615 5 P 0 0;1=3
P 10.88661004 2.96615 5 P 0 0;1=3
P 10.83661004 2.96615 5 P 0 0;1=3
P 10.88661004 3.01615 5 P 0 0;1=3
P 10.83661004 3.01615 5 P 0 0;1=3
P 10.88661004 3.11615 5 P 0 0;1=3
P 10.83661004 3.11615 5 P 0 0;1=3
P 10.83661004 3.16615 5 P 0 0;1=3
P 10.78661004 3.16615 5 P 0 0;1=3
P 10.68661004 3.16615 5 P 0 0;1=3
P 10.73661004 3.16615 5 P 0 0;1=3
P 10.78661004 3.01615 5 P 0 0;1=3
P 10.78661004 3.11615 5 P 0 0;1=3
P 10.73661004 3.01615 5 P 0 0;1=3
P 10.73661004 3.11615 5 P 0 0;1=3
P 10.68661004 3.01615 5 P 0 0;1=3
P 10.68661004 3.11615 5 P 0 0;1=3
P 10.78661004 2.96615 5 P 0 0;1=3
P 10.73661004 2.96615 5 P 0 0;1=3
P 10.68661004 2.96615 5 P 0 0;1=3
P 10.88661004 3.16615 5 P 0 0;1=3
P 10.88661004 3.26615 5 P 0 0;1=3
P 10.83661004 3.26615 5 P 0 0;1=3
P 10.83661004 3.31615 5 P 0 0;1=3
P 10.88661004 3.31615 5 P 0 0;1=3
P 10.83661004 3.41615 5 P 0 0;1=3
P 10.78661004 3.41615 5 P 0 0;1=3
P 10.68661004 3.41615 5 P 0 0;1=3
P 10.73661004 3.41615 5 P 0 0;1=3
P 10.78661004 3.31615 5 P 0 0;1=3
P 10.78661004 3.26615 5 P 0 0;1=3
P 10.68661004 3.31615 5 P 0 0;1=3
P 10.68661004 3.26615 5 P 0 0;1=3
P 10.73661004 3.26615 5 P 0 0;1=3
P 10.73661004 3.31615 5 P 0 0;1=3
P 10.88661004 3.41615 5 P 0 0;1=3
P 10.83661004 3.46615 5 P 0 0;1=3
P 10.88661004 3.46615 5 P 0 0;1=3
P 10.83661004 3.56615 5 P 0 0;1=3
P 10.88661004 3.56615 5 P 0 0;1=3
P 10.83661004 3.61615 5 P 0 0;1=3
P 10.88661004 3.61615 5 P 0 0;1=3
P 10.78661004 3.56615 5 P 0 0;1=3
P 10.78661004 3.61615 5 P 0 0;1=3
P 10.68661004 3.61615 5 P 0 0;1=3
P 10.68661004 3.56615 5 P 0 0;1=3
P 10.73661004 3.61615 5 P 0 0;1=3
P 10.73661004 3.56615 5 P 0 0;1=3
P 10.78661004 3.46615 5 P 0 0;1=3
P 10.73661004 3.46615 5 P 0 0;1=3
P 10.68661004 3.46615 5 P 0 0;1=3
P 10.83661004 3.71615 5 P 0 0;1=3
P 10.88661004 3.71615 5 P 0 0;1=3
P 10.83661004 3.76615 5 P 0 0;1=3
P 10.88661004 3.76615 5 P 0 0;1=3
P 10.83661004 3.86615 5 P 0 0;1=3
P 10.88661004 3.86615 5 P 0 0;1=3
P 10.78661004 3.86615 5 P 0 0;1=3
P 10.78661004 3.76615 5 P 0 0;1=3
P 10.68661004 3.86615 5 P 0 0;1=3
P 10.68661004 3.76615 5 P 0 0;1=3
P 10.73661004 3.86615 5 P 0 0;1=3
P 10.73661004 3.76615 5 P 0 0;1=3
P 10.78661004 3.71615 5 P 0 0;1=3
P 10.68661004 3.71615 5 P 0 0;1=3
P 10.73661004 3.71615 5 P 0 0;1=3
P 11.03661004 2.96615 5 P 0 0;1=3
P 10.93661004 2.96615 5 P 0 0;1=3
P 10.98661004 2.96615 5 P 0 0;1=3
P 11.03661004 3.01615 5 P 0 0;1=3
P 10.93661004 3.01615 5 P 0 0;1=3
P 10.98661004 3.01615 5 P 0 0;1=3
P 11.03661004 3.11615 5 P 0 0;1=3
P 10.93661004 3.11615 5 P 0 0;1=3
P 10.98661004 3.11615 5 P 0 0;1=3
P 11.03661004 3.16615 5 P 0 0;1=3
P 10.93661004 3.16615 5 P 0 0;1=3
P 10.98661004 3.16615 5 P 0 0;1=3
P 11.03661004 3.26615 5 P 0 0;1=3
P 10.93661004 3.26615 5 P 0 0;1=3
P 10.98661004 3.26615 5 P 0 0;1=3
P 10.98661004 3.31615 5 P 0 0;1=3
P 10.93661004 3.31615 5 P 0 0;1=3
P 11.03661004 3.31615 5 P 0 0;1=3
P 10.98661004 3.41615 5 P 0 0;1=3
P 10.93661004 3.41615 5 P 0 0;1=3
P 11.03661004 3.41615 5 P 0 0;1=3
P 10.98661004 3.46615 5 P 0 0;1=3
P 10.93661004 3.46615 5 P 0 0;1=3
P 11.03661004 3.46615 5 P 0 0;1=3
P 10.98661004 3.56615 5 P 0 0;1=3
P 10.93661004 3.56615 5 P 0 0;1=3
P 11.03661004 3.56615 5 P 0 0;1=3
P 10.98661004 3.61615 5 P 0 0;1=3
P 10.93661004 3.61615 5 P 0 0;1=3
P 11.03661004 3.61615 5 P 0 0;1=3
P 10.98661004 3.71615 5 P 0 0;1=3
P 10.93661004 3.71615 5 P 0 0;1=3
P 11.03661004 3.71615 5 P 0 0;1=3
P 10.98661004 3.76615 5 P 0 0;1=3
P 10.93661004 3.76615 5 P 0 0;1=3
P 11.03661004 3.76615 5 P 0 0;1=3
P 10.98661004 3.86615 5 P 0 0;1=3
P 10.93661004 3.86615 5 P 0 0;1=3
P 11.03661004 3.86615 5 P 0 0;1=3
P 5.08268002 2.06615 5 P 0 0;1=3
P 10.58661004 2.36615 5 P 0 0;1=3
P 9.975 2.4709 5 P 0 0;1=3
P 12.73621004 4.20866004 10 P 0 0;1=1
P 11.08661004 2.36615 5 P 0 0;1=3
P 5.08268002 2.11615 5 P 0 0;1=3
P 11.08661004 2.41615 5 P 0 0;1=3
P 12.73621004 2.47638002 10 P 0 0;1=1
P 10.58661004 1.96615 5 P 0 0;1=3
P 10.26 1.70445 5 P 0 0;1=3
P 10.98661004 2.41615 5 P 0 0;1=3
P 8.5 3.76615 5 P 0 0;1=3
P 9.35271004 5.1035 5 P 0 0;1=3
P 4.98268002 2.06615 5 P 0 0;1=3
P 8.5 3.81615 5 P 0 0;1=3
P 9.31271004 5.1035 5 P 0 0;1=3
P 12.55905 2.59448996 10 P 0 0;1=1
P 11.53316004 1.572 5 P 0 0;1=3
P 4.98268002 2.11615 5 P 0 0;1=3
P 10.98661004 2.36615 5 P 0 0;1=3
P 8.5 3.61615 5 P 0 0;1=3
P 9.56531004 5.14 5 P 0 0;1=3
P 4.93268002 2.01615 5 P 0 0;1=3
P 11.53316004 1.412 5 P 0 0;1=3
P 12.63778996 2.39763996 10 P 0 0;1=1
P 8.5 3.66615 5 P 0 0;1=3
P 9.52531004 5.14 5 P 0 0;1=3
P 12.73621004 2.87008002 10 P 0 0;1=1
P 10.63661004 2.06615 5 P 0 0;1=3
P 10.225 1.96645 5 P 0 0;1=3
P 11.53316004 1.452 5 P 0 0;1=3
P 12.55905 2.43701004 10 P 0 0;1=1
P 8.35 3.66615 5 P 0 0;1=3
P 9.56531004 4.71973002 5 P 0 0;1=3
P 4.93268002 2.06615 5 P 0 0;1=3
P 8.35 3.71615 5 P 0 0;1=3
P 9.52531004 4.71973002 5 P 0 0;1=3
P 11.83316004 2.212 5 P 0 0;1=3
P 12.63778996 3.65748002 10 P 0 0;1=1
P 12.73621004 3.02756004 10 P 0 0;1=1
P 10.58661004 2.11615 5 P 0 0;1=3
P 10.09 2.05655 5 P 0 0;1=3
P 11.53316004 1.932 5 P 0 0;1=3
P 12.63778996 3.26378002 10 P 0 0;1=1
P 8.74578996 5.14 5 P 0 0;1=3
P 8.05 3.61615 5 P 0 0;1=3
P 12.81495 4.01181004 10 P 0 0;1=1
P 10.09 2.57845 5 P 0 0;1=3
P 10.68661004 2.41615 5 P 0 0;1=3
P 11.73316004 1.492 5 P 0 0;1=3
P 12.63778996 2.24016004 10 P 0 0;1=1
P 8.78578996 5.14 5 P 0 0;1=3
P 8.05 3.66615 5 P 0 0;1=3
P 12.73621004 2.7126 10 P 0 0;1=1
P 10.73661004 2.06615 5 P 0 0;1=3
P 10.26025 1.86845 5 P 0 0;1=3
P 11.03661004 2.46615 5 P 0 0;1=3
P 8.15 3.61615 5 P 0 0;1=3
P 8.88441004 5.17001998 5 P 0 0;1=3
P 12.55905 4.09055 10 P 0 0;1=1
P 11.53316004 2.412 5 P 0 0;1=3
P 11.03661004 2.51615 5 P 0 0;1=3
P 8.15 3.66615 5 P 0 0;1=3
P 8.92441004 5.17001998 5 P 0 0;1=3
P 1.057 5.027 4 P 0 0;1=0
P 12.73621004 3.18503996 10 P 0 0;1=1
P 10.68661004 2.11615 5 P 0 0;1=3
P 10.09 2.17095 5 P 0 0;1=3
P 11.78316004 1.692 5 P 0 0;1=3
P 12.55905 2.04331004 10 P 0 0;1=1
P 12.81495 2.90945 10 P 0 0;1=1
P 10.63661004 2.01615 5 P 0 0;1=3
P 10.225 1.92645 5 P 0 0;1=3
P 11.78316004 1.652 5 P 0 0;1=3
P 12.63778996 2.08268002 10 P 0 0;1=1
P 1.122 5.417 4 P 0 0;1=4
P 5.855 0.925 4 P 0 0;1=4
P 3.88 4.545 4 P 0 0;1=0
P 0.96555 5.78055 4 P 0 0;1=0
P 4.07 4.625 4 P 0 0;1=4
P 10.58661004 2.71615 5 P 0 0;1=3
P 9.91 4.433 4 P 0 0;1=0
P 9.995 2.936 4 P 0 0;1=4
P 11.83316004 2.252 5 P 0 0;1=3
P 12.55905 3.61811004 10 P 0 0;1=1
P 12.81495 3.06693002 10 P 0 0;1=1
P 10.58661004 2.06615 5 P 0 0;1=3
P 10.09 2.01655 5 P 0 0;1=3
P 8.1 3.81615 5 P 0 0;1=3
P 9.10011004 5.0535 5 P 0 0;1=3
P 8.1 3.86615 5 P 0 0;1=3
P 9.14011004 5.0535 5 P 0 0;1=3
P 3.9599 5.395 4 P 0 0;1=0
P 0.88681004 5.78181004 4 P 0 0;1=4
P 12.73621004 2.3189 10 P 0 0;1=1
P 10.63661004 1.91615 5 P 0 0;1=3
P 10.38371998 1.49328002 5 P 0 0;1=3
P 8.35 3.81615 5 P 0 0;1=3
P 9.28185 5.22001998 5 P 0 0;1=3
P 0.72933002 5.463 4 P 0 0;1=0
P 11.53316004 2.572 5 P 0 0;1=3
P 12.55905 4.56298996 10 P 0 0;1=1
P 8.35 3.86615 5 P 0 0;1=3
P 9.24185 5.22001998 5 P 0 0;1=3
P 4.125 2.682 4 P 0 0;1=4
P 3.94 4.42 4 P 0 0;1=0
P 5.03 5.4 4 P 0 0;1=4
P 4.58268002 2.71615 5 P 0 0;1=3
P 8.45 3.81615 5 P 0 0;1=3
P 9.21098002 4.78291998 5 P 0 0;1=3
P 8.45 3.86615 5 P 0 0;1=3
P 9.17098002 4.78291998 5 P 0 0;1=3
P 3.75998996 0.24001004 4 P 0 0;1=0
P 9.55795 0.26133996 4 P 0 0;1=0
P 3.71203002 0.77535 4 P 0 0;1=4
P 3.70998996 0.7 4 P 0 0;1=4
P 9.50795 0.72133002 4 P 0 0;1=4
P 9.46795 0.82631998 4 P 0 0;1=4
P 4.02893002 2.59336998 4 P 0 0;1=4
P 11.395 2.725 4 P 0 0;1=0
P 11.395 2.8 4 P 0 0;1=4
P 11.58613002 2.905 4 P 0 0;1=4
P 11.58613002 2.785 4 P 0 0;1=4
P 1.33906004 4.60351004 4 P 0 0;1=0
P 3.67 4.45 4 P 0 0;1=4
P 3.72 4.545 4 P 0 0;1=4
P 5.37968996 2.8 4 P 0 0;1=4
P 5.387 2.725 4 P 0 0;1=0
P 5.5822 2.785 4 P 0 0;1=4
P 5.5822 2.905 4 P 0 0;1=4
P 7.2426 4.69351004 4 P 0 0;1=4
P 7.2926 4.60351004 4 P 0 0;1=4
P 9.98 4.51 4 P 0 0;1=4
P 10.07286004 2.82336998 4 P 0 0;1=4
P 10.03 4.61 4 P 0 0;1=4
P 1.23906004 4.69351004 4 P 0 0;1=4
P 3.89 4.655 4 P 0 0;1=4
P 3.9899 4.765 4 P 0 0;1=4
P 4.1049 4.86 4 P 0 0;1=4
P 4.0599 5.395 4 P 0 0;1=4
P 3.91 5.51 4 P 0 0;1=4
P 5.125 5.4 4 P 0 0;1=4
P 1.37925 5.78 4 P 0 0;1=4
P 1.45798996 5.78 4 P 0 0;1=4
P 1.42 5.78 4 P 0 0;1=4
P 1.335 5.78 4 P 0 0;1=4
P 12.63778996 2.55511998 10 P 0 0;1=1
P 11.53316004 1.612 5 P 0 0;1=3
P 8.4 3.76615 5 P 0 0;1=3
P 9.28185 4.642 5 P 0 0;1=3
P 12.73621004 4.36613996 10 P 0 0;1=1
P 10.63661004 2.41615 5 P 0 0;1=3
P 9.975 2.66445 5 P 0 0;1=3
P 8.4 3.81615 5 P 0 0;1=3
P 9.24185 4.642 5 P 0 0;1=3
P 11.53316004 2.532 5 P 0 0;1=3
P 12.63778996 4.60236998 10 P 0 0;1=1
P 8.45 3.66615 5 P 0 0;1=3
P 9.42358002 4.78291998 5 P 0 0;1=3
P 0.95951004 5.4595 4 P 0 0;1=0
P 8.45 3.71615 5 P 0 0;1=3
P 9.38358002 4.78291998 5 P 0 0;1=3
P 8.4 3.61615 5 P 0 0;1=3
P 9.49445 4.587 5 P 0 0;1=3
P 8.4 3.66615 5 P 0 0;1=3
P 9.45445 4.587 5 P 0 0;1=3
P 9.07353996 4.42 4 P 0 0;1=4
P 7.1926 5.15351004 4 P 0 0;1=0
P 8.1 3.66615 5 P 0 0;1=3
P 8.74578996 4.667 5 P 0 0;1=3
P 8.1 3.71615 5 P 0 0;1=3
P 8.78578996 4.667 5 P 0 0;1=3
P 8.2 3.66615 5 P 0 0;1=3
P 8.81665 4.78291998 5 P 0 0;1=3
P 8.2 3.71615 5 P 0 0;1=3
P 8.85665 4.78291998 5 P 0 0;1=3
P 8.05 3.76615 5 P 0 0;1=3
P 8.89061998 4.667 5 P 0 0;1=3
P 8.05 3.81615 5 P 0 0;1=3
P 8.93061998 4.667 5 P 0 0;1=3
P 9.02925 4.667 5 P 0 0;1=3
P 8.2 3.81615 5 P 0 0;1=3
P 9.06925 4.667 5 P 0 0;1=3
P 8.2 3.86615 5 P 0 0;1=3
P 4.68268002 2.71615 5 P 0 0;1=3
P 4.98268002 2.71615 5 P 0 0;1=3
P 2.14606004 2.51615 5 P 0 0;1=3
P 8.45 3.41615 5 P 0 0;1=3
P 8.18811004 5.0535 5 P 0 0;1=3
P 5.03268002 3.81615 5 P 0 0;1=3
P 4.07408002 4.01978996 4 P 0 0;1=0
P 8.45 3.46615 5 P 0 0;1=3
P 8.14811004 5.0535 5 P 0 0;1=3
P 5.03268002 2.16615 5 P 0 0;1=3
P 3.9099 5.395 4 P 0 0;1=0
P 8.45 3.26615 5 P 0 0;1=3
P 8.40071004 5.115 5 P 0 0;1=3
P 8.45 3.31615 5 P 0 0;1=3
P 8.36071004 5.115 5 P 0 0;1=3
P 8.35 3.26615 5 P 0 0;1=3
P 8.40071004 4.742 5 P 0 0;1=3
P 8.35 3.31615 5 P 0 0;1=3
P 8.36071004 4.742 5 P 0 0;1=3
P 8.3 3.56615 5 P 0 0;1=3
P 8.05 3.31615 5 P 0 0;1=3
P 7.58118996 5.169 5 P 0 0;1=3
P 8.25 3.56615 5 P 0 0;1=3
P 8.05 3.36615 5 P 0 0;1=3
P 7.62118996 5.169 5 P 0 0;1=3
P 2.24606004 2.86615 5 P 0 0;1=3
P 8.05 2.61615 24 P 0 0;1=3
P 8.05 2.66615 24 P 0 0;1=3
P 8.1 2.46615 24 P 0 0;1=3
P 8.1 2.41615 24 P 0 0;1=3
P 8.2 2.46615 24 P 0 0;1=3
P 8.2 2.41615 24 P 0 0;1=3
P 8.15 2.41615 24 P 0 0;1=3
P 8.15 2.36615 24 P 0 0;1=3
P 8.05 2.41615 24 P 0 0;1=3
P 8.05 2.36615 24 P 0 0;1=3
P 8.2 2.31615 24 P 0 0;1=3
P 8.2 2.26615 24 P 0 0;1=3
P 8.15 2.26615 24 P 0 0;1=3
P 8.15 2.21615 24 P 0 0;1=3
P 8.1 2.31615 24 P 0 0;1=3
P 8.1 2.26615 24 P 0 0;1=3
P 8.05 2.26615 24 P 0 0;1=3
P 8.05 2.21615 24 P 0 0;1=3
P 8.1 2.11615 24 P 0 0;1=3
P 8.1 2.06615 24 P 0 0;1=3
P 8.2 2.11615 24 P 0 0;1=3
P 8.2 2.06615 24 P 0 0;1=3
P 8.15 2.06615 24 P 0 0;1=3
P 8.15 2.01615 24 P 0 0;1=3
P 8.05 2.06615 24 P 0 0;1=3
P 8.05 2.01615 24 P 0 0;1=3
P 8.2 1.96615 24 P 0 0;1=3
P 8.2 1.91615 24 P 0 0;1=3
P 8.15 1.91615 24 P 0 0;1=3
P 8.15 1.86615 24 P 0 0;1=3
P 8.1 1.96615 24 P 0 0;1=3
P 8.1 1.91615 24 P 0 0;1=3
P 8.05 1.91615 24 P 0 0;1=3
P 8.05 1.86615 24 P 0 0;1=3
P 8.1 3.16615 24 P 0 0;1=3
P 8.1 3.11615 24 P 0 0;1=3
P 8.2 3.16615 24 P 0 0;1=3
P 8.2 3.11615 24 P 0 0;1=3
P 8.15 3.11615 24 P 0 0;1=3
P 8.15 3.06615 24 P 0 0;1=3
P 8.05 3.11615 24 P 0 0;1=3
P 8.05 3.06615 24 P 0 0;1=3
P 8.2 3.01615 24 P 0 0;1=3
P 8.2 2.96615 24 P 0 0;1=3
P 8.15 2.96615 24 P 0 0;1=3
P 8.15 2.91615 24 P 0 0;1=3
P 8.1 3.01615 24 P 0 0;1=3
P 8.1 2.96615 24 P 0 0;1=3
P 8.05 2.96615 24 P 0 0;1=3
P 8.05 2.91615 24 P 0 0;1=3
P 8 2.81615 24 P 0 0;1=3
P 8 2.76615 24 P 0 0;1=3
P 8.15 2.81615 24 P 0 0;1=3
P 8.15 2.76615 24 P 0 0;1=3
P 8.2 2.76615 24 P 0 0;1=3
P 8.2 2.71615 24 P 0 0;1=3
P 8.1 2.76615 24 P 0 0;1=3
P 8.1 2.71615 24 P 0 0;1=3
P 8.15 2.66615 24 P 0 0;1=3
P 8.15 2.61615 24 P 0 0;1=3
P 8.2 2.61615 24 P 0 0;1=3
P 8.2 2.56615 24 P 0 0;1=3
P 8.1 2.61615 24 P 0 0;1=3
P 8.1 2.56615 24 P 0 0;1=3
P 8.35 2.56615 24 P 0 0;1=3
P 8.35 2.61615 24 P 0 0;1=3
P 8.35 2.46615 24 P 0 0;1=3
P 8.35 2.41615 24 P 0 0;1=3
P 8.45 2.46615 24 P 0 0;1=3
P 8.45 2.41615 24 P 0 0;1=3
P 8.5 2.41615 24 P 0 0;1=3
P 8.5 2.36615 24 P 0 0;1=3
P 8.4 2.41615 24 P 0 0;1=3
P 8.4 2.36615 24 P 0 0;1=3
P 8.45 2.31615 24 P 0 0;1=3
P 8.45 2.26615 24 P 0 0;1=3
P 8.5 2.26615 24 P 0 0;1=3
P 8.5 2.21615 24 P 0 0;1=3
P 8.4 2.26615 24 P 0 0;1=3
P 8.4 2.21615 24 P 0 0;1=3
P 8.35 2.31615 24 P 0 0;1=3
P 8.35 2.26615 24 P 0 0;1=3
P 8.35 2.11615 24 P 0 0;1=3
P 8.35 2.06615 24 P 0 0;1=3
P 8.45 2.11615 24 P 0 0;1=3
P 8.45 2.06615 24 P 0 0;1=3
P 8.5 2.06615 24 P 0 0;1=3
P 8.5 2.01615 24 P 0 0;1=3
P 8.4 2.06615 24 P 0 0;1=3
P 8.4 2.01615 24 P 0 0;1=3
P 8.45 1.96615 24 P 0 0;1=3
P 8.45 1.91615 24 P 0 0;1=3
P 8.5 1.91615 24 P 0 0;1=3
P 8.5 1.86615 24 P 0 0;1=3
P 8.4 1.91615 24 P 0 0;1=3
P 8.4 1.86615 24 P 0 0;1=3
P 8.35 1.96615 24 P 0 0;1=3
P 8.35 1.91615 24 P 0 0;1=3
P 8.35 3.16615 24 P 0 0;1=3
P 8.35 3.11615 24 P 0 0;1=3
P 8.45 3.16615 24 P 0 0;1=3
P 8.45 3.11615 24 P 0 0;1=3
P 8.5 3.11615 24 P 0 0;1=3
P 8.5 3.06615 24 P 0 0;1=3
P 8.4 3.11615 24 P 0 0;1=3
P 8.4 3.06615 24 P 0 0;1=3
P 8.45 3.01615 24 P 0 0;1=3
P 8.45 2.96615 24 P 0 0;1=3
P 8.5 2.96615 24 P 0 0;1=3
P 8.5 2.91615 24 P 0 0;1=3
P 8.4 2.96615 24 P 0 0;1=3
P 8.4 2.91615 24 P 0 0;1=3
P 8.35 3.01615 24 P 0 0;1=3
P 8.35 2.96615 24 P 0 0;1=3
P 8.4 2.81615 24 P 0 0;1=3
P 8.4 2.76615 24 P 0 0;1=3
P 8.5 2.81615 24 P 0 0;1=3
P 8.5 2.76615 24 P 0 0;1=3
P 8.45 2.76615 24 P 0 0;1=3
P 8.45 2.71615 24 P 0 0;1=3
P 8.35 2.76615 24 P 0 0;1=3
P 8.35 2.71615 24 P 0 0;1=3
P 8.5 2.66615 24 P 0 0;1=3
P 8.5 2.61615 24 P 0 0;1=3
P 8.45 2.61615 24 P 0 0;1=3
P 8.45 2.56615 24 P 0 0;1=3
P 8.4 2.66615 24 P 0 0;1=3
P 8.4 2.61615 24 P 0 0;1=3
P 2.04606024 2.61615 24 P 0 0;1=3
P 2.04606024 2.66615 24 P 0 0;1=3
P 2.09606024 2.46615 24 P 0 0;1=3
P 2.09606024 2.41615 24 P 0 0;1=3
P 2.19606024 2.46615 24 P 0 0;1=3
P 2.19606024 2.41615 24 P 0 0;1=3
P 2.14606024 2.41615 24 P 0 0;1=3
P 2.14606024 2.36615 24 P 0 0;1=3
P 2.04606024 2.41615 24 P 0 0;1=3
P 2.04606024 2.36615 24 P 0 0;1=3
P 2.19606024 2.31615 24 P 0 0;1=3
P 2.19606024 2.26615 24 P 0 0;1=3
P 2.14606024 2.26615 24 P 0 0;1=3
P 2.14606024 2.21615 24 P 0 0;1=3
P 2.09606024 2.31615 24 P 0 0;1=3
P 2.09606024 2.26615 24 P 0 0;1=3
P 2.04606024 2.26615 24 P 0 0;1=3
P 2.04606024 2.21615 24 P 0 0;1=3
P 2.09606024 2.11615 24 P 0 0;1=3
P 2.09606024 2.06615 24 P 0 0;1=3
P 2.19606024 2.11615 24 P 0 0;1=3
P 2.19606024 2.06615 24 P 0 0;1=3
P 2.14606024 2.06615 24 P 0 0;1=3
P 2.14606024 2.01615 24 P 0 0;1=3
P 2.04606024 2.06615 24 P 0 0;1=3
P 2.04606024 2.01615 24 P 0 0;1=3
P 2.19606024 1.96615 24 P 0 0;1=3
P 2.19606024 1.91615 24 P 0 0;1=3
P 2.14606024 1.91615 24 P 0 0;1=3
P 2.14606024 1.86615 24 P 0 0;1=3
P 2.09606024 1.96615 24 P 0 0;1=3
P 2.09606024 1.91615 24 P 0 0;1=3
P 2.04606024 1.91615 24 P 0 0;1=3
P 2.04606024 1.86615 24 P 0 0;1=3
P 2.09606024 3.16615 24 P 0 0;1=3
P 2.09606024 3.11615 24 P 0 0;1=3
P 2.19606024 3.16615 24 P 0 0;1=3
P 2.19606024 3.11615 24 P 0 0;1=3
P 2.14606024 3.11615 24 P 0 0;1=3
P 2.14606024 3.06615 24 P 0 0;1=3
P 2.04606024 3.11615 24 P 0 0;1=3
P 2.04606024 3.06615 24 P 0 0;1=3
P 2.19606024 3.01615 24 P 0 0;1=3
P 2.19606024 2.96615 24 P 0 0;1=3
P 2.14606024 2.96615 24 P 0 0;1=3
P 2.14606024 2.91615 24 P 0 0;1=3
P 2.09606024 3.01615 24 P 0 0;1=3
P 2.09606024 2.96615 24 P 0 0;1=3
P 2.04606024 2.96615 24 P 0 0;1=3
P 2.04606024 2.91615 24 P 0 0;1=3
P 1.99605974 2.81615 24 P 0 0;1=3
P 1.99605974 2.76615 24 P 0 0;1=3
P 2.14606024 2.81615 24 P 0 0;1=3
P 2.14606024 2.76615 24 P 0 0;1=3
P 2.19606024 2.76615 24 P 0 0;1=3
P 2.19606024 2.71615 24 P 0 0;1=3
P 2.09606024 2.76615 24 P 0 0;1=3
P 2.09606024 2.71615 24 P 0 0;1=3
P 2.14606024 2.66615 24 P 0 0;1=3
P 2.14606024 2.61615 24 P 0 0;1=3
P 2.19606024 2.61615 24 P 0 0;1=3
P 2.19606024 2.56615 24 P 0 0;1=3
P 2.09606024 2.61615 24 P 0 0;1=3
P 2.09606024 2.56615 24 P 0 0;1=3
P 2.34606024 2.56615 24 P 0 0;1=3
P 2.34606024 2.61615 24 P 0 0;1=3
P 2.34606024 2.46615 24 P 0 0;1=3
P 2.34606024 2.41615 24 P 0 0;1=3
P 2.44606024 2.46615 24 P 0 0;1=3
P 2.44606024 2.41615 24 P 0 0;1=3
P 2.49606024 2.41615 24 P 0 0;1=3
P 2.49606024 2.36615 24 P 0 0;1=3
P 2.39606024 2.41615 24 P 0 0;1=3
P 2.39606024 2.36615 24 P 0 0;1=3
P 2.44606024 2.31615 24 P 0 0;1=3
P 2.44606024 2.26615 24 P 0 0;1=3
P 2.49606024 2.26615 24 P 0 0;1=3
P 2.49606024 2.21615 24 P 0 0;1=3
P 2.39606024 2.26615 24 P 0 0;1=3
P 2.39606024 2.21615 24 P 0 0;1=3
P 2.34606024 2.31615 24 P 0 0;1=3
P 2.34606024 2.26615 24 P 0 0;1=3
P 2.34606024 2.11615 24 P 0 0;1=3
P 2.34606024 2.06615 24 P 0 0;1=3
P 2.44606024 2.11615 24 P 0 0;1=3
P 2.44606024 2.06615 24 P 0 0;1=3
P 2.49606024 2.06615 24 P 0 0;1=3
P 2.49606024 2.01615 24 P 0 0;1=3
P 2.39606024 2.06615 24 P 0 0;1=3
P 2.39606024 2.01615 24 P 0 0;1=3
P 2.44606024 1.96615 24 P 0 0;1=3
P 2.44606024 1.91615 24 P 0 0;1=3
P 2.49606024 1.91615 24 P 0 0;1=3
P 2.49606024 1.86615 24 P 0 0;1=3
P 2.39606024 1.91615 24 P 0 0;1=3
P 2.39606024 1.86615 24 P 0 0;1=3
P 2.34606024 1.96615 24 P 0 0;1=3
P 2.34606024 1.91615 24 P 0 0;1=3
P 2.34606024 3.16615 24 P 0 0;1=3
P 2.34606024 3.11615 24 P 0 0;1=3
P 2.44606024 3.16615 24 P 0 0;1=3
P 2.44606024 3.11615 24 P 0 0;1=3
P 2.49606024 3.11615 24 P 0 0;1=3
P 2.49606024 3.06615 24 P 0 0;1=3
P 2.39606024 3.11615 24 P 0 0;1=3
P 2.39606024 3.06615 24 P 0 0;1=3
P 2.44606024 3.01615 24 P 0 0;1=3
P 2.44606024 2.96615 24 P 0 0;1=3
P 2.49606024 2.96615 24 P 0 0;1=3
P 2.49606024 2.91615 24 P 0 0;1=3
P 2.39606024 2.96615 24 P 0 0;1=3
P 2.39606024 2.91615 24 P 0 0;1=3
P 2.34606024 3.01615 24 P 0 0;1=3
P 2.34606024 2.96615 24 P 0 0;1=3
P 2.39606024 2.81615 24 P 0 0;1=3
P 2.39606024 2.76615 24 P 0 0;1=3
P 2.49606024 2.81615 24 P 0 0;1=3
P 2.49606024 2.76615 24 P 0 0;1=3
P 2.44606024 2.76615 24 P 0 0;1=3
P 2.44606024 2.71615 24 P 0 0;1=3
P 2.34606024 2.76615 24 P 0 0;1=3
P 2.34606024 2.71615 24 P 0 0;1=3
P 2.49606024 2.66615 24 P 0 0;1=3
P 2.49606024 2.61615 24 P 0 0;1=3
P 2.44606024 2.61615 24 P 0 0;1=3
P 2.44606024 2.56615 24 P 0 0;1=3
P 2.39606024 2.66615 24 P 0 0;1=3
P 2.39606024 2.61615 24 P 0 0;1=3
P 8.94061998 4.70574026 24 P 0 0;1=4
P 9.01925 4.70574026 24 P 0 0;1=4
P 9.07925 4.70574026 24 P 0 0;1=4
P 8.73579006 4.70573996 24 P 0 0;1=4
P 8.79579006 4.70573996 24 P 0 0;1=4
P 8.86665 4.74417972 24 P 0 0;1=4
P 8.80665 4.74417972 24 P 0 0;1=4
P 9.43358002 4.74417972 24 P 0 0;1=4
P 9.51531004 4.68098996 24 P 0 0;1=4
P 9.57531004 4.68098996 24 P 0 0;1=4
P 9.44445 4.62574026 24 P 0 0;1=4
P 9.50445 4.62574026 24 P 0 0;1=4
P 9.23185 4.68074026 24 P 0 0;1=4
P 9.29185 4.68074026 24 P 0 0;1=4
P 9.16098002 4.74417972 24 P 0 0;1=4
P 9.37358002 4.74417972 24 P 0 0;1=4
P 9.22098002 4.74417972 24 P 0 0;1=4
P 9.51531004 5.17873996 24 P 0 0;1=4
P 9.57531004 5.17873996 24 P 0 0;1=4
P 9.43358002 5.18127972 24 P 0 0;1=4
P 9.23185 5.18127972 24 P 0 0;1=4
P 9.29185 5.18127972 24 P 0 0;1=4
P 9.37358002 5.18127972 24 P 0 0;1=4
P 9.36271004 5.14223996 24 P 0 0;1=4
P 9.30271004 5.14223996 24 P 0 0;1=4
P 9.15011004 5.09223996 24 P 0 0;1=4
P 9.09011004 5.09223996 24 P 0 0;1=4
P 9.07925 5.20374026 24 P 0 0;1=4
P 9.01925 5.20374026 24 P 0 0;1=4
P 8.93440994 5.20876004 24 P 0 0;1=4
P 8.73579006 5.17873996 24 P 0 0;1=4
P 8.79579006 5.17873996 24 P 0 0;1=4
P 8.87440994 5.20876004 24 P 0 0;1=4
P 7.64205 4.74417972 24 P 0 0;1=4
P 7.70205 4.74417972 24 P 0 0;1=4
P 7.63118996 4.66826004 24 P 0 0;1=4
P 7.57118996 4.66826004 24 P 0 0;1=4
P 7.91465 4.61825974 24 P 0 0;1=4
P 7.78378996 4.74418002 24 P 0 0;1=4
P 7.84378996 4.74418002 24 P 0 0;1=4
P 7.85465 4.61825974 24 P 0 0;1=4
P 8.06725 4.74417972 24 P 0 0;1=4
P 8.12725 4.74417972 24 P 0 0;1=4
P 8.02207028 4.62815 24 P 0 0;1=4
P 8.08207028 4.62815 24 P 0 0;1=4
P 8.41070994 4.70326004 24 P 0 0;1=4
P 8.35070994 4.70326004 24 P 0 0;1=4
P 8.20898002 4.74417972 24 P 0 0;1=4
P 8.26898002 4.74417972 24 P 0 0;1=4
P 8.21208996 4.62826004 24 P 0 0;1=4
P 8.27208996 4.62826004 24 P 0 0;1=4
P 8.19811004 5.09223996 24 P 0 0;1=4
P 8.12725 5.13025974 24 P 0 0;1=4
P 8.06725 5.13025974 24 P 0 0;1=4
P 7.91465 5.13025974 24 P 0 0;1=4
P 7.92551004 5.09223996 24 P 0 0;1=4
P 7.98551004 5.09223996 24 P 0 0;1=4
P 7.85465 5.13025974 24 P 0 0;1=4
P 7.64204006 5.09223996 24 P 0 0;1=4
P 7.70204006 5.09223996 24 P 0 0;1=4
P 7.57118996 5.13026004 24 P 0 0;1=4
P 7.63118996 5.13026004 24 P 0 0;1=4
P 2.73225 4.70574026 24 P 0 0;1=4
P 2.79225 4.70574026 24 P 0 0;1=4
P 3.22830994 5.18128002 24 P 0 0;1=4
P 3.28830994 5.18128002 24 P 0 0;1=4
P 3.01571004 5.20373996 24 P 0 0;1=4
P 3.07571004 5.20373996 24 P 0 0;1=4
P 2.73225 5.17874026 24 P 0 0;1=4
P 2.79225 5.17874026 24 P 0 0;1=4
P 1.56765 4.66825974 24 P 0 0;1=4
P 1.62765 4.66825974 24 P 0 0;1=4
P 1.56765 5.13025974 24 P 0 0;1=4
P 1.62765 5.13025974 24 P 0 0;1=4
P 1.91110994 5.13026004 24 P 0 0;1=4
P 1.85110994 5.13026004 24 P 0 0;1=4
P 5.08267972 2.76615 24 P 0 0;1=3
P 5.03267972 2.76615 24 P 0 0;1=3
P 5.03267972 2.71615 24 P 0 0;1=3
P 4.93267972 2.76615 24 P 0 0;1=3
P 4.98267972 2.76615 24 P 0 0;1=3
P 4.93267972 2.71615 24 P 0 0;1=3
P 5.08267972 2.66615 24 P 0 0;1=3
P 4.98267972 2.66615 24 P 0 0;1=3
P 5.03267972 2.56615 24 P 0 0;1=3
P 4.93267972 2.56615 24 P 0 0;1=3
P 4.98267972 2.46615 24 P 0 0;1=3
P 4.98267972 2.51615 24 P 0 0;1=3
P 4.93267972 2.51615 24 P 0 0;1=3
P 5.08267972 2.51615 24 P 0 0;1=3
P 5.08267972 2.46615 24 P 0 0;1=3
P 5.03267972 2.21615 24 P 0 0;1=3
P 4.93267972 2.21615 24 P 0 0;1=3
P 4.98267972 2.31615 24 P 0 0;1=3
P 4.93267972 2.36615 24 P 0 0;1=3
P 5.08267972 2.31615 24 P 0 0;1=3
P 5.08267972 2.16615 24 P 0 0;1=3
P 4.93267972 2.16615 24 P 0 0;1=3
P 4.98267972 2.16615 24 P 0 0;1=3
P 4.93267972 1.96615 24 P 0 0;1=3
P 5.03267972 1.96615 24 P 0 0;1=3
P 5.03267972 2.11615 24 P 0 0;1=3
P 4.93267972 2.11615 24 P 0 0;1=3
P 4.98267972 2.01615 24 P 0 0;1=3
P 5.08267972 2.01615 24 P 0 0;1=3
P 4.98267972 1.86615 24 P 0 0;1=3
P 5.08267972 1.86615 24 P 0 0;1=3
P 4.78267972 3.81615 24 P 0 0;1=3
P 4.78267972 3.66615 24 P 0 0;1=3
P 4.73267972 3.81615 24 P 0 0;1=3
P 4.73267972 3.66615 24 P 0 0;1=3
P 4.68267972 3.81615 24 P 0 0;1=3
P 4.68267972 3.66615 24 P 0 0;1=3
P 4.78267972 3.51615 24 P 0 0;1=3
P 4.73267972 3.51615 24 P 0 0;1=3
P 4.68267972 3.51615 24 P 0 0;1=3
P 4.78267972 3.36615 24 P 0 0;1=3
P 4.73267972 3.36615 24 P 0 0;1=3
P 4.78267972 3.21615 24 P 0 0;1=3
P 4.73267972 3.21615 24 P 0 0;1=3
P 4.68267972 3.36615 24 P 0 0;1=3
P 4.68267972 3.21615 24 P 0 0;1=3
P 4.78267972 3.06615 24 P 0 0;1=3
P 4.73267972 3.06615 24 P 0 0;1=3
P 4.68267972 3.06615 24 P 0 0;1=3
P 4.78267972 2.91615 24 P 0 0;1=3
P 4.73267972 2.91615 24 P 0 0;1=3
P 4.68267972 2.91615 24 P 0 0;1=3
P 4.88267972 2.76615 24 P 0 0;1=3
P 4.88267972 2.66615 24 P 0 0;1=3
P 4.78267972 2.46615 24 P 0 0;1=3
P 4.88267972 2.56615 24 P 0 0;1=3
P 4.88267972 2.61615 24 P 0 0;1=3
P 4.68267972 2.46615 24 P 0 0;1=3
P 4.88267972 2.46615 24 P 0 0;1=3
P 4.88267972 2.51615 24 P 0 0;1=3
P 4.78267972 2.41615 24 P 0 0;1=3
P 4.88267972 2.41615 24 P 0 0;1=3
P 4.78267972 2.36615 24 P 0 0;1=3
P 4.78267972 2.31615 24 P 0 0;1=3
P 4.78267972 2.26615 24 P 0 0;1=3
P 4.78267972 2.21615 24 P 0 0;1=3
P 4.73267972 2.36615 24 P 0 0;1=3
P 4.68267972 2.31615 24 P 0 0;1=3
P 4.73267972 2.21615 24 P 0 0;1=3
P 4.88267972 2.21615 24 P 0 0;1=3
P 4.88267972 2.26615 24 P 0 0;1=3
P 4.88267972 2.31615 24 P 0 0;1=3
P 4.88267972 2.36615 24 P 0 0;1=3
P 4.73267972 2.16615 24 P 0 0;1=3
P 4.68267972 2.16615 24 P 0 0;1=3
P 4.78267972 1.96615 24 P 0 0;1=3
P 4.78267972 2.06615 24 P 0 0;1=3
P 4.78267972 2.01615 24 P 0 0;1=3
P 4.88267972 1.96615 24 P 0 0;1=3
P 4.88267972 2.06615 24 P 0 0;1=3
P 4.88267972 2.01615 24 P 0 0;1=3
P 4.78267972 2.11615 24 P 0 0;1=3
P 4.88267972 2.11615 24 P 0 0;1=3
P 4.73267972 2.11615 24 P 0 0;1=3
P 4.68267972 2.01615 24 P 0 0;1=3
P 4.73267972 1.96615 24 P 0 0;1=3
P 4.78267972 1.86615 24 P 0 0;1=3
P 4.88267972 1.86615 24 P 0 0;1=3
P 4.68267972 1.86615 24 P 0 0;1=3
P 4.63267972 3.81615 24 P 0 0;1=3
P 4.63267972 3.66615 24 P 0 0;1=3
P 4.58267972 3.81615 24 P 0 0;1=3
P 4.58267972 3.66615 24 P 0 0;1=3
P 4.63267972 3.51615 24 P 0 0;1=3
P 4.58267972 3.51615 24 P 0 0;1=3
P 4.63267972 3.36615 24 P 0 0;1=3
P 4.58267972 3.36615 24 P 0 0;1=3
P 4.63267972 3.21615 24 P 0 0;1=3
P 4.58267972 3.21615 24 P 0 0;1=3
P 4.63267972 3.06615 24 P 0 0;1=3
P 4.58267972 3.06615 24 P 0 0;1=3
P 4.63267972 2.91615 24 P 0 0;1=3
P 4.58267972 2.91615 24 P 0 0;1=3
P 4.58267972 2.46615 24 P 0 0;1=3
P 4.63267972 2.21615 24 P 0 0;1=3
P 4.58267972 2.31615 24 P 0 0;1=3
P 4.63267972 2.36615 24 P 0 0;1=3
P 4.58267972 2.01615 24 P 0 0;1=3
P 4.63267972 2.11615 24 P 0 0;1=3
P 4.63267972 1.96615 24 P 0 0;1=3
P 4.58267972 1.86615 24 P 0 0;1=3
P 2.04606024 3.41615 24 P 0 0;1=3
P 2.09606024 3.51615 24 P 0 0;1=3
P 3.37003996 5.18128002 24 P 0 0;1=4
P 3.43003996 5.18128002 24 P 0 0;1=4
P 3.29916998 5.14224026 24 P 0 0;1=4
P 3.35916998 5.14224026 24 P 0 0;1=4
P 2.93708002 4.70573996 24 P 0 0;1=4
P 3.07571004 4.70573996 24 P 0 0;1=4
P 3.01571004 4.70573996 24 P 0 0;1=4
P 2.87708002 4.70573996 24 P 0 0;1=4
P 2.93086998 5.20876024 24 P 0 0;1=4
P 2.87086998 5.20876024 24 P 0 0;1=4
P 2.80310994 4.74418002 24 P 0 0;1=4
P 2.86310994 4.74418002 24 P 0 0;1=4
P 3.08656998 5.09224026 24 P 0 0;1=4
P 3.14656998 5.09224026 24 P 0 0;1=4
P 2.26855 4.62825974 24 P 0 0;1=4
P 2.20855 4.62825974 24 P 0 0;1=4
P 2.26543996 4.74418002 24 P 0 0;1=4
P 2.20543996 4.74418002 24 P 0 0;1=4
P 2.34716998 4.70326004 24 P 0 0;1=4
P 2.07853002 4.62815 24 P 0 0;1=4
P 2.01853002 4.62815 24 P 0 0;1=4
P 2.12370994 4.74418002 24 P 0 0;1=4
P 2.06370994 4.74418002 24 P 0 0;1=4
P 2.19456998 5.09224026 24 P 0 0;1=4
P 2.13456998 5.09224026 24 P 0 0;1=4
P 2.12370994 5.13026004 24 P 0 0;1=4
P 2.06370994 5.13026004 24 P 0 0;1=4
P 1.6985 5.09224026 24 P 0 0;1=4
P 1.6385 5.09224026 24 P 0 0;1=4
P 1.85110994 4.61826004 24 P 0 0;1=4
P 1.63850994 4.74418002 24 P 0 0;1=4
P 1.69850994 4.74418002 24 P 0 0;1=4
P 1.98196998 5.09224026 24 P 0 0;1=4
P 1.92196998 5.09224026 24 P 0 0;1=4
P 1.84025 4.74417972 24 P 0 0;1=4
P 1.78025 4.74417972 24 P 0 0;1=4
P 11.03660974 2.71615 24 P 0 0;1=3
P 10.93660974 2.71615 24 P 0 0;1=3
P 11.03660974 2.76615 24 P 0 0;1=3
P 10.98660974 2.76615 24 P 0 0;1=3
P 10.93660974 2.76615 24 P 0 0;1=3
P 11.08660974 2.76615 24 P 0 0;1=3
P 11.03660974 2.56615 24 P 0 0;1=3
P 10.93660974 2.56615 24 P 0 0;1=3
P 10.98660974 2.66615 24 P 0 0;1=3
P 10.98660974 2.51615 24 P 0 0;1=3
P 10.93660974 2.51615 24 P 0 0;1=3
P 11.08660974 2.66615 24 P 0 0;1=3
P 11.08660974 2.51615 24 P 0 0;1=3
P 11.08660974 2.46615 24 P 0 0;1=3
P 10.98660974 2.46615 24 P 0 0;1=3
P 11.08660974 2.31615 24 P 0 0;1=3
P 10.93660974 2.36615 24 P 0 0;1=3
P 10.98660974 2.31615 24 P 0 0;1=3
P 10.93660974 2.21615 24 P 0 0;1=3
P 11.03660974 2.21615 24 P 0 0;1=3
P 11.03660974 2.11615 24 P 0 0;1=3
P 10.93660974 2.11615 24 P 0 0;1=3
P 10.98660974 2.01615 24 P 0 0;1=3
P 10.93660974 1.96615 24 P 0 0;1=3
P 11.03660974 1.96615 24 P 0 0;1=3
P 11.08660974 2.01615 24 P 0 0;1=3
P 10.98660974 2.16615 24 P 0 0;1=3
P 10.93660974 2.16615 24 P 0 0;1=3
P 11.08660974 2.16615 24 P 0 0;1=3
P 10.98660974 1.86615 24 P 0 0;1=3
P 11.08660974 1.86615 24 P 0 0;1=3
P 10.73660974 2.71615 24 P 0 0;1=3
P 10.73660974 2.76615 24 P 0 0;1=3
P 10.88660974 2.76615 24 P 0 0;1=3
P 10.78660974 2.76615 24 P 0 0;1=3
P 10.73660974 2.56615 24 P 0 0;1=3
P 10.68660974 2.66615 24 P 0 0;1=3
P 10.73660974 2.51615 24 P 0 0;1=3
P 10.68660974 2.51615 24 P 0 0;1=3
P 10.88660974 2.61615 24 P 0 0;1=3
P 10.88660974 2.56615 24 P 0 0;1=3
P 10.88660974 2.51615 24 P 0 0;1=3
P 10.78660974 2.56615 24 P 0 0;1=3
P 10.78660974 2.61615 24 P 0 0;1=3
P 10.78660974 2.66615 24 P 0 0;1=3
P 10.78660974 2.51615 24 P 0 0;1=3
P 10.78660974 2.46615 24 P 0 0;1=3
P 10.68660974 2.46615 24 P 0 0;1=3
P 10.88660974 2.46615 24 P 0 0;1=3
P 10.78660974 2.21615 24 P 0 0;1=3
P 10.78660974 2.26615 24 P 0 0;1=3
P 10.78660974 2.31615 24 P 0 0;1=3
P 10.78660974 2.36615 24 P 0 0;1=3
P 10.68660974 2.31615 24 P 0 0;1=3
P 10.73660974 2.36615 24 P 0 0;1=3
P 10.73660974 2.21615 24 P 0 0;1=3
P 10.78660974 2.41615 24 P 0 0;1=3
P 10.88660974 2.36615 24 P 0 0;1=3
P 10.88660974 2.31615 24 P 0 0;1=3
P 10.88660974 2.26615 24 P 0 0;1=3
P 10.88660974 2.21615 24 P 0 0;1=3
P 10.73660974 1.96615 24 P 0 0;1=3
P 10.68660974 2.01615 24 P 0 0;1=3
P 10.73660974 2.11615 24 P 0 0;1=3
P 10.78660974 2.11615 24 P 0 0;1=3
P 10.78660974 2.01615 24 P 0 0;1=3
P 10.78660974 1.96615 24 P 0 0;1=3
P 10.78660974 2.06615 24 P 0 0;1=3
P 10.68660974 2.16615 24 P 0 0;1=3
P 10.73660974 2.16615 24 P 0 0;1=3
P 10.88660974 2.01615 24 P 0 0;1=3
P 10.88660974 2.06615 24 P 0 0;1=3
P 10.88660974 2.11615 24 P 0 0;1=3
P 10.88660974 1.96615 24 P 0 0;1=3
P 10.78660974 1.91615 24 P 0 0;1=3
P 10.68660974 1.86615 24 P 0 0;1=3
P 10.78660974 1.86615 24 P 0 0;1=3
P 10.88660974 1.86615 24 P 0 0;1=3
P 10.63660974 2.71615 24 P 0 0;1=3
P 10.63660974 2.76615 24 P 0 0;1=3
P 10.63660974 2.56615 24 P 0 0;1=3
P 10.58660974 2.66615 24 P 0 0;1=3
P 10.63660974 2.51615 24 P 0 0;1=3
P 10.58660974 2.51615 24 P 0 0;1=3
P 10.58660974 2.46615 24 P 0 0;1=3
P 10.63660974 2.36615 24 P 0 0;1=3
P 10.58660974 2.31615 24 P 0 0;1=3
P 10.58660974 2.01615 24 P 0 0;1=3
P 10.63660974 1.96615 24 P 0 0;1=3
P 10.63660974 2.11615 24 P 0 0;1=3
P 10.58660974 1.86615 24 P 0 0;1=3
P 1.92345974 5.377 24 P 0 0;1=4
P 2.14345974 5.377 24 P 0 0;1=4
P 7.927 5.377 24 P 0 0;1=4
P 8.147 5.377 24 P 0 0;1=4
P 3.43003996 4.74418002 24 P 0 0;1=4
P 3.51177008 4.68098996 24 P 0 0;1=4
P 3.57177008 4.68098996 24 P 0 0;1=4
P 3.21743996 4.74418002 24 P 0 0;1=4
P 3.37003996 4.74418002 24 P 0 0;1=4
P 3.41 5.332 24 P 0 0;1=4
P 5.38047972 1.5957 24 P 0 0;1=4
P 5.38047972 1.7891 24 P 0 0;1=4
P 5.38047972 1.732 24 P 0 0;1=4
P 5.38047972 1.6528 24 P 0 0;1=4
P 5.53530974 1.8603 24 P 0 0;1=4
P 5.53530974 1.8032 24 P 0 0;1=4
P 5.53530974 2.2727 24 P 0 0;1=4
P 5.53530974 2.1373 24 P 0 0;1=4
P 5.53530974 1.9964 24 P 0 0;1=4
P 5.38047972 2.3403 24 P 0 0;1=4
P 5.38047972 2.2832 24 P 0 0;1=4
P 5.38047972 2.2049 24 P 0 0;1=4
P 5.38047972 2.1478 24 P 0 0;1=4
P 5.38047972 2.0642 24 P 0 0;1=4
P 5.38047972 2.0071 24 P 0 0;1=4
P 5.38047972 1.9288 24 P 0 0;1=4
P 5.38047972 1.8717 24 P 0 0;1=4
P 5.53530974 2.351 24 P 0 0;1=4
P 5.38047972 2.4757 24 P 0 0;1=4
P 5.38047972 2.4186 24 P 0 0;1=4
P 5.53530974 2.4902 24 P 0 0;1=4
P 5.53530974 2.6825 24 P 0 0;1=4
P 5.53530974 2.6254 24 P 0 0;1=4
P 5.38047972 2.5578 24 P 0 0;1=4
P 5.38047972 2.6149 24 P 0 0;1=4
P 10.43 1.3341 24 P 0 0;1=4
P 10.43 1.277 24 P 0 0;1=4
P 10.4159 1.43 24 P 0 0;1=4
P 10.473 1.43 24 P 0 0;1=4
P 10.37313996 1.55333474 24 P 0 0;1=4
P 10.41451004 1.51195472 24 P 0 0;1=4
P 10.295 1.713 24 P 0 0;1=4
P 10.295 1.6559 24 P 0 0;1=4
P 10.26 1.9179 24 P 0 0;1=4
P 10.29525 1.877 24 P 0 0;1=4
P 10.29525 1.8199 24 P 0 0;1=4
P 10.26 1.975 24 P 0 0;1=4
P 10.125 2.0651 24 P 0 0;1=4
P 10.125 2.1224 24 P 0 0;1=4
P 10.125 2.1795 24 P 0 0;1=4
P 10.01 2.2481 24 P 0 0;1=4
P 10.01 2.191 24 P 0 0;1=4
P 10.01 2.38435 24 P 0 0;1=4
P 10.01 2.32725 24 P 0 0;1=4
P 10.125 2.3168 24 P 0 0;1=4
P 10.125 2.2597 24 P 0 0;1=4
P 10.125 2.4519 24 P 0 0;1=4
P 10.125 2.3948 24 P 0 0;1=4
P 10.01 2.51945 24 P 0 0;1=4
P 10.01 2.46235 24 P 0 0;1=4
P 10.125 2.587 24 P 0 0;1=4
P 10.125 2.5299 24 P 0 0;1=4
P 10.01 2.673 24 P 0 0;1=4
P 10.01 2.6159 24 P 0 0;1=4
P 11.74315974 1.7035 24 P 0 0;1=4
P 11.74315974 1.6405 24 P 0 0;1=4
P 11.69315974 1.4805 24 P 0 0;1=4
P 11.69315974 1.5435 24 P 0 0;1=4
P 11.49315974 1.5605 24 P 0 0;1=4
P 11.49315974 1.6235 24 P 0 0;1=4
P 11.49315974 1.4635 24 P 0 0;1=4
P 11.49365974 1.401 24 P 0 0;1=4
P 11.69315974 2.6005 24 P 0 0;1=4
P 11.69315974 2.5035 24 P 0 0;1=4
P 11.69315974 2.4405 24 P 0 0;1=4
P 11.69315974 2.3435 24 P 0 0;1=4
P 11.69315974 2.2805 24 P 0 0;1=4
P 11.69315974 2.1835 24 P 0 0;1=4
P 11.69315974 1.9605 24 P 0 0;1=4
P 11.69315974 2.0235 24 P 0 0;1=4
P 11.69315974 2.1205 24 P 0 0;1=4
P 11.69315974 1.8005 24 P 0 0;1=4
P 11.69315974 1.8635 24 P 0 0;1=4
P 11.49315974 2.5205 24 P 0 0;1=4
P 11.49315974 2.5835 24 P 0 0;1=4
P 11.49315974 2.4235 24 P 0 0;1=4
P 11.49315974 2.3605 24 P 0 0;1=4
P 11.79315974 2.2635 24 P 0 0;1=4
P 11.79315974 2.2005 24 P 0 0;1=4
P 11.49315974 1.9435 24 P 0 0;1=4
P 11.49315974 2.1035 24 P 0 0;1=4
P 11.49315974 2.0405 24 P 0 0;1=4
P 11.49315974 1.8805 24 P 0 0;1=4
P 11.49365974 1.721 24 P 0 0;1=4
P 11.49315974 1.7835 24 P 0 0;1=4
P 10.125 2.7451 24 P 0 0;1=4
P 10.125 2.688 24 P 0 0;1=4
P 12.34 2.19 24 P 0 0;1=4
P 9.415 5.332 24 P 0 0;1=4
P 9.265 5.332 24 P 0 0;1=4
P 9.07 5.332 24 P 0 0;1=4
P 4.7 5.54929026 24 P 0 0;1=4
P 4.81 5.375 24 P 0 0;1=4
P 4.96 5.375 24 P 0 0;1=4
P 5.16 5.645 24 P 0 0;1=4
P 5.04440974 5.605 24 P 0 0;1=4
P 4.92 5.7 24 P 0 0;1=4
P 9.91 4.7 24 P 0 0;1=4
P 3.57 4.45 24 P 0 0;1=4
P 10.465 5.195 24 P 0 0;1=4
P 10.515 5.32 24 P 0 0;1=4
P 10.465 5.275 24 P 0 0;1=4
P 12.025 4.915 24 P 0 0;1=4
P 12.12 4.965 24 P 0 0;1=4
P 12.185 4.915 24 P 0 0;1=4
P 3.72 4.45 24 P 0 0;1=4
P 3.66 4.63 24 P 0 0;1=4
P 3.77 4.86 24 P 0 0;1=4
P 9.96 4.69 24 P 0 0;1=4
P 10.03 4.51 24 P 0 0;1=4
P 3.835 4.6 24 P 0 0;1=4
P 3.9865 4.635 24 P 0 0;1=4
P 4.14 4.655 24 P 0 0;1=4
P 4.1049 4.7649 24 P 0 0;1=4
P 1.28050974 5.78 24 P 0 0;1=4
P 3.87 5.125 24 P 0 0;1=4
P 0.4826 5.8976 24 P 0 0;1=4
P 0.84952972 5.17 24 P 0 0;1=4
P 0.955 5.325 24 P 0 0;1=4
P 1.31 5.355 24 P 0 0;1=4
P 1.20176998 5.78 24 P 0 0;1=4
P 6.31295 4.99705 24 P 0 0;1=4
P 6.87 5 24 P 0 0;1=4
P 9.64795974 0.79643002 24 P 0 0;1=4
P 9.40795 0.26133002 24 P 0 0;1=4
P 3.60998976 0.24 24 P 0 0;1=4
P 3.65998976 0.345 24 P 0 0;1=4
P 3.86 0.7751 24 P 0 0;1=0
P 6.905 4.94705 24 P 0 0;1=4
P 6.905 4.88705 24 P 0 0;1=4
P 6.955 4.8 24 P 0 0;1=4
P 6.955 4.84 24 P 0 0;1=4
P 6.955 4.72 24 P 0 0;1=4
P 6.955 4.76 24 P 0 0;1=4
P 6.59708976 5.0502 24 P 0 0;1=4
P 6.65218976 4.77 24 P 0 0;1=4
P 6.62119006 4.95641998 24 P 0 0;1=8
P 6.6015 4.93674026 24 P 0 0;1=8
P 6.64088002 4.93673996 24 P 0 0;1=8
P 6.62118976 4.91705 24 P 0 0;1=8
P 6.62118976 4.87768002 24 P 0 0;1=8
P 6.6015 4.89736024 24 P 0 0;1=8
P 6.64087992 4.89736004 24 P 0 0;1=8
P 6.62 4.69 24 P 0 0;1=4
P 6.62 4.725 24 P 0 0;1=4
P 6.385 5.07 24 P 0 0;1=4
P 5.53594026 4.55505 24 P 0 0;1=4
P 6.05708976 4.5102 24 P 0 0;1=4
P 6.01708976 4.5102 24 P 0 0;1=4
P 5.97708976 4.5102 24 P 0 0;1=4
P 5.93708976 4.5102 24 P 0 0;1=4
P 5.89708976 4.5102 24 P 0 0;1=4
P 6.09708976 4.5102 24 P 0 0;1=4
P 5.61708976 4.5102 24 P 0 0;1=4
P 5.65708976 4.5102 24 P 0 0;1=4
P 5.85708976 4.5102 24 P 0 0;1=4
P 5.81708976 4.5102 24 P 0 0;1=4
P 5.77708976 4.5102 24 P 0 0;1=4
P 5.73708976 4.5102 24 P 0 0;1=4
P 5.69708976 4.5102 24 P 0 0;1=4
P 5.57708976 4.5102 24 P 0 0;1=4
P 0.036 0.10868002 24 P 0 0;1=4
P 0.036 0.15868002 24 P 0 0;1=4
P 0.036 0.20868002 24 P 0 0;1=4
P 0.22873976 0.036 24 P 0 0;1=4
P 0.17873976 0.036 24 P 0 0;1=4
P 0.12873976 0.036 24 P 0 0;1=4
P 0.07873976 0.036 24 P 0 0;1=4
P 0.47873976 0.036 24 P 0 0;1=4
P 0.42873976 0.036 24 P 0 0;1=4
P 0.37873976 0.036 24 P 0 0;1=4
P 0.32873976 0.036 24 P 0 0;1=4
P 0.27873976 0.036 24 P 0 0;1=4
P 0.77873976 0.036 24 P 0 0;1=4
P 0.72873976 0.036 24 P 0 0;1=4
P 0.67873976 0.036 24 P 0 0;1=4
P 0.62873976 0.036 24 P 0 0;1=4
P 0.57873976 0.036 24 P 0 0;1=4
P 0.52873976 0.036 24 P 0 0;1=4
P 1.02873976 0.036 24 P 0 0;1=4
P 0.97873976 0.036 24 P 0 0;1=4
P 0.92873976 0.036 24 P 0 0;1=4
P 0.87873976 0.036 24 P 0 0;1=4
P 0.82873976 0.036 24 P 0 0;1=4
P 1.27873976 0.036 24 P 0 0;1=4
P 1.22873976 0.036 24 P 0 0;1=4
P 1.17873976 0.036 24 P 0 0;1=4
P 1.12873976 0.036 24 P 0 0;1=4
P 1.07873976 0.036 24 P 0 0;1=4
P 1.52873976 0.036 24 P 0 0;1=4
P 1.47873976 0.036 24 P 0 0;1=4
P 1.42873976 0.036 24 P 0 0;1=4
P 1.37873976 0.036 24 P 0 0;1=4
P 1.32873976 0.036 24 P 0 0;1=4
P 1.82873976 0.036 24 P 0 0;1=4
P 1.77873976 0.036 24 P 0 0;1=4
P 1.72873976 0.036 24 P 0 0;1=4
P 1.67873976 0.036 24 P 0 0;1=4
P 1.62873976 0.036 24 P 0 0;1=4
P 1.57873976 0.036 24 P 0 0;1=4
P 2.07873976 0.036 24 P 0 0;1=4
P 2.02873976 0.036 24 P 0 0;1=4
P 1.97873976 0.036 24 P 0 0;1=4
P 1.92873976 0.036 24 P 0 0;1=4
P 1.87873976 0.036 24 P 0 0;1=4
P 2.32873976 0.036 24 P 0 0;1=4
P 2.27873976 0.036 24 P 0 0;1=4
P 2.22873976 0.036 24 P 0 0;1=4
P 2.17873976 0.036 24 P 0 0;1=4
P 2.12873976 0.036 24 P 0 0;1=4
P 2.62873976 0.036 24 P 0 0;1=4
P 2.57873976 0.036 24 P 0 0;1=4
P 2.52873976 0.036 24 P 0 0;1=4
P 2.47873976 0.036 24 P 0 0;1=4
P 2.42873976 0.036 24 P 0 0;1=4
P 2.37873976 0.036 24 P 0 0;1=4
P 2.87873976 0.036 24 P 0 0;1=4
P 2.82873976 0.036 24 P 0 0;1=4
P 2.77873976 0.036 24 P 0 0;1=4
P 2.72873976 0.036 24 P 0 0;1=4
P 2.67873976 0.036 24 P 0 0;1=4
P 3.12873976 0.036 24 P 0 0;1=4
P 3.07873976 0.036 24 P 0 0;1=4
P 3.02873976 0.036 24 P 0 0;1=4
P 2.97873976 0.036 24 P 0 0;1=4
P 2.92873976 0.036 24 P 0 0;1=4
P 3.37873976 0.036 24 P 0 0;1=4
P 3.32873976 0.036 24 P 0 0;1=4
P 3.27873976 0.036 24 P 0 0;1=4
P 3.22873976 0.036 24 P 0 0;1=4
P 3.17873976 0.036 24 P 0 0;1=4
P 3.67873976 0.036 24 P 0 0;1=4
P 3.62873976 0.036 24 P 0 0;1=4
P 3.57873976 0.036 24 P 0 0;1=4
P 3.52873976 0.036 24 P 0 0;1=4
P 3.47873976 0.036 24 P 0 0;1=4
P 3.42873976 0.036 24 P 0 0;1=4
P 3.92873976 0.036 24 P 0 0;1=4
P 3.87873976 0.036 24 P 0 0;1=4
P 3.82873976 0.036 24 P 0 0;1=4
P 3.77873976 0.036 24 P 0 0;1=4
P 3.72873976 0.036 24 P 0 0;1=4
P 4.17873976 0.036 24 P 0 0;1=4
P 4.12873976 0.036 24 P 0 0;1=4
P 4.07873976 0.036 24 P 0 0;1=4
P 4.02873976 0.036 24 P 0 0;1=4
P 3.97873976 0.036 24 P 0 0;1=4
P 4.42873976 0.036 24 P 0 0;1=4
P 4.37873976 0.036 24 P 0 0;1=4
P 4.32873976 0.036 24 P 0 0;1=4
P 4.27873976 0.036 24 P 0 0;1=4
P 4.22873976 0.036 24 P 0 0;1=4
P 4.72873976 0.036 24 P 0 0;1=4
P 4.67873976 0.036 24 P 0 0;1=4
P 4.62873976 0.036 24 P 0 0;1=4
P 4.57873976 0.036 24 P 0 0;1=4
P 4.52873976 0.036 24 P 0 0;1=4
P 4.47873976 0.036 24 P 0 0;1=4
P 4.81833976 0.21825 24 P 0 0;1=4
P 4.81833976 0.16825 24 P 0 0;1=4
P 4.81833976 0.11825 24 P 0 0;1=4
P 4.81703888 0.06825906 24 P 0 0;1=4
P 4.77873809 0.03612175 24 P 0 0;1=4
P 6.80730974 0.036 24 P 0 0;1=4
P 6.75730974 0.036 24 P 0 0;1=4
P 6.70730974 0.036 24 P 0 0;1=4
P 6.65730955 0.03676043 24 P 0 0;1=4
P 6.62298947 0.07311939 24 P 0 0;1=4
P 6.62261998 0.12311998 24 P 0 0;1=4
P 6.62261998 0.17311998 24 P 0 0;1=4
P 6.62261998 0.22311998 24 P 0 0;1=4
P 7.00730974 0.036 24 P 0 0;1=4
P 6.95730974 0.036 24 P 0 0;1=4
P 6.90730974 0.036 24 P 0 0;1=4
P 6.85730974 0.036 24 P 0 0;1=4
P 0.036 0.25868002 24 P 0 0;1=4
P 0.036 0.30868002 24 P 0 0;1=4
P 0.036 0.35868002 24 P 0 0;1=4
P 0.036 0.40868002 24 P 0 0;1=4
P 0.036 0.45868002 24 P 0 0;1=4
P 4.96804006 0.46906998 24 P 0 0;1=4
P 4.91804941 0.46808051 24 P 0 0;1=4
P 4.87108927 0.45089055 24 P 0 0;1=4
P 4.83591132 0.41536132 24 P 0 0;1=4
P 4.81919035 0.36823996 24 P 0 0;1=4
P 4.81833976 0.31825 24 P 0 0;1=4
P 4.81833976 0.26825 24 P 0 0;1=4
P 5.21804006 0.46906998 24 P 0 0;1=4
P 5.16804006 0.46906998 24 P 0 0;1=4
P 5.11804006 0.46906998 24 P 0 0;1=4
P 5.06804006 0.46906998 24 P 0 0;1=4
P 5.01804006 0.46906998 24 P 0 0;1=4
P 5.51804006 0.46906998 24 P 0 0;1=4
P 5.46804006 0.46906998 24 P 0 0;1=4
P 5.41804006 0.46906998 24 P 0 0;1=4
P 5.36804006 0.46906998 24 P 0 0;1=4
P 5.31804006 0.46906998 24 P 0 0;1=4
P 5.26804006 0.46906998 24 P 0 0;1=4
P 5.76804006 0.46906998 24 P 0 0;1=4
P 5.71804006 0.46906998 24 P 0 0;1=4
P 5.66804006 0.46906998 24 P 0 0;1=4
P 5.61804006 0.46906998 24 P 0 0;1=4
P 5.56804006 0.46906998 24 P 0 0;1=4
P 6.01804006 0.46906998 24 P 0 0;1=4
P 5.96804006 0.46906998 24 P 0 0;1=4
P 5.91804006 0.46906998 24 P 0 0;1=4
P 5.86804006 0.46906998 24 P 0 0;1=4
P 5.81804006 0.46906998 24 P 0 0;1=4
P 6.31804006 0.46906998 24 P 0 0;1=4
P 6.26804006 0.46906998 24 P 0 0;1=4
P 6.21804006 0.46906998 24 P 0 0;1=4
P 6.16804006 0.46906998 24 P 0 0;1=4
P 6.11804006 0.46906998 24 P 0 0;1=4
P 6.06804006 0.46906998 24 P 0 0;1=4
P 6.56567894 0.45345098 24 P 0 0;1=4
P 6.5180314 0.46861841 24 P 0 0;1=4
P 6.46804006 0.46906998 24 P 0 0;1=4
P 6.41804006 0.46906998 24 P 0 0;1=4
P 6.36804006 0.46906998 24 P 0 0;1=4
P 6.62261998 0.27311998 24 P 0 0;1=4
P 6.62261998 0.32311998 24 P 0 0;1=4
P 6.62106949 0.37309951 24 P 0 0;1=4
P 6.60234085 0.41946063 24 P 0 0;1=4
P 0.036 0.50868002 24 P 0 0;1=4
P 0.036 0.55868002 24 P 0 0;1=4
P 11.845 2.85 24 P 0 0;1=4
P 8.98115 2.7861 24 P 0 0;1=4
P 8.98115 2.8989 24 P 0 0;1=4
P 11.58612972 2.855 24 P 0 0;1=4
P 11.50361998 2.8 24 P 0 0;1=4
P 11.50361998 2.73 24 P 0 0;1=4
P 5.5722 3 24 P 0 0;1=4
P 5.75779006 3.02558996 24 P 0 0;1=4
P 5.9192 2.943 24 P 0 0;1=4
P 4.07385974 2.55 24 P 0 0;1=4
P 3.86826998 2.64559026 24 P 0 0;1=4
P 9.995 2.87559026 24 P 0 0;1=4
P 10.11778976 2.78 24 P 0 0;1=4
P 7.2426 4.60351024 24 P 0 0;1=4
P 7.3401 4.85601024 24 P 0 0;1=4
P 7.1926 5.04351024 24 P 0 0;1=4
P 0.66 2.045 24 P 0 0;1=0
P 1.792 2.4781 24 P 0 0;1=4
P 2.97720974 2.8989 24 P 0 0;1=4
P 2.97720974 2.7861 24 P 0 0;1=4
P 2.9422 2.925 24 P 0 0;1=4
P 8.94278976 2.925 24 P 0 0;1=4
P 5.5822 2.855 24 P 0 0;1=4
P 5.84969026 2.85 24 P 0 0;1=4
P 0.65348996 1.85608996 24 P 0 0;1=4
P 0.65348996 1.91628996 24 P 0 0;1=4
P 0.09448996 4.60236998 26 P 0 3;1=1
P 0.35038996 4.20865994 26 P 0 3;1=1
P 0.09448996 4.2874 26 P 0 3;1=1
P 0.09448996 4.12991998 26 P 0 3;1=1
P 0.17322992 4.16928996 26 P 0 3;1=1
P 0.27165 4.09055 26 P 0 3;1=1
P 0.27165 3.93306998 26 P 0 3;1=1
P 0.35038996 4.05117992 26 P 0 3;1=1
P 0.35038996 3.8937 26 P 0 3;1=1
P 0.09448996 3.97243996 26 P 0 3;1=1
P 0.09448996 3.81495994 26 P 0 3;1=1
P 0.17322992 4.01180994 26 P 0 3;1=1
P 0.17322992 3.85432992 26 P 0 3;1=1
P 0.27165 3.77558996 26 P 0 3;1=1
P 0.27165 3.61810994 26 P 0 3;1=1
P 0.35038996 3.73621998 26 P 0 3;1=1
P 0.35038996 3.57873996 26 P 0 3;1=1
P 0.09448996 3.65747992 26 P 0 3;1=1
P 0.09448996 3.5 26 P 0 3;1=1
P 0.17322992 3.69685 26 P 0 3;1=1
P 0.17322992 3.53936998 26 P 0 3;1=1
P 0.27165 3.46062992 26 P 0 3;1=1
P 0.35038996 3.42125994 26 P 0 3;1=1
P 0.27165 3.30315 26 P 0 3;1=1
P 0.27165 3.22440994 26 P 0 3;1=1
P 0.17322992 3.38188996 26 P 0 3;1=1
P 0.17322992 3.30315 26 P 0 3;1=1
P 0.35038996 3.1063 26 P 0 3;1=1
P 0.35038996 2.94881998 26 P 0 3;1=1
P 0.27165 3.06692992 26 P 0 3;1=1
P 0.27165 2.90945 26 P 0 3;1=1
P 0.17322992 3.14566998 26 P 0 3;1=1
P 0.17322992 2.98818996 26 P 0 3;1=1
P 0.09448996 3.18503996 26 P 0 3;1=1
P 0.09448996 3.02755994 26 P 0 3;1=1
P 0.35038996 2.79133996 26 P 0 3;1=1
P 0.27165 2.75196998 26 P 0 3;1=1
P 0.35038996 2.63385994 26 P 0 3;1=1
P 0.17322992 2.83070994 26 P 0 3;1=1
P 0.09448996 2.87007992 26 P 0 3;1=1
P 0.09448996 2.7126 26 P 0 3;1=1
P 0.35038996 2.39763996 26 P 0 3;1=1
P 0.27165 2.51575 26 P 0 3;1=1
P 0.27165 2.35826998 26 P 0 3;1=1
P 0.17322992 2.59448996 26 P 0 3;1=1
P 0.17322992 2.43700994 26 P 0 3;1=1
P 0.09448996 2.47637992 26 P 0 3;1=1
P 0.09448996 2.3189 26 P 0 3;1=1
P 0.35038996 2.24015994 26 P 0 3;1=1
P 0.35038996 2.08267992 26 P 0 3;1=1
P 0.35038996 2.00393996 26 P 0 3;1=1
P 0.27165 2.20078996 26 P 0 3;1=1
P 0.17322992 2.27952992 26 P 0 3;1=1
P 0.09448996 2.16141998 26 P 0 3;1=1
P 0.09448996 2.08267992 26 P 0 3;1=1
P 0.17322992 1.96456998 26 P 0 3;1=1
P 0.09448996 1.84645994 26 P 0 3;1=1
P 0.09448996 4.44487992 26 P 0 3;1=1
P 12.63778996 2.00393996 26 P 0 3;1=1
P 12.55905 2.12205 26 P 0 3;1=1
P 12.55905 1.88582992 26 P 0 3;1=1
P 12.81495 2.12205 26 P 0 3;1=1
P 12.81495 2.04330994 26 P 0 3;1=1
P 12.73620994 2.39763996 26 P 0 3;1=1
P 12.73620994 2.24015994 26 P 0 3;1=1
P 12.63778996 2.3189 26 P 0 3;1=1
P 12.55905 2.35826998 26 P 0 3;1=1
P 12.55905 2.20078996 26 P 0 3;1=1
P 12.81495 2.43700994 26 P 0 3;1=1
P 12.81495 2.27952992 26 P 0 3;1=1
P 12.73620994 2.55511998 26 P 0 3;1=1
P 12.63778996 2.63385994 26 P 0 3;1=1
P 12.63778996 2.47637992 26 P 0 3;1=1
P 12.55905 2.51575 26 P 0 3;1=1
P 12.81495 2.67322992 26 P 0 3;1=1
P 12.73620994 2.94881998 26 P 0 3;1=1
P 12.73620994 2.79133996 26 P 0 3;1=1
P 12.63778996 3.02755994 26 P 0 3;1=1
P 12.63778996 2.87007992 26 P 0 3;1=1
P 12.55905 2.90945 26 P 0 3;1=1
P 12.55905 2.75196998 26 P 0 3;1=1
P 12.81495 2.98818996 26 P 0 3;1=1
P 12.81495 2.83070994 26 P 0 3;1=1
P 12.73620994 3.26377992 26 P 0 3;1=1
P 12.73620994 3.1063 26 P 0 3;1=1
P 12.63778996 3.18503996 26 P 0 3;1=1
P 12.55905 3.22440994 26 P 0 3;1=1
P 12.55905 3.06692992 26 P 0 3;1=1
P 12.81495 3.14566998 26 P 0 3;1=1
P 12.55905 3.53936998 26 P 0 3;1=1
P 12.63778996 3.57873996 26 P 0 3;1=1
P 12.63778996 3.42125994 26 P 0 3;1=1
P 12.73620994 3.5 26 P 0 3;1=1
P 12.73620994 3.34251998 26 P 0 3;1=1
P 12.63778996 3.34251998 26 P 0 3;1=1
P 12.81495 3.61810994 26 P 0 3;1=1
P 12.81495 3.46062992 26 P 0 3;1=1
P 12.55905 3.85432992 26 P 0 3;1=1
P 12.55905 3.69685 26 P 0 3;1=1
P 12.63778996 3.8937 26 P 0 3;1=1
P 12.63778996 3.73621998 26 P 0 3;1=1
P 12.73620994 3.81495994 26 P 0 3;1=1
P 12.73620994 3.65747992 26 P 0 3;1=1
P 12.81495 3.93306998 26 P 0 3;1=1
P 12.81495 3.77558996 26 P 0 3;1=1
P 12.55905 4.16928996 26 P 0 3;1=1
P 12.55905 4.01180994 26 P 0 3;1=1
P 12.63778996 4.20865994 26 P 0 3;1=1
P 12.63778996 4.05117992 26 P 0 3;1=1
P 12.73620994 4.12991998 26 P 0 3;1=1
P 12.73620994 3.97243996 26 P 0 3;1=1
P 12.81495 4.09055 26 P 0 3;1=1
P 12.55905 4.48425 26 P 0 3;1=1
P 12.55905 4.32676998 26 P 0 3;1=1
P 12.63778996 4.52361998 26 P 0 3;1=1
P 12.63778996 4.36613996 26 P 0 3;1=1
P 12.73620994 4.44487992 26 P 0 3;1=1
P 12.73620994 4.2874 26 P 0 3;1=1
P 12.81495 4.40550994 26 P 0 3;1=1
P 12.81495 4.24802992 26 P 0 3;1=1
P 12.55905 4.64173996 26 P 0 3;1=1
P 12.81495 4.56298996 26 P 0 3;1=1
P 0.27165 4.40550994 26 P 0 3;1=1
P 0.35038996 4.52361998 26 P 0 3;1=1
P 0.17322992 4.48425 26 P 0 3;1=1
P 0.27165 4.24802992 26 P 0 3;1=1
P 0.35038996 4.36613996 26 P 0 3;1=1
P 0.17322992 4.32676998 26 P 0 3;1=1
P 5.49220974 2.73 24 P 0 0;1=4
P 5.44885974 2.9414 24 P 0 0;1=4
P 5.44885974 3.0214 24 P 0 0;1=4
P 5.44885974 3.0564 24 P 0 0;1=4
P 5.44885974 3.1014 24 P 0 0;1=4
P 5.44885974 3.1364 24 P 0 0;1=4
P 5.44885974 3.2164 24 P 0 0;1=4
P 5.44885974 3.1814 24 P 0 0;1=4
P 5.44885974 2.9764 24 P 0 0;1=4
P 5.44885974 3.2614 24 P 0 0;1=4
P 5.44885974 3.2964 24 P 0 0;1=4
P 10.33998976 4.9231 24 P 0 0;1=4
P 10.38498976 4.9231 24 P 0 0;1=0
P 10.77498976 4.9231 24 P 0 0;1=4
P 10.72998976 4.9231 24 P 0 0;1=4
P 10.30498976 4.9431 24 P 0 0;1=4
P 10.26498976 4.9431 24 P 0 0;1=4
P 10.30498976 5.0281 24 P 0 0;1=4
P 10.30498976 5.0731 24 P 0 0;1=4
P 10.30498976 4.9831 24 P 0 0;1=4
P 10.26498976 5.0281 24 P 0 0;1=4
P 10.26498976 5.0731 24 P 0 0;1=4
P 10.26498976 4.9831 24 P 0 0;1=4
P 10.26498976 5.1181 24 P 0 0;1=4
P 10.30498976 5.1181 24 P 0 0;1=4
P 10.34498976 5.1181 24 P 0 0;1=4
P 10.42498976 4.9431 24 P 0 0;1=4
P 10.46498976 4.9431 24 P 0 0;1=4
P 10.38498976 5.1181 24 P 0 0;1=4
P 10.46498976 5.1181 24 P 0 0;1=4
P 10.42498976 5.1181 24 P 0 0;1=4
P 10.42498976 4.9831 24 P 0 0;1=4
P 10.42498976 5.0731 24 P 0 0;1=4
P 10.42498976 5.0281 24 P 0 0;1=4
P 10.46498976 4.9831 24 P 0 0;1=4
P 10.46498976 5.0731 24 P 0 0;1=4
P 10.46498976 5.0281 24 P 0 0;1=4
P 10.85498976 4.9431 24 P 0 0;1=4
P 10.81498976 4.9431 24 P 0 0;1=4
P 10.65498976 4.9431 24 P 0 0;1=4
P 10.69498976 4.9431 24 P 0 0;1=4
P 10.85498976 5.0281 24 P 0 0;1=4
P 10.85498976 5.0731 24 P 0 0;1=4
P 10.85498976 4.9831 24 P 0 0;1=4
P 10.81498976 5.0281 24 P 0 0;1=4
P 10.81498976 5.0731 24 P 0 0;1=4
P 10.81498976 4.9831 24 P 0 0;1=4
P 10.81498976 5.1181 24 P 0 0;1=4
P 10.85498976 5.1181 24 P 0 0;1=4
P 10.73498976 5.1181 24 P 0 0;1=4
P 10.69498976 5.1181 24 P 0 0;1=4
P 10.65498976 5.1181 24 P 0 0;1=4
P 10.77498976 5.1181 24 P 0 0;1=4
P 10.65498976 4.9831 24 P 0 0;1=4
P 10.65498976 5.0731 24 P 0 0;1=4
P 10.65498976 5.0281 24 P 0 0;1=4
P 10.69498976 4.9831 24 P 0 0;1=4
P 10.69498976 5.0731 24 P 0 0;1=4
P 10.69498976 5.0281 24 P 0 0;1=4
P 1.23905994 4.60351004 24 P 0 0;1=4
P 1.18905994 5.04351004 24 P 0 0;1=4
P 1.33655994 4.85601004 24 P 0 0;1=4
P 10.16606998 2.81 24 P 0 0;1=4
P 4.15220974 2.9281 24 P 0 0;1=4
P 11.45278976 2.9414 24 P 0 0;1=4
P 11.45278976 3.0214 24 P 0 0;1=4
P 11.45278976 3.0564 24 P 0 0;1=4
P 11.45278976 3.1014 24 P 0 0;1=4
P 11.45278976 3.1364 24 P 0 0;1=4
P 11.45278976 3.2164 24 P 0 0;1=4
P 11.45278976 3.1814 24 P 0 0;1=4
P 11.45278976 2.9764 24 P 0 0;1=4
P 11.45278976 3.2614 24 P 0 0;1=4
P 11.45278976 3.2964 24 P 0 0;1=4
P 0.09448996 1.45275994 26 P 0 3;1=1
P 0.27165 1.57086998 26 P 0 3;1=1
P 0.35038996 1.45275994 26 P 0 3;1=1
P 12.81495 1.49212992 26 P 0 3;1=1
P 12.73620994 1.61023996 26 P 0 3;1=1
P 12.55905 1.49212992 26 P 0 3;1=1
P 0.27165 1.88582992 26 P 0 3;1=1
P 12.73620994 1.9252 26 P 0 3;1=1
P 7.35730974 0.036 24 P 0 0;1=4
P 7.60730974 0.036 24 P 0 0;1=4
P 7.55730974 0.036 24 P 0 0;1=4
P 7.50730974 0.036 24 P 0 0;1=4
P 7.45730974 0.036 24 P 0 0;1=4
P 7.40730974 0.036 24 P 0 0;1=4
P 7.85730974 0.036 24 P 0 0;1=4
P 7.80730974 0.036 24 P 0 0;1=4
P 7.75730974 0.036 24 P 0 0;1=4
P 7.70730974 0.036 24 P 0 0;1=4
P 7.65730974 0.036 24 P 0 0;1=4
P 8.15730974 0.036 24 P 0 0;1=4
P 8.10730974 0.036 24 P 0 0;1=4
P 8.05730974 0.036 24 P 0 0;1=4
P 8.00730974 0.036 24 P 0 0;1=4
P 7.95730974 0.036 24 P 0 0;1=4
P 7.90730974 0.036 24 P 0 0;1=4
P 8.40730974 0.036 24 P 0 0;1=4
P 8.35730974 0.036 24 P 0 0;1=4
P 8.30730974 0.036 24 P 0 0;1=4
P 8.25730974 0.036 24 P 0 0;1=4
P 8.20730974 0.036 24 P 0 0;1=4
P 8.65730974 0.036 24 P 0 0;1=4
P 8.60730974 0.036 24 P 0 0;1=4
P 8.55730974 0.036 24 P 0 0;1=4
P 8.50730974 0.036 24 P 0 0;1=4
P 8.45730974 0.036 24 P 0 0;1=4
P 8.90730974 0.036 24 P 0 0;1=4
P 8.85730974 0.036 24 P 0 0;1=4
P 8.80730974 0.036 24 P 0 0;1=4
P 8.75730974 0.036 24 P 0 0;1=4
P 8.70730974 0.036 24 P 0 0;1=4
P 9.20730974 0.036 24 P 0 0;1=4
P 9.15730974 0.036 24 P 0 0;1=4
P 9.10730974 0.036 24 P 0 0;1=4
P 9.05730974 0.036 24 P 0 0;1=4
P 9.00730974 0.036 24 P 0 0;1=4
P 8.95730974 0.036 24 P 0 0;1=4
P 9.45730974 0.036 24 P 0 0;1=4
P 9.40730974 0.036 24 P 0 0;1=4
P 9.35730974 0.036 24 P 0 0;1=4
P 9.30730974 0.036 24 P 0 0;1=4
P 9.25730974 0.036 24 P 0 0;1=4
P 9.70730974 0.036 24 P 0 0;1=4
P 9.65730974 0.036 24 P 0 0;1=4
P 9.60730974 0.036 24 P 0 0;1=4
P 9.55730974 0.036 24 P 0 0;1=4
P 9.50730974 0.036 24 P 0 0;1=4
P 10.00730974 0.036 24 P 0 0;1=4
P 9.95730974 0.036 24 P 0 0;1=4
P 9.90730974 0.036 24 P 0 0;1=4
P 9.85730974 0.036 24 P 0 0;1=4
P 9.80730974 0.036 24 P 0 0;1=4
P 9.75730974 0.036 24 P 0 0;1=4
P 10.25730974 0.036 24 P 0 0;1=4
P 10.20730974 0.036 24 P 0 0;1=4
P 10.15730974 0.036 24 P 0 0;1=4
P 10.10730974 0.036 24 P 0 0;1=4
P 10.05730974 0.036 24 P 0 0;1=4
P 10.50730974 0.036 24 P 0 0;1=4
P 10.45730974 0.036 24 P 0 0;1=4
P 10.40730974 0.036 24 P 0 0;1=4
P 10.35730974 0.036 24 P 0 0;1=4
P 10.30730974 0.036 24 P 0 0;1=4
P 10.75730974 0.036 24 P 0 0;1=4
P 10.70730974 0.036 24 P 0 0;1=4
P 10.65730974 0.036 24 P 0 0;1=4
P 10.60730974 0.036 24 P 0 0;1=4
P 10.55730974 0.036 24 P 0 0;1=4
P 11.05730974 0.036 24 P 0 0;1=4
P 11.00730974 0.036 24 P 0 0;1=4
P 10.95730974 0.036 24 P 0 0;1=4
P 10.90730974 0.036 24 P 0 0;1=4
P 10.85730974 0.036 24 P 0 0;1=4
P 10.80730974 0.036 24 P 0 0;1=4
P 11.30730974 0.036 24 P 0 0;1=4
P 11.25730974 0.036 24 P 0 0;1=4
P 11.20730974 0.036 24 P 0 0;1=4
P 11.15730974 0.036 24 P 0 0;1=4
P 11.10730974 0.036 24 P 0 0;1=4
P 11.55730974 0.036 24 P 0 0;1=4
P 11.50730974 0.036 24 P 0 0;1=4
P 11.45730974 0.036 24 P 0 0;1=4
P 11.40730974 0.036 24 P 0 0;1=4
P 11.35730974 0.036 24 P 0 0;1=4
P 11.80730974 0.036 24 P 0 0;1=4
P 11.75730974 0.036 24 P 0 0;1=4
P 11.70730974 0.036 24 P 0 0;1=4
P 11.65730974 0.036 24 P 0 0;1=4
P 11.60730974 0.036 24 P 0 0;1=4
P 12.10730974 0.036 24 P 0 0;1=4
P 12.05730974 0.036 24 P 0 0;1=4
P 12.00730974 0.036 24 P 0 0;1=4
P 11.95730974 0.036 24 P 0 0;1=4
P 11.90730974 0.036 24 P 0 0;1=4
P 11.85730974 0.036 24 P 0 0;1=4
P 12.35730974 0.036 24 P 0 0;1=4
P 12.30730974 0.036 24 P 0 0;1=4
P 12.25730974 0.036 24 P 0 0;1=4
P 12.20730974 0.036 24 P 0 0;1=4
P 12.15730974 0.036 24 P 0 0;1=4
P 12.60730974 0.036 24 P 0 0;1=4
P 12.55730974 0.036 24 P 0 0;1=4
P 12.50730974 0.036 24 P 0 0;1=4
P 12.45730974 0.036 24 P 0 0;1=4
P 12.40730974 0.036 24 P 0 0;1=4
P 12.8892 0.22595974 24 P 0 0;1=4
P 12.8892 0.17595974 24 P 0 0;1=4
P 12.8892 0.12595974 24 P 0 0;1=4
P 12.88911073 0.07596083 24 P 0 0;1=4
P 12.85728868 0.03739114 24 P 0 0;1=4
P 12.80730974 0.036 24 P 0 0;1=4
P 12.75730974 0.036 24 P 0 0;1=4
P 12.70730974 0.036 24 P 0 0;1=4
P 12.65730974 0.036 24 P 0 0;1=4
P 12.8892 0.47595974 24 P 0 0;1=4
P 12.8892 0.42595974 24 P 0 0;1=4
P 12.8892 0.37595974 24 P 0 0;1=4
P 12.8892 0.32595974 24 P 0 0;1=4
P 12.8892 0.27595974 24 P 0 0;1=4
P 12.8892 0.62595974 24 P 0 0;1=4
P 12.8892 0.57595974 24 P 0 0;1=4
P 12.8892 0.52595974 24 P 0 0;1=4
P 0.036 1.00868002 24 P 0 0;1=4
P 0.036 1.05868002 24 P 0 0;1=4
P 0.036 1.10868002 24 P 0 0;1=4
P 0.036 1.15868002 24 P 0 0;1=4
P 0.036 1.20868002 24 P 0 0;1=4
P 0.036 1.25868002 24 P 0 0;1=4
P 0.036 1.30868002 24 P 0 0;1=4
P 0.036 1.35868002 24 P 0 0;1=4
P 0.036 1.40868002 24 P 0 0;1=4
P 0.036 1.45868002 24 P 0 0;1=4
P 0.036 1.50868002 24 P 0 0;1=4
P 0.036 1.55868002 24 P 0 0;1=4
P 0.036 1.60868002 24 P 0 0;1=4
P 0.036 1.65868002 24 P 0 0;1=4
P 0.036 1.70868002 24 P 0 0;1=4
P 0.036 1.75868002 24 P 0 0;1=4
P 0.036 1.80868002 24 P 0 0;1=4
P 0.036 1.85868002 24 P 0 0;1=4
P 0.036 1.90868002 24 P 0 0;1=4
P 0.036 1.95868002 24 P 0 0;1=4
P 0.036 2.00868002 24 P 0 0;1=4
P 0.036 2.05868002 24 P 0 0;1=4
P 0.036 2.10868002 24 P 0 0;1=4
P 0.036 2.15868002 24 P 0 0;1=4
P 0.036 2.20868002 24 P 0 0;1=4
P 0.036 2.25868002 24 P 0 0;1=4
P 0.036 2.30868002 24 P 0 0;1=4
P 0.036 2.35868002 24 P 0 0;1=4
P 0.036 2.40868002 24 P 0 0;1=4
P 0.036 2.45868002 24 P 0 0;1=4
P 0.036 2.50868002 24 P 0 0;1=4
P 0.036 2.55868002 24 P 0 0;1=4
P 0.036 2.60868002 24 P 0 0;1=4
P 0.036 2.65868002 24 P 0 0;1=4
P 0.036 2.70868002 24 P 0 0;1=4
P 0.036 2.75868002 24 P 0 0;1=4
P 0.036 2.80868002 24 P 0 0;1=4
P 0.036 2.85868002 24 P 0 0;1=4
P 0.036 2.90868002 24 P 0 0;1=4
P 0.036 2.95868002 24 P 0 0;1=4
P 0.036 3.00868002 24 P 0 0;1=4
P 0.036 3.05868002 24 P 0 0;1=4
P 0.036 3.10868002 24 P 0 0;1=4
P 0.036 3.15868002 24 P 0 0;1=4
P 0.036 3.20868002 24 P 0 0;1=4
P 0.036 3.25868002 24 P 0 0;1=4
P 0.036 3.30868002 24 P 0 0;1=4
P 0.036 3.35868002 24 P 0 0;1=4
P 0.036 3.40868002 24 P 0 0;1=4
P 0.036 3.45868002 24 P 0 0;1=4
P 0.036 3.50868002 24 P 0 0;1=4
P 0.036 3.55868002 24 P 0 0;1=4
P 0.036 3.60868002 24 P 0 0;1=4
P 0.036 3.65868002 24 P 0 0;1=4
P 0.036 3.70868002 24 P 0 0;1=4
P 0.036 3.75868002 24 P 0 0;1=4
P 0.036 3.80868002 24 P 0 0;1=4
P 0.036 3.85868002 24 P 0 0;1=4
P 0.036 3.90868002 24 P 0 0;1=4
P 0.036 3.95868002 24 P 0 0;1=4
P 0.036 4.00868002 24 P 0 0;1=4
P 0.036 4.05868002 24 P 0 0;1=4
P 0.036 4.10868002 24 P 0 0;1=4
P 0.036 4.15868002 24 P 0 0;1=4
P 0.036 4.20868002 24 P 0 0;1=4
P 0.036 4.25868002 24 P 0 0;1=4
P 0.036 4.30868002 24 P 0 0;1=4
P 0.036 4.35868002 24 P 0 0;1=4
P 0.036 4.40868002 24 P 0 0;1=4
P 0.036 4.45868002 24 P 0 0;1=4
P 0.036 4.50868002 24 P 0 0;1=4
P 0.036 4.55868002 24 P 0 0;1=4
P 0.036 4.60868002 24 P 0 0;1=4
P 0.036 4.65868002 24 P 0 0;1=4
P 0.036 4.70868002 24 P 0 0;1=4
P 0.036 4.75868002 24 P 0 0;1=4
P 12.8892 1.02595974 24 P 0 0;1=4
P 12.8892 1.27595974 24 P 0 0;1=4
P 12.8892 1.22595974 24 P 0 0;1=4
P 12.8892 1.17595974 24 P 0 0;1=4
P 12.8892 1.12595974 24 P 0 0;1=4
P 12.8892 1.07595974 24 P 0 0;1=4
P 12.8892 1.52595974 24 P 0 0;1=4
P 12.8892 1.47595974 24 P 0 0;1=4
P 12.8892 1.42595974 24 P 0 0;1=4
P 12.8892 1.37595974 24 P 0 0;1=4
P 12.8892 1.32595974 24 P 0 0;1=4
P 12.8892 1.77595974 24 P 0 0;1=4
P 12.8892 1.72595974 24 P 0 0;1=4
P 12.8892 1.67595974 24 P 0 0;1=4
P 12.8892 1.62595974 24 P 0 0;1=4
P 12.8892 1.57595974 24 P 0 0;1=4
P 12.8892 2.07595974 24 P 0 0;1=4
P 12.8892 2.02595974 24 P 0 0;1=4
P 12.8892 1.97595974 24 P 0 0;1=4
P 12.8892 1.92595974 24 P 0 0;1=4
P 12.8892 1.87595974 24 P 0 0;1=4
P 12.8892 1.82595974 24 P 0 0;1=4
P 12.8892 2.32595974 24 P 0 0;1=4
P 12.8892 2.27595974 24 P 0 0;1=4
P 12.8892 2.22595974 24 P 0 0;1=4
P 12.8892 2.17595974 24 P 0 0;1=4
P 12.8892 2.57595974 24 P 0 0;1=4
P 12.8892 2.52595974 24 P 0 0;1=4
P 12.8892 2.47595974 24 P 0 0;1=4
P 12.8892 2.42595974 24 P 0 0;1=4
P 12.8892 2.37595974 24 P 0 0;1=4
P 12.8892 2.82595974 24 P 0 0;1=4
P 12.8892 2.77595974 24 P 0 0;1=4
P 12.8892 2.72595974 24 P 0 0;1=4
P 12.8892 2.67595974 24 P 0 0;1=4
P 12.8892 2.62595974 24 P 0 0;1=4
P 12.8892 3.12595974 24 P 0 0;1=4
P 12.8892 3.07595974 24 P 0 0;1=4
P 12.8892 3.02595974 24 P 0 0;1=4
P 12.8892 2.97595974 24 P 0 0;1=4
P 12.8892 2.92595974 24 P 0 0;1=4
P 12.8892 2.87595974 24 P 0 0;1=4
P 12.8892 3.37595974 24 P 0 0;1=4
P 12.8892 3.32595974 24 P 0 0;1=4
P 12.8892 3.27595974 24 P 0 0;1=4
P 12.8892 3.22595974 24 P 0 0;1=4
P 12.8892 3.17595974 24 P 0 0;1=4
P 12.8892 3.62595974 24 P 0 0;1=4
P 12.8892 3.57595974 24 P 0 0;1=4
P 12.8892 3.52595974 24 P 0 0;1=4
P 12.8892 3.47595974 24 P 0 0;1=4
P 12.8892 3.42595974 24 P 0 0;1=4
P 12.8892 3.92595974 24 P 0 0;1=4
P 12.8892 3.87595974 24 P 0 0;1=4
P 12.8892 3.82595974 24 P 0 0;1=4
P 12.8892 3.77595974 24 P 0 0;1=4
P 12.8892 3.72595974 24 P 0 0;1=4
P 12.8892 3.67595974 24 P 0 0;1=4
P 12.8892 4.17595974 24 P 0 0;1=4
P 12.8892 4.12595974 24 P 0 0;1=4
P 12.8892 4.07595974 24 P 0 0;1=4
P 12.8892 4.02595974 24 P 0 0;1=4
P 12.8892 3.97595974 24 P 0 0;1=4
P 12.8892 4.42595974 24 P 0 0;1=4
P 12.8892 4.37595974 24 P 0 0;1=4
P 12.8892 4.32595974 24 P 0 0;1=4
P 12.8892 4.27595974 24 P 0 0;1=4
P 12.8892 4.22595974 24 P 0 0;1=4
P 12.8892 4.67595974 24 P 0 0;1=4
P 12.8892 4.62595974 24 P 0 0;1=4
P 12.8892 4.57595974 24 P 0 0;1=4
P 12.8892 4.52595974 24 P 0 0;1=4
P 12.8892 4.47595974 24 P 0 0;1=4
P 12.8892 4.82595974 24 P 0 0;1=4
P 12.8892 4.77595974 24 P 0 0;1=4
P 12.8892 4.72595974 24 P 0 0;1=4
P 0.036 5.25868002 24 P 0 0;1=4
P 0.036 5.30868002 24 P 0 0;1=4
P 0.036 5.35868002 24 P 0 0;1=4
P 0.036 5.40868002 24 P 0 0;1=4
P 0.036 5.45868002 24 P 0 0;1=4
P 0.036 5.50868002 24 P 0 0;1=4
P 0.036 5.55868002 24 P 0 0;1=4
P 0.036 5.60868002 24 P 0 0;1=4
P 0.036 5.65868002 24 P 0 0;1=4
P 0.036 5.70868002 24 P 0 0;1=4
P 0.036 5.75868002 24 P 0 0;1=4
P 0.036 5.80868002 24 P 0 0;1=4
P 0.036 5.85868002 24 P 0 0;1=4
P 0.036 5.90868002 24 P 0 0;1=4
P 0.03826998 5.95863002 24 P 0 0;1=4
P 0.07901024 5.98761998 24 P 0 0;1=4
P 0.12901024 5.98761998 24 P 0 0;1=4
P 0.17901024 5.98761998 24 P 0 0;1=4
P 0.22901024 5.98761998 24 P 0 0;1=4
P 0.27901024 5.98761998 24 P 0 0;1=4
P 0.32901024 5.98761998 24 P 0 0;1=4
P 0.37901024 5.98761998 24 P 0 0;1=4
P 0.42901024 5.98761998 24 P 0 0;1=4
P 0.47901024 5.98761998 24 P 0 0;1=4
P 0.52901024 5.98761998 24 P 0 0;1=4
P 0.57901024 5.98761998 24 P 0 0;1=4
P 0.62901024 5.98761998 24 P 0 0;1=4
P 0.67901024 5.98761998 24 P 0 0;1=4
P 0.72901024 5.98761998 24 P 0 0;1=4
P 0.77901024 5.98761998 24 P 0 0;1=4
P 0.82901024 5.98761998 24 P 0 0;1=4
P 0.87901024 5.98761998 24 P 0 0;1=4
P 0.92901024 5.98761998 24 P 0 0;1=4
P 0.97901024 5.98761998 24 P 0 0;1=4
P 1.02901024 5.98761998 24 P 0 0;1=4
P 1.07901024 5.98761998 24 P 0 0;1=4
P 1.12901024 5.98761998 24 P 0 0;1=4
P 1.17901024 5.98761998 24 P 0 0;1=4
P 1.22901024 5.98761998 24 P 0 0;1=4
P 1.27901024 5.98761998 24 P 0 0;1=4
P 1.32901024 5.98761998 24 P 0 0;1=4
P 1.37901024 5.98761998 24 P 0 0;1=4
P 1.42901024 5.98761998 24 P 0 0;1=4
P 1.47901024 5.98761998 24 P 0 0;1=4
P 1.52901024 5.98761998 24 P 0 0;1=4
P 1.57901024 5.98761998 24 P 0 0;1=4
P 1.62901024 5.98761998 24 P 0 0;1=4
P 1.67901024 5.98761998 24 P 0 0;1=4
P 1.72901024 5.98761998 24 P 0 0;1=4
P 1.77901024 5.98761998 24 P 0 0;1=4
P 1.82901024 5.98761998 24 P 0 0;1=4
P 1.87901024 5.98761998 24 P 0 0;1=4
P 1.92901024 5.98761998 24 P 0 0;1=4
P 1.97901024 5.98761998 24 P 0 0;1=4
P 2.02901024 5.98761998 24 P 0 0;1=4
P 2.07901024 5.98761998 24 P 0 0;1=4
P 2.12901024 5.98761998 24 P 0 0;1=4
P 2.17901024 5.98761998 24 P 0 0;1=4
P 2.22901024 5.98761998 24 P 0 0;1=4
P 2.27901024 5.98761998 24 P 0 0;1=4
P 2.32901024 5.98761998 24 P 0 0;1=4
P 2.37901024 5.98761998 24 P 0 0;1=4
P 2.42901024 5.98761998 24 P 0 0;1=4
P 2.47901024 5.98761998 24 P 0 0;1=4
P 2.52901024 5.98761998 24 P 0 0;1=4
P 2.57901024 5.98761998 24 P 0 0;1=4
P 2.62901024 5.98761998 24 P 0 0;1=4
P 2.67901024 5.98761998 24 P 0 0;1=4
P 2.72901024 5.98761998 24 P 0 0;1=4
P 2.77901024 5.98761998 24 P 0 0;1=4
P 2.82901024 5.98761998 24 P 0 0;1=4
P 2.87901024 5.98761998 24 P 0 0;1=4
P 2.92901024 5.98761998 24 P 0 0;1=4
P 2.97901024 5.98761998 24 P 0 0;1=4
P 3.02901024 5.98761998 24 P 0 0;1=4
P 3.07901024 5.98761998 24 P 0 0;1=4
P 3.12901024 5.98761998 24 P 0 0;1=4
P 3.17901024 5.98761998 24 P 0 0;1=4
P 3.22901024 5.98761998 24 P 0 0;1=4
P 3.27901024 5.98761998 24 P 0 0;1=4
P 3.32901024 5.98761998 24 P 0 0;1=4
P 3.37901024 5.98761998 24 P 0 0;1=4
P 3.42901024 5.98761998 24 P 0 0;1=4
P 3.47901024 5.98761998 24 P 0 0;1=4
P 3.52901024 5.98761998 24 P 0 0;1=4
P 3.57901024 5.98761998 24 P 0 0;1=4
P 3.62901024 5.98761998 24 P 0 0;1=4
P 3.67901024 5.98761998 24 P 0 0;1=4
P 3.72901024 5.98761998 24 P 0 0;1=4
P 3.77901024 5.98761998 24 P 0 0;1=4
P 3.82901024 5.98761998 24 P 0 0;1=4
P 3.87901024 5.98761998 24 P 0 0;1=4
P 3.92901024 5.98761998 24 P 0 0;1=4
P 3.97901024 5.98761998 24 P 0 0;1=4
P 4.02901024 5.98761998 24 P 0 0;1=4
P 4.07901024 5.98761998 24 P 0 0;1=4
P 4.12901024 5.98761998 24 P 0 0;1=4
P 4.17901024 5.98761998 24 P 0 0;1=4
P 4.22901024 5.98761998 24 P 0 0;1=4
P 4.27901024 5.98761998 24 P 0 0;1=4
P 4.32901024 5.98761998 24 P 0 0;1=4
P 4.37901024 5.98761998 24 P 0 0;1=4
P 4.42901024 5.98761998 24 P 0 0;1=4
P 4.47901024 5.98761998 24 P 0 0;1=4
P 4.52901024 5.98761998 24 P 0 0;1=4
P 4.57901024 5.98761998 24 P 0 0;1=4
P 4.62901024 5.98761998 24 P 0 0;1=4
P 4.67901024 5.98761998 24 P 0 0;1=4
P 4.72901024 5.98761998 24 P 0 0;1=4
P 4.77901024 5.98761998 24 P 0 0;1=4
P 4.82901024 5.98761998 24 P 0 0;1=4
P 4.87901024 5.98761998 24 P 0 0;1=4
P 4.92901024 5.98761998 24 P 0 0;1=4
P 4.97901024 5.98761998 24 P 0 0;1=4
P 5.02901024 5.98761998 24 P 0 0;1=4
P 5.07901024 5.98761998 24 P 0 0;1=4
P 5.12901024 5.98761998 24 P 0 0;1=4
P 5.17901024 5.98761998 24 P 0 0;1=4
P 5.22901024 5.98761998 24 P 0 0;1=4
P 5.27901024 5.98761998 24 P 0 0;1=4
P 5.32901024 5.98761998 24 P 0 0;1=4
P 5.37901024 5.98761998 24 P 0 0;1=4
P 5.42901024 5.98761998 24 P 0 0;1=4
P 5.47901024 5.98761998 24 P 0 0;1=4
P 5.52901024 5.98761998 24 P 0 0;1=4
P 5.57901024 5.98761998 24 P 0 0;1=4
P 5.62901024 5.98761998 24 P 0 0;1=4
P 5.67901024 5.98761998 24 P 0 0;1=4
P 5.72901024 5.98761998 24 P 0 0;1=4
P 5.77901024 5.98761998 24 P 0 0;1=4
P 5.82901024 5.98761998 24 P 0 0;1=4
P 5.87901024 5.98761998 24 P 0 0;1=4
P 5.92901024 5.98761998 24 P 0 0;1=4
P 5.97901024 5.98761998 24 P 0 0;1=4
P 6.02901024 5.98761998 24 P 0 0;1=4
P 6.07901024 5.98761998 24 P 0 0;1=4
P 6.12901024 5.98761998 24 P 0 0;1=4
P 6.17901024 5.98761998 24 P 0 0;1=4
P 6.22901024 5.98761998 24 P 0 0;1=4
P 6.27901024 5.98761998 24 P 0 0;1=4
P 6.32901024 5.98761998 24 P 0 0;1=4
P 6.37901024 5.98761998 24 P 0 0;1=4
P 6.42901024 5.98761998 24 P 0 0;1=4
P 6.47901024 5.98761998 24 P 0 0;1=4
P 6.52901024 5.98761998 24 P 0 0;1=4
P 6.57901024 5.98761998 24 P 0 0;1=4
P 6.62901024 5.98761998 24 P 0 0;1=4
P 6.67901024 5.98761998 24 P 0 0;1=4
P 6.72901024 5.98761998 24 P 0 0;1=4
P 6.77901024 5.98761998 24 P 0 0;1=4
P 6.82901024 5.98761998 24 P 0 0;1=4
P 6.87901024 5.98761998 24 P 0 0;1=4
P 6.92901024 5.98761998 24 P 0 0;1=4
P 6.97901024 5.98761998 24 P 0 0;1=4
P 12.8892 5.47595974 24 P 0 0;1=4
P 12.8892 5.42595974 24 P 0 0;1=4
P 12.8892 5.37595974 24 P 0 0;1=4
P 12.8892 5.32595974 24 P 0 0;1=4
P 12.8892 5.27595974 24 P 0 0;1=4
P 12.8892 5.72595974 24 P 0 0;1=4
P 12.8892 5.67595974 24 P 0 0;1=4
P 12.8892 5.62595974 24 P 0 0;1=4
P 12.8892 5.57595974 24 P 0 0;1=4
P 12.8892 5.52595974 24 P 0 0;1=4
P 7.37901024 5.98761998 24 P 0 0;1=4
P 7.42901024 5.98761998 24 P 0 0;1=4
P 7.47901024 5.98761998 24 P 0 0;1=4
P 7.52901024 5.98761998 24 P 0 0;1=4
P 7.57901024 5.98761998 24 P 0 0;1=4
P 7.62901024 5.98761998 24 P 0 0;1=4
P 7.67901024 5.98761998 24 P 0 0;1=4
P 7.72901024 5.98761998 24 P 0 0;1=4
P 7.77901024 5.98761998 24 P 0 0;1=4
P 7.82901024 5.98761998 24 P 0 0;1=4
P 7.87901024 5.98761998 24 P 0 0;1=4
P 7.92901024 5.98761998 24 P 0 0;1=4
P 7.97901024 5.98761998 24 P 0 0;1=4
P 8.02901024 5.98761998 24 P 0 0;1=4
P 8.07901024 5.98761998 24 P 0 0;1=4
P 8.12901024 5.98761998 24 P 0 0;1=4
P 8.17901024 5.98761998 24 P 0 0;1=4
P 8.22901024 5.98761998 24 P 0 0;1=4
P 8.27901024 5.98761998 24 P 0 0;1=4
P 8.32901024 5.98761998 24 P 0 0;1=4
P 8.37901024 5.98761998 24 P 0 0;1=4
P 8.42901024 5.98761998 24 P 0 0;1=4
P 8.47901024 5.98761998 24 P 0 0;1=4
P 8.52901024 5.98761998 24 P 0 0;1=4
P 8.57901024 5.98761998 24 P 0 0;1=4
P 8.62901024 5.98761998 24 P 0 0;1=4
P 8.67901024 5.98761998 24 P 0 0;1=4
P 8.72901024 5.98761998 24 P 0 0;1=4
P 8.77901024 5.98761998 24 P 0 0;1=4
P 8.82901024 5.98761998 24 P 0 0;1=4
P 8.87901024 5.98761998 24 P 0 0;1=4
P 8.92901024 5.98761998 24 P 0 0;1=4
P 8.97901024 5.98761998 24 P 0 0;1=4
P 9.02901024 5.98761998 24 P 0 0;1=4
P 9.07901024 5.98761998 24 P 0 0;1=4
P 9.12901024 5.98761998 24 P 0 0;1=4
P 9.17901024 5.98761998 24 P 0 0;1=4
P 9.22901024 5.98761998 24 P 0 0;1=4
P 9.27901024 5.98761998 24 P 0 0;1=4
P 9.32901024 5.98761998 24 P 0 0;1=4
P 9.37901024 5.98761998 24 P 0 0;1=4
P 9.42901024 5.98761998 24 P 0 0;1=4
P 9.47901024 5.98761998 24 P 0 0;1=4
P 9.52901024 5.98761998 24 P 0 0;1=4
P 9.57901024 5.98761998 24 P 0 0;1=4
P 9.62901024 5.98761998 24 P 0 0;1=4
P 9.67901024 5.98761998 24 P 0 0;1=4
P 9.72901024 5.98761998 24 P 0 0;1=4
P 9.77901024 5.98761998 24 P 0 0;1=4
P 9.82901024 5.98761998 24 P 0 0;1=4
P 9.87901024 5.98761998 24 P 0 0;1=4
P 9.92901024 5.98761998 24 P 0 0;1=4
P 9.97901024 5.98761998 24 P 0 0;1=4
P 10.02901024 5.98761998 24 P 0 0;1=4
P 10.07901024 5.98761998 24 P 0 0;1=4
P 10.12901024 5.98761998 24 P 0 0;1=4
P 10.17901024 5.98761998 24 P 0 0;1=4
P 10.22901024 5.98761998 24 P 0 0;1=4
P 10.27901024 5.98761998 24 P 0 0;1=4
P 10.32901024 5.98761998 24 P 0 0;1=4
P 10.37901024 5.98761998 24 P 0 0;1=4
P 10.42901024 5.98761998 24 P 0 0;1=4
P 10.47901024 5.98761998 24 P 0 0;1=4
P 10.52901024 5.98761998 24 P 0 0;1=4
P 10.57901024 5.98761998 24 P 0 0;1=4
P 10.62901024 5.98761998 24 P 0 0;1=4
P 10.67901024 5.98761998 24 P 0 0;1=4
P 10.72901024 5.98761998 24 P 0 0;1=4
P 10.77901024 5.98761998 24 P 0 0;1=4
P 10.82901024 5.98761998 24 P 0 0;1=4
P 10.87901024 5.98761998 24 P 0 0;1=4
P 10.92901024 5.98761998 24 P 0 0;1=4
P 10.97901024 5.98761998 24 P 0 0;1=4
P 11.02901024 5.98761998 24 P 0 0;1=4
P 11.07901024 5.98761998 24 P 0 0;1=4
P 11.12901024 5.98761998 24 P 0 0;1=4
P 11.17901024 5.98761998 24 P 0 0;1=4
P 11.22901024 5.98761998 24 P 0 0;1=4
P 11.27901024 5.98761998 24 P 0 0;1=4
P 11.32901024 5.98761998 24 P 0 0;1=4
P 11.37901024 5.98761998 24 P 0 0;1=4
P 11.42901024 5.98761998 24 P 0 0;1=4
P 11.47901024 5.98761998 24 P 0 0;1=4
P 11.52901024 5.98761998 24 P 0 0;1=4
P 11.57901024 5.98761998 24 P 0 0;1=4
P 11.62901024 5.98761998 24 P 0 0;1=4
P 11.67901024 5.98761998 24 P 0 0;1=4
P 11.72901024 5.98761998 24 P 0 0;1=4
P 11.77901024 5.98761998 24 P 0 0;1=4
P 11.82901024 5.98761998 24 P 0 0;1=4
P 11.87901024 5.98761998 24 P 0 0;1=4
P 11.92901024 5.98761998 24 P 0 0;1=4
P 11.97901024 5.98761998 24 P 0 0;1=4
P 12.02901024 5.98761998 24 P 0 0;1=4
P 12.07901024 5.98761998 24 P 0 0;1=4
P 12.12901024 5.98761998 24 P 0 0;1=4
P 12.17901024 5.98761998 24 P 0 0;1=4
P 12.22901024 5.98761998 24 P 0 0;1=4
P 12.27901024 5.98761998 24 P 0 0;1=4
P 12.32901024 5.98761998 24 P 0 0;1=4
P 12.37901024 5.98761998 24 P 0 0;1=4
P 12.42901024 5.98761998 24 P 0 0;1=4
P 12.47901024 5.98761998 24 P 0 0;1=4
P 12.52901024 5.98761998 24 P 0 0;1=4
P 12.57901024 5.98761998 24 P 0 0;1=4
P 12.62901024 5.98761998 24 P 0 0;1=4
P 12.67901024 5.98761998 24 P 0 0;1=4
P 12.72901024 5.98761998 24 P 0 0;1=4
P 12.77901024 5.98761998 24 P 0 0;1=4
P 12.82901024 5.98761998 24 P 0 0;1=4
P 12.87725994 5.97451004 24 P 0 0;1=4
P 12.8892 5.92595974 24 P 0 0;1=4
P 12.8892 5.87595974 24 P 0 0;1=4
P 12.8892 5.82595974 24 P 0 0;1=4
P 12.8892 5.77595974 24 P 0 0;1=4
P 4.33605 4.9231 24 P 0 0;1=4
P 4.38105 4.9231 24 P 0 0;1=4
P 4.30105 4.9431 24 P 0 0;1=4
P 4.42105 4.9431 24 P 0 0;1=4
P 4.46105 4.9431 24 P 0 0;1=4
P 4.26105 4.9431 24 P 0 0;1=4
P 4.72605 4.9231 24 P 0 0;1=4
P 4.65105 4.9431 24 P 0 0;1=4
P 4.69105 4.9431 24 P 0 0;1=4
P 4.85105 4.9431 24 P 0 0;1=4
P 4.81105 4.9431 24 P 0 0;1=4
P 4.77105 4.9231 24 P 0 0;1=4
P 4.30105 5.0281 24 P 0 0;1=4
P 4.30105 5.0731 24 P 0 0;1=4
P 4.30105 4.9831 24 P 0 0;1=4
P 4.34105 5.1181 24 P 0 0;1=4
P 4.38105 5.1181 24 P 0 0;1=4
P 4.46105 5.1181 24 P 0 0;1=4
P 4.42105 5.1181 24 P 0 0;1=4
P 4.42105 4.9831 24 P 0 0;1=4
P 4.42105 5.0731 24 P 0 0;1=4
P 4.42105 5.0281 24 P 0 0;1=4
P 4.46105 4.9831 24 P 0 0;1=4
P 4.46105 5.0731 24 P 0 0;1=4
P 4.46105 5.0281 24 P 0 0;1=4
P 4.26105 5.0281 24 P 0 0;1=4
P 4.26105 5.0731 24 P 0 0;1=4
P 4.26105 4.9831 24 P 0 0;1=4
P 4.73105 5.1181 24 P 0 0;1=4
P 4.69105 5.1181 24 P 0 0;1=4
P 4.65105 5.1181 24 P 0 0;1=4
P 4.65105 4.9831 24 P 0 0;1=4
P 4.65105 5.0731 24 P 0 0;1=4
P 4.65105 5.0281 24 P 0 0;1=4
P 4.69105 4.9831 24 P 0 0;1=4
P 4.69105 5.0731 24 P 0 0;1=4
P 4.69105 5.0281 24 P 0 0;1=4
P 4.85105 5.0281 24 P 0 0;1=4
P 4.85105 5.0731 24 P 0 0;1=4
P 4.85105 4.9831 24 P 0 0;1=4
P 4.81105 5.0281 24 P 0 0;1=4
P 4.81105 5.0731 24 P 0 0;1=4
P 4.81105 4.9831 24 P 0 0;1=4
P 4.81105 5.1181 24 P 0 0;1=4
P 4.85105 5.1181 24 P 0 0;1=4
P 4.77105 5.1181 24 P 0 0;1=4
P 4.30105 5.1181 24 P 0 0;1=4
P 4.26105 5.1181 24 P 0 0;1=4
P 9.45795 0.36633002 24 P 0 0;1=4
P 6.62 4.645 24 P 0 0;1=4
P 6.62 4.61 24 P 0 0;1=4
P 6.605 4.77 24 P 0 0;1=4
P 6.315 4.9 24 P 0 0;1=4
P 6.315 4.865 24 P 0 0;1=4
P 6.315 4.82 24 P 0 0;1=4
P 6.315 4.785 24 P 0 0;1=4
P 6.315 4.705 24 P 0 0;1=4
P 6.315 4.74 24 P 0 0;1=4
P 6.315 4.66 24 P 0 0;1=4
P 6.315 4.625 24 P 0 0;1=4
P 1.51672972 5.78 24 P 0 0;1=4
P 1.12303002 5.46015974 24 P 0 0;1=4
P 1.20176998 5.46016004 24 P 0 0;1=4
P 1.51673002 5.46015974 24 P 0 0;1=4
P 1.36 5.355 24 P 0 0;1=4
P 1.41 5.355 24 P 0 0;1=4
P 1.46 5.355 24 P 0 0;1=4
P 1.305 5.885 24 P 0 0;1=4
P 1.355 5.885 24 P 0 0;1=4
P 1.405 5.885 24 P 0 0;1=4
P 1.455 5.885 24 P 0 0;1=4
P 0.705 5.355 24 P 0 0;1=4
P 0.7 5.267 24 P 0 0;1=0
P 0.73 5.175 24 P 0 0;1=4
P 1.03 5.065 24 P 0 0;1=4
P 1.28050994 5.46016004 24 P 0 0;1=4
P 12.215 4.915 24 P 0 0;1=4
P 12.055 4.915 24 P 0 0;1=4
P 10.465 5.245 24 P 0 0;1=4
P 10.465 5.165 24 P 0 0;1=4
P 11.7719 4.80998976 24 P 0 0;1=4
P 11.7719 4.85498976 24 P 0 0;1=4
P 11.7719 4.90498976 24 P 0 0;1=4
P 11.7719 4.94998976 24 P 0 0;1=4
P 11.9719 4.94998976 24 P 0 0;1=4
P 11.9719 4.80998976 24 P 0 0;1=4
P 11.9719 4.85498976 24 P 0 0;1=4
P 11.9719 4.90498976 24 P 0 0;1=4
P 11.9219 4.94998976 24 P 0 0;1=4
P 11.9219 4.80998976 24 P 0 0;1=4
P 11.8719 4.94998976 24 P 0 0;1=4
P 11.8719 4.80998976 24 P 0 0;1=4
P 11.8219 4.80998976 24 P 0 0;1=4
P 11.8219 4.94998976 24 P 0 0;1=4
P 11.69315974 2.6635 24 P 0 0;1=4
P 10.125 2.008 24 P 0 0;1=4
P 5.53530974 1.6642 24 P 0 0;1=4
P 5.53530974 1.7213 24 P 0 0;1=4
P 5.53530974 2.0802 24 P 0 0;1=4
P 5.53530974 1.9393 24 P 0 0;1=4
P 5.53530974 2.2156 24 P 0 0;1=4
P 5.53530974 2.4081 24 P 0 0;1=4
P 5.53530974 2.5473 24 P 0 0;1=4
P 2.86855 4.92 24 P 0 0;1=4
P 2.79767972 4.92 24 P 0 0;1=4
P 3.08113976 4.92 24 P 0 0;1=4
P 3.36460974 4.926 24 P 0 0;1=4
P 3.22287972 4.92 24 P 0 0;1=4
P 3.50633976 4.92 24 P 0 0;1=4
P 3.43546998 4.928 24 P 0 0;1=4
P 3.15398002 4.81401998 24 P 0 0;1=4
P 3.22288002 4.81401998 24 P 0 0;1=4
P 3.36461024 4.81401998 24 P 0 0;1=4
P 3.43547028 4.81401998 24 P 0 0;1=4
P 3.50634026 4.81401998 24 P 0 0;1=4
P 3.22287972 5.023 24 P 0 0;1=4
P 3.50633976 5.023 24 P 0 0;1=4
P 3.43546998 5.023 24 P 0 0;1=4
P 3.14 4.92 24 P 0 0;1=4
P 3.275 4.92 24 P 0 0;1=4
P 3.26 5.332 24 P 0 0;1=4
P 3.06792028 5.332 24 P 0 0;1=4
P 3.51176998 5.17874026 24 P 0 0;1=4
P 3.57176998 5.17874026 24 P 0 0;1=4
P 3.15743996 4.74418002 24 P 0 0;1=4
P 1.63307972 4.92 24 P 0 0;1=4
P 1.84567972 4.92 24 P 0 0;1=4
P 1.77480974 4.92 24 P 0 0;1=4
P 1.70395 4.92 24 P 0 0;1=4
P 2.12913976 4.92 24 P 0 0;1=4
P 2.05827972 4.92 24 P 0 0;1=4
P 1.98740974 4.92 24 P 0 0;1=4
P 1.91653976 4.92 24 P 0 0;1=4
P 2.34173976 4.92 24 P 0 0;1=4
P 2.27086998 4.92 24 P 0 0;1=4
P 2.20000974 4.926 24 P 0 0;1=4
P 2.34173976 4.81 24 P 0 0;1=4
P 2.27086998 4.81 24 P 0 0;1=4
P 2.20000974 4.81 24 P 0 0;1=4
P 1.63173002 4.81526998 24 P 0 0;1=4
P 1.7 4.812 24 P 0 0;1=4
P 1.84567972 4.81 24 P 0 0;1=4
P 1.776 4.812 24 P 0 0;1=4
P 2.12913976 4.81 24 P 0 0;1=4
P 1.99 4.81 24 P 0 0;1=4
P 1.92 4.81 24 P 0 0;1=4
P 2.40716998 5.15374026 24 P 0 0;1=4
P 2.34716998 5.15374026 24 P 0 0;1=4
P 10.58660974 2.16615 24 P 0 0;1=3
P 10.63660974 2.16615 24 P 0 0;1=3
P 10.63660974 2.21615 24 P 0 0;1=3
P 10.88660974 1.91615 24 P 0 0;1=3
P 10.88660974 2.41615 24 P 0 0;1=3
P 10.88660974 2.66615 24 P 0 0;1=3
P 11.03660974 2.41615 24 P 0 0;1=3
P 11.03660974 2.36615 24 P 0 0;1=3
P 1.91110994 4.61826004 24 P 0 0;1=4
P 2.40716998 4.70326004 24 P 0 0;1=4
P 2.945 4.92 24 P 0 0;1=4
P 3.01027972 4.92 24 P 0 0;1=4
P 7.78 2.4781 24 P 0 0;1=0
P 2.24606024 3.86615 24 P 0 0;1=3
P 2.49606024 3.86615 24 P 0 0;1=3
P 2.24606024 3.81615 24 P 0 0;1=3
P 2.19606024 3.76615 24 P 0 0;1=3
P 2.24606024 3.76615 24 P 0 0;1=3
P 2.29606024 3.76615 24 P 0 0;1=3
P 2.49606024 3.71615 24 P 0 0;1=3
P 2.49606024 3.56615 24 P 0 0;1=3
P 2.44606024 3.56615 24 P 0 0;1=3
P 2.39606024 3.56615 24 P 0 0;1=3
P 2.29606024 3.61615 24 P 0 0;1=3
P 2.24606024 3.71615 24 P 0 0;1=3
P 2.24606024 3.66615 24 P 0 0;1=3
P 2.24606024 3.61615 24 P 0 0;1=3
P 2.19606024 3.61615 24 P 0 0;1=3
P 2.19606024 3.56615 24 P 0 0;1=3
P 2.14606024 3.56615 24 P 0 0;1=3
P 2.04606024 3.56615 24 P 0 0;1=3
P 1.99605974 3.56615 24 P 0 0;1=3
P 2.04606024 3.51615 24 P 0 0;1=3
P 2.04605974 3.46615 24 P 0 0;1=3
P 2.19606024 3.51615 24 P 0 0;1=3
P 2.24606024 3.51615 24 P 0 0;1=3
P 2.29606024 3.51615 24 P 0 0;1=3
P 2.49606024 3.41615 24 P 0 0;1=3
P 2.44606024 3.36615 24 P 0 0;1=3
P 2.24606024 3.46615 24 P 0 0;1=3
P 2.24606024 3.41615 24 P 0 0;1=3
P 2.29606024 3.36615 24 P 0 0;1=3
P 2.24606024 3.36615 24 P 0 0;1=3
P 2.19606024 3.36615 24 P 0 0;1=3
P 1.99605974 3.41615 24 P 0 0;1=3
P 2.09606024 3.36615 24 P 0 0;1=3
P 2.24606024 3.31615 24 P 0 0;1=3
P 2.24606024 3.26615 24 P 0 0;1=3
P 2.29606024 3.21615 24 P 0 0;1=3
P 2.24606024 3.21615 24 P 0 0;1=3
P 2.19606024 3.21615 24 P 0 0;1=3
P 2.09606024 3.21615 24 P 0 0;1=3
P 2.14606024 3.16615 24 P 0 0;1=3
P 2.04606024 3.16615 24 P 0 0;1=3
P 2.24606024 3.16615 24 P 0 0;1=3
P 2.29606024 3.16615 24 P 0 0;1=3
P 2.34606024 3.21615 24 P 0 0;1=3
P 2.44606024 3.21615 24 P 0 0;1=3
P 2.49606024 3.21615 24 P 0 0;1=3
P 2.49606024 3.26615 24 P 0 0;1=3
P 2.49606024 3.16615 24 P 0 0;1=3
P 2.39606024 3.16615 24 P 0 0;1=3
P 2.29606024 3.06615 24 P 0 0;1=3
P 2.29606024 3.11615 24 P 0 0;1=3
P 2.29606024 2.96615 24 P 0 0;1=3
P 2.29606024 3.01615 24 P 0 0;1=3
P 2.24606024 3.06615 24 P 0 0;1=3
P 2.24606024 3.11615 24 P 0 0;1=3
P 2.24606024 2.96615 24 P 0 0;1=3
P 2.24606024 3.01615 24 P 0 0;1=3
P 2.34606024 2.86615 24 P 0 0;1=3
P 2.34606024 2.91615 24 P 0 0;1=3
P 2.29606024 2.76615 24 P 0 0;1=3
P 2.29606024 2.81615 24 P 0 0;1=3
P 2.24606024 2.76615 24 P 0 0;1=3
P 2.24606024 2.81615 24 P 0 0;1=3
P 2.19606024 2.81615 24 P 0 0;1=3
P 2.09606024 2.81615 24 P 0 0;1=3
P 2.09606024 2.86615 24 P 0 0;1=3
P 2.19606024 3.06615 24 P 0 0;1=3
P 2.14606024 3.01615 24 P 0 0;1=3
P 2.09606024 3.06615 24 P 0 0;1=3
P 2.04606024 3.01615 24 P 0 0;1=3
P 2.09606024 2.91615 24 P 0 0;1=3
P 2.14606024 2.86615 24 P 0 0;1=3
P 2.04606024 2.86615 24 P 0 0;1=3
P 2.19606024 2.91615 24 P 0 0;1=3
P 2.24606024 2.91615 24 P 0 0;1=3
P 2.29606024 2.91615 24 P 0 0;1=3
P 2.39606024 3.01615 24 P 0 0;1=3
P 2.34606024 3.06615 24 P 0 0;1=3
P 2.44606024 3.06615 24 P 0 0;1=3
P 2.49606024 3.01615 24 P 0 0;1=3
P 2.44606024 2.91615 24 P 0 0;1=3
P 2.44606024 2.86615 24 P 0 0;1=3
P 2.39606024 2.86615 24 P 0 0;1=3
P 2.34606024 2.81615 24 P 0 0;1=3
P 2.44606024 2.81615 24 P 0 0;1=3
P 2.49606024 2.86615 24 P 0 0;1=3
P 2.49606024 2.71615 24 P 0 0;1=3
P 2.44606024 2.66615 24 P 0 0;1=3
P 2.39606024 2.71615 24 P 0 0;1=3
P 2.34606024 2.66615 24 P 0 0;1=3
P 2.29606024 2.71615 24 P 0 0;1=3
P 2.29606024 2.66615 24 P 0 0;1=3
P 2.24606024 2.71615 24 P 0 0;1=3
P 2.24606024 2.66615 24 P 0 0;1=3
P 2.19606024 2.66615 24 P 0 0;1=3
P 2.14606024 2.71615 24 P 0 0;1=3
P 2.09606024 2.66615 24 P 0 0;1=3
P 2.04606024 2.71615 24 P 0 0;1=3
P 2.04606024 2.56615 24 P 0 0;1=3
P 2.04606024 2.51615 24 P 0 0;1=3
P 2.04606024 2.46615 24 P 0 0;1=3
P 2.09606024 2.51615 24 P 0 0;1=3
P 2.14606024 2.56615 24 P 0 0;1=3
P 2.24606024 2.61615 24 P 0 0;1=3
P 2.24606024 2.56615 24 P 0 0;1=3
P 2.29606024 2.61615 24 P 0 0;1=3
P 2.29606024 2.56615 24 P 0 0;1=3
P 2.34606024 2.51615 24 P 0 0;1=3
P 2.29606024 2.51615 24 P 0 0;1=3
P 2.24606024 2.51615 24 P 0 0;1=3
P 2.19606024 2.51615 24 P 0 0;1=3
P 2.14606024 2.46615 24 P 0 0;1=3
P 2.24606024 2.46615 24 P 0 0;1=3
P 2.29606024 2.46615 24 P 0 0;1=3
P 2.29606024 2.41615 24 P 0 0;1=3
P 2.24606024 2.41615 24 P 0 0;1=3
P 2.24606024 2.36615 24 P 0 0;1=3
P 2.19606024 2.36615 24 P 0 0;1=3
P 2.29606024 2.36615 24 P 0 0;1=3
P 2.39606024 2.46615 24 P 0 0;1=3
P 2.39606024 2.51615 24 P 0 0;1=3
P 2.39606024 2.56615 24 P 0 0;1=3
P 2.44606024 2.51615 24 P 0 0;1=3
P 2.49606024 2.56615 24 P 0 0;1=3
P 2.49606024 2.51615 24 P 0 0;1=3
P 2.49606024 2.46615 24 P 0 0;1=3
P 2.44606024 2.36615 24 P 0 0;1=3
P 2.49606024 2.31615 24 P 0 0;1=3
P 2.39606024 2.31615 24 P 0 0;1=3
P 2.34606024 2.36615 24 P 0 0;1=3
P 2.29606024 2.31615 24 P 0 0;1=3
P 2.24606024 2.31615 24 P 0 0;1=3
P 2.04606024 2.31615 24 P 0 0;1=3
P 2.04606024 2.16615 24 P 0 0;1=3
P 2.04606024 2.11615 24 P 0 0;1=3
P 2.04606024 1.96615 24 P 0 0;1=3
P 2.09606024 2.01615 24 P 0 0;1=3
P 2.14606024 1.96615 24 P 0 0;1=3
P 2.09606024 1.86615 24 P 0 0;1=3
P 2.19606024 1.86615 24 P 0 0;1=3
P 2.24606024 1.86615 24 P 0 0;1=3
P 2.29606024 1.86615 24 P 0 0;1=3
P 2.34606024 1.86615 24 P 0 0;1=3
P 2.24606024 1.91615 24 P 0 0;1=3
P 2.29606024 1.91615 24 P 0 0;1=3
P 2.24606024 1.96615 24 P 0 0;1=3
P 2.29606024 1.96615 24 P 0 0;1=3
P 2.19606024 2.01615 24 P 0 0;1=3
P 2.24606024 2.01615 24 P 0 0;1=3
P 2.29606024 2.01615 24 P 0 0;1=3
P 2.34606024 2.01615 24 P 0 0;1=3
P 2.39606024 1.96615 24 P 0 0;1=3
P 2.44606024 2.01615 24 P 0 0;1=3
P 2.49606024 1.96615 24 P 0 0;1=3
P 2.44606024 1.86615 24 P 0 0;1=3
P 2.49606024 2.11615 24 P 0 0;1=3
P 2.44606024 2.16615 24 P 0 0;1=3
P 2.49606024 2.16615 24 P 0 0;1=3
P 2.44606024 2.21615 24 P 0 0;1=3
P 2.39606024 2.16615 24 P 0 0;1=3
P 2.39606024 2.11615 24 P 0 0;1=3
P 2.34606024 2.16615 24 P 0 0;1=3
P 2.34606024 2.21615 24 P 0 0;1=3
P 2.29606024 2.21615 24 P 0 0;1=3
P 2.29606024 2.16615 24 P 0 0;1=3
P 2.29606024 2.06615 24 P 0 0;1=3
P 2.29606024 2.11615 24 P 0 0;1=3
P 2.24606024 2.11615 24 P 0 0;1=3
P 2.24606024 2.16615 24 P 0 0;1=3
P 2.24606024 2.06615 24 P 0 0;1=3
P 2.24606024 2.21615 24 P 0 0;1=3
P 2.29606024 2.26615 24 P 0 0;1=3
P 2.24606024 2.26615 24 P 0 0;1=3
P 2.19606024 2.21615 24 P 0 0;1=3
P 2.19606024 2.16615 24 P 0 0;1=3
P 2.14606024 2.11615 24 P 0 0;1=3
P 2.14606024 2.16615 24 P 0 0;1=3
P 2.09606024 2.21615 24 P 0 0;1=3
P 2.09606024 2.16615 24 P 0 0;1=3
P 2.09606024 2.36615 24 P 0 0;1=3
P 2.14606024 2.31615 24 P 0 0;1=3
P 1.99605974 2.71615 24 P 0 0;1=3
P 1.99605974 2.86615 24 P 0 0;1=3
P 2.04605974 2.81615 24 P 0 0;1=3
P 2.04605974 2.76615 24 P 0 0;1=3
P 3.29373976 5.023 24 P 0 0;1=4
P 2.14606024 3.26615 24 P 0 0;1=3
P 2.04606024 3.26615 24 P 0 0;1=3
P 2.04606024 3.21615 24 P 0 0;1=3
P 2.14606024 3.21615 24 P 0 0;1=3
P 2.39606024 3.21615 24 P 0 0;1=3
P 2.39606024 3.26615 24 P 0 0;1=3
P 2.29606024 3.26615 24 P 0 0;1=3
P 2.29606024 3.31615 24 P 0 0;1=3
P 2.34606024 3.36615 24 P 0 0;1=3
P 2.14606024 3.41615 24 P 0 0;1=3
P 2.09606024 3.61615 24 P 0 0;1=3
P 2.29606024 3.46615 24 P 0 0;1=3
P 2.29606024 3.41615 24 P 0 0;1=3
P 2.39606024 3.41615 24 P 0 0;1=3
P 2.34606024 3.51615 24 P 0 0;1=3
P 2.34606024 3.61615 24 P 0 0;1=3
P 2.34606024 3.56615 24 P 0 0;1=3
P 2.44606024 3.51615 24 P 0 0;1=3
P 2.44606024 3.61615 24 P 0 0;1=3
P 2.14606024 3.71615 24 P 0 0;1=3
P 2.04606024 3.71615 24 P 0 0;1=3
P 2.09606024 3.76615 24 P 0 0;1=3
P 2.14606024 3.86615 24 P 0 0;1=3
P 2.04606024 3.86615 24 P 0 0;1=3
P 2.29606024 3.71615 24 P 0 0;1=3
P 2.29606024 3.66615 24 P 0 0;1=3
P 2.39606024 3.71615 24 P 0 0;1=3
P 2.34606024 3.76615 24 P 0 0;1=3
P 2.29606024 3.81615 24 P 0 0;1=3
P 2.39606024 3.86615 24 P 0 0;1=3
P 2.29606024 3.86615 24 P 0 0;1=3
P 2.44606024 3.76615 24 P 0 0;1=3
P 2.19606024 2.86615 24 P 0 0;1=3
P 3.36460974 5.023 24 P 0 0;1=4
P 3.29374026 4.81401998 24 P 0 0;1=4
P 3.01028002 4.81401998 24 P 0 0;1=4
P 2.94141024 4.81401998 24 P 0 0;1=4
P 2.86555 4.81401998 24 P 0 0;1=4
P 2.79768002 4.81401998 24 P 0 0;1=4
P 3.15200974 5.023 24 P 0 0;1=4
P 3.08113976 5.023 24 P 0 0;1=4
P 3.01027972 5.023 24 P 0 0;1=4
P 2.93940974 5.023 24 P 0 0;1=4
P 2.86855 5.023 24 P 0 0;1=4
P 2.79767972 5.023 24 P 0 0;1=4
P 1.70395 5.023 24 P 0 0;1=4
P 1.63307972 5.023 24 P 0 0;1=4
P 1.77480974 5.023 24 P 0 0;1=4
P 1.91653976 5.023 24 P 0 0;1=4
P 1.84567972 5.023 24 P 0 0;1=4
P 1.98740974 5.023 24 P 0 0;1=4
P 2.05827972 5.023 24 P 0 0;1=4
P 2.12913976 5.023 24 P 0 0;1=4
P 2.20000974 5.023 24 P 0 0;1=4
P 2.27086998 5.023 24 P 0 0;1=4
P 2.34173976 5.023 24 P 0 0;1=4
P 1.56220974 5.023 24 P 0 0;1=4
P 1.56221024 4.81401998 24 P 0 0;1=4
P 2.06086998 4.81 24 P 0 0;1=4
P 2.41260974 5.023 24 P 0 0;1=4
P 2.41261024 4.81401998 24 P 0 0;1=4
P 2.72680974 5.023 24 P 0 0;1=4
P 2.72681024 4.81401998 24 P 0 0;1=4
P 3.57721024 4.81401998 24 P 0 0;1=4
P 3.57720974 5.023 24 P 0 0;1=4
P 4.88267972 1.91615 24 P 0 0;1=3
P 4.78267972 1.91615 24 P 0 0;1=3
P 5.03267972 2.36615 24 P 0 0;1=3
P 5.03267972 2.41615 24 P 0 0;1=3
P 4.88267972 3.66615 24 P 0 0;1=3
P 4.83267972 3.66615 24 P 0 0;1=3
P 5.03267972 3.66615 24 P 0 0;1=3
P 4.93267972 3.66615 24 P 0 0;1=3
P 4.98267972 3.66615 24 P 0 0;1=3
P 4.88267972 3.51615 24 P 0 0;1=3
P 4.83267972 3.51615 24 P 0 0;1=3
P 5.03267972 3.51615 24 P 0 0;1=3
P 4.93267972 3.51615 24 P 0 0;1=3
P 4.98267972 3.51615 24 P 0 0;1=3
P 4.88267972 3.81615 24 P 0 0;1=3
P 4.83267972 3.81615 24 P 0 0;1=3
P 4.93267972 3.81615 24 P 0 0;1=3
P 4.98267972 3.81615 24 P 0 0;1=3
P 4.88267972 3.36615 24 P 0 0;1=3
P 4.83267972 3.36615 24 P 0 0;1=3
P 5.03267972 3.36615 24 P 0 0;1=3
P 4.93267972 3.36615 24 P 0 0;1=3
P 4.98267972 3.36615 24 P 0 0;1=3
P 4.83267972 3.21615 24 P 0 0;1=3
P 4.88267972 3.21615 24 P 0 0;1=3
P 4.98267972 3.21615 24 P 0 0;1=3
P 4.93267972 3.21615 24 P 0 0;1=3
P 5.03267972 3.21615 24 P 0 0;1=3
P 4.83267972 3.06615 24 P 0 0;1=3
P 4.88267972 3.06615 24 P 0 0;1=3
P 4.98267972 3.06615 24 P 0 0;1=3
P 4.93267972 3.06615 24 P 0 0;1=3
P 5.03267972 3.06615 24 P 0 0;1=3
P 4.83267972 2.91615 24 P 0 0;1=3
P 4.88267972 2.91615 24 P 0 0;1=3
P 4.98267972 2.91615 24 P 0 0;1=3
P 4.93267972 2.91615 24 P 0 0;1=3
P 5.03267972 2.91615 24 P 0 0;1=3
P 4.78268002 2.51615 24 P 0 0;1=3
P 4.73268002 2.51615 24 P 0 0;1=3
P 4.68268002 2.51615 24 P 0 0;1=3
P 4.63268002 2.51615 24 P 0 0;1=3
P 4.58268002 2.51615 24 P 0 0;1=3
P 4.63268002 2.56615 24 P 0 0;1=3
P 4.73268002 2.56615 24 P 0 0;1=3
P 4.78268002 2.56615 24 P 0 0;1=3
P 4.78268002 2.61615 24 P 0 0;1=3
P 4.78268002 2.66615 24 P 0 0;1=3
P 4.68268002 2.66615 24 P 0 0;1=3
P 4.58268002 2.66615 24 P 0 0;1=3
P 4.73268002 2.71615 24 P 0 0;1=3
P 4.63268002 2.71615 24 P 0 0;1=3
P 4.63268002 2.76615 24 P 0 0;1=3
P 4.73268002 2.76615 24 P 0 0;1=3
P 4.78268002 2.76615 24 P 0 0;1=3
P 4.63267972 2.16615 24 P 0 0;1=3
P 4.78267972 2.16615 24 P 0 0;1=3
P 10.63660974 2.91615 24 P 0 0;1=3
P 10.58660974 2.91615 24 P 0 0;1=3
P 10.63660974 3.06615 24 P 0 0;1=3
P 10.58660974 3.06615 24 P 0 0;1=3
P 10.63660974 3.36615 24 P 0 0;1=3
P 10.58660974 3.36615 24 P 0 0;1=3
P 10.63660974 3.21615 24 P 0 0;1=3
P 10.58660974 3.21615 24 P 0 0;1=3
P 10.58660974 3.66615 24 P 0 0;1=3
P 10.63660974 3.51615 24 P 0 0;1=3
P 10.58660974 3.51615 24 P 0 0;1=3
P 10.63660974 3.81615 24 P 0 0;1=3
P 10.63660974 3.66615 24 P 0 0;1=3
P 10.58660974 3.81615 24 P 0 0;1=3
P 10.83660974 2.91615 24 P 0 0;1=3
P 10.78660974 2.91615 24 P 0 0;1=3
P 10.73660974 2.91615 24 P 0 0;1=3
P 10.68660974 2.91615 24 P 0 0;1=3
P 10.88660974 2.91615 24 P 0 0;1=3
P 10.88660974 3.06615 24 P 0 0;1=3
P 10.83660974 3.06615 24 P 0 0;1=3
P 10.78660974 3.06615 24 P 0 0;1=3
P 10.73660974 3.06615 24 P 0 0;1=3
P 10.68660974 3.06615 24 P 0 0;1=3
P 10.88660974 3.21615 24 P 0 0;1=3
P 10.83660974 3.21615 24 P 0 0;1=3
P 10.83660974 3.36615 24 P 0 0;1=3
P 10.88660974 3.36615 24 P 0 0;1=3
P 10.78660974 3.36615 24 P 0 0;1=3
P 10.73660974 3.36615 24 P 0 0;1=3
P 10.78660974 3.21615 24 P 0 0;1=3
P 10.73660974 3.21615 24 P 0 0;1=3
P 10.68660974 3.36615 24 P 0 0;1=3
P 10.68660974 3.21615 24 P 0 0;1=3
P 10.83660974 3.51615 24 P 0 0;1=3
P 10.88660974 3.51615 24 P 0 0;1=3
P 10.83660974 3.66615 24 P 0 0;1=3
P 10.78660974 3.66615 24 P 0 0;1=3
P 10.73660974 3.66615 24 P 0 0;1=3
P 10.68660974 3.66615 24 P 0 0;1=3
P 10.78660974 3.51615 24 P 0 0;1=3
P 10.73660974 3.51615 24 P 0 0;1=3
P 10.68660974 3.51615 24 P 0 0;1=3
P 10.83660974 3.81615 24 P 0 0;1=3
P 10.88660974 3.81615 24 P 0 0;1=3
P 10.88660974 3.66615 24 P 0 0;1=3
P 10.78660974 3.81615 24 P 0 0;1=3
P 10.73660974 3.81615 24 P 0 0;1=3
P 10.68660974 3.81615 24 P 0 0;1=3
P 11.03660974 2.91615 24 P 0 0;1=3
P 10.93660974 2.91615 24 P 0 0;1=3
P 10.98660974 2.91615 24 P 0 0;1=3
P 11.03660974 3.06615 24 P 0 0;1=3
P 10.93660974 3.06615 24 P 0 0;1=3
P 10.98660974 3.06615 24 P 0 0;1=3
P 11.03660974 3.21615 24 P 0 0;1=3
P 10.93660974 3.21615 24 P 0 0;1=3
P 10.98660974 3.21615 24 P 0 0;1=3
P 10.98660974 3.36615 24 P 0 0;1=3
P 10.93660974 3.36615 24 P 0 0;1=3
P 11.03660974 3.36615 24 P 0 0;1=3
P 10.98660974 3.51615 24 P 0 0;1=3
P 10.93660974 3.51615 24 P 0 0;1=3
P 11.03660974 3.51615 24 P 0 0;1=3
P 10.98660974 3.66615 24 P 0 0;1=3
P 10.93660974 3.66615 24 P 0 0;1=3
P 11.03660974 3.66615 24 P 0 0;1=3
P 10.98660974 3.81615 24 P 0 0;1=3
P 10.93660974 3.81615 24 P 0 0;1=3
P 3.07691024 4.81401998 24 P 0 0;1=4
P 8.1 1.86615 24 P 0 0;1=3
P 8.15 2.16615 24 P 0 0;1=3
P 8.15 2.11615 24 P 0 0;1=3
P 8.15 1.96615 24 P 0 0;1=3
P 8.1 2.01615 24 P 0 0;1=3
P 8.05 1.96615 24 P 0 0;1=3
P 8.05 2.11615 24 P 0 0;1=3
P 8.05 2.16615 24 P 0 0;1=3
P 8.15 2.31615 24 P 0 0;1=3
P 8.1 2.36615 24 P 0 0;1=3
P 8.1 2.16615 24 P 0 0;1=3
P 8.1 2.21615 24 P 0 0;1=3
P 8.05 2.31615 24 P 0 0;1=3
P 8.15 2.46615 24 P 0 0;1=3
P 8.15 2.56615 24 P 0 0;1=3
P 8.1 2.51615 24 P 0 0;1=3
P 8.05 2.46615 24 P 0 0;1=3
P 8.05 2.51615 24 P 0 0;1=3
P 8.05 2.56615 24 P 0 0;1=3
P 8.1 2.66615 24 P 0 0;1=3
P 8.05 2.76615 24 P 0 0;1=3
P 8.05 2.81615 24 P 0 0;1=3
P 8 2.86615 24 P 0 0;1=3
P 8 2.71615 24 P 0 0;1=3
P 8.05 2.71615 24 P 0 0;1=3
P 8.15 2.71615 24 P 0 0;1=3
P 8.05 2.86615 24 P 0 0;1=3
P 8.15 2.86615 24 P 0 0;1=3
P 8.1 2.91615 24 P 0 0;1=3
P 8.1 2.86615 24 P 0 0;1=3
P 8.1 2.81615 24 P 0 0;1=3
P 8.05 3.01615 24 P 0 0;1=3
P 8.1 3.06615 24 P 0 0;1=3
P 8.15 3.01615 24 P 0 0;1=3
P 8.15 3.16615 24 P 0 0;1=3
P 8.05 3.16615 24 P 0 0;1=3
P 8 3.41615 24 P 0 0;1=3
P 8.05 3.41615 24 P 0 0;1=3
P 8.1 3.36615 24 P 0 0;1=3
P 8.1 3.21615 24 P 0 0;1=3
P 8.15 3.56615 24 P 0 0;1=3
P 8.05 3.56615 24 P 0 0;1=3
P 8 3.56615 24 P 0 0;1=3
P 8.05 3.51615 24 P 0 0;1=3
P 8.05 3.46615 24 P 0 0;1=3
P 8.1 3.51615 24 P 0 0;1=3
P 8.35 1.86615 24 P 0 0;1=3
P 8.3 1.86615 24 P 0 0;1=3
P 8.25 1.86615 24 P 0 0;1=3
P 8.2 1.86615 24 P 0 0;1=3
P 8.25 2.06615 24 P 0 0;1=3
P 8.25 2.16615 24 P 0 0;1=3
P 8.25 2.11615 24 P 0 0;1=3
P 8.3 2.11615 24 P 0 0;1=3
P 8.3 2.06615 24 P 0 0;1=3
P 8.4 2.11615 24 P 0 0;1=3
P 8.4 2.16615 24 P 0 0;1=3
P 8.4 1.96615 24 P 0 0;1=3
P 8.35 2.01615 24 P 0 0;1=3
P 8.3 2.01615 24 P 0 0;1=3
P 8.25 2.01615 24 P 0 0;1=3
P 8.2 2.01615 24 P 0 0;1=3
P 8.3 1.96615 24 P 0 0;1=3
P 8.25 1.96615 24 P 0 0;1=3
P 8.3 1.91615 24 P 0 0;1=3
P 8.25 1.91615 24 P 0 0;1=3
P 8.2 2.16615 24 P 0 0;1=3
P 8.2 2.21615 24 P 0 0;1=3
P 8.25 2.26615 24 P 0 0;1=3
P 8.3 2.26615 24 P 0 0;1=3
P 8.25 2.21615 24 P 0 0;1=3
P 8.3 2.16615 24 P 0 0;1=3
P 8.3 2.21615 24 P 0 0;1=3
P 8.35 2.21615 24 P 0 0;1=3
P 8.35 2.16615 24 P 0 0;1=3
P 8.25 2.31615 24 P 0 0;1=3
P 8.3 2.31615 24 P 0 0;1=3
P 8.35 2.36615 24 P 0 0;1=3
P 8.4 2.31615 24 P 0 0;1=3
P 8.3 2.36615 24 P 0 0;1=3
P 8.2 2.36615 24 P 0 0;1=3
P 8.25 2.36615 24 P 0 0;1=3
P 8.25 2.41615 24 P 0 0;1=3
P 8.3 2.41615 24 P 0 0;1=3
P 8.4 2.56615 24 P 0 0;1=3
P 8.4 2.51615 24 P 0 0;1=3
P 8.4 2.46615 24 P 0 0;1=3
P 8.3 2.46615 24 P 0 0;1=3
P 8.25 2.46615 24 P 0 0;1=3
P 8.2 2.51615 24 P 0 0;1=3
P 8.25 2.51615 24 P 0 0;1=3
P 8.3 2.51615 24 P 0 0;1=3
P 8.35 2.51615 24 P 0 0;1=3
P 8.3 2.56615 24 P 0 0;1=3
P 8.3 2.61615 24 P 0 0;1=3
P 8.25 2.56615 24 P 0 0;1=3
P 8.25 2.61615 24 P 0 0;1=3
P 8.2 2.66615 24 P 0 0;1=3
P 8.25 2.66615 24 P 0 0;1=3
P 8.3 2.66615 24 P 0 0;1=3
P 8.35 2.66615 24 P 0 0;1=3
P 8.25 2.71615 24 P 0 0;1=3
P 8.3 2.71615 24 P 0 0;1=3
P 8.4 2.71615 24 P 0 0;1=3
P 8.35 2.81615 24 P 0 0;1=3
P 8.4 2.86615 24 P 0 0;1=3
P 8.3 2.91615 24 P 0 0;1=3
P 8.25 2.91615 24 P 0 0;1=3
P 8.2 2.91615 24 P 0 0;1=3
P 8.2 2.81615 24 P 0 0;1=3
P 8.25 2.81615 24 P 0 0;1=3
P 8.25 2.76615 24 P 0 0;1=3
P 8.3 2.81615 24 P 0 0;1=3
P 8.3 2.76615 24 P 0 0;1=3
P 8.35 2.91615 24 P 0 0;1=3
P 8.35 2.86615 24 P 0 0;1=3
P 8.35 3.06615 24 P 0 0;1=3
P 8.4 3.01615 24 P 0 0;1=3
P 8.2 3.06615 24 P 0 0;1=3
P 8.25 3.01615 24 P 0 0;1=3
P 8.25 2.96615 24 P 0 0;1=3
P 8.25 3.11615 24 P 0 0;1=3
P 8.25 3.06615 24 P 0 0;1=3
P 8.3 3.01615 24 P 0 0;1=3
P 8.3 2.96615 24 P 0 0;1=3
P 8.3 3.11615 24 P 0 0;1=3
P 8.3 3.06615 24 P 0 0;1=3
P 8.25 3.16615 24 P 0 0;1=3
P 8.3 3.16615 24 P 0 0;1=3
P 8.4 3.16615 24 P 0 0;1=3
P 8.25 3.41615 24 P 0 0;1=3
P 8.3 3.36615 24 P 0 0;1=3
P 8.25 3.36615 24 P 0 0;1=3
P 8.2 3.36615 24 P 0 0;1=3
P 8.25 3.31615 24 P 0 0;1=3
P 8.25 3.26615 24 P 0 0;1=3
P 8.3 3.21615 24 P 0 0;1=3
P 8.25 3.21615 24 P 0 0;1=3
P 8.2 3.21615 24 P 0 0;1=3
P 8.35 3.21615 24 P 0 0;1=3
P 8.4 3.56615 24 P 0 0;1=3
P 8.3 3.61615 24 P 0 0;1=3
P 8.25 3.66615 24 P 0 0;1=3
P 8.25 3.61615 24 P 0 0;1=3
P 8.2 3.61615 24 P 0 0;1=3
P 8.2 3.56615 24 P 0 0;1=3
P 8.2 3.51615 24 P 0 0;1=3
P 8.25 3.51615 24 P 0 0;1=3
P 8.3 3.51615 24 P 0 0;1=3
P 8.25 3.46615 24 P 0 0;1=3
P 8.25 3.86615 24 P 0 0;1=3
P 8.25 3.81615 24 P 0 0;1=3
P 8.2 3.76615 24 P 0 0;1=3
P 8.25 3.76615 24 P 0 0;1=3
P 8.3 3.76615 24 P 0 0;1=3
P 8.25 3.71615 24 P 0 0;1=3
P 8.45 1.86615 24 P 0 0;1=3
P 8.5 2.16615 24 P 0 0;1=3
P 8.5 2.11615 24 P 0 0;1=3
P 8.5 1.96615 24 P 0 0;1=3
P 8.45 2.01615 24 P 0 0;1=3
P 8.45 2.21615 24 P 0 0;1=3
P 8.45 2.16615 24 P 0 0;1=3
P 8.5 2.31615 24 P 0 0;1=3
P 8.45 2.36615 24 P 0 0;1=3
P 8.5 2.46615 24 P 0 0;1=3
P 8.5 2.51615 24 P 0 0;1=3
P 8.5 2.56615 24 P 0 0;1=3
P 8.45 2.51615 24 P 0 0;1=3
P 8.45 2.66615 24 P 0 0;1=3
P 8.5 2.71615 24 P 0 0;1=3
P 8.5 2.86615 24 P 0 0;1=3
P 8.45 2.81615 24 P 0 0;1=3
P 8.45 2.86615 24 P 0 0;1=3
P 8.45 2.91615 24 P 0 0;1=3
P 8.5 3.01615 24 P 0 0;1=3
P 8.45 3.06615 24 P 0 0;1=3
P 8.5 3.16615 24 P 0 0;1=3
P 8.5 3.41615 24 P 0 0;1=3
P 8.45 3.36615 24 P 0 0;1=3
P 8.45 3.21615 24 P 0 0;1=3
P 8.5 3.21615 24 P 0 0;1=3
P 8.5 3.26615 24 P 0 0;1=3
P 8.5 3.56615 24 P 0 0;1=3
P 8.45 3.56615 24 P 0 0;1=3
P 8.5 3.86615 24 P 0 0;1=3
P 8.5 3.71615 24 P 0 0;1=3
P 8.2 2.86615 24 P 0 0;1=3
P 8.05 3.26615 24 P 0 0;1=3
P 8.05 3.21615 24 P 0 0;1=3
P 8.3 3.26615 24 P 0 0;1=3
P 8.3 3.31615 24 P 0 0;1=3
P 8.35 3.36615 24 P 0 0;1=3
P 8.15 3.26615 24 P 0 0;1=3
P 8.15 3.21615 24 P 0 0;1=3
P 8.4 3.21615 24 P 0 0;1=3
P 8.4 3.26615 24 P 0 0;1=3
P 8.1 3.61615 24 P 0 0;1=3
P 8.3 3.46615 24 P 0 0;1=3
P 8.3 3.41615 24 P 0 0;1=3
P 8.35 3.51615 24 P 0 0;1=3
P 8.35 3.61615 24 P 0 0;1=3
P 8.35 3.56615 24 P 0 0;1=3
P 8.15 3.41615 24 P 0 0;1=3
P 8.45 3.51615 24 P 0 0;1=3
P 8.45 3.61615 24 P 0 0;1=3
P 8.4 3.41615 24 P 0 0;1=3
P 8.05 3.71615 24 P 0 0;1=3
P 8.1 3.76615 24 P 0 0;1=3
P 8.05 3.86615 24 P 0 0;1=3
P 8.3 3.71615 24 P 0 0;1=3
P 8.3 3.66615 24 P 0 0;1=3
P 8.35 3.76615 24 P 0 0;1=3
P 8.3 3.81615 24 P 0 0;1=3
P 8.3 3.86615 24 P 0 0;1=3
P 8.15 3.71615 24 P 0 0;1=3
P 8.15 3.86615 24 P 0 0;1=3
P 8.45 3.76615 24 P 0 0;1=3
P 8.4 3.71615 24 P 0 0;1=3
P 8.4 3.86615 24 P 0 0;1=3
P 3.28831004 4.68073996 24 P 0 0;1=4
P 3.22831004 4.68073996 24 P 0 0;1=4
P 3.50091004 4.62573996 24 P 0 0;1=4
P 3.44091004 4.62573996 24 P 0 0;1=4
P 7.56575 5.023 24 P 0 0;1=4
P 7.63661998 5.023 24 P 0 0;1=4
P 7.84921998 5.023 24 P 0 0;1=4
P 7.77835 5.023 24 P 0 0;1=4
P 7.70748976 5.023 24 P 0 0;1=4
P 7.92007972 5.023 24 P 0 0;1=4
P 8.06181998 5.023 24 P 0 0;1=4
P 8.13267972 5.023 24 P 0 0;1=4
P 7.99095 5.023 24 P 0 0;1=4
P 8.34527972 5.023 24 P 0 0;1=4
P 8.27440974 5.023 24 P 0 0;1=4
P 8.20355 5.023 24 P 0 0;1=4
P 8.41615 5.023 24 P 0 0;1=4
P 7.63661998 4.92 24 P 0 0;1=4
P 7.84921998 4.9207 24 P 0 0;1=4
P 7.70748976 4.9207 24 P 0 0;1=4
P 7.77835 4.9207 24 P 0 0;1=4
P 7.99095 4.9207 24 P 0 0;1=4
P 7.92007972 4.9207 24 P 0 0;1=4
P 8.06181998 4.9207 24 P 0 0;1=4
P 8.13267972 4.9207 24 P 0 0;1=4
P 8.27440974 4.9207 24 P 0 0;1=4
P 8.20355 4.9267 24 P 0 0;1=4
P 8.34527972 4.9207 24 P 0 0;1=4
P 7.63526998 4.81527028 24 P 0 0;1=4
P 7.84921998 4.81 24 P 0 0;1=4
P 7.77953976 4.812 24 P 0 0;1=4
P 7.70353976 4.812 24 P 0 0;1=4
P 8.13267972 4.81 24 P 0 0;1=4
P 8.06440974 4.81 24 P 0 0;1=4
P 7.99353976 4.81 24 P 0 0;1=4
P 7.92353976 4.81 24 P 0 0;1=4
P 8.27440974 4.81 24 P 0 0;1=4
P 8.34527972 4.81 24 P 0 0;1=4
P 8.20355 4.81 24 P 0 0;1=4
P 8.41615 4.81401998 24 P 0 0;1=4
P 8.86909026 4.81401998 24 P 0 0;1=4
P 8.73035 4.81401998 24 P 0 0;1=4
P 8.80122028 4.81401998 24 P 0 0;1=4
P 8.94495 4.81401998 24 P 0 0;1=4
P 9.08045 4.81401998 24 P 0 0;1=4
P 9.01382028 4.81401998 24 P 0 0;1=4
P 9.36815 4.81401998 24 P 0 0;1=4
P 9.29728002 4.81401998 24 P 0 0;1=4
P 9.22642028 4.81401998 24 P 0 0;1=4
P 9.15752028 4.81401998 24 P 0 0;1=4
P 9.43901024 4.81401998 24 P 0 0;1=4
P 9.50988002 4.81401998 24 P 0 0;1=4
P 9.58075 4.81401998 24 P 0 0;1=4
P 8.80121998 5.023 24 P 0 0;1=4
P 8.73035 5.023 24 P 0 0;1=4
P 8.87208976 5.023 24 P 0 0;1=4
P 9.08467972 5.023 24 P 0 0;1=4
P 9.01381998 5.023 24 P 0 0;1=4
P 8.94295 5.023 24 P 0 0;1=4
P 8.87208976 4.92 24 P 0 0;1=4
P 8.80121998 4.92 24 P 0 0;1=4
P 9.01381998 4.92 24 P 0 0;1=4
P 9.08467972 4.92 24 P 0 0;1=4
P 9.22641998 4.92 24 P 0 0;1=4
P 9.36815 4.926 24 P 0 0;1=4
P 9.50987972 4.92 24 P 0 0;1=4
P 9.43900974 4.928 24 P 0 0;1=4
P 9.36815 5.023 24 P 0 0;1=4
P 9.29727972 5.023 24 P 0 0;1=4
P 9.22641998 5.023 24 P 0 0;1=4
P 9.15555 5.023 24 P 0 0;1=4
P 9.50987972 5.023 24 P 0 0;1=4
P 9.43900974 5.023 24 P 0 0;1=4
P 9.58075 5.023 24 P 0 0;1=4
P 8.94853976 4.92 24 P 0 0;1=4
P 9.27853976 4.92 24 P 0 0;1=4
P 9.14353976 4.92 24 P 0 0;1=4
P 8.13811004 5.09223996 24 P 0 0;1=4
P 8.35071004 5.15373996 24 P 0 0;1=4
P 8.41071004 5.15373996 24 P 0 0;1=4
P 7.56575 4.81401998 24 P 0 0;1=4
P 8.88061998 4.70574026 24 P 0 0;1=4
P 2.45985 4.77875 26 P 0 0;1=9
P 1.51496998 4.77875 26 P 0 0;1=9
P 2.44016998 5.05826998 26 P 0 0;1=9
P 1.53465 5.05826998 26 P 0 0;1=9
P 3.60476998 4.77875 26 P 0 0;1=9
P 2.67956998 4.77875 26 P 0 0;1=9
P 3.60476998 5.05826998 26 P 0 0;1=9
P 2.69925 5.05826998 26 P 0 0;1=9
P 8.46338996 4.77875 26 P 0 0;1=9
P 7.51850994 4.77875 26 P 0 0;1=9
P 8.44370994 5.05826998 26 P 0 0;1=9
P 7.53818996 5.05826998 26 P 0 0;1=9
P 9.60830994 4.77875 26 P 0 0;1=9
P 8.68310994 4.77875 26 P 0 0;1=9
P 9.60830994 5.05826998 26 P 0 0;1=9
P 8.70278996 5.05826998 26 P 0 0;1=9
P 10.82676998 5.49685 27 P 0 2;1=10
P 10.99213002 5.49685 27 P 0 2;1=10
P 11.15748002 5.49685 27 P 0 2;1=10
P 11.32283996 5.49685 27 P 0 2;1=10
P 11.48818996 5.49685 27 P 0 2;1=10
P 11.65353996 5.49685 27 P 0 2;1=10
P 11.8189 5.49685 27 P 0 2;1=10
P 11.98425 5.49685 27 P 0 2;1=10
P 12.14961004 5.49685 27 P 0 2;1=11
P 10.83662028 1.37795 24 P 0 2;1=12
P 10.83661998 1.6378 24 P 0 2;1=12
P 8.25 1.6378 24 P 0 2;1=12
P 8.25 1.37795 24 P 0 2;1=12
P 6.96457008 1.39763996 24 P 0 2;1=12
P 6.96456998 1.65748002 24 P 0 2;1=12
P 6.96457028 4.0748 24 P 0 2;1=12
P 6.96456998 4.33465 24 P 0 2;1=12
P 8.25 4.09448976 24 P 0 2;1=12
P 8.25 4.35433002 24 P 0 2;1=12
P 10.83662008 4.09448996 24 P 0 2;1=12
P 10.83661998 4.35433002 24 P 0 2;1=12
P 12.12205 4.0748 24 P 0 2;1=12
P 12.12205 4.33465 24 P 0 2;1=12
P 12.12205 1.65748002 24 P 0 2;1=12
P 12.12205 1.39763976 24 P 0 2;1=12
P 11.99212972 4.20473002 24 P 0 2;1=4
P 12.03020522 4.11286004 24 P 0 2;1=4
P 12.03018002 4.2965747 24 P 0 2;1=4
P 12.21391998 4.11288524 24 P 0 2;1=4
P 12.25196998 4.20473002 24 P 0 2;1=4
P 12.21389469 4.2966 24 P 0 2;1=4
P 10.7067 4.22441024 24 P 0 2;1=4
P 10.7447752 4.13253996 24 P 0 2;1=4
P 10.74475 4.31625472 24 P 0 2;1=4
P 10.92848996 4.13256516 24 P 0 2;1=4
P 10.96653996 4.22441004 24 P 0 2;1=4
P 10.92846467 4.31628002 24 P 0 2;1=4
P 8.12007992 4.22441004 24 P 0 2;1=4
P 8.15815522 4.13253996 24 P 0 2;1=4
P 8.15813002 4.31625472 24 P 0 2;1=4
P 8.34186998 4.13256516 24 P 0 2;1=4
P 8.37991998 4.22441004 24 P 0 2;1=4
P 8.34184469 4.31628002 24 P 0 2;1=4
P 6.83465 4.20473002 24 P 0 2;1=4
P 6.8727252 4.11286004 24 P 0 2;1=4
P 6.8727 4.2965747 24 P 0 2;1=4
P 7.05643996 4.11288524 24 P 0 2;1=4
P 7.09448996 4.20473002 24 P 0 2;1=4
P 7.05641467 4.2966 24 P 0 2;1=4
P 6.83465 1.52756024 24 P 0 2;1=4
P 6.8727252 1.43568996 24 P 0 2;1=4
P 6.8727 1.61940472 24 P 0 2;1=4
P 7.05643996 1.43571516 24 P 0 2;1=4
P 7.09448996 1.52756004 24 P 0 2;1=4
P 7.05641467 1.61943002 24 P 0 2;1=4
P 8.15815522 1.416 24 P 0 2;1=4
P 8.12008002 1.50786998 24 P 0 2;1=4
P 8.15813002 1.5997247 24 P 0 2;1=4
P 8.34186998 1.4160252 24 P 0 2;1=4
P 8.34184469 1.59975 24 P 0 2;1=4
P 8.37992028 1.50786998 24 P 0 2;1=4
P 10.74475 1.5997247 24 P 0 2;1=4
P 10.92846467 1.59975 24 P 0 2;1=4
P 10.96654026 1.50786998 24 P 0 2;1=4
P 10.92848996 1.4160252 24 P 0 2;1=4
P 10.7447752 1.416 24 P 0 2;1=4
P 10.7067 1.50787028 24 P 0 2;1=4
P 12.2126 1.43700974 24 P 0 2;1=4
P 12.25196998 1.52756004 24 P 0 2;1=4
P 12.2126 1.61810974 24 P 0 2;1=4
P 12.0315 1.61810974 24 P 0 2;1=4
P 11.99213002 1.52755974 24 P 0 2;1=4
P 12.0315 1.43700974 24 P 0 2;1=4
P 4.83268002 1.37795 24 P 0 2;1=12
P 4.83267972 1.6378 24 P 0 2;1=12
P 2.24605974 1.6378 24 P 0 2;1=12
P 2.24606024 1.37795 24 P 0 2;1=12
P 0.96063002 1.39763976 24 P 0 2;1=12
P 0.96062972 1.65748002 24 P 0 2;1=12
P 0.96063002 4.0748 24 P 0 2;1=12
P 0.96062972 4.33465 24 P 0 2;1=12
P 2.24606004 4.09448996 24 P 0 2;1=12
P 2.24605974 4.35433002 24 P 0 2;1=12
P 4.83268002 4.09448976 24 P 0 2;1=12
P 4.83267972 4.35433002 24 P 0 2;1=12
P 6.11811024 4.0748 24 P 0 2;1=12
P 6.11810974 4.33465 24 P 0 2;1=12
P 6.11810974 1.65748002 24 P 0 2;1=12
P 6.11811004 1.39763996 24 P 0 2;1=12
P 5.98818976 4.20473002 24 P 0 2;1=4
P 6.02626516 4.11286004 24 P 0 2;1=4
P 6.02623996 4.2965747 24 P 0 2;1=4
P 6.20998002 4.11288524 24 P 0 2;1=4
P 6.24803002 4.20472972 24 P 0 2;1=4
P 6.20995472 4.2966 24 P 0 2;1=4
P 4.70275994 4.22441004 24 P 0 2;1=4
P 4.74083524 4.13253996 24 P 0 2;1=4
P 4.74081004 4.31625472 24 P 0 2;1=4
P 4.92455 4.13256516 24 P 0 2;1=4
P 4.9626 4.22440974 24 P 0 2;1=4
P 4.9245247 4.31628002 24 P 0 2;1=4
P 2.11613996 4.22441004 24 P 0 2;1=4
P 2.15421516 4.13253996 24 P 0 2;1=4
P 2.15418996 4.31625472 24 P 0 2;1=4
P 2.33793002 4.13256516 24 P 0 2;1=4
P 2.37598002 4.22440974 24 P 0 2;1=4
P 2.33790472 4.31628002 24 P 0 2;1=4
P 0.83070974 4.20473002 24 P 0 2;1=4
P 0.86878524 4.11286004 24 P 0 2;1=4
P 0.86876004 4.2965747 24 P 0 2;1=4
P 1.0525 4.11288524 24 P 0 2;1=4
P 1.09055 4.20472972 24 P 0 2;1=4
P 1.0524747 4.2966 24 P 0 2;1=4
P 0.83070994 1.52756004 24 P 0 2;1=4
P 0.86878524 1.43568996 24 P 0 2;1=4
P 0.86876004 1.61940472 24 P 0 2;1=4
P 1.0525 1.43571516 24 P 0 2;1=4
P 1.09055 1.52755974 24 P 0 2;1=4
P 1.0524747 1.61943002 24 P 0 2;1=4
P 2.15421516 1.416 24 P 0 2;1=4
P 2.11614006 1.50786998 24 P 0 2;1=4
P 2.15418996 1.5997247 24 P 0 2;1=4
P 2.33793002 1.4160252 24 P 0 2;1=4
P 2.33790472 1.59975 24 P 0 2;1=4
P 2.37598002 1.50786998 24 P 0 2;1=4
P 4.74081004 1.5997247 24 P 0 2;1=4
P 4.9245247 1.59975 24 P 0 2;1=4
P 4.9626 1.50786998 24 P 0 2;1=4
P 4.92455 1.4160252 24 P 0 2;1=4
P 4.74083524 1.416 24 P 0 2;1=4
P 4.70276004 1.50786998 24 P 0 2;1=4
P 6.20865994 1.43701004 24 P 0 2;1=4
P 6.24803002 1.52755974 24 P 0 2;1=4
P 6.20865994 1.61811004 24 P 0 2;1=4
P 6.02755994 1.61811004 24 P 0 2;1=4
P 5.98818996 1.52756004 24 P 0 2;1=4
P 6.02755994 1.43701004 24 P 0 2;1=4
P 12.59646998 0.8189 24 P 0 0;1=4
P 12.5571 0.72835 24 P 0 0;1=4
P 12.59646998 0.6378 24 P 0 0;1=4
P 12.68701998 0.59843002 24 P 0 0;1=12
P 12.77756998 0.6378 24 P 0 0;1=4
P 12.81693976 0.72835 24 P 0 0;1=4
P 12.77756998 0.8189 24 P 0 0;1=4
P 12.68701998 0.85827028 24 P 0 0;1=12
P 12.59646998 5.24803002 24 P 0 0;1=4
P 12.5571 5.15748002 24 P 0 0;1=4
P 12.59646998 5.06693002 24 P 0 0;1=4
P 12.68701998 5.02756004 24 P 0 0;1=12
P 12.77756998 5.06693002 24 P 0 0;1=4
P 12.81693976 5.15748002 24 P 0 0;1=4
P 12.77756998 5.24803002 24 P 0 0;1=4
P 12.68701998 5.2874 24 P 0 0;1=12
P 0.1319 5.20866024 24 P 0 0;1=4
P 0.09252992 5.11811004 24 P 0 0;1=4
P 0.1319 5.02756024 24 P 0 0;1=4
P 0.22245 4.98818976 24 P 0 0;1=12
P 0.313 5.02756024 24 P 0 0;1=4
P 0.35236998 5.11811024 24 P 0 0;1=4
P 0.313 5.20866024 24 P 0 0;1=4
P 0.22245 5.24803002 24 P 0 0;1=12
P 0.1319 0.77953002 24 P 0 0;1=4
P 0.09252972 0.68898002 24 P 0 0;1=4
P 0.1319 0.59843002 24 P 0 0;1=4
P 0.22245 0.55905974 24 P 0 0;1=12
P 0.313 0.59843002 24 P 0 0;1=4
P 0.35236998 0.68898002 24 P 0 0;1=4
P 0.313 0.77953002 24 P 0 0;1=4
P 0.22245 0.8189 24 P 0 0;1=12
P 10.80498996 5.56656004 24 P 0 0;1=4
P 10.84498996 5.56656004 24 P 0 0;1=4
P 10.80498996 5.42656004 24 P 0 0;1=4
P 10.84498996 5.42656004 24 P 0 0;1=4
P 11.01035 5.42656024 24 P 0 0;1=4
P 10.97035 5.42656024 24 P 0 0;1=4
P 11.01035 5.56656024 24 P 0 0;1=4
P 10.97035 5.56656024 24 P 0 0;1=4
P 11.17570994 5.42656004 24 P 0 0;1=4
P 11.13570994 5.42656004 24 P 0 0;1=4
P 11.17570994 5.56656004 24 P 0 0;1=4
P 11.13570994 5.56656004 24 P 0 0;1=4
P 11.34106998 5.42656024 24 P 0 0;1=4
P 11.30106998 5.42656024 24 P 0 0;1=4
P 11.34106998 5.56656024 24 P 0 0;1=4
P 11.30106998 5.56656024 24 P 0 0;1=4
P 11.50642992 5.42656004 24 P 0 0;1=4
P 11.46642992 5.42656004 24 P 0 0;1=4
P 11.50642992 5.56656004 24 P 0 0;1=4
P 11.46642992 5.56656004 24 P 0 0;1=4
P 11.67178996 5.42656004 24 P 0 0;1=4
P 11.63178996 5.42656004 24 P 0 0;1=4
P 11.67178996 5.56656004 24 P 0 0;1=4
P 11.63178996 5.56656004 24 P 0 0;1=4
P 11.83715 5.42656024 24 P 0 0;1=4
P 11.79715 5.42656024 24 P 0 0;1=4
P 11.83715 5.56656024 24 P 0 0;1=4
P 11.79715 5.56656024 24 P 0 0;1=4
P 12.00250994 5.42656004 24 P 0 0;1=4
P 11.96250994 5.42656004 24 P 0 0;1=4
P 12.00250994 5.56656004 24 P 0 0;1=4
P 11.96250994 5.56656004 24 P 0 0;1=4
P 12.16786998 5.42656024 24 P 0 0;1=4
P 12.12786998 5.42656024 24 P 0 0;1=4
P 12.16786998 5.56656024 24 P 0 0;1=4
P 12.12786998 5.56656024 24 P 0 0;1=4
P 7.32284006 0.23621998 24 P 0 0;1=4
P 7.28019518 0.33921998 24 P 0 0;1=4
P 7.17716998 0.38189026 24 P 0 0;1=13
P 7.28016998 0.13319469 24 P 0 0;1=4
P 7.17717028 0.09055 24 P 0 0;1=13
P 7.07414469 0.13321998 24 P 0 0;1=4
P 7.0315 0.23621998 24 P 0 0;1=4
P 7.07416998 0.33924518 24 P 0 0;1=4
P 7.32283976 5.7874 24 P 0 0;1=4
P 7.28019518 5.8904 24 P 0 0;1=4
P 7.17716998 5.93307028 24 P 0 0;1=13
P 7.28016998 5.6843747 24 P 0 0;1=4
P 7.17716998 5.64173002 24 P 0 0;1=13
P 7.07414469 5.6844 24 P 0 0;1=4
P 7.0315 5.7874 24 P 0 0;1=4
P 7.07416998 5.8904252 24 P 0 0;1=4
P 2.24606004 3.56615 5 P 0 0;1=3
P 8.2 3.26615 5 P 0 0;1=3
P 7.65203996 5.0535 5 P 0 0;1=3
P 2.29606004 2.86615 5 P 0 0;1=3
P 2.29606004 3.56615 5 P 0 0;1=3
P 7.69203996 5.0535 5 P 0 0;1=3
P 8.2 3.31615 5 P 0 0;1=3
P 1.33906004 4.69351004 4 P 0 0;1=0
P 0.80806998 5.46193996 4 P 0 0;1=0
P 3.733 5.075 4 P 0 0;1=4
P 1.28906004 4.69351004 4 P 0 0;1=0
P 8.2 3.41615 5 P 0 0;1=3
P 7.86465 5.169 5 P 0 0;1=3
P 3.94 4.765 4 P 0 0;1=0
P 2.34606004 3.26615 5 P 0 0;1=3
P 2.39716998 4.742 5 P 0 0;1=3
P 8.2 3.46615 5 P 0 0;1=3
P 7.90465 5.169 5 P 0 0;1=3
P 2.06646004 5.29 4 P 0 0;1=0
P 2.34606004 3.31615 5 P 0 0;1=3
P 2.35716998 4.742 5 P 0 0;1=3
P 1.33906004 5.15351004 4 P 0 0;1=0
P 3.105 4.47 4 P 0 0;1=4
P 8 3.46615 5 P 0 0;1=3
P 7.93551004 5.0535 5 P 0 0;1=3
P 2.00146004 5.29 4 P 0 0;1=0
P 2.25855 4.667 5 P 0 0;1=3
P 2.39606004 3.31615 5 P 0 0;1=3
P 1.18906004 5.15351004 4 P 0 0;1=0
P 3.07 4.42 4 P 0 0;1=4
P 8 3.51615 5 P 0 0;1=3
P 7.97551004 5.0535 5 P 0 0;1=3
P 2.21855 4.667 5 P 0 0;1=3
P 2.39606004 3.36615 5 P 0 0;1=3
P 8.11725 5.169 5 P 0 0;1=3
P 8.4 3.46615 5 P 0 0;1=3
P 3.635 0.715 4 P 0 0;1=0
P 4.63268002 2.81615 5 P 0 0;1=3
P 2.44606004 3.26615 5 P 0 0;1=3
P 2.39716998 5.115 5 P 0 0;1=3
P 8.07725 5.169 5 P 0 0;1=3
P 8.4 3.51615 5 P 0 0;1=3
P 2.44606004 3.31615 5 P 0 0;1=3
P 2.35716998 5.115 5 P 0 0;1=3
P 8.5 3.46615 5 P 0 0;1=3
P 8.07206998 4.66688996 5 P 0 0;1=3
P 2.25543996 4.78291998 5 P 0 0;1=3
P 2.49606004 3.31615 5 P 0 0;1=3
P 8.5 3.51615 5 P 0 0;1=3
P 8.03206998 4.66688996 5 P 0 0;1=3
P 4.02 4.42 4 P 0 0;1=0
P 4.58268002 2.76615 5 P 0 0;1=3
P 2.21543996 4.78291998 5 P 0 0;1=3
P 2.49606004 3.36615 5 P 0 0;1=3
P 8.35 3.41615 5 P 0 0;1=3
P 8.11725 4.78291998 5 P 0 0;1=3
P 4.78268002 2.71615 5 P 0 0;1=3
P 2.11371004 4.78291998 5 P 0 0;1=3
P 2.34606004 3.41615 5 P 0 0;1=3
P 8.35 3.46615 5 P 0 0;1=3
P 8.07725 4.78291998 5 P 0 0;1=3
P 5.08268002 2.71615 5 P 0 0;1=3
P 4.06 4.86 4 P 0 0;1=0
P 2.07371004 4.78291998 5 P 0 0;1=3
P 2.34606004 3.46615 5 P 0 0;1=3
P 2.18456998 5.0535 5 P 0 0;1=3
P 2.44606004 3.41615 5 P 0 0;1=3
P 10.93661004 2.41615 5 P 0 0;1=3
P 2.14456998 5.0535 5 P 0 0;1=3
P 2.44606004 3.46615 5 P 0 0;1=3
P 10.93661004 2.46615 5 P 0 0;1=3
P 8.5 3.31615 5 P 0 0;1=3
P 8.25898002 4.78291998 5 P 0 0;1=3
P 4.88268002 2.71615 5 P 0 0;1=3
P 2.06853002 4.66688996 5 P 0 0;1=3
P 2.49606004 3.46615 5 P 0 0;1=3
P 8.5 3.36615 5 P 0 0;1=3
P 8.21898002 4.78291998 5 P 0 0;1=3
P 2.02853002 4.66688996 5 P 0 0;1=3
P 2.49606004 3.51615 5 P 0 0;1=3
P 8.4 3.31615 5 P 0 0;1=3
P 8.26208996 4.667 5 P 0 0;1=3
P 2.11371004 5.169 5 P 0 0;1=3
P 2.39606004 3.46615 5 P 0 0;1=3
P 8.4 3.36615 5 P 0 0;1=3
P 8.22208996 4.667 5 P 0 0;1=3
P 3.84 0.69 4 P 0 0;1=0
P 4.68268002 2.76615 5 P 0 0;1=3
P 2.07371004 5.169 5 P 0 0;1=3
P 2.39606004 3.51615 5 P 0 0;1=3
P 3.56 0.49 4 P 0 0;1=0
P 4.73268002 2.81615 5 P 0 0;1=3
P 1.57765 5.169 5 P 0 0;1=3
P 2.04606004 3.31615 5 P 0 0;1=3
P 9.10853996 4.47 4 P 0 0;1=4
P 7.3426 5.15351004 4 P 0 0;1=0
P 3.785 0.69 4 P 0 0;1=0
P 4.78268002 2.81615 5 P 0 0;1=3
P 1.61765 5.169 5 P 0 0;1=3
P 2.04606004 3.36615 5 P 0 0;1=3
P 8.1 3.26615 5 P 0 0;1=3
P 7.58118996 4.707 5 P 0 0;1=3
P 2.09606004 3.26615 5 P 0 0;1=3
P 1.57765 4.707 5 P 0 0;1=3
P 5.08268002 1.96615 5 P 0 0;1=3
P 8.1 3.31615 5 P 0 0;1=3
P 7.62118996 4.707 5 P 0 0;1=3
P 3.75998996 0.345 4 P 0 0;1=0
P 4.68268002 2.81615 5 P 0 0;1=3
P 2.09606004 3.31615 5 P 0 0;1=3
P 1.61765 4.707 5 P 0 0;1=3
P 0.58 5.591 4 P 0 0;1=0
P 11.67761998 2.85 4 P 0 0;1=4
P 11.865 4.455 4 P 0 0;1=0
P 5.67368996 2.85 4 P 0 0;1=4
P 5.855 3.07 4 P 0 0;1=4
P 5.8522 2.97 4 P 0 0;1=4
P 7.2926 5.15351004 4 P 0 0;1=4
P 7.2426 5.15351004 4 P 0 0;1=4
P 7.1926 4.95351004 4 P 0 0;1=4
P 7.42603996 5.15895 4 P 0 0;1=0
P 3.94 4.655 4 P 0 0;1=4
P 3.77 4.765 4 P 0 0;1=4
P 4.14 4.745 4 P 0 0;1=4
P 4.76 5.375 4 P 0 0;1=4
P 4.96 5.5 4 P 0 0;1=4
P 5.16 5.555 4 P 0 0;1=4
P 4.892 5.767 4 P 0 0;1=4
P 5.088 5.767 4 P 0 0;1=4
P 0.91 5.075 4 P 0 0;1=4
P 1.03 4.96 4 P 0 0;1=4
P 1.03 5.155 4 P 0 0;1=4
P 1.38906004 5.15351004 4 P 0 0;1=0
P 1.23906004 5.15351004 4 P 0 0;1=4
P 1.28906004 5.15351004 4 P 0 0;1=4
P 1.18906004 4.95351004 4 P 0 0;1=4
P 0.83 5.355 4 P 0 0;1=4
P 0.9 5.355 4 P 0 0;1=4
P 0.755 5.355 4 P 0 0;1=4
P 0.73 5.205 4 P 0 0;1=4
P 0.81016004 5.17 4 P 0 0;1=4
P 1.094 5.356 4 P 0 0;1=0
P 1.044 5.448 4 P 0 0;1=4
P 1.4 5.46 4 P 0 0;1=4
P 1.32 5.46 4 P 0 0;1=4
P 1.43798996 5.46016004 4 P 0 0;1=4
P 1.35925 5.46016004 4 P 0 0;1=4
P 0.89 5.885 4 P 0 0;1=4
P 0.81 5.885 4 P 0 0;1=4
P 0.73 5.885 4 P 0 0;1=4
P 0.97 5.885 4 P 0 0;1=4
P 1.04 5.885 4 P 0 0;1=4
P 1.12 5.885 4 P 0 0;1=4
P 8.15 3.31615 5 P 0 0;1=3
P 7.65205 4.78291998 5 P 0 0;1=3
P 11.235 3.3 4 P 0 0;1=4
P 5.815 0.925 4 P 0 0;1=0
P 3.635 0.49 4 P 0 0;1=0
P 4.58268002 2.81615 5 P 0 0;1=3
P 2.19606004 3.26615 5 P 0 0;1=3
P 1.6485 5.0535 5 P 0 0;1=3
P 8.15 3.36615 5 P 0 0;1=3
P 7.69205 4.78291998 5 P 0 0;1=3
P 2.19606004 3.31615 5 P 0 0;1=3
P 1.6885 5.0535 5 P 0 0;1=3
P 8.1 3.41615 5 P 0 0;1=3
P 7.79378996 4.78291998 5 P 0 0;1=3
P 2.14606004 3.31615 5 P 0 0;1=3
P 1.64851004 4.78291998 5 P 0 0;1=3
P 8.1 3.46615 5 P 0 0;1=3
P 7.83378996 4.78291998 5 P 0 0;1=3
P 2.14606004 3.36615 5 P 0 0;1=3
P 1.68851004 4.78291998 5 P 0 0;1=3
P 0.73 4.96 4 P 0 0;1=0
P 3.795 4.6 4 P 0 0;1=4
P 4.86 5.375 4 P 0 0;1=4
P 8.15 3.46615 5 P 0 0;1=3
P 7.86465 4.657 5 P 0 0;1=3
P 2.09606004 3.41615 5 P 0 0;1=3
P 1.79025 4.78291998 5 P 0 0;1=3
P 8.15 3.51615 5 P 0 0;1=3
P 7.90465 4.657 5 P 0 0;1=3
P 2.09606004 3.46615 5 P 0 0;1=3
P 1.83025 4.78291998 5 P 0 0;1=3
P 2.19606004 3.41615 5 P 0 0;1=3
P 1.86111004 5.169 5 P 0 0;1=3
P 2.19606004 3.46615 5 P 0 0;1=3
P 1.90111004 5.169 5 P 0 0;1=3
P 6.72708996 4.5652 4 P 0 0;1=4
P 6.76208996 4.5652 4 P 0 0;1=4
P 6.79708996 4.5652 4 P 0 0;1=4
P 6.83708996 4.5652 4 P 0 0;1=0
P 6.90208996 4.5652 4 P 0 0;1=4
P 6.87208996 4.5652 4 P 0 0;1=4
P 10.99998996 4.9531 4 P 0 0;1=4
P 11.03998996 4.9531 4 P 0 0;1=4
P 10.99998996 4.9131 4 P 0 0;1=4
P 11.03998996 4.9131 4 P 0 0;1=4
P 11.21998996 4.9531 4 P 0 0;1=4
P 11.17998996 4.9531 4 P 0 0;1=4
P 11.13498996 4.9531 4 P 0 0;1=4
P 11.08498996 4.9531 4 P 0 0;1=4
P 11.21998996 4.9131 4 P 0 0;1=4
P 11.17998996 4.9131 4 P 0 0;1=4
P 11.08498996 4.9131 4 P 0 0;1=4
P 11.13498996 4.9131 4 P 0 0;1=4
P 10.99998996 5.1631 4 P 0 0;1=4
P 11.03998996 5.1631 4 P 0 0;1=4
P 10.99998996 5.1231 4 P 0 0;1=4
P 10.99998996 5.0381 4 P 0 0;1=4
P 10.99998996 5.0831 4 P 0 0;1=4
P 10.99998996 4.9931 4 P 0 0;1=4
P 11.03998996 4.9931 4 P 0 0;1=4
P 11.03998996 5.0831 4 P 0 0;1=4
P 11.03998996 5.0381 4 P 0 0;1=4
P 11.03998996 5.1231 4 P 0 0;1=4
P 11.21998996 5.1631 4 P 0 0;1=4
P 11.17998996 5.1631 4 P 0 0;1=4
P 11.08498996 5.1631 4 P 0 0;1=4
P 11.13498996 5.1631 4 P 0 0;1=4
P 11.21998996 5.1231 4 P 0 0;1=4
P 11.21998996 5.0381 4 P 0 0;1=4
P 11.21998996 5.0831 4 P 0 0;1=4
P 11.21998996 4.9931 4 P 0 0;1=4
P 11.17998996 4.9931 4 P 0 0;1=4
P 11.17998996 5.1231 4 P 0 0;1=4
P 11.17998996 5.0831 4 P 0 0;1=4
P 11.17998996 5.0381 4 P 0 0;1=4
P 11.13498996 5.1231 4 P 0 0;1=4
P 11.08498996 5.1231 4 P 0 0;1=4
P 11.6269 4.90498996 4 P 0 0;1=4
P 11.6269 4.85498996 4 P 0 0;1=4
P 11.4269 4.80998996 4 P 0 0;1=4
P 11.4269 4.85498996 4 P 0 0;1=4
P 11.4269 4.90498996 4 P 0 0;1=4
P 11.4269 4.94998996 4 P 0 0;1=4
P 11.4769 4.94998996 4 P 0 0;1=4
P 11.4769 4.80998996 4 P 0 0;1=4
P 11.5269 4.94998996 4 P 0 0;1=4
P 11.5269 4.80998996 4 P 0 0;1=4
P 11.5769 4.94998996 4 P 0 0;1=4
P 11.6269 4.94998996 4 P 0 0;1=4
P 11.6269 4.80998996 4 P 0 0;1=4
P 11.5769 4.80998996 4 P 0 0;1=4
P 10.82676998 5.71338996 12 P 0 0;1=10
P 10.99213002 5.71338996 12 P 0 0;1=10
P 11.15748002 5.71338996 12 P 0 0;1=10
P 11.32283996 5.71338996 12 P 0 0;1=10
P 11.48818996 5.71338996 12 P 0 0;1=10
P 11.65353996 5.71338996 12 P 0 0;1=10
P 11.8189 5.71338996 12 P 0 0;1=10
P 11.98425 5.71338996 12 P 0 0;1=10
P 12.14961004 5.71338996 12 P 0 0;1=10
P 10.80498996 5.7831 4 P 0 0;1=4
P 10.84498996 5.7831 4 P 0 0;1=4
P 10.80498996 5.6431 4 P 0 0;1=4
P 10.84498996 5.6431 4 P 0 0;1=4
P 11.01035 5.6431 4 P 0 0;1=4
P 10.97035 5.6431 4 P 0 0;1=4
P 11.01035 5.7831 4 P 0 0;1=4
P 10.97035 5.7831 4 P 0 0;1=4
P 11.17571004 5.6431 4 P 0 0;1=4
P 11.13571004 5.6431 4 P 0 0;1=4
P 11.17571004 5.7831 4 P 0 0;1=4
P 11.13571004 5.7831 4 P 0 0;1=4
P 11.34106998 5.6431 4 P 0 0;1=4
P 11.30106998 5.6431 4 P 0 0;1=4
P 11.34106998 5.7831 4 P 0 0;1=4
P 11.30106998 5.7831 4 P 0 0;1=4
P 11.50643002 5.6431 4 P 0 0;1=4
P 11.46643002 5.6431 4 P 0 0;1=4
P 11.50643002 5.7831 4 P 0 0;1=4
P 11.46643002 5.7831 4 P 0 0;1=4
P 11.67178996 5.6431 4 P 0 0;1=4
P 11.63178996 5.6431 4 P 0 0;1=4
P 11.67178996 5.7831 4 P 0 0;1=4
P 11.63178996 5.7831 4 P 0 0;1=4
P 11.83715 5.6431 4 P 0 0;1=4
P 11.79715 5.6431 4 P 0 0;1=4
P 11.83715 5.7831 4 P 0 0;1=4
P 11.79715 5.7831 4 P 0 0;1=4
P 12.00251004 5.6431 4 P 0 0;1=4
P 11.96251004 5.6431 4 P 0 0;1=4
P 12.00251004 5.7831 4 P 0 0;1=4
P 11.96251004 5.7831 4 P 0 0;1=4
P 12.16786998 5.6431 4 P 0 0;1=4
P 12.12786998 5.6431 4 P 0 0;1=4
P 12.16786998 5.7831 4 P 0 0;1=4
P 12.12786998 5.7831 4 P 0 0;1=4
P 5.03605 5.1631 4 P 0 0;1=4
P 5.03605 4.9931 4 P 0 0;1=4
P 5.03605 5.0831 4 P 0 0;1=4
P 5.03605 5.0381 4 P 0 0;1=4
P 5.03605 5.1231 4 P 0 0;1=4
P 5.21605 5.1631 4 P 0 0;1=4
P 5.17605 5.1631 4 P 0 0;1=4
P 5.08105 5.1631 4 P 0 0;1=4
P 5.13105 5.1631 4 P 0 0;1=4
P 5.21605 5.1231 4 P 0 0;1=4
P 5.21605 5.0381 4 P 0 0;1=4
P 5.21605 5.0831 4 P 0 0;1=4
P 5.21605 4.9931 4 P 0 0;1=4
P 5.17605 4.9931 4 P 0 0;1=4
P 5.17605 5.1231 4 P 0 0;1=4
P 5.17605 5.0831 4 P 0 0;1=4
P 5.17605 5.0381 4 P 0 0;1=4
P 5.13105 5.1231 4 P 0 0;1=4
P 5.08105 5.1231 4 P 0 0;1=4
P 4.99605 5.1631 4 P 0 0;1=4
P 4.99605 5.1231 4 P 0 0;1=4
P 4.99605 5.0381 4 P 0 0;1=4
P 4.99605 5.0831 4 P 0 0;1=4
P 4.99605 4.9931 4 P 0 0;1=4
P 5.03605 4.9531 4 P 0 0;1=4
P 5.03605 4.9131 4 P 0 0;1=4
P 5.21605 4.9531 4 P 0 0;1=4
P 5.17605 4.9531 4 P 0 0;1=4
P 5.13105 4.9531 4 P 0 0;1=4
P 5.08105 4.9531 4 P 0 0;1=4
P 5.21605 4.9131 4 P 0 0;1=4
P 5.17605 4.9131 4 P 0 0;1=4
P 5.08105 4.9131 4 P 0 0;1=4
P 5.13105 4.9131 4 P 0 0;1=4
P 4.99605 4.9531 4 P 0 0;1=4
P 4.99605 4.9131 4 P 0 0;1=4
P 6.34948996 5.03 4 P 0 0;1=4
P 2.74225 5.14 5 P 0 0;1=3
P 2.04606004 3.61615 5 P 0 0;1=3
P 2.14606004 3.46615 5 P 0 0;1=3
P 1.86111004 4.657 5 P 0 0;1=3
P 2.78225 5.14 5 P 0 0;1=3
P 2.04606004 3.66615 5 P 0 0;1=3
P 2.14606004 3.51615 5 P 0 0;1=3
P 1.90111004 4.657 5 P 0 0;1=3
P 1.93196998 5.0535 5 P 0 0;1=3
P 1.99606004 3.46615 5 P 0 0;1=3
P 4.58268002 2.56615 5 P 0 0;1=3
P 1.97196998 5.0535 5 P 0 0;1=3
P 1.99606004 3.51615 5 P 0 0;1=3
P 2.88086998 5.17001998 5 P 0 0;1=3
P 2.14606004 3.61615 5 P 0 0;1=3
P 2.34606004 3.66615 5 P 0 0;1=3
P 3.56176998 4.71973002 5 P 0 0;1=3
P 2.92086998 5.17001998 5 P 0 0;1=3
P 2.14606004 3.66615 5 P 0 0;1=3
P 2.34606004 3.71615 5 P 0 0;1=3
P 3.52176998 4.71973002 5 P 0 0;1=3
P 2.39606004 3.61615 5 P 0 0;1=3
P 3.49091004 4.587 5 P 0 0;1=3
P 2.39606004 3.66615 5 P 0 0;1=3
P 3.45091004 4.587 5 P 0 0;1=3
P 2.49606004 3.61615 5 P 0 0;1=3
P 3.56176998 5.14 5 P 0 0;1=3
P 2.49606004 3.66615 5 P 0 0;1=3
P 3.52176998 5.14 5 P 0 0;1=3
P 2.44606004 3.66615 5 P 0 0;1=3
P 3.42003996 4.78291998 5 P 0 0;1=3
P 4.30605 4.6631 4 P 0 0;1=4
P 4.34105 4.6431 4 P 0 0;1=4
P 4.38605 4.6431 4 P 0 0;1=4
P 4.42605 4.6631 4 P 0 0;1=4
P 4.46605 4.6631 4 P 0 0;1=4
P 4.30605 4.7031 4 P 0 0;1=4
P 4.42605 4.7031 4 P 0 0;1=4
P 4.46605 4.7031 4 P 0 0;1=4
P 4.26605 4.6631 4 P 0 0;1=4
P 4.26605 4.7031 4 P 0 0;1=4
P 4.65605 4.6631 4 P 0 0;1=4
P 4.69605 4.6631 4 P 0 0;1=4
P 4.65605 4.7031 4 P 0 0;1=4
P 4.69605 4.7031 4 P 0 0;1=4
P 4.73105 4.6431 4 P 0 0;1=4
P 4.81605 4.6631 4 P 0 0;1=4
P 4.85605 4.6631 4 P 0 0;1=4
P 4.81605 4.7031 4 P 0 0;1=4
P 4.85605 4.7031 4 P 0 0;1=4
P 4.77605 4.6431 4 P 0 0;1=4
P 5.17605 4.7131 4 P 0 0;1=4
P 5.17605 4.6731 4 P 0 0;1=4
P 5.08105 4.6731 4 P 0 0;1=4
P 5.13105 4.6731 4 P 0 0;1=4
P 5.03605 4.6731 4 P 0 0;1=4
P 5.03605 4.7131 4 P 0 0;1=4
P 4.30605 4.7481 4 P 0 0;1=4
P 4.30605 4.7931 4 P 0 0;1=4
P 4.30605 4.8381 4 P 0 0;1=4
P 4.38605 4.8381 4 P 0 0;1=4
P 4.34605 4.8381 4 P 0 0;1=4
P 4.46605 4.8381 4 P 0 0;1=4
P 4.42605 4.8381 4 P 0 0;1=4
P 4.42605 4.7931 4 P 0 0;1=4
P 4.42605 4.7481 4 P 0 0;1=4
P 4.46605 4.7931 4 P 0 0;1=4
P 4.46605 4.7481 4 P 0 0;1=4
P 4.26605 4.7481 4 P 0 0;1=4
P 4.26605 4.7931 4 P 0 0;1=4
P 4.26605 4.8381 4 P 0 0;1=4
P 4.65605 4.8381 4 P 0 0;1=4
P 4.65605 4.7931 4 P 0 0;1=4
P 4.65605 4.7481 4 P 0 0;1=4
P 4.69605 4.8381 4 P 0 0;1=4
P 4.69605 4.7931 4 P 0 0;1=4
P 4.69605 4.7481 4 P 0 0;1=4
P 4.73605 4.8381 4 P 0 0;1=4
P 4.81605 4.8381 4 P 0 0;1=4
P 4.81605 4.7931 4 P 0 0;1=4
P 4.81605 4.7481 4 P 0 0;1=4
P 4.85605 4.8381 4 P 0 0;1=4
P 4.85605 4.7931 4 P 0 0;1=4
P 4.85605 4.7481 4 P 0 0;1=4
P 4.77605 4.8381 4 P 0 0;1=4
P 5.08105 4.8431 4 P 0 0;1=4
P 5.13105 4.8431 4 P 0 0;1=4
P 5.17605 4.8431 4 P 0 0;1=4
P 5.17605 4.8031 4 P 0 0;1=4
P 5.17605 4.7581 4 P 0 0;1=4
P 5.03605 4.8431 4 P 0 0;1=4
P 5.03605 4.8031 4 P 0 0;1=4
P 5.03605 4.7581 4 P 0 0;1=4
P 4.58268002 2.96615 5 P 0 0;1=3
P 4.63268002 2.96615 5 P 0 0;1=3
P 4.63268002 3.11615 5 P 0 0;1=3
P 4.58268002 3.01615 5 P 0 0;1=3
P 4.58268002 3.11615 5 P 0 0;1=3
P 4.63268002 3.01615 5 P 0 0;1=3
P 4.63268002 3.31615 5 P 0 0;1=3
P 4.58268002 3.26615 5 P 0 0;1=3
P 4.58268002 3.31615 5 P 0 0;1=3
P 4.63268002 3.26615 5 P 0 0;1=3
P 4.63268002 3.16615 5 P 0 0;1=3
P 4.58268002 3.16615 5 P 0 0;1=3
P 4.58268002 3.46615 5 P 0 0;1=3
P 4.63268002 3.41615 5 P 0 0;1=3
P 4.63268002 3.46615 5 P 0 0;1=3
P 4.58268002 3.41615 5 P 0 0;1=3
P 4.58268002 3.61615 5 P 0 0;1=3
P 4.58268002 3.56615 5 P 0 0;1=3
P 4.63268002 3.61615 5 P 0 0;1=3
P 4.63268002 3.56615 5 P 0 0;1=3
P 4.58268002 3.71615 5 P 0 0;1=3
P 4.63268002 3.71615 5 P 0 0;1=3
P 4.58268002 3.76615 5 P 0 0;1=3
P 4.58268002 3.86615 5 P 0 0;1=3
P 4.63268002 3.76615 5 P 0 0;1=3
P 4.63268002 3.86615 5 P 0 0;1=3
P 4.68268002 2.96615 5 P 0 0;1=3
P 4.73268002 2.96615 5 P 0 0;1=3
P 4.78268002 2.96615 5 P 0 0;1=3
P 4.68268002 3.11615 5 P 0 0;1=3
P 4.68268002 3.01615 5 P 0 0;1=3
P 4.73268002 3.11615 5 P 0 0;1=3
P 4.73268002 3.01615 5 P 0 0;1=3
P 4.78268002 3.11615 5 P 0 0;1=3
P 4.78268002 3.01615 5 P 0 0;1=3
P 4.73268002 3.31615 5 P 0 0;1=3
P 4.73268002 3.26615 5 P 0 0;1=3
P 4.68268002 3.26615 5 P 0 0;1=3
P 4.68268002 3.31615 5 P 0 0;1=3
P 4.78268002 3.26615 5 P 0 0;1=3
P 4.78268002 3.31615 5 P 0 0;1=3
P 4.73268002 3.16615 5 P 0 0;1=3
P 4.68268002 3.16615 5 P 0 0;1=3
P 4.78268002 3.16615 5 P 0 0;1=3
P 4.73268002 3.41615 5 P 0 0;1=3
P 4.68268002 3.41615 5 P 0 0;1=3
P 4.68268002 3.46615 5 P 0 0;1=3
P 4.73268002 3.46615 5 P 0 0;1=3
P 4.78268002 3.46615 5 P 0 0;1=3
P 4.78268002 3.41615 5 P 0 0;1=3
P 4.73268002 3.56615 5 P 0 0;1=3
P 4.73268002 3.61615 5 P 0 0;1=3
P 4.68268002 3.56615 5 P 0 0;1=3
P 4.68268002 3.61615 5 P 0 0;1=3
P 4.78268002 3.61615 5 P 0 0;1=3
P 4.78268002 3.56615 5 P 0 0;1=3
P 4.73268002 3.71615 5 P 0 0;1=3
P 4.68268002 3.71615 5 P 0 0;1=3
P 4.78268002 3.71615 5 P 0 0;1=3
P 4.73268002 3.76615 5 P 0 0;1=3
P 4.73268002 3.86615 5 P 0 0;1=3
P 4.68268002 3.76615 5 P 0 0;1=3
P 4.68268002 3.86615 5 P 0 0;1=3
P 4.78268002 3.76615 5 P 0 0;1=3
P 4.78268002 3.86615 5 P 0 0;1=3
P 4.88268002 3.86615 5 P 0 0;1=3
P 4.83268002 3.86615 5 P 0 0;1=3
P 5.03268002 3.86615 5 P 0 0;1=3
P 4.93268002 3.86615 5 P 0 0;1=3
P 4.98268002 3.86615 5 P 0 0;1=3
P 4.88268002 3.76615 5 P 0 0;1=3
P 4.83268002 3.76615 5 P 0 0;1=3
P 5.03268002 3.76615 5 P 0 0;1=3
P 4.93268002 3.76615 5 P 0 0;1=3
P 4.98268002 3.76615 5 P 0 0;1=3
P 4.88268002 3.71615 5 P 0 0;1=3
P 4.83268002 3.71615 5 P 0 0;1=3
P 5.03268002 3.71615 5 P 0 0;1=3
P 4.93268002 3.71615 5 P 0 0;1=3
P 4.98268002 3.71615 5 P 0 0;1=3
P 4.88268002 3.61615 5 P 0 0;1=3
P 4.83268002 3.61615 5 P 0 0;1=3
P 5.03268002 3.61615 5 P 0 0;1=3
P 4.93268002 3.61615 5 P 0 0;1=3
P 4.98268002 3.61615 5 P 0 0;1=3
P 4.88268002 3.56615 5 P 0 0;1=3
P 4.83268002 3.56615 5 P 0 0;1=3
P 5.03268002 3.56615 5 P 0 0;1=3
P 4.93268002 3.56615 5 P 0 0;1=3
P 4.98268002 3.56615 5 P 0 0;1=3
P 4.88268002 3.46615 5 P 0 0;1=3
P 4.83268002 3.46615 5 P 0 0;1=3
P 5.03268002 3.46615 5 P 0 0;1=3
P 4.93268002 3.46615 5 P 0 0;1=3
P 4.98268002 3.46615 5 P 0 0;1=3
P 4.88268002 3.41615 5 P 0 0;1=3
P 4.83268002 3.41615 5 P 0 0;1=3
P 5.03268002 3.41615 5 P 0 0;1=3
P 4.93268002 3.41615 5 P 0 0;1=3
P 4.98268002 3.41615 5 P 0 0;1=3
P 4.88268002 3.31615 5 P 0 0;1=3
P 4.83268002 3.31615 5 P 0 0;1=3
P 5.03268002 3.31615 5 P 0 0;1=3
P 4.93268002 3.31615 5 P 0 0;1=3
P 4.98268002 3.31615 5 P 0 0;1=3
P 4.83268002 3.26615 5 P 0 0;1=3
P 4.88268002 3.26615 5 P 0 0;1=3
P 4.98268002 3.26615 5 P 0 0;1=3
P 4.93268002 3.26615 5 P 0 0;1=3
P 5.03268002 3.26615 5 P 0 0;1=3
P 4.83268002 3.16615 5 P 0 0;1=3
P 4.88268002 3.16615 5 P 0 0;1=3
P 4.98268002 3.16615 5 P 0 0;1=3
P 4.93268002 3.16615 5 P 0 0;1=3
P 5.03268002 3.16615 5 P 0 0;1=3
P 4.83268002 3.11615 5 P 0 0;1=3
P 4.88268002 3.11615 5 P 0 0;1=3
P 4.98268002 3.11615 5 P 0 0;1=3
P 4.93268002 3.11615 5 P 0 0;1=3
P 5.03268002 3.11615 5 P 0 0;1=3
P 4.83268002 3.01615 5 P 0 0;1=3
P 4.88268002 3.01615 5 P 0 0;1=3
P 4.98268002 3.01615 5 P 0 0;1=3
P 4.93268002 3.01615 5 P 0 0;1=3
P 5.03268002 3.01615 5 P 0 0;1=3
P 4.83268002 2.96615 5 P 0 0;1=3
P 4.88268002 2.96615 5 P 0 0;1=3
P 4.98268002 2.96615 5 P 0 0;1=3
P 4.93268002 2.96615 5 P 0 0;1=3
P 5.03268002 2.96615 5 P 0 0;1=3
P 2.44606004 3.71615 5 P 0 0;1=3
P 3.38003996 4.78291998 5 P 0 0;1=3
P 2.19606004 3.81615 5 P 0 0;1=3
P 3.02571004 4.667 5 P 0 0;1=3
P 2.19606004 3.86615 5 P 0 0;1=3
P 3.06571004 4.667 5 P 0 0;1=3
P 3.27831004 4.642 5 P 0 0;1=3
P 2.39606004 3.76615 5 P 0 0;1=3
P 4.73268002 2.66615 5 P 0 0;1=3
P 10.73661004 2.66615 5 P 0 0;1=3
P 3.23831004 4.642 5 P 0 0;1=3
P 2.39606004 3.81615 5 P 0 0;1=3
P 5.03268002 2.61615 5 P 0 0;1=3
P 3.34916998 5.1035 5 P 0 0;1=3
P 2.49606004 3.76615 5 P 0 0;1=3
P 3.30916998 5.1035 5 P 0 0;1=3
P 2.49606004 3.81615 5 P 0 0;1=3
P 11.03661004 2.61615 5 P 0 0;1=3
P 2.74225 4.667 5 P 0 0;1=3
P 2.09606004 3.66615 5 P 0 0;1=3
P 2.44606004 3.81615 5 P 0 0;1=3
P 3.20743996 4.78291998 5 P 0 0;1=3
P 2.78225 4.667 5 P 0 0;1=3
P 2.09606004 3.71615 5 P 0 0;1=3
P 2.44606004 3.86615 5 P 0 0;1=3
P 3.16743996 4.78291998 5 P 0 0;1=3
P 2.34606004 3.81615 5 P 0 0;1=3
P 3.27831004 5.22001998 5 P 0 0;1=3
P 2.34606004 3.86615 5 P 0 0;1=3
P 3.23831004 5.22001998 5 P 0 0;1=3
P 4.63268002 2.61615 5 P 0 0;1=3
P 10.98661004 2.61615 5 P 0 0;1=3
P 2.19606004 3.66615 5 P 0 0;1=3
P 2.81311004 4.78291998 5 P 0 0;1=3
P 10.98661004 2.56615 5 P 0 0;1=3
P 2.19606004 3.71615 5 P 0 0;1=3
P 2.85311004 4.78291998 5 P 0 0;1=3
P 0.64808996 1.655 4 P 0 0;1=4
P 5.76 2.66 4 P 0 0;1=0
P 10.63661004 2.61615 5 P 0 0;1=3
P 2.09606004 3.81615 5 P 0 0;1=3
P 3.09656998 5.0535 5 P 0 0;1=3
P 2.09606004 3.86615 5 P 0 0;1=3
P 3.13656998 5.0535 5 P 0 0;1=3
P 2.88708002 4.667 5 P 0 0;1=3
P 2.04606004 3.76615 5 P 0 0;1=3
P 10.73661004 2.61615 5 P 0 0;1=3
P 2.92708002 4.667 5 P 0 0;1=3
P 2.04606004 3.81615 5 P 0 0;1=3
P 10.68661004 2.61615 5 P 0 0;1=3
P 5.03268002 2.46615 5 P 0 0;1=3
P 5.03268002 2.51615 5 P 0 0;1=3
P 11.08661004 2.56615 5 P 0 0;1=3
P 10.68661004 2.56615 5 P 0 0;1=3
P 9.175 5.255 4 P 0 0;1=0
P 4.73268002 2.61615 5 P 0 0;1=3
P 9.11853996 5.255 4 P 0 0;1=0
P 5.08268002 2.41615 5 P 0 0;1=3
P 10.93661004 2.66615 5 P 0 0;1=3
P 10.58661004 2.61615 5 P 0 0;1=3
P 8.15 3.76615 5 P 0 0;1=3
P 9.02925 5.165 5 P 0 0;1=3
P 4.98268002 2.21615 5 P 0 0;1=3
P 10.58661004 2.56615 5 P 0 0;1=3
P 8.15 3.81615 5 P 0 0;1=3
P 9.06925 5.165 5 P 0 0;1=3
P 11.03661004 2.66615 5 P 0 0;1=3
P 4.98268002 2.26615 5 P 0 0;1=3
P 10.93661004 2.61615 5 P 0 0;1=3
P 5.03268002 2.26615 5 P 0 0;1=3
P 11.08661004 2.61615 5 P 0 0;1=3
P 5.03268002 2.31615 5 P 0 0;1=3
P 10.63661004 2.66615 5 P 0 0;1=3
P 3.775 5.295 4 P 0 0;1=0
P 0.73 5.78 4 P 0 0;1=4
P 8.07 5.29 4 P 0 0;1=0
P 3.8399 4.765 4 P 0 0;1=0
P 0.81 5.78 4 P 0 0;1=4
P 8.005 5.29 4 P 0 0;1=0
P 11.08661004 1.91615 5 P 0 0;1=3
P 4.98268002 1.91615 5 P 0 0;1=3
P 4.98268002 1.96615 5 P 0 0;1=3
P 4.93268002 1.86615 5 P 0 0;1=3
P 4.93268002 1.91615 5 P 0 0;1=3
P 5.03268002 1.86615 5 P 0 0;1=3
P 5.08268002 1.91615 5 P 0 0;1=3
P 5.08268002 2.56615 5 P 0 0;1=3
P 8.15 2.51615 5 P 0 0;1=3
P 4.98268002 2.61615 5 P 0 0;1=3
P 10.68661004 2.71615 5 P 0 0;1=3
P 10.98661004 2.71615 5 P 0 0;1=3
P 10.78661004 2.71615 5 P 0 0;1=3
P 4.93268002 2.66615 5 P 0 0;1=3
P 10.88661004 2.71615 5 P 0 0;1=3
P 10.68661004 2.76615 5 P 0 0;1=3
P 9.64 0.71 4 P 0 0;1=0
P 10.58661004 2.81615 5 P 0 0;1=3
P 9.43296004 0.49133002 4 P 0 0;1=0
P 9.43296004 0.73633002 4 P 0 0;1=0
P 10.63661004 2.81615 5 P 0 0;1=3
P 4.68268002 2.56615 5 P 0 0;1=3
P 10.68661004 2.81615 5 P 0 0;1=3
P 9.55795 0.36633002 4 P 0 0;1=0
P 10.73661004 2.81615 5 P 0 0;1=3
P 9.35796004 0.49133002 4 P 0 0;1=0
P 5.03268002 2.66615 5 P 0 0;1=3
P 10.78661004 2.81615 5 P 0 0;1=3
P 9.58296004 0.71133002 4 P 0 0;1=0
P 5.08268002 2.61615 5 P 0 0;1=3
P 11.08661004 1.96615 5 P 0 0;1=3
P 11.03661004 1.86615 5 P 0 0;1=3
P 11.03661004 1.91615 5 P 0 0;1=3
P 10.93661004 1.86615 5 P 0 0;1=3
P 10.93661004 1.91615 5 P 0 0;1=3
P 10.98661004 1.91615 5 P 0 0;1=3
P 10.98661004 1.96615 5 P 0 0;1=3
P 4.93268002 2.61615 5 P 0 0;1=3
P 11.03661004 2.01615 5 P 0 0;1=3
P 11.03661004 2.06615 5 P 0 0;1=3
P 10.93661004 2.01615 5 P 0 0;1=3
P 10.93661004 2.06615 5 P 0 0;1=3
P 10.98661004 2.06615 5 P 0 0;1=3
P 10.98661004 2.11615 5 P 0 0;1=3
P 11.08661004 2.06615 5 P 0 0;1=3
P 11.08661004 2.11615 5 P 0 0;1=3
P 3.115 5.255 4 P 0 0;1=0
P 4.63268002 2.66615 5 P 0 0;1=3
P 11.08661004 2.21615 5 P 0 0;1=3
P 4.98268002 2.56615 5 P 0 0;1=3
P 11.08661004 2.26615 5 P 0 0;1=3
P 11.03661004 2.26615 5 P 0 0;1=3
P 2.14606004 3.76615 5 P 0 0;1=3
P 3.02571004 5.165 5 P 0 0;1=3
P 11.03661004 2.31615 5 P 0 0;1=3
P 10.98661004 2.21615 5 P 0 0;1=3
P 10.98661004 2.26615 5 P 0 0;1=3
P 3.17146004 5.255 4 P 0 0;1=0
P 4.68268002 2.61615 5 P 0 0;1=3
P 10.93661004 2.26615 5 P 0 0;1=3
P 10.58661004 2.76615 5 P 0 0;1=3
P 4 5.29 4 P 0 0;1=0
P 10.93661004 2.31615 5 P 0 0;1=3
P 10.88661004 2.16615 5 P 0 0;1=3
P 10.73661004 1.91615 5 P 0 0;1=3
P 10.395 1.28555 5 P 0 0;1=3
P 12.81495 1.96456998 10 P 0 0;1=1
P 9.42358002 5.22001998 5 P 0 0;1=3
P 8.98115 2.825 5 P 0 0;1=3
P 4.58268002 2.61615 5 P 0 0;1=3
P 9.38358002 5.22001998 5 P 0 0;1=3
P 8.98115 2.865 5 P 0 0;1=3
P 2.14606004 3.81615 5 P 0 0;1=3
P 3.06571004 5.165 5 P 0 0;1=3
P 11.08661004 2.71615 5 P 0 0;1=3
P 3.985 4.88998996 4 P 0 0;1=0
P 11.73316004 2.652 5 P 0 0;1=3
P 12.55905 4.40551004 10 P 0 0;1=1
P 11.73316004 2.612 5 P 0 0;1=3
P 12.63778996 4.44488002 10 P 0 0;1=1
P 8.3 2.86615 5 P 0 0;1=3
P 4.83268002 2.16615 5 P 0 0;1=3
P 0.69348996 1.90611998 5 P 0 0;1=3
P 11.73316004 2.492 5 P 0 0;1=3
P 12.55905 4.24803002 10 P 0 0;1=1
P 4.88268002 2.16615 5 P 0 0;1=3
P 0.69348996 1.86611998 5 P 0 0;1=3
P 11.73316004 2.452 5 P 0 0;1=3
P 12.63778996 4.2874 10 P 0 0;1=1
P 8.25 2.86615 5 P 0 0;1=3
P 12.55905 3.93306998 10 P 0 0;1=1
P 11.73316004 2.332 5 P 0 0;1=3
P 12.63778996 3.97243996 10 P 0 0;1=1
P 11.73316004 2.292 5 P 0 0;1=3
P 10.83661004 2.16615 5 P 0 0;1=3
P 11.53316004 2.092 5 P 0 0;1=3
P 12.55905 3.77558996 10 P 0 0;1=1
P 11.53316004 2.052 5 P 0 0;1=3
P 12.63778996 3.81496004 10 P 0 0;1=1
P 12.81495 3.53936998 10 P 0 0;1=1
P 10.68661004 2.26615 5 P 0 0;1=3
P 9.975 2.3758 5 P 0 0;1=3
P 12.81495 3.38188996 10 P 0 0;1=1
P 10.73661004 2.31615 5 P 0 0;1=3
P 9.975 2.23955 5 P 0 0;1=3
P 12.81495 2.20078996 10 P 0 0;1=1
P 10.68661004 1.91615 5 P 0 0;1=3
P 10.42445 1.395 5 P 0 0;1=3
P 12.81495 2.75196998 10 P 0 0;1=1
P 10.73661004 2.01615 5 P 0 0;1=3
P 10.26025 1.82845 5 P 0 0;1=3
P 12.73621004 3.73621998 10 P 0 0;1=1
P 10.58661004 2.21615 5 P 0 0;1=3
P 10.09 2.26825 5 P 0 0;1=3
P 10.73661004 2.41615 5 P 0 0;1=3
P 10.09 2.69655 5 P 0 0;1=3
P 12.73621004 4.52361998 10 P 0 0;1=1
P 7.3426 4.69351004 4 P 0 0;1=0
P 11.73316004 1.532 5 P 0 0;1=3
P 12.55905 2.27953002 10 P 0 0;1=1
P 7.2926 4.69351004 4 P 0 0;1=0
P 12.73621004 3.57873996 10 P 0 0;1=1
P 10.68661004 2.21615 5 P 0 0;1=3
P 9.975 2.3358 5 P 0 0;1=3
P 12.73621004 3.42126004 10 P 0 0;1=1
P 10.73661004 2.26615 5 P 0 0;1=3
P 9.975 2.19955 5 P 0 0;1=3
P 11.73316004 2.172 5 P 0 0;1=3
P 12.55905 3.46063002 10 P 0 0;1=1
P 4.98268002 2.36615 5 P 0 0;1=3
P 10.73661004 1.86615 5 P 0 0;1=3
P 10.395 1.32555 5 P 0 0;1=3
P 12.73621004 2.00393996 10 P 0 0;1=1
P 11.73316004 2.132 5 P 0 0;1=3
P 12.63778996 3.5 10 P 0 0;1=1
P 3.38003996 5.22001998 5 P 0 0;1=3
P 2.97721004 2.865 5 P 0 0;1=3
P 4.98268002 2.41615 5 P 0 0;1=3
P 12.63778996 1.76771998 10 P 0 0;1=1
P 3.42003996 5.22001998 5 P 0 0;1=3
P 2.97721004 2.825 5 P 0 0;1=3
P 4.88268002 2.81615 5 P 0 0;1=3
P 4.93268002 2.81615 5 P 0 0;1=3
P 4.98268002 2.81615 5 P 0 0;1=3
P 5.03268002 2.81615 5 P 0 0;1=3
P 5.08268002 2.81615 5 P 0 0;1=3
P 11.03661004 2.81615 5 P 0 0;1=3
P 11.08661004 2.81615 5 P 0 0;1=3
P 10.98661004 2.81615 5 P 0 0;1=3
P 10.93661004 2.81615 5 P 0 0;1=3
P 10.88661004 2.81615 5 P 0 0;1=3
P 5.27886004 3.0214 4 P 0 0;1=4
P 5.27886004 3.0564 4 P 0 0;1=4
P 5.27886004 3.1014 4 P 0 0;1=4
P 5.27886004 3.1364 4 P 0 0;1=4
P 5.27886004 2.9764 4 P 0 0;1=4
P 5.27886004 2.9414 4 P 0 0;1=4
P 5.27886004 3.2614 4 P 0 0;1=4
P 5.27886004 3.2964 4 P 0 0;1=4
P 5.27886004 3.2164 4 P 0 0;1=4
P 5.27886004 3.1814 4 P 0 0;1=4
P 11.28278996 3.1814 4 P 0 0;1=4
P 11.28278996 3.2164 4 P 0 0;1=4
P 11.28278996 3.2964 4 P 0 0;1=4
P 11.28278996 3.2614 4 P 0 0;1=4
P 11.28278996 2.9414 4 P 0 0;1=4
P 11.28278996 2.9764 4 P 0 0;1=4
P 11.28278996 3.1364 4 P 0 0;1=4
P 11.28278996 3.1014 4 P 0 0;1=4
P 11.28278996 3.0564 4 P 0 0;1=4
P 11.28278996 3.0214 4 P 0 0;1=4
P 5.59708996 4.7302 4 P 0 0;1=4
P 5.57708996 4.6802 4 P 0 0;1=4
P 5.75708996 4.7302 4 P 0 0;1=4
P 5.83708996 4.7302 4 P 0 0;1=4
P 5.69708996 4.6802 4 P 0 0;1=4
P 5.73708996 4.6802 4 P 0 0;1=4
P 5.77708996 4.6802 4 P 0 0;1=4
P 5.81708996 4.6802 4 P 0 0;1=4
P 5.85708996 4.6802 4 P 0 0;1=4
P 5.67708996 4.7302 4 P 0 0;1=4
P 5.65708996 4.6802 4 P 0 0;1=4
P 5.61708996 4.6802 4 P 0 0;1=4
P 6.13708996 4.7602 4 P 0 0;1=4
P 6.09708996 4.6802 4 P 0 0;1=4
P 6.13708996 4.6402 4 P 0 0;1=4
P 6.13708996 4.6802 4 P 0 0;1=4
P 6.13708996 4.7202 4 P 0 0;1=4
P 5.91708996 4.7302 4 P 0 0;1=4
P 5.99708996 4.7302 4 P 0 0;1=4
P 6.07708996 4.7302 4 P 0 0;1=4
P 5.89708996 4.6802 4 P 0 0;1=4
P 5.93708996 4.6802 4 P 0 0;1=4
P 5.97708996 4.6802 4 P 0 0;1=4
P 6.01708996 4.6802 4 P 0 0;1=4
P 6.05708996 4.6802 4 P 0 0;1=4
P 5.59708996 4.7702 4 P 0 0;1=4
P 5.59708996 4.8102 4 P 0 0;1=4
P 5.75708996 4.8102 4 P 0 0;1=4
P 5.83708996 4.8102 4 P 0 0;1=4
P 5.75708996 4.7702 4 P 0 0;1=4
P 5.83708996 4.7702 4 P 0 0;1=4
P 5.67708996 4.8102 4 P 0 0;1=4
P 5.67708996 4.7702 4 P 0 0;1=4
P 6.13708996 4.9252 4 P 0 0;1=4
P 6.13708996 4.8402 4 P 0 0;1=4
P 6.13708996 4.8002 4 P 0 0;1=4
P 6.13708996 4.8852 4 P 0 0;1=4
P 5.91708996 4.8102 4 P 0 0;1=4
P 5.99708996 4.8102 4 P 0 0;1=4
P 5.91708996 4.7702 4 P 0 0;1=4
P 5.99708996 4.7702 4 P 0 0;1=4
P 6.07708996 4.8102 4 P 0 0;1=4
P 6.07708996 4.7702 4 P 0 0;1=4
P 4.93268002 2.26615 5 P 0 0;1=3
P 4.93268002 2.31615 5 P 0 0;1=3
P 5.08268002 2.36615 5 P 0 0;1=3
P 12.81495 3.22441004 10 P 0 0;1=1
P 10.68661004 2.06615 5 P 0 0;1=3
P 10.09 2.13095 5 P 0 0;1=3
P 10.63661004 2.31615 5 P 0 0;1=3
P 10.09 2.40335 5 P 0 0;1=3
P 12.81495 3.85433002 10 P 0 0;1=1
P 11.73316004 2.012 5 P 0 0;1=3
P 12.63778996 3.1063 10 P 0 0;1=1
P 11.73316004 1.972 5 P 0 0;1=3
P 12.55905 3.14566998 10 P 0 0;1=1
P 11.53316004 1.732 5 P 0 0;1=3
P 12.55905 2.98818996 10 P 0 0;1=1
P 12.81495 3.69685 10 P 0 0;1=1
P 10.58661004 2.26615 5 P 0 0;1=3
P 10.09 2.30825 5 P 0 0;1=3
P 11.53316004 1.772 5 P 0 0;1=3
P 12.63778996 2.94881998 10 P 0 0;1=1
P 12.81495 4.32676998 10 P 0 0;1=1
P 10.63661004 2.46615 5 P 0 0;1=3
P 9.975 2.62445 5 P 0 0;1=3
P 12.63778996 2.79133996 10 P 0 0;1=1
P 11.73316004 1.852 5 P 0 0;1=3
P 12.55905 2.83071004 10 P 0 0;1=1
P 11.73316004 1.812 5 P 0 0;1=3
P 10.73661004 2.46615 5 P 0 0;1=3
P 10.09 2.73655 5 P 0 0;1=3
P 12.81495 4.48425 10 P 0 0;1=1
P 10.63661004 2.26615 5 P 0 0;1=3
P 10.09 2.44335 5 P 0 0;1=3
P 12.73621004 3.8937 10 P 0 0;1=1
P 10.58661004 2.41615 5 P 0 0;1=3
P 9.975 2.5109 5 P 0 0;1=3
P 12.81495 4.16928996 10 P 0 0;1=1
P 1.025 -0.35 26 P 0 3;1=6
P 1.325 -0.35 26 P 0 3;1=6
P 1.175 -0.35 26 P 0 3;1=6
P 0.725 -0.35 26 P 0 3;1=6
P 0.875 -0.35 26 P 0 3;1=6
P 12.73621004 4.05118002 10 P 0 0;1=1
P 10.68661004 2.36615 5 P 0 0;1=3
P 10.09 2.53845 5 P 0 0;1=3
P 12.81495 2.35826998 10 P 0 0;1=1
P 10.63661004 1.86615 5 P 0 0;1=3
P 10.35543002 1.52156998 5 P 0 0;1=3
P 5.03268002 2.01615 5 P 0 0;1=3
P 5.08268002 2.21615 5 P 0 0;1=3
P 12.73621004 2.16141998 10 P 0 0;1=1
P 10.68661004 1.96615 5 P 0 0;1=3
P 10.46445 1.395 5 P 0 0;1=3
P 0.2 -0.293 18 P 0 0;1=14
P 12.27 0.29 18 P 0 0;1=14
P 0.66 0.29 18 P 0 0;1=14
P 0.2 5.82361998 18 P 0 0;1=14
P 12.81495 1.57086998 10 P 0 0;1=1
P 12.73621004 1.5315 10 P 0 0;1=1
P 12.63778996 2.7126 10 P 0 0;1=1
P 12.55905 2.67323002 10 P 0 0;1=1
P 12.55905 1.64961004 10 P 0 0;1=1
P 12.63778996 1.61023996 10 P 0 0;1=1
P 12.55905 1.57086998 10 P 0 0;1=1
P 12.63778996 1.5315 10 P 0 0;1=1
P 12.73621004 1.68898002 10 P 0 0;1=1
P 12.81495 1.64961004 10 P 0 0;1=1
P 12.63778996 1.68898002 10 P 0 0;1=1
P 12.55905 1.72835 10 P 0 0;1=1
P 12.81495 1.72835 10 P 0 0;1=1
P 12.73621004 1.45276004 10 P 0 0;1=1
P 12.81495 1.41338996 10 P 0 0;1=1
P 12.73621004 1.37401998 10 P 0 0;1=7
P 12.63778996 1.45276004 10 P 0 0;1=1
P 12.55905 1.41338996 10 P 0 0;1=1
P 0.35038996 1.5315 10 P 0 0;1=1
P 0.27165 1.49213002 10 P 0 0;1=1
P 0.17323002 2.67323002 10 P 0 0;1=1
P 0.09448996 2.63386004 10 P 0 0;1=1
P 0.09448996 1.61023996 10 P 0 0;1=1
P 0.17323002 1.57086998 10 P 0 0;1=1
P 0.09448996 1.5315 10 P 0 0;1=1
P 0.17323002 1.49213002 10 P 0 0;1=1
P 0.27165 1.64961004 10 P 0 0;1=1
P 0.35038996 1.61023996 10 P 0 0;1=1
P 0.17323002 1.64961004 10 P 0 0;1=1
P 0.09448996 1.68898002 10 P 0 0;1=1
P 0.35038996 1.68898002 10 P 0 0;1=1
P 0.27165 1.41338996 10 P 0 0;1=1
P 0.35038996 1.37401998 10 P 0 0;1=1
P 0.27165 1.33465 10 P 0 0;1=7
P 0.17323002 1.41338996 10 P 0 0;1=1
P 0.09448996 1.37401998 10 P 0 0;1=1
P 10.20866004 5.4441 23 P 0 0;1=15
P 5.78346004 5.4441 23 P 0 0;1=15
P 12.7252 6.31661998 18 P 0 0;1=14
P 0.2 6.31661998 18 P 0 0;1=14
P 12.7252 -0.293 18 P 0 0;1=14
P 0.22245 4.87401004 16 P 0 0;1=5
P 12.68701004 0.46063002 19 P 0 0;1=16
P 12.68701998 5.4252 19 P 0 0;1=16
P 0.22245 0.42126004 19 P 0 0;1=16
P 0.22255 5.38583002 19 P 0 0;1=16
P 7.17716998 5.7874 22 P 0 0;1=17
P 7.17716998 0.23621998 22 P 0 0;1=17
P 0.22245 0.68898002 21 P 0 0;1=18
P 0.22245 5.11811004 21 P 0 0;1=18
P 12.68701998 5.15748002 21 P 0 0;1=18
P 12.68701998 0.72835 21 P 0 0;1=18
P 6.11811004 1.52756004 21 P 0 0;1=18
P 6.11811004 4.20473002 21 P 0 0;1=18
P 4.83268002 4.22441004 21 P 0 0;1=18
P 2.24606004 4.22441004 21 P 0 0;1=18
P 0.96063002 4.20473002 21 P 0 0;1=18
P 0.96063002 1.52756004 21 P 0 0;1=18
P 2.24606004 1.50786998 21 P 0 0;1=18
P 4.83268002 1.50786998 21 P 0 0;1=18
P 6.04921004 2.58268002 20 P 0 0;1=19
P 1.05905 2.58268002 25 P 0 0;1=20
P 12.12205 1.52756004 21 P 0 0;1=18
P 12.12205 4.20473002 21 P 0 0;1=18
P 10.83661998 4.22441004 21 P 0 0;1=18
P 8.25 4.22441004 21 P 0 0;1=18
P 6.96456998 4.20473002 21 P 0 0;1=18
P 6.96456998 1.52756004 21 P 0 0;1=18
P 8.25 1.50786998 21 P 0 0;1=18
P 10.83661998 1.50786998 21 P 0 0;1=18
P 12.05315 2.58268002 20 P 0 0;1=19
P 7.06298996 2.58268002 25 P 0 0;1=20
P 12.33465 5.69528002 17 P 0 0;1=21
P 3.58311004 4.91851004 13 P 0 0;1=22
P 2.72091004 4.91851004 13 P 0 0;1=22
P 9.58665 4.91851004 13 P 0 0;1=22
P 8.72445 4.91851004 13 P 0 0;1=22
P 2.41851004 4.91851004 13 P 0 0;1=22
P 1.55631004 4.91851004 13 P 0 0;1=22
P 8.42205 4.91851004 13 P 0 0;1=22
P 7.55985 4.91851004 13 P 0 0;1=22
P 0.22243996 1.79331004 15 P 0 0;1=23
P 0.22243996 4.67323002 15 P 0 0;1=23
P 12.687 1.83268002 15 P 0 0;1=23
P 12.687 4.7126 15 P 0 0;1=23
P 0.7687 5.62008002 11 P 0 0;1=24
P 1.47736004 5.62008002 11 P 0 0;1=24
L 1.88908002 -1.91246004 1.89293002 -1.91246004 0 P 0 ;0
L 1.89126998 -1.91146004 1.89656998 -1.91146004 0 P 0 ;0
L 1.89393996 -1.91046004 1.9155 -1.91046004 0 P 0 ;0
L 1.91593996 -1.91246004 1.92048996 -1.91246004 0 P 0 ;0
L 1.9126 -1.91146004 1.9184 -1.91146004 0 P 0 ;0
L 1.89763002 -1.90946004 1.91016998 -1.90946004 0 P 0 ;0
L 1.89053002 -1.96001004 1.8974 -1.96001004 0 P 0 ;0
L 1.89053002 -1.95901004 1.8974 -1.95901004 0 P 0 ;0
L 1.89053002 -1.95801004 1.8974 -1.95801004 0 P 0 ;0
L 1.89053002 -1.95701004 1.8974 -1.95701004 0 P 0 ;0
L 1.89053002 -1.95601004 1.8974 -1.95601004 0 P 0 ;0
L 1.89053002 -1.95501004 1.8974 -1.95501004 0 P 0 ;0
L 1.89053002 -1.95401004 1.8974 -1.95401004 0 P 0 ;0
L 1.89053002 -1.95301004 1.89741004 -1.95301004 0 P 0 ;0
L 1.89053002 -1.95201004 1.89741998 -1.95201004 0 P 0 ;0
L 1.89053002 -1.95101004 1.89743996 -1.95101004 0 P 0 ;0
L 1.89053002 -1.95001004 1.89745 -1.95001004 0 P 0 ;0
L 1.89053002 -1.94901004 1.89746004 -1.94901004 0 P 0 ;0
L 1.89053002 -1.94801004 1.89753002 -1.94801004 0 P 0 ;0
L 1.89053002 -1.94701004 1.8977 -1.94701004 0 P 0 ;0
L 1.89053002 -1.94601004 1.89798002 -1.94601004 0 P 0 ;0
L 1.89053002 -1.94501004 1.89861004 -1.94501004 0 P 0 ;0
L 1.89053002 -1.94401004 1.90005 -1.94401004 0 P 0 ;0
L 1.89053002 -1.94301004 1.9113 -1.94301004 0 P 0 ;0
L 1.89053002 -1.94201004 1.91168002 -1.94201004 0 P 0 ;0
L 1.89053002 -1.94101004 1.91246998 -1.94101004 0 P 0 ;0
L 1.89053002 -1.94001004 1.90093996 -1.94001004 0 P 0 ;0
L 1.89053002 -1.93901004 1.89856004 -1.93901004 0 P 0 ;0
L 1.89053002 -1.93801004 1.89786998 -1.93801004 0 P 0 ;0
L 1.89053002 -1.93701004 1.89753996 -1.93701004 0 P 0 ;0
L 1.89053002 -1.93601004 1.89746998 -1.93601004 0 P 0 ;0
L 1.89053002 -1.93501004 1.89743996 -1.93501004 0 P 0 ;0
L 1.89053002 -1.93401004 1.89741998 -1.93401004 0 P 0 ;0
L 1.89053002 -1.93301004 1.8974 -1.93301004 0 P 0 ;0
L 1.89053002 -1.93201004 1.8974 -1.93201004 0 P 0 ;0
L 1.89053002 -1.93101004 1.8974 -1.93101004 0 P 0 ;0
L 1.89053002 -1.93001004 1.8974 -1.93001004 0 P 0 ;0
L 1.89053002 -1.92901004 1.8974 -1.92901004 0 P 0 ;0
L 1.89053002 -1.92801004 1.89753002 -1.92801004 0 P 0 ;0
L 1.89053002 -1.92701004 1.89793996 -1.92701004 0 P 0 ;0
L 1.89053002 -1.92601004 1.91713002 -1.92601004 0 P 0 ;0
L 1.89053002 -1.92501004 1.91628996 -1.92501004 0 P 0 ;0
L 1.89053002 -1.92401004 1.91513996 -1.92401004 0 P 0 ;0
L 1.89053002 -1.92301004 1.91321998 -1.92301004 0 P 0 ;0
L 1.89053002 -1.92201004 1.90551004 -1.92201004 0 P 0 ;0
L 1.89438996 -1.97246004 1.91331004 -1.97246004 0 P 0 ;0
L 1.89106998 -1.97146004 1.89973002 -1.97146004 0 P 0 ;0
L 1.88878002 -1.97046004 1.8949 -1.97046004 0 P 0 ;0
L 1.88698002 -1.96946004 1.89206998 -1.96946004 0 P 0 ;0
L 1.88546004 -1.96846004 1.88986998 -1.96846004 0 P 0 ;0
L 1.88416998 -1.96746004 1.88808996 -1.96746004 0 P 0 ;0
L 1.88288002 -1.96646004 1.88655 -1.96646004 0 P 0 ;0
L 1.88176998 -1.96546004 1.88518002 -1.96546004 0 P 0 ;0
L 1.88068996 -1.96446004 1.88393996 -1.96446004 0 P 0 ;0
L 1.87968996 -1.96346004 1.88286004 -1.96346004 0 P 0 ;0
L 1.87878002 -1.96246004 1.88186004 -1.96246004 0 P 0 ;0
L 1.8786 -1.92046004 1.88126998 -1.92046004 0 P 0 ;0
L 1.87946998 -1.91946004 1.88223002 -1.91946004 0 P 0 ;0
L 1.88048002 -1.91846004 1.88321004 -1.91846004 0 P 0 ;0
L 1.88153996 -1.91746004 1.88436998 -1.91746004 0 P 0 ;0
L 1.88273002 -1.91646004 1.88558996 -1.91646004 0 P 0 ;0
L 1.88406004 -1.91546004 1.88696998 -1.91546004 0 P 0 ;0
L 1.88548996 -1.91446004 1.88853002 -1.91446004 0 P 0 ;0
L 1.88718002 -1.91346004 1.89041998 -1.91346004 0 P 0 ;0
L 1.90896004 -1.92963996 1.90921998 -1.92991998 0 P 0 ;0
L 1.90921998 -1.92991998 1.90945 -1.93021998 0 P 0 ;0
L 1.90945 -1.93021998 1.90966004 -1.93053002 0 P 0 ;0
L 1.90966004 -1.93053002 1.90983002 -1.93086004 0 P 0 ;0
L 1.90983002 -1.93086004 1.90998002 -1.93121004 0 P 0 ;0
L 1.90998002 -1.93121004 1.9101 -1.93156998 0 P 0 ;0
L 1.9101 -1.93156998 1.91018996 -1.93193996 0 P 0 ;0
L 1.91018996 -1.93193996 1.91023996 -1.93231004 0 P 0 ;0
L 1.91023996 -1.93231004 1.91026998 -1.93265 0 P 0 ;0
L 1.91026998 -1.93265 1.91026004 -1.93298002 0 P 0 ;0
L 1.91026004 -1.93298002 1.91023002 -1.93331004 0 P 0 ;0
L 1.91023002 -1.93331004 1.91016998 -1.93363996 0 P 0 ;0
L 1.91016998 -1.93363996 1.91008996 -1.93396004 0 P 0 ;0
L 1.91008996 -1.93396004 1.90998002 -1.93428002 0 P 0 ;0
L 1.90998002 -1.93428002 1.90983996 -1.93458002 0 P 0 ;0
L 1.90983996 -1.93458002 1.90968996 -1.93486998 0 P 0 ;0
L 1.90968996 -1.93486998 1.90951004 -1.93516004 0 P 0 ;0
L 1.90951004 -1.93516004 1.90921004 -1.93556004 0 P 0 ;0
L 1.90921004 -1.93556004 1.90888002 -1.93593002 0 P 0 ;0
L 1.90888002 -1.93593002 1.90853002 -1.93626998 0 P 0 ;0
L 1.90853002 -1.93626998 1.90815 -1.93658996 0 P 0 ;0
L 1.90815 -1.93658996 1.90773996 -1.93686998 0 P 0 ;0
L 1.90773996 -1.93686998 1.90731998 -1.93711998 0 P 0 ;0
L 1.90731998 -1.93711998 1.90686998 -1.93733996 0 P 0 ;0
L 1.90686998 -1.93733996 1.90615 -1.93761004 0 P 0 ;0
L 1.90615 -1.93761004 1.90541998 -1.93783002 0 P 0 ;0
L 1.90541998 -1.93783002 1.90466004 -1.93798002 0 P 0 ;0
L 1.90466004 -1.93798002 1.9039 -1.93808002 0 P 0 ;0
L 1.9039 -1.93808002 1.90311998 -1.9381 0 P 0 ;0
L 1.90311998 -1.9381 1.90196004 -1.93808002 0 P 0 ;0
L 1.90196004 -1.93808002 1.90078996 -1.93798996 0 P 0 ;0
L 1.90078996 -1.93798996 1.90068002 -1.93798002 0 P 0 ;0
L 1.90068002 -1.93798002 1.90058002 -1.93795 0 P 0 ;0
L 1.90058002 -1.93795 1.90046998 -1.93791998 0 P 0 ;0
L 1.90046998 -1.93791998 1.90038002 -1.93788002 0 P 0 ;0
L 1.90038002 -1.93788002 1.90028002 -1.93783002 0 P 0 ;0
L 1.90028002 -1.93783002 1.90018996 -1.93778002 0 P 0 ;0
L 1.90018996 -1.93778002 1.9001 -1.93771004 0 P 0 ;0
L 1.9001 -1.93771004 1.90001998 -1.93763996 0 P 0 ;0
L 1.90001998 -1.93763996 1.89988002 -1.93748002 0 P 0 ;0
L 1.89988002 -1.93748002 1.89978002 -1.93733996 0 P 0 ;0
L 1.89978002 -1.93733996 1.89961998 -1.93703996 0 P 0 ;0
L 1.89961998 -1.93703996 1.89956998 -1.93688002 0 P 0 ;0
L 1.89956998 -1.93688002 1.89951998 -1.93671004 0 P 0 ;0
L 1.89951998 -1.93671004 1.89948996 -1.93655 0 P 0 ;0
L 1.89948996 -1.93655 1.89946998 -1.93636998 0 P 0 ;0
L 1.89946998 -1.93636998 1.8994 -1.93323002 0 P 0 ;0
L 1.8994 -1.93323002 1.8994 -1.92833002 0 P 0 ;0
L 1.8994 -1.92833002 1.90353996 -1.92833002 0 P 0 ;0
L 1.90353996 -1.92833002 1.90436998 -1.92835 0 P 0 ;0
L 1.90436998 -1.92835 1.9052 -1.92843002 0 P 0 ;0
L 1.9052 -1.92843002 1.90603002 -1.92853996 0 P 0 ;0
L 1.90603002 -1.92853996 1.90683996 -1.92871004 0 P 0 ;0
L 1.90683996 -1.92871004 1.90751004 -1.9289 0 P 0 ;0
L 1.90751004 -1.9289 1.90818002 -1.92913002 0 P 0 ;0
L 1.90818002 -1.92913002 1.90851998 -1.92928996 0 P 0 ;0
L 1.90851998 -1.92928996 1.90868002 -1.92938996 0 P 0 ;0
L 1.90868002 -1.92938996 1.90883002 -1.92951004 0 P 0 ;0
L 1.90883002 -1.92951004 1.90896004 -1.92963996 0 P 0 ;0
L 1.91188996 -1.96001004 1.91638996 -1.96001004 0 P 0 ;0
L 1.91156998 -1.95901004 1.91926998 -1.95901004 0 P 0 ;0
L 1.91125 -1.95801004 1.91891998 -1.95801004 0 P 0 ;0
L 1.91091998 -1.95701004 1.91853002 -1.95701004 0 P 0 ;0
L 1.9106 -1.95601004 1.91811004 -1.95601004 0 P 0 ;0
L 1.91025 -1.95501004 1.91765 -1.95501004 0 P 0 ;0
L 1.90988996 -1.95401004 1.91718996 -1.95401004 0 P 0 ;0
L 1.90953002 -1.95301004 1.91673002 -1.95301004 0 P 0 ;0
L 1.90918002 -1.95201004 1.91626998 -1.95201004 0 P 0 ;0
L 1.90881998 -1.95101004 1.91576004 -1.95101004 0 P 0 ;0
L 1.90841004 -1.95001004 1.91523996 -1.95001004 0 P 0 ;0
L 1.90793996 -1.94901004 1.91471004 -1.94901004 0 P 0 ;0
L 1.90738996 -1.94801004 1.91418002 -1.94801004 0 P 0 ;0
L 1.90676998 -1.94701004 1.9136 -1.94701004 0 P 0 ;0
L 1.90598996 -1.94601004 1.91261004 -1.94601004 0 P 0 ;0
L 1.90495 -1.94501004 1.91175 -1.94501004 0 P 0 ;0
L 1.90325 -1.94401004 1.91133002 -1.94401004 0 P 0 ;0
L 1.90456004 -1.94001004 1.91383002 -1.94001004 0 P 0 ;0
L 1.90801004 -1.93901004 1.91523002 -1.93901004 0 P 0 ;0
L 1.90956998 -1.93801004 1.91635 -1.93801004 0 P 0 ;0
L 1.9106 -1.93701004 1.91718002 -1.93701004 0 P 0 ;0
L 1.91133996 -1.93601004 1.91781004 -1.93601004 0 P 0 ;0
L 1.91183996 -1.93501004 1.91826004 -1.93501004 0 P 0 ;0
L 1.91213002 -1.93401004 1.9186 -1.93401004 0 P 0 ;0
L 1.91226004 -1.93301004 1.9188 -1.93301004 0 P 0 ;0
L 1.91221998 -1.93201004 1.9189 -1.93201004 0 P 0 ;0
L 1.91201998 -1.93101004 1.9189 -1.93101004 0 P 0 ;0
L 1.91163996 -1.93001004 1.91878996 -1.93001004 0 P 0 ;0
L 1.91105 -1.92901004 1.91856998 -1.92901004 0 P 0 ;0
L 1.91013996 -1.92801004 1.91823002 -1.92801004 0 P 0 ;0
L 1.90816998 -1.92701004 1.91776004 -1.92701004 0 P 0 ;0
L 1.90313996 -1.94011004 1.90316998 -1.9401 0 P 0 ;0
L 1.90316998 -1.9401 1.9032 -1.9401 0 P 0 ;0
L 1.9032 -1.9401 1.90398002 -1.94006998 0 P 0 ;0
L 1.90398002 -1.94006998 1.90406004 -1.94006998 0 P 0 ;0
L 1.90406004 -1.94006998 1.90413996 -1.94006004 0 P 0 ;0
L 1.90413996 -1.94006004 1.9049 -1.93996998 0 P 0 ;0
L 1.9049 -1.93996998 1.90493996 -1.93996004 0 P 0 ;0
L 1.90493996 -1.93996004 1.90498996 -1.93996004 0 P 0 ;0
L 1.90498996 -1.93996004 1.90506998 -1.93993996 0 P 0 ;0
L 1.90506998 -1.93993996 1.90581998 -1.93978002 0 P 0 ;0
L 1.90581998 -1.93978002 1.90586004 -1.93978002 0 P 0 ;0
L 1.90586004 -1.93978002 1.90593996 -1.93976004 0 P 0 ;0
L 1.90593996 -1.93976004 1.90596998 -1.93973996 0 P 0 ;0
L 1.90596998 -1.93973996 1.90671004 -1.93953002 0 P 0 ;0
L 1.90671004 -1.93953002 1.90678996 -1.93951004 0 P 0 ;0
L 1.90678996 -1.93951004 1.90758996 -1.93921004 0 P 0 ;0
L 1.90758996 -1.93921004 1.90766004 -1.93916998 0 P 0 ;0
L 1.90766004 -1.93916998 1.9077 -1.93915 0 P 0 ;0
L 1.9077 -1.93915 1.90773996 -1.93913996 0 P 0 ;0
L 1.90773996 -1.93913996 1.90818996 -1.93891998 0 P 0 ;0
L 1.90818996 -1.93891998 1.90821998 -1.9389 0 P 0 ;0
L 1.90821998 -1.9389 1.90826004 -1.93888996 0 P 0 ;0
L 1.90826004 -1.93888996 1.90828996 -1.93886998 0 P 0 ;0
L 1.90828996 -1.93886998 1.90833002 -1.93885 0 P 0 ;0
L 1.90833002 -1.93885 1.90875 -1.9386 0 P 0 ;0
L 1.90875 -1.9386 1.90883002 -1.93856004 0 P 0 ;0
L 1.90883002 -1.93856004 1.90888996 -1.93851004 0 P 0 ;0
L 1.90888996 -1.93851004 1.90928996 -1.93823002 0 P 0 ;0
L 1.90928996 -1.93823002 1.90933002 -1.9382 0 P 0 ;0
L 1.90933002 -1.9382 1.90936004 -1.93818002 0 P 0 ;0
L 1.90936004 -1.93818002 1.90938996 -1.93815 0 P 0 ;0
L 1.90938996 -1.93815 1.90941998 -1.93813002 0 P 0 ;0
L 1.90941998 -1.93813002 1.9098 -1.93781998 0 P 0 ;0
L 1.9098 -1.93781998 1.90986004 -1.93776004 0 P 0 ;0
L 1.90986004 -1.93776004 1.90988996 -1.93773996 0 P 0 ;0
L 1.90988996 -1.93773996 1.90991998 -1.93771004 0 P 0 ;0
L 1.90991998 -1.93771004 1.91028002 -1.93736004 0 P 0 ;0
L 1.91028002 -1.93736004 1.91038996 -1.93725 0 P 0 ;0
L 1.91038996 -1.93725 1.91071004 -1.93688002 0 P 0 ;0
L 1.91071004 -1.93688002 1.91073996 -1.93685 0 P 0 ;0
L 1.91073996 -1.93685 1.91116004 -1.9363 0 P 0 ;0
L 1.91116004 -1.9363 1.9112 -1.93623002 0 P 0 ;0
L 1.9112 -1.93623002 1.91138002 -1.93595 0 P 0 ;0
L 1.91138002 -1.93595 1.9114 -1.93591004 0 P 0 ;0
L 1.9114 -1.93591004 1.91143996 -1.93585 0 P 0 ;0
L 1.91143996 -1.93585 1.91146004 -1.93581004 0 P 0 ;0
L 1.91146004 -1.93581004 1.91161004 -1.93551998 0 P 0 ;0
L 1.91161004 -1.93551998 1.91163002 -1.93548996 0 P 0 ;0
L 1.91163002 -1.93548996 1.91165 -1.93545 0 P 0 ;0
L 1.91165 -1.93545 1.91166004 -1.93541004 0 P 0 ;0
L 1.91166004 -1.93541004 1.91168002 -1.93538002 0 P 0 ;0
L 1.91168002 -1.93538002 1.91181004 -1.93506998 0 P 0 ;0
L 1.91181004 -1.93506998 1.91183996 -1.935 0 P 0 ;0
L 1.91183996 -1.935 1.91186004 -1.93496004 0 P 0 ;0
L 1.91186004 -1.93496004 1.91186998 -1.93493002 0 P 0 ;0
L 1.91186998 -1.93493002 1.91198002 -1.93461004 0 P 0 ;0
L 1.91198002 -1.93461004 1.91198996 -1.93456998 0 P 0 ;0
L 1.91198996 -1.93456998 1.912 -1.93453996 0 P 0 ;0
L 1.912 -1.93453996 1.9121 -1.93413996 0 P 0 ;0
L 1.9121 -1.93413996 1.91211998 -1.9341 0 P 0 ;0
L 1.91211998 -1.9341 1.91211998 -1.93406004 0 P 0 ;0
L 1.91211998 -1.93406004 1.91213002 -1.93401998 0 P 0 ;0
L 1.91213002 -1.93401998 1.91213996 -1.93398996 0 P 0 ;0
L 1.91213996 -1.93398996 1.9122 -1.93366004 0 P 0 ;0
L 1.9122 -1.93366004 1.91221004 -1.93358002 0 P 0 ;0
L 1.91221004 -1.93358002 1.91221004 -1.93353996 0 P 0 ;0
L 1.91221004 -1.93353996 1.91221998 -1.9335 0 P 0 ;0
L 1.91221998 -1.9335 1.91225 -1.93316998 0 P 0 ;0
L 1.91225 -1.93316998 1.91226004 -1.93308996 0 P 0 ;0
L 1.91226004 -1.93308996 1.91226004 -1.93268002 0 P 0 ;0
L 1.91226004 -1.93268002 1.91226998 -1.93263996 0 P 0 ;0
L 1.91226998 -1.93263996 1.91226998 -1.9326 0 P 0 ;0
L 1.91226998 -1.9326 1.91226004 -1.93251998 0 P 0 ;0
L 1.91226004 -1.93251998 1.91223996 -1.93218996 0 P 0 ;0
L 1.91223996 -1.93218996 1.91223996 -1.93215 0 P 0 ;0
L 1.91223996 -1.93215 1.91223002 -1.9321 0 P 0 ;0
L 1.91223002 -1.9321 1.91223002 -1.93206004 0 P 0 ;0
L 1.91223002 -1.93206004 1.91221998 -1.93201998 0 P 0 ;0
L 1.91221998 -1.93201998 1.91216998 -1.93163996 0 P 0 ;0
L 1.91216998 -1.93163996 1.91216004 -1.9316 0 P 0 ;0
L 1.91216004 -1.9316 1.91213996 -1.93151004 0 P 0 ;0
L 1.91213996 -1.93151004 1.91213002 -1.93146998 0 P 0 ;0
L 1.91213002 -1.93146998 1.91205 -1.93111004 0 P 0 ;0
L 1.91205 -1.93111004 1.91203996 -1.93106004 0 P 0 ;0
L 1.91203996 -1.93106004 1.91203002 -1.93101998 0 P 0 ;0
L 1.91203002 -1.93101998 1.91201004 -1.93098002 0 P 0 ;0
L 1.91201004 -1.93098002 1.912 -1.93093996 0 P 0 ;0
L 1.912 -1.93093996 1.91188002 -1.93058002 0 P 0 ;0
L 1.91188002 -1.93058002 1.91186998 -1.93053996 0 P 0 ;0
L 1.91186998 -1.93053996 1.91185 -1.9305 0 P 0 ;0
L 1.91185 -1.9305 1.91183996 -1.93046004 0 P 0 ;0
L 1.91183996 -1.93046004 1.91181998 -1.93043002 0 P 0 ;0
L 1.91181998 -1.93043002 1.91166998 -1.93008002 0 P 0 ;0
L 1.91166998 -1.93008002 1.91166004 -1.93003996 0 P 0 ;0
L 1.91166004 -1.93003996 1.9116 -1.92991998 0 P 0 ;0
L 1.9116 -1.92991998 1.91141998 -1.92958996 0 P 0 ;0
L 1.91141998 -1.92958996 1.9114 -1.92955 0 P 0 ;0
L 1.9114 -1.92955 1.91138002 -1.92951998 0 P 0 ;0
L 1.91138002 -1.92951998 1.91133002 -1.92945 0 P 0 ;0
L 1.91133002 -1.92945 1.91113002 -1.92913002 0 P 0 ;0
L 1.91113002 -1.92913002 1.91111004 -1.92908996 0 P 0 ;0
L 1.91111004 -1.92908996 1.91108996 -1.92906004 0 P 0 ;0
L 1.91108996 -1.92906004 1.91106004 -1.92901998 0 P 0 ;0
L 1.91106004 -1.92901998 1.91103002 -1.92898996 0 P 0 ;0
L 1.91103002 -1.92898996 1.9108 -1.92868996 0 P 0 ;0
L 1.9108 -1.92868996 1.91076998 -1.92866004 0 P 0 ;0
L 1.91076998 -1.92866004 1.91075 -1.92861998 0 P 0 ;0
L 1.91075 -1.92861998 1.91068996 -1.92856004 0 P 0 ;0
L 1.91068996 -1.92856004 1.91043002 -1.92828002 0 P 0 ;0
L 1.91043002 -1.92828002 1.91035 -1.9282 0 P 0 ;0
L 1.91035 -1.9282 1.91033002 -1.92816998 0 P 0 ;0
L 1.91033002 -1.92816998 1.91018996 -1.92803996 0 P 0 ;0
L 1.91018996 -1.92803996 1.91018002 -1.92803996 0 P 0 ;0
L 1.91018002 -1.92803996 1.91016004 -1.92801998 0 P 0 ;0
L 1.91016004 -1.92801998 1.91011998 -1.92798996 0 P 0 ;0
L 1.91011998 -1.92798996 1.91006004 -1.92793002 0 P 0 ;0
L 1.91006004 -1.92793002 1.90991004 -1.92781998 0 P 0 ;0
L 1.90991004 -1.92781998 1.90988002 -1.9278 0 P 0 ;0
L 1.90988002 -1.9278 1.90983996 -1.92776998 0 P 0 ;0
L 1.90983996 -1.92776998 1.90976998 -1.92771998 0 P 0 ;0
L 1.90976998 -1.92771998 1.90961004 -1.92761998 0 P 0 ;0
L 1.90961004 -1.92761998 1.90953996 -1.92756998 0 P 0 ;0
L 1.90953996 -1.92756998 1.9095 -1.92755 0 P 0 ;0
L 1.9095 -1.92755 1.90946998 -1.92753002 0 P 0 ;0
L 1.90946998 -1.92753002 1.9093 -1.92743996 0 P 0 ;0
L 1.9093 -1.92743996 1.90926004 -1.92741998 0 P 0 ;0
L 1.90926004 -1.92741998 1.90923002 -1.9274 0 P 0 ;0
L 1.90923002 -1.9274 1.90915 -1.92736998 0 P 0 ;0
L 1.90915 -1.92736998 1.90896998 -1.92728996 0 P 0 ;0
L 1.90896998 -1.92728996 1.90893996 -1.92728002 0 P 0 ;0
L 1.90893996 -1.92728002 1.9089 -1.92726004 0 P 0 ;0
L 1.9089 -1.92726004 1.90886998 -1.92725 0 P 0 ;0
L 1.90886998 -1.92725 1.90883002 -1.92723996 0 P 0 ;0
L 1.90883002 -1.92723996 1.90816004 -1.92701004 0 P 0 ;0
L 1.90816004 -1.92701004 1.90813996 -1.927 0 P 0 ;0
L 1.90813996 -1.927 1.9081 -1.92698996 0 P 0 ;0
L 1.9081 -1.92698996 1.90803996 -1.92696998 0 P 0 ;0
L 1.90803996 -1.92696998 1.90736998 -1.92678002 0 P 0 ;0
L 1.90736998 -1.92678002 1.90723996 -1.92675 0 P 0 ;0
L 1.90723996 -1.92675 1.90643002 -1.92658996 0 P 0 ;0
L 1.90643002 -1.92658996 1.90636998 -1.92656998 0 P 0 ;0
L 1.90636998 -1.92656998 1.90633996 -1.92656998 0 P 0 ;0
L 1.90633996 -1.92656998 1.90631004 -1.92656004 0 P 0 ;0
L 1.90631004 -1.92656004 1.90548996 -1.92645 0 P 0 ;0
L 1.90548996 -1.92645 1.90543996 -1.92643996 0 P 0 ;0
L 1.90543996 -1.92643996 1.9054 -1.92643002 0 P 0 ;0
L 1.9054 -1.92643002 1.90538002 -1.92643002 0 P 0 ;0
L 1.90538002 -1.92643002 1.90455 -1.92636004 0 P 0 ;0
L 1.90455 -1.92636004 1.90443002 -1.92636004 0 P 0 ;0
L 1.90443002 -1.92636004 1.9036 -1.92633002 0 P 0 ;0
L 1.9036 -1.92633002 1.8994 -1.92633002 0 P 0 ;0
L 1.8994 -1.92633002 1.89798002 -1.92691004 0 P 0 ;0
L 1.89798002 -1.92691004 1.8974 -1.92833002 0 P 0 ;0
L 1.8974 -1.92833002 1.8974 -1.93328002 0 P 0 ;0
L 1.8974 -1.93328002 1.89748002 -1.93643002 0 P 0 ;0
L 1.89748002 -1.93643002 1.89748002 -1.93656004 0 P 0 ;0
L 1.89748002 -1.93656004 1.8975 -1.93673002 0 P 0 ;0
L 1.8975 -1.93673002 1.89751004 -1.93681004 0 P 0 ;0
L 1.89751004 -1.93681004 1.89751998 -1.9369 0 P 0 ;0
L 1.89751998 -1.9369 1.89755 -1.93706004 0 P 0 ;0
L 1.89755 -1.93706004 1.89758002 -1.93718996 0 P 0 ;0
L 1.89758002 -1.93718996 1.89758996 -1.93723002 0 P 0 ;0
L 1.89758996 -1.93723002 1.89763002 -1.9374 0 P 0 ;0
L 1.89763002 -1.9374 1.89763996 -1.93743996 0 P 0 ;0
L 1.89763996 -1.93743996 1.89766004 -1.93748002 0 P 0 ;0
L 1.89766004 -1.93748002 1.89768002 -1.93756004 0 P 0 ;0
L 1.89768002 -1.93756004 1.89773996 -1.93771998 0 P 0 ;0
L 1.89773996 -1.93771998 1.89776004 -1.93776004 0 P 0 ;0
L 1.89776004 -1.93776004 1.89776998 -1.9378 0 P 0 ;0
L 1.89776998 -1.9378 1.89781004 -1.93788002 0 P 0 ;0
L 1.89781004 -1.93788002 1.89788002 -1.93803996 0 P 0 ;0
L 1.89788002 -1.93803996 1.8979 -1.93808002 0 P 0 ;0
L 1.8979 -1.93808002 1.89791998 -1.93811004 0 P 0 ;0
L 1.89791998 -1.93811004 1.89796004 -1.93818996 0 P 0 ;0
L 1.89796004 -1.93818996 1.89803996 -1.93833996 0 P 0 ;0
L 1.89803996 -1.93833996 1.89813996 -1.93848002 0 P 0 ;0
L 1.89813996 -1.93848002 1.89823002 -1.93861998 0 P 0 ;0
L 1.89823002 -1.93861998 1.89828002 -1.93868996 0 P 0 ;0
L 1.89828002 -1.93868996 1.89831004 -1.93873002 0 P 0 ;0
L 1.89831004 -1.93873002 1.89833996 -1.93876004 0 P 0 ;0
L 1.89833996 -1.93876004 1.8984 -1.93883996 0 P 0 ;0
L 1.8984 -1.93883996 1.89848996 -1.93893002 0 P 0 ;0
L 1.89848996 -1.93893002 1.89851004 -1.93896004 0 P 0 ;0
L 1.89851004 -1.93896004 1.89868002 -1.93913002 0 P 0 ;0
L 1.89868002 -1.93913002 1.89871004 -1.93915 0 P 0 ;0
L 1.89871004 -1.93915 1.89878996 -1.93921998 0 P 0 ;0
L 1.89878996 -1.93921998 1.89885 -1.93928002 0 P 0 ;0
L 1.89885 -1.93928002 1.89888002 -1.9393 0 P 0 ;0
L 1.89888002 -1.9393 1.89891998 -1.93931998 0 P 0 ;0
L 1.89891998 -1.93931998 1.89901004 -1.93938996 0 P 0 ;0
L 1.89901004 -1.93938996 1.89903996 -1.93941004 0 P 0 ;0
L 1.89903996 -1.93941004 1.89906998 -1.93943996 0 P 0 ;0
L 1.89906998 -1.93943996 1.8991 -1.93946004 0 P 0 ;0
L 1.8991 -1.93946004 1.89913996 -1.93948002 0 P 0 ;0
L 1.89913996 -1.93948002 1.89923002 -1.93953996 0 P 0 ;0
L 1.89923002 -1.93953996 1.89926998 -1.93956004 0 P 0 ;0
L 1.89926998 -1.93956004 1.8993 -1.93958002 0 P 0 ;0
L 1.8993 -1.93958002 1.89933996 -1.9396 0 P 0 ;0
L 1.89933996 -1.9396 1.89936998 -1.93961004 0 P 0 ;0
L 1.89936998 -1.93961004 1.89938002 -1.93961004 0 P 0 ;0
L 1.89938002 -1.93961004 1.89946998 -1.93966004 0 P 0 ;0
L 1.89946998 -1.93966004 1.89953996 -1.9397 0 P 0 ;0
L 1.89953996 -1.9397 1.89971998 -1.93976998 0 P 0 ;0
L 1.89971998 -1.93976998 1.89975 -1.93978996 0 P 0 ;0
L 1.89975 -1.93978996 1.89978996 -1.9398 0 P 0 ;0
L 1.89978996 -1.9398 1.89986998 -1.93983002 0 P 0 ;0
L 1.89986998 -1.93983002 1.89996998 -1.93986004 0 P 0 ;0
L 1.89996998 -1.93986004 1.90001004 -1.93986998 0 P 0 ;0
L 1.90001004 -1.93986998 1.90005 -1.93988996 0 P 0 ;0
L 1.90005 -1.93988996 1.90013002 -1.9399 0 P 0 ;0
L 1.90013002 -1.9399 1.90023002 -1.93993002 0 P 0 ;0
L 1.90023002 -1.93993002 1.90023996 -1.93993002 0 P 0 ;0
L 1.90023996 -1.93993002 1.90028002 -1.93993996 0 P 0 ;0
L 1.90028002 -1.93993996 1.90031004 -1.93995 0 P 0 ;0
L 1.90031004 -1.93995 1.90036004 -1.93995 0 P 0 ;0
L 1.90036004 -1.93995 1.9004 -1.93996004 0 P 0 ;0
L 1.9004 -1.93996004 1.9005 -1.93996998 0 P 0 ;0
L 1.9005 -1.93996998 1.90061004 -1.93998996 0 P 0 ;0
L 1.90061004 -1.93998996 1.90063996 -1.93998996 0 P 0 ;0
L 1.90063996 -1.93998996 1.90181004 -1.94006998 0 P 0 ;0
L 1.90181004 -1.94006998 1.90183996 -1.94008002 0 P 0 ;0
L 1.90183996 -1.94008002 1.90191004 -1.94008002 0 P 0 ;0
L 1.90191004 -1.94008002 1.90308002 -1.9401 0 P 0 ;0
L 1.90308002 -1.9401 1.90311004 -1.9401 0 P 0 ;0
L 1.90311004 -1.9401 1.90313996 -1.94011004 0 P 0 ;0
L 1.90841004 -1.97146004 1.91683996 -1.97146004 0 P 0 ;0
L 1.9135 -1.97046004 1.91931004 -1.97046004 0 P 0 ;0
L 1.91655 -1.96946004 1.92131004 -1.96946004 0 P 0 ;0
L 1.91891998 -1.96846004 1.92301004 -1.96846004 0 P 0 ;0
L 1.92088996 -1.96746004 1.9245 -1.96746004 0 P 0 ;0
L 1.92251004 -1.96646004 1.9258 -1.96646004 0 P 0 ;0
L 1.92391004 -1.96546004 1.92696004 -1.96546004 0 P 0 ;0
L 1.92513002 -1.96446004 1.92803002 -1.96446004 0 P 0 ;0
L 1.9262 -1.96346004 1.92898996 -1.96346004 0 P 0 ;0
L 1.92713996 -1.96246004 1.92986004 -1.96246004 0 P 0 ;0
L 1.928 -1.96146004 1.93068996 -1.96146004 0 P 0 ;0
L 1.92878002 -1.96046004 1.93143002 -1.96046004 0 P 0 ;0
L 1.92951004 -1.95946004 1.93216004 -1.95946004 0 P 0 ;0
L 1.93016998 -1.95846004 1.93278996 -1.95846004 0 P 0 ;0
L 1.93078002 -1.95746004 1.93341004 -1.95746004 0 P 0 ;0
L 1.93133002 -1.95646004 1.93396004 -1.95646004 0 P 0 ;0
L 1.93185 -1.95546004 1.93448996 -1.95546004 0 P 0 ;0
L 1.93231004 -1.95446004 1.93495 -1.95446004 0 P 0 ;0
L 1.93275 -1.95346004 1.93541004 -1.95346004 0 P 0 ;0
L 1.93311998 -1.95246004 1.93586004 -1.95246004 0 P 0 ;0
L 1.93348002 -1.95146004 1.93628996 -1.95146004 0 P 0 ;0
L 1.93376998 -1.95046004 1.93666004 -1.95046004 0 P 0 ;0
L 1.93405 -1.94946004 1.93693002 -1.94946004 0 P 0 ;0
L 1.93428002 -1.94846004 1.93715 -1.94846004 0 P 0 ;0
L 1.93446998 -1.94746004 1.93733002 -1.94746004 0 P 0 ;0
L 1.93466004 -1.94646004 1.93743002 -1.94646004 0 P 0 ;0
L 1.93478996 -1.94546004 1.93748996 -1.94546004 0 P 0 ;0
L 1.9349 -1.94446998 1.93751998 -1.94446998 0 P 0 ;0
L 1.93496998 -1.94346004 1.93755 -1.94346004 0 P 0 ;0
L 1.93501998 -1.94246004 1.93758002 -1.94246004 0 P 0 ;0
L 1.93505 -1.94146998 1.93758996 -1.94146998 0 P 0 ;0
L 1.93503002 -1.94046004 1.93755 -1.94046004 0 P 0 ;0
L 1.935 -1.93946004 1.93751998 -1.93946004 0 P 0 ;0
L 1.93491998 -1.93846004 1.93748002 -1.93846004 0 P 0 ;0
L 1.93481004 -1.93746004 1.93738996 -1.93746004 0 P 0 ;0
L 1.93468996 -1.93646004 1.93726998 -1.93646004 0 P 0 ;0
L 1.93451004 -1.93546004 1.93716004 -1.93546004 0 P 0 ;0
L 1.93433002 -1.93446004 1.93703996 -1.93446004 0 P 0 ;0
L 1.93408996 -1.93346004 1.93685 -1.93346004 0 P 0 ;0
L 1.93383002 -1.93246004 1.93666004 -1.93246004 0 P 0 ;0
L 1.93353002 -1.93146004 1.93638996 -1.93146004 0 P 0 ;0
L 1.9332 -1.93046004 1.93611998 -1.93046004 0 P 0 ;0
L 1.93283996 -1.92946004 1.93576998 -1.92946004 0 P 0 ;0
L 1.93241004 -1.92846004 1.93541004 -1.92846004 0 P 0 ;0
L 1.93198996 -1.92746004 1.93498002 -1.92746004 0 P 0 ;0
L 1.93146998 -1.92646004 1.93451004 -1.92646004 0 P 0 ;0
L 1.93096004 -1.92546004 1.93398002 -1.92546004 0 P 0 ;0
L 1.93035 -1.92446998 1.93338002 -1.92446998 0 P 0 ;0
L 1.92973002 -1.92346004 1.93275 -1.92346004 0 P 0 ;0
L 1.92903002 -1.92246004 1.93201004 -1.92246004 0 P 0 ;0
L 1.92831004 -1.92146004 1.93125 -1.92146004 0 P 0 ;0
L 1.92746998 -1.92046004 1.93041004 -1.92046004 0 P 0 ;0
L 1.92661004 -1.91946004 1.92948996 -1.91946004 0 P 0 ;0
L 1.92558996 -1.91846004 1.92851004 -1.91846004 0 P 0 ;0
L 1.9245 -1.91746004 1.92741998 -1.91746004 0 P 0 ;0
L 1.92328996 -1.91646004 1.92621998 -1.91646004 0 P 0 ;0
L 1.92188002 -1.91546004 1.92491998 -1.91546004 0 P 0 ;0
L 1.92026004 -1.91446004 1.92358996 -1.91446004 0 P 0 ;0
L 1.91835 -1.91346004 1.92208002 -1.91346004 0 P 0 ;0
L 1.82446998 -2.08323996 1.87608002 -2.08323996 0 P 0 ;0
L 1.82403002 -2.08223996 1.87601004 -2.08223996 0 P 0 ;0
L 1.8234 -2.08123996 1.87591004 -2.08123996 0 P 0 ;0
L 1.82256004 -2.08023996 1.87578002 -2.08023996 0 P 0 ;0
L 1.82166004 -2.07923996 1.87558996 -2.07923996 0 P 0 ;0
L 1.82061998 -2.07823996 1.87533002 -2.07823996 0 P 0 ;0
L 1.81946004 -2.07723996 1.87498996 -2.07723996 0 P 0 ;0
L 1.81818002 -2.07623996 1.8746 -2.07623996 0 P 0 ;0
L 1.8168 -2.07523996 1.87416998 -2.07523996 0 P 0 ;0
L 1.81541998 -2.07423996 1.87371004 -2.07423996 0 P 0 ;0
L 1.81403002 -2.07323996 1.87316998 -2.07323996 0 P 0 ;0
L 1.81265 -2.07223996 1.87261004 -2.07223996 0 P 0 ;0
L 1.81126998 -2.07123996 1.87196004 -2.07123996 0 P 0 ;0
L 1.80986004 -2.07023996 1.87128002 -2.07023996 0 P 0 ;0
L 1.80843996 -2.06923996 1.87051998 -2.06923996 0 P 0 ;0
L 1.80703002 -2.06823996 1.8697 -2.06823996 0 P 0 ;0
L 1.80561004 -2.06723996 1.86883002 -2.06723996 0 P 0 ;0
L 1.8042 -2.06623996 1.86796004 -2.06623996 0 P 0 ;0
L 1.80278002 -2.06523996 1.86705 -2.06523996 0 P 0 ;0
L 1.80136004 -2.06423996 1.86608002 -2.06423996 0 P 0 ;0
L 1.79995 -2.06323996 1.8651 -2.06323996 0 P 0 ;0
L 1.79865 -2.06223996 1.86411004 -2.06223996 0 P 0 ;0
L 1.79735 -2.06123996 1.86301998 -2.06123996 0 P 0 ;0
L 1.79605 -2.06023996 1.86193002 -2.06023996 0 P 0 ;0
L 1.79475 -2.05923996 1.86083996 -2.05923996 0 P 0 ;0
L 1.79345 -2.05823996 1.85966998 -2.05823996 0 P 0 ;0
L 1.79215 -2.05723996 1.85846004 -2.05723996 0 P 0 ;0
L 1.79088002 -2.05623996 1.85726004 -2.05623996 0 P 0 ;0
L 1.78971998 -2.05523996 1.85598996 -2.05523996 0 P 0 ;0
L 1.78856004 -2.05423996 1.85461998 -2.05423996 0 P 0 ;0
L 1.7874 -2.05323996 1.85326004 -2.05323996 0 P 0 ;0
L 1.78623002 -2.05223996 1.8519 -2.05223996 0 P 0 ;0
L 1.78506998 -2.05123996 1.85053996 -2.05123996 0 P 0 ;0
L 1.78398002 -2.05023996 1.84918002 -2.05023996 0 P 0 ;0
L 1.783 -2.04923996 1.84781004 -2.04923996 0 P 0 ;0
L 1.87086004 -2.03023996 1.87535 -2.03023996 0 P 0 ;0
L 1.91633002 -1.91473002 1.9183 -1.91565 0 P 0 ;0
L 1.9183 -1.91565 1.92018996 -1.91673002 0 P 0 ;0
L 1.92018996 -1.91673002 1.92196998 -1.91796998 0 P 0 ;0
L 1.92196998 -1.91796998 1.92365 -1.91936004 0 P 0 ;0
L 1.92365 -1.91936004 1.9252 -1.92088002 0 P 0 ;0
L 1.9252 -1.92088002 1.92661004 -1.92253996 0 P 0 ;0
L 1.92661004 -1.92253996 1.92795 -1.92436998 0 P 0 ;0
L 1.92795 -1.92436998 1.92913996 -1.9263 0 P 0 ;0
L 1.92913996 -1.9263 1.93018002 -1.92831998 0 P 0 ;0
L 1.93018002 -1.92831998 1.93106998 -1.93041004 0 P 0 ;0
L 1.93106998 -1.93041004 1.93178996 -1.93256004 0 P 0 ;0
L 1.93178996 -1.93256004 1.93236004 -1.93476004 0 P 0 ;0
L 1.93236004 -1.93476004 1.93276004 -1.93703996 0 P 0 ;0
L 1.93276004 -1.93703996 1.93298996 -1.93933996 0 P 0 ;0
L 1.93298996 -1.93933996 1.93306004 -1.94165 0 P 0 ;0
L 1.93306004 -1.94165 1.93295 -1.94396998 0 P 0 ;0
L 1.93295 -1.94396998 1.93268002 -1.94626004 0 P 0 ;0
L 1.93268002 -1.94626004 1.93223002 -1.94853996 0 P 0 ;0
L 1.93223002 -1.94853996 1.93161998 -1.95071998 0 P 0 ;0
L 1.93161998 -1.95071998 1.93085 -1.95285 0 P 0 ;0
L 1.93085 -1.95285 1.92991004 -1.95491004 0 P 0 ;0
L 1.92991004 -1.95491004 1.92881004 -1.95688996 0 P 0 ;0
L 1.92881004 -1.95688996 1.92756004 -1.95878002 0 P 0 ;0
L 1.92756004 -1.95878002 1.92616004 -1.96056998 0 P 0 ;0
L 1.92616004 -1.96056998 1.92493996 -1.9619 0 P 0 ;0
L 1.92493996 -1.9619 1.92361998 -1.96313996 0 P 0 ;0
L 1.92361998 -1.96313996 1.9222 -1.96426004 0 P 0 ;0
L 1.9222 -1.96426004 1.9207 -1.96526998 0 P 0 ;0
L 1.9207 -1.96526998 1.91911004 -1.96616998 0 P 0 ;0
L 1.91911004 -1.96616998 1.91686998 -1.96721004 0 P 0 ;0
L 1.91686998 -1.96721004 1.91456004 -1.96806998 0 P 0 ;0
L 1.91456004 -1.96806998 1.91218996 -1.96876004 0 P 0 ;0
L 1.91218996 -1.96876004 1.90975 -1.96926998 0 P 0 ;0
L 1.90975 -1.96926998 1.90725 -1.9696 0 P 0 ;0
L 1.90725 -1.9696 1.90473002 -1.96973996 0 P 0 ;0
L 1.90473002 -1.96973996 1.9022 -1.96968996 0 P 0 ;0
L 1.9022 -1.96968996 1.89966998 -1.96945 0 P 0 ;0
L 1.89966998 -1.96945 1.89778002 -1.96913002 0 P 0 ;0
L 1.89778002 -1.96913002 1.89591998 -1.96868996 0 P 0 ;0
L 1.89591998 -1.96868996 1.8941 -1.96811004 0 P 0 ;0
L 1.8941 -1.96811004 1.89231004 -1.96741004 0 P 0 ;0
L 1.89231004 -1.96741004 1.89058002 -1.96658002 0 P 0 ;0
L 1.89058002 -1.96658002 1.88875 -1.96553996 0 P 0 ;0
L 1.88875 -1.96553996 1.88698996 -1.96435 0 P 0 ;0
L 1.88698996 -1.96435 1.88533996 -1.96303002 0 P 0 ;0
L 1.88533996 -1.96303002 1.88378996 -1.9616 0 P 0 ;0
L 1.88378996 -1.9616 1.88235 -1.96003996 0 P 0 ;0
L 1.88235 -1.96003996 1.88103002 -1.95838996 0 P 0 ;0
L 1.88103002 -1.95838996 1.87983996 -1.95663002 0 P 0 ;0
L 1.87983996 -1.95663002 1.87861998 -1.95446998 0 P 0 ;0
L 1.87861998 -1.95446998 1.87758002 -1.9522 0 P 0 ;0
L 1.87758002 -1.9522 1.87673996 -1.94986004 0 P 0 ;0
L 1.87673996 -1.94986004 1.8761 -1.94745 0 P 0 ;0
L 1.8761 -1.94745 1.87568002 -1.945 0 P 0 ;0
L 1.87568002 -1.945 1.87546004 -1.94248996 0 P 0 ;0
L 1.87546004 -1.94248996 1.87546004 -1.93998996 0 P 0 ;0
L 1.87546004 -1.93998996 1.87566998 -1.93748996 0 P 0 ;0
L 1.87566998 -1.93748996 1.87608996 -1.93501998 0 P 0 ;0
L 1.87608996 -1.93501998 1.87671998 -1.9326 0 P 0 ;0
L 1.87671998 -1.9326 1.87755 -1.93023002 0 P 0 ;0
L 1.87755 -1.93023002 1.8786 -1.92793002 0 P 0 ;0
L 1.8786 -1.92793002 1.87981998 -1.92575 0 P 0 ;0
L 1.87981998 -1.92575 1.88123002 -1.92368002 0 P 0 ;0
L 1.88123002 -1.92368002 1.88281004 -1.92175 0 P 0 ;0
L 1.88281004 -1.92175 1.88455 -1.91996004 0 P 0 ;0
L 1.88455 -1.91996004 1.88643002 -1.91831998 0 P 0 ;0
L 1.88643002 -1.91831998 1.88845 -1.91686004 0 P 0 ;0
L 1.88845 -1.91686004 1.88986998 -1.91598996 0 P 0 ;0
L 1.88986998 -1.91598996 1.89135 -1.91523002 0 P 0 ;0
L 1.89135 -1.91523002 1.89288002 -1.91458996 0 P 0 ;0
L 1.89288002 -1.91458996 1.89446998 -1.91406004 0 P 0 ;0
L 1.89446998 -1.91406004 1.89688996 -1.91343996 0 P 0 ;0
L 1.89688996 -1.91343996 1.89935 -1.91298996 0 P 0 ;0
L 1.89935 -1.91298996 1.90183996 -1.91271004 0 P 0 ;0
L 1.90183996 -1.91271004 1.9044 -1.91261004 0 P 0 ;0
L 1.9044 -1.91261004 1.90695 -1.91268002 0 P 0 ;0
L 1.90695 -1.91268002 1.90948996 -1.91291998 0 P 0 ;0
L 1.90948996 -1.91291998 1.91181998 -1.91331998 0 P 0 ;0
L 1.91181998 -1.91331998 1.91408996 -1.91393002 0 P 0 ;0
L 1.91408996 -1.91393002 1.91633002 -1.91473002 0 P 0 ;0
L 1.89498002 -1.90801998 1.8922 -1.90893002 0 P 0 ;0
L 1.8922 -1.90893002 1.88948002 -1.91003002 0 P 0 ;0
L 1.88948002 -1.91003002 1.88686004 -1.91133002 0 P 0 ;0
L 1.88686004 -1.91133002 1.88431004 -1.91283996 0 P 0 ;0
L 1.88431004 -1.91283996 1.88201004 -1.91446004 0 P 0 ;0
L 1.88201004 -1.91446004 1.87985 -1.91626998 0 P 0 ;0
L 1.87985 -1.91626998 1.87785 -1.91826004 0 P 0 ;0
L 1.87785 -1.91826004 1.87601998 -1.92041004 0 P 0 ;0
L 1.87601998 -1.92041004 1.87441004 -1.92266998 0 P 0 ;0
L 1.87441004 -1.92266998 1.87298996 -1.92505 0 P 0 ;0
L 1.87298996 -1.92505 1.87178002 -1.92756004 0 P 0 ;0
L 1.87178002 -1.92756004 1.87078996 -1.93015 0 P 0 ;0
L 1.87078996 -1.93015 1.87 -1.93286998 0 P 0 ;0
L 1.87 -1.93286998 1.86943996 -1.93563996 0 P 0 ;0
L 1.86943996 -1.93563996 1.86908996 -1.93845 0 P 0 ;0
L 1.86908996 -1.93845 1.86898002 -1.94128996 0 P 0 ;0
L 1.86898002 -1.94128996 1.86911998 -1.94485 0 P 0 ;0
L 1.86911998 -1.94485 1.86953996 -1.94841004 0 P 0 ;0
L 1.86953996 -1.94841004 1.86996004 -1.95048996 0 P 0 ;0
L 1.86996004 -1.95048996 1.87053002 -1.95251998 0 P 0 ;0
L 1.87053002 -1.95251998 1.87125 -1.95451998 0 P 0 ;0
L 1.87125 -1.95451998 1.87211004 -1.95643002 0 P 0 ;0
L 1.87211004 -1.95643002 1.8731 -1.95826004 0 P 0 ;0
L 1.8731 -1.95826004 1.87423996 -1.96001998 0 P 0 ;0
L 1.87423996 -1.96001998 1.87636998 -1.96278996 0 P 0 ;0
L 1.87636998 -1.96278996 1.87871998 -1.96536998 0 P 0 ;0
L 1.87871998 -1.96536998 1.88145 -1.96788002 0 P 0 ;0
L 1.88145 -1.96788002 1.88436998 -1.97015 0 P 0 ;0
L 1.88436998 -1.97015 1.88621004 -1.97135 0 P 0 ;0
L 1.88621004 -1.97135 1.88813002 -1.97238002 0 P 0 ;0
L 1.88813002 -1.97238002 1.89013002 -1.97326004 0 P 0 ;0
L 1.89013002 -1.97326004 1.89228002 -1.97398996 0 P 0 ;0
L 1.89228002 -1.97398996 1.89446998 -1.97455 0 P 0 ;0
L 1.89446998 -1.97455 1.89671004 -1.97493996 0 P 0 ;0
L 1.89671004 -1.97493996 1.90076998 -1.97533996 0 P 0 ;0
L 1.90076998 -1.97533996 1.90485 -1.97546998 0 P 0 ;0
L 1.90485 -1.97546998 1.90821004 -1.97531998 0 P 0 ;0
L 1.90821004 -1.97531998 1.91153996 -1.97488996 0 P 0 ;0
L 1.91153996 -1.97488996 1.91481998 -1.97418996 0 P 0 ;0
L 1.91481998 -1.97418996 1.9171 -1.9735 0 P 0 ;0
L 1.9171 -1.9735 1.91933002 -1.97266004 0 P 0 ;0
L 1.91933002 -1.97266004 1.92148002 -1.97166004 0 P 0 ;0
L 1.92148002 -1.97166004 1.92356998 -1.97048996 0 P 0 ;0
L 1.92356998 -1.97048996 1.92553996 -1.96918996 0 P 0 ;0
L 1.92553996 -1.96918996 1.92741004 -1.96773996 0 P 0 ;0
L 1.92741004 -1.96773996 1.92916004 -1.96616998 0 P 0 ;0
L 1.92916004 -1.96616998 1.93081004 -1.96446004 0 P 0 ;0
L 1.93081004 -1.96446004 1.93236998 -1.96256998 0 P 0 ;0
L 1.93236998 -1.96256998 1.93381004 -1.96058996 0 P 0 ;0
L 1.93381004 -1.96058996 1.93511998 -1.95851004 0 P 0 ;0
L 1.93511998 -1.95851004 1.93628996 -1.95633996 0 P 0 ;0
L 1.93628996 -1.95633996 1.93803996 -1.95251998 0 P 0 ;0
L 1.93803996 -1.95251998 1.93858002 -1.95101998 0 P 0 ;0
L 1.93858002 -1.95101998 1.93898996 -1.94948002 0 P 0 ;0
L 1.93898996 -1.94948002 1.93928996 -1.94786998 0 P 0 ;0
L 1.93928996 -1.94786998 1.93946004 -1.94625 0 P 0 ;0
L 1.93946004 -1.94625 1.9396 -1.94178002 0 P 0 ;0
L 1.9396 -1.94178002 1.93946004 -1.93803996 0 P 0 ;0
L 1.93946004 -1.93803996 1.93905 -1.9343 0 P 0 ;0
L 1.93905 -1.9343 1.93863996 -1.93213996 0 P 0 ;0
L 1.93863996 -1.93213996 1.93808002 -1.93001998 0 P 0 ;0
L 1.93808002 -1.93001998 1.93736004 -1.92795 0 P 0 ;0
L 1.93736004 -1.92795 1.93653002 -1.92601004 0 P 0 ;0
L 1.93653002 -1.92601004 1.93555 -1.92415 0 P 0 ;0
L 1.93555 -1.92415 1.93441998 -1.92236004 0 P 0 ;0
L 1.93441998 -1.92236004 1.9331 -1.92056004 0 P 0 ;0
L 1.9331 -1.92056004 1.93166998 -1.91885 0 P 0 ;0
L 1.93166998 -1.91885 1.93011998 -1.91723002 0 P 0 ;0
L 1.93011998 -1.91723002 1.92896004 -1.91615 0 P 0 ;0
L 1.92896004 -1.91615 1.92775 -1.91511004 0 P 0 ;0
L 1.92775 -1.91511004 1.92493002 -1.91295 0 P 0 ;0
L 1.92493002 -1.91295 1.9221 -1.91108002 0 P 0 ;0
L 1.9221 -1.91108002 1.92095 -1.91043002 0 P 0 ;0
L 1.92095 -1.91043002 1.91975 -1.90985 0 P 0 ;0
L 1.91975 -1.90985 1.91796004 -1.90913996 0 P 0 ;0
L 1.91796004 -1.90913996 1.91613002 -1.90856004 0 P 0 ;0
L 1.91613002 -1.90856004 1.91423996 -1.9081 0 P 0 ;0
L 1.91423996 -1.9081 1.91086004 -1.90751998 0 P 0 ;0
L 1.91086004 -1.90751998 1.90743002 -1.90716004 0 P 0 ;0
L 1.90743002 -1.90716004 1.90401004 -1.90701004 0 P 0 ;0
L 1.90401004 -1.90701004 1.90058002 -1.90708002 0 P 0 ;0
L 1.90058002 -1.90708002 1.8987 -1.90726004 0 P 0 ;0
L 1.8987 -1.90726004 1.89683002 -1.90756998 0 P 0 ;0
L 1.89683002 -1.90756998 1.89498002 -1.90801998 0 P 0 ;0
L 1.86643002 -2.02923996 1.87525 -2.02923996 0 P 0 ;0
L 1.86176998 -2.02823996 1.87515 -2.02823996 0 P 0 ;0
L 1.85588996 -2.02723996 1.87505 -2.02723996 0 P 0 ;0
L 1.78365 -2.00523996 1.87281004 -2.00523996 0 P 0 ;0
L 1.78451004 -2.00423996 1.87271004 -2.00423996 0 P 0 ;0
L 1.78546998 -2.00323996 1.87261004 -2.00323996 0 P 0 ;0
L 1.78655 -2.00223996 1.8725 -2.00223996 0 P 0 ;0
L 1.78776004 -2.00123996 1.8724 -2.00123996 0 P 0 ;0
L 1.78915 -2.00023996 1.8723 -2.00023996 0 P 0 ;0
L 1.79078996 -1.99923996 1.8722 -1.99923996 0 P 0 ;0
L 1.79263996 -1.99823996 1.87208996 -1.99823996 0 P 0 ;0
L 1.79458996 -1.99723996 1.87198996 -1.99723996 0 P 0 ;0
L 1.79686998 -1.99623996 1.87188002 -1.99623996 0 P 0 ;0
L 1.79946004 -1.99523996 1.87178002 -1.99523996 0 P 0 ;0
L 1.80231004 -1.99423996 1.86961998 -1.99423996 0 P 0 ;0
L 1.80596004 -1.99323996 1.86218002 -1.99323996 0 P 0 ;0
L 1.81051004 -1.99223996 1.85398002 -1.99223996 0 P 0 ;0
L 1.81676004 -1.99123996 1.84395 -1.99123996 0 P 0 ;0
L 1.87786998 -1.96146004 1.88093996 -1.96146004 0 P 0 ;0
L 1.8771 -1.96046004 1.88013002 -1.96046004 0 P 0 ;0
L 1.87633996 -1.95946004 1.87933996 -1.95946004 0 P 0 ;0
L 1.87561998 -1.95846004 1.87866998 -1.95846004 0 P 0 ;0
L 1.87496998 -1.95746004 1.87801998 -1.95746004 0 P 0 ;0
L 1.8744 -1.95646004 1.87745 -1.95646004 0 P 0 ;0
L 1.87386998 -1.95546004 1.87688002 -1.95546004 0 P 0 ;0
L 1.87341998 -1.95446004 1.87641998 -1.95446004 0 P 0 ;0
L 1.87298996 -1.95346004 1.87596004 -1.95346004 0 P 0 ;0
L 1.87263002 -1.95246004 1.87555 -1.95246004 0 P 0 ;0
L 1.87231004 -1.95146004 1.87518996 -1.95146004 0 P 0 ;0
L 1.87203002 -1.95046004 1.87483002 -1.95046004 0 P 0 ;0
L 1.87178996 -1.94946004 1.87456998 -1.94946004 0 P 0 ;0
L 1.87158996 -1.94846004 1.87431004 -1.94846004 0 P 0 ;0
L 1.87143996 -1.94746004 1.87408002 -1.94746004 0 P 0 ;0
L 1.87133002 -1.94646004 1.8739 -1.94646004 0 P 0 ;0
L 1.87121004 -1.94546004 1.87373002 -1.94546004 0 P 0 ;0
L 1.8711 -1.94446998 1.87361998 -1.94446998 0 P 0 ;0
L 1.87106998 -1.94346004 1.87353996 -1.94346004 0 P 0 ;0
L 1.87103002 -1.94246004 1.87346004 -1.94246004 0 P 0 ;0
L 1.87098996 -1.94146998 1.87346004 -1.94146998 0 P 0 ;0
L 1.87101004 -1.94046004 1.87346004 -1.94046004 0 P 0 ;0
L 1.87106004 -1.93946004 1.87348996 -1.93946004 0 P 0 ;0
L 1.87111004 -1.93846004 1.87358002 -1.93846004 0 P 0 ;0
L 1.87123002 -1.93746004 1.87366004 -1.93746004 0 P 0 ;0
L 1.87135 -1.93646004 1.87381998 -1.93646004 0 P 0 ;0
L 1.87151004 -1.93546004 1.87398996 -1.93546004 0 P 0 ;0
L 1.87171998 -1.93446004 1.87416998 -1.93446004 0 P 0 ;0
L 1.87191998 -1.93346004 1.87443002 -1.93346004 0 P 0 ;0
L 1.8722 -1.93246004 1.87468996 -1.93246004 0 P 0 ;0
L 1.87248996 -1.93146004 1.875 -1.93146004 0 P 0 ;0
L 1.87281004 -1.93046004 1.87535 -1.93046004 0 P 0 ;0
L 1.87318996 -1.92946004 1.87571004 -1.92946004 0 P 0 ;0
L 1.87356998 -1.92846004 1.87616004 -1.92846004 0 P 0 ;0
L 1.87405 -1.92746004 1.87661004 -1.92746004 0 P 0 ;0
L 1.87453002 -1.92646004 1.87711998 -1.92646004 0 P 0 ;0
L 1.87506998 -1.92546004 1.87768996 -1.92546004 0 P 0 ;0
L 1.87566004 -1.92446998 1.87826998 -1.92446998 0 P 0 ;0
L 1.87628996 -1.92346004 1.87896004 -1.92346004 0 P 0 ;0
L 1.87701004 -1.92246004 1.87963996 -1.92246004 0 P 0 ;0
L 1.87775 -1.92146004 1.88046004 -1.92146004 0 P 0 ;0
L 1.90483996 -1.97346004 1.9009 -1.97333996 0 P 0 ;0
L 1.9009 -1.97333996 1.89698002 -1.97295 0 P 0 ;0
L 1.89698002 -1.97295 1.89488996 -1.97258996 0 P 0 ;0
L 1.89488996 -1.97258996 1.89285 -1.97206998 0 P 0 ;0
L 1.89285 -1.97206998 1.89086004 -1.97138996 0 P 0 ;0
L 1.89086004 -1.97138996 1.889 -1.97058002 0 P 0 ;0
L 1.889 -1.97058002 1.88723002 -1.96961998 0 P 0 ;0
L 1.88723002 -1.96961998 1.88553002 -1.96851998 0 P 0 ;0
L 1.88553002 -1.96851998 1.88273996 -1.96636004 0 P 0 ;0
L 1.88273996 -1.96636004 1.88013996 -1.96396004 0 P 0 ;0
L 1.88013996 -1.96396004 1.8779 -1.9615 0 P 0 ;0
L 1.8779 -1.9615 1.87588002 -1.95886998 0 P 0 ;0
L 1.87588002 -1.95886998 1.87483002 -1.95723996 0 P 0 ;0
L 1.87483002 -1.95723996 1.8739 -1.95553996 0 P 0 ;0
L 1.8739 -1.95553996 1.87311004 -1.95376998 0 P 0 ;0
L 1.87311004 -1.95376998 1.87243002 -1.95191004 0 P 0 ;0
L 1.87243002 -1.95191004 1.8719 -1.95001998 0 P 0 ;0
L 1.8719 -1.95001998 1.87151998 -1.9481 0 P 0 ;0
L 1.87151998 -1.9481 1.87111004 -1.94468996 0 P 0 ;0
L 1.87111004 -1.94468996 1.87098002 -1.94128996 0 P 0 ;0
L 1.87098002 -1.94128996 1.87108996 -1.93861004 0 P 0 ;0
L 1.87108996 -1.93861004 1.87141004 -1.93596998 0 P 0 ;0
L 1.87141004 -1.93596998 1.87195 -1.93335 0 P 0 ;0
L 1.87195 -1.93335 1.87268996 -1.93078996 0 P 0 ;0
L 1.87268996 -1.93078996 1.87361998 -1.92835 0 P 0 ;0
L 1.87361998 -1.92835 1.87475 -1.926 0 P 0 ;0
L 1.87475 -1.926 1.87608996 -1.92376004 0 P 0 ;0
L 1.87608996 -1.92376004 1.8776 -1.92163996 0 P 0 ;0
L 1.8776 -1.92163996 1.87931998 -1.91961998 0 P 0 ;0
L 1.87931998 -1.91961998 1.8812 -1.91775 0 P 0 ;0
L 1.8812 -1.91775 1.88323002 -1.91605 0 P 0 ;0
L 1.88323002 -1.91605 1.8854 -1.91451998 0 P 0 ;0
L 1.8854 -1.91451998 1.88781004 -1.91308996 0 P 0 ;0
L 1.88781004 -1.91308996 1.89031004 -1.91186004 0 P 0 ;0
L 1.89031004 -1.91186004 1.89288002 -1.9108 0 P 0 ;0
L 1.89288002 -1.9108 1.89553002 -1.90995 0 P 0 ;0
L 1.89553002 -1.90995 1.89723002 -1.90953002 0 P 0 ;0
L 1.89723002 -1.90953002 1.89896004 -1.90923996 0 P 0 ;0
L 1.89896004 -1.90923996 1.90068996 -1.90908002 0 P 0 ;0
L 1.90068996 -1.90908002 1.90398996 -1.90901004 0 P 0 ;0
L 1.90398996 -1.90901004 1.90728002 -1.90915 0 P 0 ;0
L 1.90728002 -1.90915 1.91058996 -1.90951004 0 P 0 ;0
L 1.91058996 -1.90951004 1.91383996 -1.91006004 0 P 0 ;0
L 1.91383996 -1.91006004 1.91558996 -1.91048996 0 P 0 ;0
L 1.91558996 -1.91048996 1.91728996 -1.91101998 0 P 0 ;0
L 1.91728996 -1.91101998 1.91895 -1.91168002 0 P 0 ;0
L 1.91895 -1.91168002 1.92001998 -1.9122 0 P 0 ;0
L 1.92001998 -1.9122 1.92105 -1.91278996 0 P 0 ;0
L 1.92105 -1.91278996 1.92376998 -1.91458002 0 P 0 ;0
L 1.92376998 -1.91458002 1.92648996 -1.91666998 0 P 0 ;0
L 1.92648996 -1.91666998 1.92763002 -1.91763996 0 P 0 ;0
L 1.92763002 -1.91763996 1.92871004 -1.91865 0 P 0 ;0
L 1.92871004 -1.91865 1.93018002 -1.92018996 0 P 0 ;0
L 1.93018002 -1.92018996 1.93153002 -1.9218 0 P 0 ;0
L 1.93153002 -1.9218 1.93276998 -1.92348996 0 P 0 ;0
L 1.93276998 -1.92348996 1.93381004 -1.92515 0 P 0 ;0
L 1.93381004 -1.92515 1.93471998 -1.92686998 0 P 0 ;0
L 1.93471998 -1.92686998 1.9355 -1.92866998 0 P 0 ;0
L 1.9355 -1.92866998 1.93616998 -1.93061004 0 P 0 ;0
L 1.93616998 -1.93061004 1.93668996 -1.93258002 0 P 0 ;0
L 1.93668996 -1.93258002 1.93706998 -1.93458996 0 P 0 ;0
L 1.93706998 -1.93458996 1.93746998 -1.93818996 0 P 0 ;0
L 1.93746998 -1.93818996 1.9376 -1.94178996 0 P 0 ;0
L 1.9376 -1.94178996 1.93746004 -1.94611004 0 P 0 ;0
L 1.93746004 -1.94611004 1.93731004 -1.94758996 0 P 0 ;0
L 1.93731004 -1.94758996 1.93705 -1.94903996 0 P 0 ;0
L 1.93705 -1.94903996 1.93666998 -1.95041998 0 P 0 ;0
L 1.93666998 -1.95041998 1.93618002 -1.95176004 0 P 0 ;0
L 1.93618002 -1.95176004 1.9345 -1.95545 0 P 0 ;0
L 1.9345 -1.95545 1.93338996 -1.9575 0 P 0 ;0
L 1.93338996 -1.9575 1.93216004 -1.95946998 0 P 0 ;0
L 1.93216004 -1.95946998 1.93078996 -1.96133996 0 P 0 ;0
L 1.93078996 -1.96133996 1.92931004 -1.96311998 0 P 0 ;0
L 1.92931004 -1.96311998 1.92776998 -1.96473002 0 P 0 ;0
L 1.92776998 -1.96473002 1.92613002 -1.96621004 0 P 0 ;0
L 1.92613002 -1.96621004 1.92438002 -1.96756004 0 P 0 ;0
L 1.92438002 -1.96756004 1.92253002 -1.96878002 0 P 0 ;0
L 1.92253002 -1.96878002 1.92056998 -1.96986998 0 P 0 ;0
L 1.92056998 -1.96986998 1.91855 -1.97081998 0 P 0 ;0
L 1.91855 -1.97081998 1.91646004 -1.97161004 0 P 0 ;0
L 1.91646004 -1.97161004 1.91433002 -1.97223996 0 P 0 ;0
L 1.91433002 -1.97223996 1.9112 -1.97291004 0 P 0 ;0
L 1.9112 -1.97291004 1.90803996 -1.97331998 0 P 0 ;0
L 1.90803996 -1.97331998 1.90483996 -1.97346004 0 P 0 ;0
L 1.90476004 -1.97173996 1.9048 -1.97173996 0 P 0 ;0
L 1.9048 -1.97173996 1.90483996 -1.97173002 0 P 0 ;0
L 1.90483996 -1.97173002 1.90736004 -1.9716 0 P 0 ;0
L 1.90736004 -1.9716 1.9074 -1.97158996 0 P 0 ;0
L 1.9074 -1.97158996 1.90746998 -1.97158996 0 P 0 ;0
L 1.90746998 -1.97158996 1.90751004 -1.97158002 0 P 0 ;0
L 1.90751004 -1.97158002 1.91001004 -1.97126004 0 P 0 ;0
L 1.91001004 -1.97126004 1.91005 -1.97125 0 P 0 ;0
L 1.91005 -1.97125 1.91008002 -1.97123996 0 P 0 ;0
L 1.91008002 -1.97123996 1.91011998 -1.97123996 0 P 0 ;0
L 1.91011998 -1.97123996 1.91016004 -1.97123002 0 P 0 ;0
L 1.91016004 -1.97123002 1.9126 -1.97071998 0 P 0 ;0
L 1.9126 -1.97071998 1.9126 -1.97071004 0 P 0 ;0
L 1.9126 -1.97071004 1.91266998 -1.97071004 0 P 0 ;0
L 1.91266998 -1.97071004 1.91271004 -1.97068996 0 P 0 ;0
L 1.91271004 -1.97068996 1.91275 -1.97068002 0 P 0 ;0
L 1.91275 -1.97068002 1.91511998 -1.96998996 0 P 0 ;0
L 1.91511998 -1.96998996 1.91515 -1.96998996 0 P 0 ;0
L 1.91515 -1.96998996 1.91518996 -1.96996998 0 P 0 ;0
L 1.91518996 -1.96996998 1.91523002 -1.96996004 0 P 0 ;0
L 1.91523002 -1.96996004 1.91526004 -1.96995 0 P 0 ;0
L 1.91526004 -1.96995 1.91756998 -1.96908002 0 P 0 ;0
L 1.91756998 -1.96908002 1.91761004 -1.96906998 0 P 0 ;0
L 1.91761004 -1.96906998 1.91768002 -1.96903996 0 P 0 ;0
L 1.91768002 -1.96903996 1.91771004 -1.96901998 0 P 0 ;0
L 1.91771004 -1.96901998 1.91995 -1.96798002 0 P 0 ;0
L 1.91995 -1.96798002 1.92001998 -1.96795 0 P 0 ;0
L 1.92001998 -1.96795 1.92005 -1.96793002 0 P 0 ;0
L 1.92005 -1.96793002 1.92008996 -1.96791004 0 P 0 ;0
L 1.92008996 -1.96791004 1.92168002 -1.96701998 0 P 0 ;0
L 1.92168002 -1.96701998 1.92171998 -1.967 0 P 0 ;0
L 1.92171998 -1.967 1.92175 -1.96698002 0 P 0 ;0
L 1.92175 -1.96698002 1.92178996 -1.96695 0 P 0 ;0
L 1.92178996 -1.96695 1.92181998 -1.96693002 0 P 0 ;0
L 1.92181998 -1.96693002 1.92331998 -1.96591998 0 P 0 ;0
L 1.92331998 -1.96591998 1.92336004 -1.9659 0 P 0 ;0
L 1.92336004 -1.9659 1.92341998 -1.96586004 0 P 0 ;0
L 1.92341998 -1.96586004 1.92345 -1.96583002 0 P 0 ;0
L 1.92345 -1.96583002 1.92486004 -1.9647 0 P 0 ;0
L 1.92486004 -1.9647 1.92493002 -1.96465 0 P 0 ;0
L 1.92493002 -1.96465 1.92496004 -1.96463002 0 P 0 ;0
L 1.92496004 -1.96463002 1.92498996 -1.9646 0 P 0 ;0
L 1.92498996 -1.9646 1.92631004 -1.96336998 0 P 0 ;0
L 1.92631004 -1.96336998 1.9264 -1.96328002 0 P 0 ;0
L 1.9264 -1.96328002 1.92641998 -1.96325 0 P 0 ;0
L 1.92641998 -1.96325 1.92763996 -1.96191998 0 P 0 ;0
L 1.92763996 -1.96191998 1.92766998 -1.96188996 0 P 0 ;0
L 1.92766998 -1.96188996 1.92768996 -1.96186004 0 P 0 ;0
L 1.92768996 -1.96186004 1.92771998 -1.96183002 0 P 0 ;0
L 1.92771998 -1.96183002 1.92773996 -1.9618 0 P 0 ;0
L 1.92773996 -1.9618 1.92913996 -1.96001004 0 P 0 ;0
L 1.92913996 -1.96001004 1.92918996 -1.95995 0 P 0 ;0
L 1.92918996 -1.95995 1.92921004 -1.95991004 0 P 0 ;0
L 1.92921004 -1.95991004 1.92923002 -1.95988002 0 P 0 ;0
L 1.92923002 -1.95988002 1.93048002 -1.95798996 0 P 0 ;0
L 1.93048002 -1.95798996 1.93051998 -1.95793002 0 P 0 ;0
L 1.93051998 -1.95793002 1.93053996 -1.95788996 0 P 0 ;0
L 1.93053996 -1.95788996 1.93056004 -1.95786004 0 P 0 ;0
L 1.93056004 -1.95786004 1.93166004 -1.95588002 0 P 0 ;0
L 1.93166004 -1.95588002 1.93171004 -1.95576998 0 P 0 ;0
L 1.93171004 -1.95576998 1.93173002 -1.95573996 0 P 0 ;0
L 1.93173002 -1.95573996 1.93266998 -1.95366998 0 P 0 ;0
L 1.93266998 -1.95366998 1.93271004 -1.95356998 0 P 0 ;0
L 1.93271004 -1.95356998 1.93273002 -1.95353002 0 P 0 ;0
L 1.93273002 -1.95353002 1.9335 -1.9514 0 P 0 ;0
L 1.9335 -1.9514 1.93351004 -1.95136998 0 P 0 ;0
L 1.93351004 -1.95136998 1.93353002 -1.95133002 0 P 0 ;0
L 1.93353002 -1.95133002 1.93355 -1.95125 0 P 0 ;0
L 1.93355 -1.95125 1.93416004 -1.94906998 0 P 0 ;0
L 1.93416004 -1.94906998 1.93416998 -1.94903002 0 P 0 ;0
L 1.93416998 -1.94903002 1.93418002 -1.949 0 P 0 ;0
L 1.93418002 -1.949 1.93418002 -1.94896004 0 P 0 ;0
L 1.93418002 -1.94896004 1.93418996 -1.94891998 0 P 0 ;0
L 1.93418996 -1.94891998 1.93463996 -1.94665 0 P 0 ;0
L 1.93463996 -1.94665 1.93463996 -1.94661004 0 P 0 ;0
L 1.93463996 -1.94661004 1.93465 -1.94656998 0 P 0 ;0
L 1.93465 -1.94656998 1.93466004 -1.9465 0 P 0 ;0
L 1.93466004 -1.9465 1.93493996 -1.9442 0 P 0 ;0
L 1.93493996 -1.9442 1.93493996 -1.94413002 0 P 0 ;0
L 1.93493996 -1.94413002 1.93495 -1.94408996 0 P 0 ;0
L 1.93495 -1.94408996 1.93495 -1.94406004 0 P 0 ;0
L 1.93495 -1.94406004 1.93505 -1.94173996 0 P 0 ;0
L 1.93505 -1.94173996 1.93506004 -1.94171004 0 P 0 ;0
L 1.93506004 -1.94171004 1.93506004 -1.9416 0 P 0 ;0
L 1.93506004 -1.9416 1.93498996 -1.93928996 0 P 0 ;0
L 1.93498996 -1.93928996 1.93498996 -1.93921004 0 P 0 ;0
L 1.93498996 -1.93921004 1.93498002 -1.93913996 0 P 0 ;0
L 1.93498002 -1.93913996 1.93475 -1.93683996 0 P 0 ;0
L 1.93475 -1.93683996 1.93473996 -1.93676998 0 P 0 ;0
L 1.93473996 -1.93676998 1.93473002 -1.93673002 0 P 0 ;0
L 1.93473002 -1.93673002 1.93473002 -1.93668996 0 P 0 ;0
L 1.93473002 -1.93668996 1.93433002 -1.93441004 0 P 0 ;0
L 1.93433002 -1.93441004 1.93431998 -1.93436998 0 P 0 ;0
L 1.93431998 -1.93436998 1.93431004 -1.93433996 0 P 0 ;0
L 1.93431004 -1.93433996 1.93428996 -1.93426004 0 P 0 ;0
L 1.93428996 -1.93426004 1.93373002 -1.93206004 0 P 0 ;0
L 1.93373002 -1.93206004 1.93368996 -1.93191998 0 P 0 ;0
L 1.93368996 -1.93191998 1.93296004 -1.92976998 0 P 0 ;0
L 1.93296004 -1.92976998 1.93293996 -1.9297 0 P 0 ;0
L 1.93293996 -1.9297 1.93291004 -1.92963002 0 P 0 ;0
L 1.93291004 -1.92963002 1.93201998 -1.92753996 0 P 0 ;0
L 1.93201998 -1.92753996 1.93196998 -1.92743002 0 P 0 ;0
L 1.93196998 -1.92743002 1.93196004 -1.9274 0 P 0 ;0
L 1.93196004 -1.9274 1.93091998 -1.92538996 0 P 0 ;0
L 1.93091998 -1.92538996 1.9309 -1.92536004 0 P 0 ;0
L 1.9309 -1.92536004 1.93088002 -1.92531998 0 P 0 ;0
L 1.93088002 -1.92531998 1.93086004 -1.92528996 0 P 0 ;0
L 1.93086004 -1.92528996 1.93083996 -1.92525 0 P 0 ;0
L 1.93083996 -1.92525 1.92965 -1.92331998 0 P 0 ;0
L 1.92965 -1.92331998 1.92956998 -1.9232 0 P 0 ;0
L 1.92956998 -1.9232 1.92823002 -1.92136004 0 P 0 ;0
L 1.92823002 -1.92136004 1.92818002 -1.9213 0 P 0 ;0
L 1.92818002 -1.9213 1.92816004 -1.92126998 0 P 0 ;0
L 1.92816004 -1.92126998 1.92813002 -1.92123996 0 P 0 ;0
L 1.92813002 -1.92123996 1.92671998 -1.91958002 0 P 0 ;0
L 1.92671998 -1.91958002 1.9266 -1.91946004 0 P 0 ;0
L 1.9266 -1.91946004 1.92505 -1.91793002 0 P 0 ;0
L 1.92505 -1.91793002 1.92498996 -1.91786998 0 P 0 ;0
L 1.92498996 -1.91786998 1.92493002 -1.91781998 0 P 0 ;0
L 1.92493002 -1.91781998 1.92325 -1.91643002 0 P 0 ;0
L 1.92325 -1.91643002 1.92318996 -1.91636998 0 P 0 ;0
L 1.92318996 -1.91636998 1.92311998 -1.91631998 0 P 0 ;0
L 1.92311998 -1.91631998 1.92133002 -1.91508002 0 P 0 ;0
L 1.92133002 -1.91508002 1.92126004 -1.91503996 0 P 0 ;0
L 1.92126004 -1.91503996 1.92121998 -1.91501004 0 P 0 ;0
L 1.92121998 -1.91501004 1.92118002 -1.91498996 0 P 0 ;0
L 1.92118002 -1.91498996 1.91928996 -1.91391004 0 P 0 ;0
L 1.91928996 -1.91391004 1.91926004 -1.91388996 0 P 0 ;0
L 1.91926004 -1.91388996 1.91913996 -1.91383002 0 P 0 ;0
L 1.91913996 -1.91383002 1.91716998 -1.91291004 0 P 0 ;0
L 1.91716998 -1.91291004 1.91711998 -1.91288996 0 P 0 ;0
L 1.91711998 -1.91288996 1.91705 -1.91286004 0 P 0 ;0
L 1.91705 -1.91286004 1.917 -1.91285 0 P 0 ;0
L 1.917 -1.91285 1.91476998 -1.91203996 0 P 0 ;0
L 1.91476998 -1.91203996 1.91468996 -1.91201998 0 P 0 ;0
L 1.91468996 -1.91201998 1.91465 -1.912 0 P 0 ;0
L 1.91465 -1.912 1.9146 -1.91198996 0 P 0 ;0
L 1.9146 -1.91198996 1.91233002 -1.91138996 0 P 0 ;0
L 1.91233002 -1.91138996 1.91228002 -1.91138002 0 P 0 ;0
L 1.91228002 -1.91138002 1.91223996 -1.91136998 0 P 0 ;0
L 1.91223996 -1.91136998 1.91216004 -1.91136004 0 P 0 ;0
L 1.91216004 -1.91136004 1.90983002 -1.91095 0 P 0 ;0
L 1.90983002 -1.91095 1.9098 -1.91093996 0 P 0 ;0
L 1.9098 -1.91093996 1.90976004 -1.91093996 0 P 0 ;0
L 1.90976004 -1.91093996 1.90971998 -1.91093002 0 P 0 ;0
L 1.90971998 -1.91093002 1.90968002 -1.91093002 0 P 0 ;0
L 1.90968002 -1.91093002 1.90713996 -1.91068996 0 P 0 ;0
L 1.90713996 -1.91068996 1.9071 -1.91068002 0 P 0 ;0
L 1.9071 -1.91068002 1.907 -1.91068002 0 P 0 ;0
L 1.907 -1.91068002 1.90445 -1.91061004 0 P 0 ;0
L 1.90445 -1.91061004 1.90431004 -1.91061004 0 P 0 ;0
L 1.90431004 -1.91061004 1.90176004 -1.91071004 0 P 0 ;0
L 1.90176004 -1.91071004 1.90173002 -1.91071998 0 P 0 ;0
L 1.90173002 -1.91071998 1.90166004 -1.91071998 0 P 0 ;0
L 1.90166004 -1.91071998 1.90161998 -1.91073002 0 P 0 ;0
L 1.90161998 -1.91073002 1.89913002 -1.911 0 P 0 ;0
L 1.89913002 -1.911 1.89906004 -1.91101004 0 P 0 ;0
L 1.89906004 -1.91101004 1.89901998 -1.91101998 0 P 0 ;0
L 1.89901998 -1.91101998 1.89898996 -1.91101998 0 P 0 ;0
L 1.89898996 -1.91101998 1.89653002 -1.91146998 0 P 0 ;0
L 1.89653002 -1.91146998 1.8965 -1.91148002 0 P 0 ;0
L 1.8965 -1.91148002 1.89646004 -1.91148002 0 P 0 ;0
L 1.89646004 -1.91148002 1.8964 -1.9115 0 P 0 ;0
L 1.8964 -1.9115 1.89396998 -1.91211998 0 P 0 ;0
L 1.89396998 -1.91211998 1.89393996 -1.91213002 0 P 0 ;0
L 1.89393996 -1.91213002 1.89383002 -1.91216004 0 P 0 ;0
L 1.89383002 -1.91216004 1.89225 -1.91268996 0 P 0 ;0
L 1.89225 -1.91268996 1.89218002 -1.91271998 0 P 0 ;0
L 1.89218002 -1.91271998 1.89211004 -1.91273996 0 P 0 ;0
L 1.89211004 -1.91273996 1.8921 -1.91273996 0 P 0 ;0
L 1.8921 -1.91273996 1.89058002 -1.91338996 0 P 0 ;0
L 1.89058002 -1.91338996 1.89043996 -1.91345 0 P 0 ;0
L 1.89043996 -1.91345 1.88896004 -1.91421004 0 P 0 ;0
L 1.88896004 -1.91421004 1.88893002 -1.91423002 0 P 0 ;0
L 1.88893002 -1.91423002 1.8889 -1.91423996 0 P 0 ;0
L 1.8889 -1.91423996 1.88886004 -1.91426004 0 P 0 ;0
L 1.88886004 -1.91426004 1.88883002 -1.91428002 0 P 0 ;0
L 1.88883002 -1.91428002 1.88741004 -1.91515 0 P 0 ;0
L 1.88741004 -1.91515 1.88733996 -1.91518996 0 P 0 ;0
L 1.88733996 -1.91518996 1.88728002 -1.91523996 0 P 0 ;0
L 1.88728002 -1.91523996 1.88526004 -1.9167 0 P 0 ;0
L 1.88526004 -1.9167 1.88521998 -1.91673002 0 P 0 ;0
L 1.88521998 -1.91673002 1.88518996 -1.91675 0 P 0 ;0
L 1.88518996 -1.91675 1.88516004 -1.91678002 0 P 0 ;0
L 1.88516004 -1.91678002 1.88511998 -1.91681004 0 P 0 ;0
L 1.88511998 -1.91681004 1.88323002 -1.91845 0 P 0 ;0
L 1.88323002 -1.91845 1.8832 -1.91846998 0 P 0 ;0
L 1.8832 -1.91846998 1.88311004 -1.91856004 0 P 0 ;0
L 1.88311004 -1.91856004 1.88136998 -1.92036004 0 P 0 ;0
L 1.88136998 -1.92036004 1.88128002 -1.92045 0 P 0 ;0
L 1.88128002 -1.92045 1.88125 -1.92048996 0 P 0 ;0
L 1.88125 -1.92048996 1.87968002 -1.92241998 0 P 0 ;0
L 1.87968002 -1.92241998 1.87965 -1.92245 0 P 0 ;0
L 1.87965 -1.92245 1.87961998 -1.92248996 0 P 0 ;0
L 1.87961998 -1.92248996 1.87956998 -1.92256004 0 P 0 ;0
L 1.87956998 -1.92256004 1.87816998 -1.92461998 0 P 0 ;0
L 1.87816998 -1.92461998 1.8781 -1.92473002 0 P 0 ;0
L 1.8781 -1.92473002 1.87808002 -1.92476998 0 P 0 ;0
L 1.87808002 -1.92476998 1.87685 -1.92695 0 P 0 ;0
L 1.87685 -1.92695 1.87683002 -1.92698996 0 P 0 ;0
L 1.87683002 -1.92698996 1.87681004 -1.92701998 0 P 0 ;0
L 1.87681004 -1.92701998 1.87678996 -1.92706998 0 P 0 ;0
L 1.87678996 -1.92706998 1.87676998 -1.92711004 0 P 0 ;0
L 1.87676998 -1.92711004 1.87573002 -1.92941004 0 P 0 ;0
L 1.87573002 -1.92941004 1.87571004 -1.92945 0 P 0 ;0
L 1.87571004 -1.92945 1.8757 -1.92948996 0 P 0 ;0
L 1.8757 -1.92948996 1.87568002 -1.92951998 0 P 0 ;0
L 1.87568002 -1.92951998 1.87566998 -1.92956998 0 P 0 ;0
L 1.87566998 -1.92956998 1.87483996 -1.93193002 0 P 0 ;0
L 1.87483996 -1.93193002 1.87481004 -1.93201004 0 P 0 ;0
L 1.87481004 -1.93201004 1.87478996 -1.93208996 0 P 0 ;0
L 1.87478996 -1.93208996 1.87416004 -1.93451998 0 P 0 ;0
L 1.87416004 -1.93451998 1.87413996 -1.93456004 0 P 0 ;0
L 1.87413996 -1.93456004 1.87413002 -1.9346 0 P 0 ;0
L 1.87413002 -1.9346 1.87413002 -1.93463996 0 P 0 ;0
L 1.87413002 -1.93463996 1.87411998 -1.93468002 0 P 0 ;0
L 1.87411998 -1.93468002 1.8737 -1.93715 0 P 0 ;0
L 1.8737 -1.93715 1.87368996 -1.93718996 0 P 0 ;0
L 1.87368996 -1.93718996 1.87368002 -1.93723996 0 P 0 ;0
L 1.87368002 -1.93723996 1.87368002 -1.93731998 0 P 0 ;0
L 1.87368002 -1.93731998 1.87346998 -1.93981998 0 P 0 ;0
L 1.87346998 -1.93981998 1.87346004 -1.93986004 0 P 0 ;0
L 1.87346004 -1.93986004 1.87346004 -1.94258002 0 P 0 ;0
L 1.87346004 -1.94258002 1.87346998 -1.94266004 0 P 0 ;0
L 1.87346998 -1.94266004 1.87368002 -1.94516998 0 P 0 ;0
L 1.87368002 -1.94516998 1.87368996 -1.94521004 0 P 0 ;0
L 1.87368996 -1.94521004 1.87368996 -1.94525 0 P 0 ;0
L 1.87368996 -1.94525 1.87371004 -1.94533996 0 P 0 ;0
L 1.87371004 -1.94533996 1.87413996 -1.94778996 0 P 0 ;0
L 1.87413996 -1.94778996 1.87413996 -1.94783996 0 P 0 ;0
L 1.87413996 -1.94783996 1.87416998 -1.94796004 0 P 0 ;0
L 1.87416998 -1.94796004 1.87481004 -1.95036998 0 P 0 ;0
L 1.87481004 -1.95036998 1.87483996 -1.95048996 0 P 0 ;0
L 1.87483996 -1.95048996 1.87486004 -1.95053002 0 P 0 ;0
L 1.87486004 -1.95053002 1.8757 -1.95288002 0 P 0 ;0
L 1.8757 -1.95288002 1.87571004 -1.95291998 0 P 0 ;0
L 1.87571004 -1.95291998 1.87575 -1.953 0 P 0 ;0
L 1.87575 -1.953 1.87576004 -1.95303996 0 P 0 ;0
L 1.87576004 -1.95303996 1.8768 -1.9553 0 P 0 ;0
L 1.8768 -1.9553 1.87686004 -1.95541998 0 P 0 ;0
L 1.87686004 -1.95541998 1.87688002 -1.95545 0 P 0 ;0
L 1.87688002 -1.95545 1.8781 -1.95761004 0 P 0 ;0
L 1.8781 -1.95761004 1.87811998 -1.95761004 0 P 0 ;0
L 1.87811998 -1.95761004 1.8781 -1.95761998 0 P 0 ;0
L 1.8781 -1.95761998 1.87813996 -1.95768996 0 P 0 ;0
L 1.87813996 -1.95768996 1.87816998 -1.95771998 0 P 0 ;0
L 1.87816998 -1.95771998 1.87818996 -1.95775 0 P 0 ;0
L 1.87818996 -1.95775 1.87938002 -1.95951004 0 P 0 ;0
L 1.87938002 -1.95951004 1.87943996 -1.9596 0 P 0 ;0
L 1.87943996 -1.9596 1.87946998 -1.95963002 0 P 0 ;0
L 1.87946998 -1.95963002 1.88078002 -1.96128996 0 P 0 ;0
L 1.88078002 -1.96128996 1.88081004 -1.96131998 0 P 0 ;0
L 1.88081004 -1.96131998 1.88083002 -1.96135 0 P 0 ;0
L 1.88083002 -1.96135 1.88086004 -1.96136998 0 P 0 ;0
L 1.88086004 -1.96136998 1.88088002 -1.9614 0 P 0 ;0
L 1.88088002 -1.9614 1.88231998 -1.96295 0 P 0 ;0
L 1.88231998 -1.96295 1.88233996 -1.96298002 0 P 0 ;0
L 1.88233996 -1.96298002 1.8824 -1.96303996 0 P 0 ;0
L 1.8824 -1.96303996 1.88243002 -1.96306004 0 P 0 ;0
L 1.88243002 -1.96306004 1.88398002 -1.9645 0 P 0 ;0
L 1.88398002 -1.9645 1.88401004 -1.96451998 0 P 0 ;0
L 1.88401004 -1.96451998 1.88403002 -1.96455 0 P 0 ;0
L 1.88403002 -1.96455 1.88406998 -1.96458002 0 P 0 ;0
L 1.88406998 -1.96458002 1.88408996 -1.9646 0 P 0 ;0
L 1.88408996 -1.9646 1.88575 -1.96591004 0 P 0 ;0
L 1.88575 -1.96591004 1.88578002 -1.96593996 0 P 0 ;0
L 1.88578002 -1.96593996 1.88586998 -1.966 0 P 0 ;0
L 1.88586998 -1.966 1.88761998 -1.96718996 0 P 0 ;0
L 1.88761998 -1.96718996 1.88766004 -1.96721004 0 P 0 ;0
L 1.88766004 -1.96721004 1.88775 -1.96726998 0 P 0 ;0
L 1.88775 -1.96726998 1.88958996 -1.96831998 0 P 0 ;0
L 1.88958996 -1.96831998 1.88965 -1.96836004 0 P 0 ;0
L 1.88965 -1.96836004 1.88968002 -1.96836998 0 P 0 ;0
L 1.88968002 -1.96836998 1.88971998 -1.96838996 0 P 0 ;0
L 1.88971998 -1.96838996 1.89145 -1.96921998 0 P 0 ;0
L 1.89145 -1.96921998 1.89151004 -1.96925 0 P 0 ;0
L 1.89151004 -1.96925 1.89155 -1.96926004 0 P 0 ;0
L 1.89155 -1.96926004 1.89158002 -1.96926998 0 P 0 ;0
L 1.89158002 -1.96926998 1.89336004 -1.96996998 0 P 0 ;0
L 1.89336004 -1.96996998 1.89336004 -1.96998002 0 P 0 ;0
L 1.89336004 -1.96998002 1.89346004 -1.97001004 0 P 0 ;0
L 1.89346004 -1.97001004 1.89348996 -1.97001998 0 P 0 ;0
L 1.89348996 -1.97001998 1.89531998 -1.9706 0 P 0 ;0
L 1.89531998 -1.9706 1.89536004 -1.97061004 0 P 0 ;0
L 1.89536004 -1.97061004 1.89541998 -1.97063002 0 P 0 ;0
L 1.89541998 -1.97063002 1.89546004 -1.97063002 0 P 0 ;0
L 1.89546004 -1.97063002 1.89731998 -1.97108002 0 P 0 ;0
L 1.89731998 -1.97108002 1.89741998 -1.9711 0 P 0 ;0
L 1.89741998 -1.9711 1.89746004 -1.9711 0 P 0 ;0
L 1.89746004 -1.9711 1.89746004 -1.97111004 0 P 0 ;0
L 1.89746004 -1.97111004 1.89933996 -1.97141998 0 P 0 ;0
L 1.89933996 -1.97141998 1.89936998 -1.97143002 0 P 0 ;0
L 1.89936998 -1.97143002 1.89941004 -1.97143002 0 P 0 ;0
L 1.89941004 -1.97143002 1.89945 -1.97143996 0 P 0 ;0
L 1.89945 -1.97143996 1.89948002 -1.97143996 0 P 0 ;0
L 1.89948002 -1.97143996 1.90201004 -1.97168002 0 P 0 ;0
L 1.90201004 -1.97168002 1.90205 -1.97168002 0 P 0 ;0
L 1.90205 -1.97168002 1.90208996 -1.97168996 0 P 0 ;0
L 1.90208996 -1.97168996 1.90216004 -1.97168996 0 P 0 ;0
L 1.90216004 -1.97168996 1.90468996 -1.97173996 0 P 0 ;0
L 1.90468996 -1.97173996 1.90476004 -1.97173996 0 P 0 ;0
L 1.80616004 -2.12823996 1.83348996 -2.12823996 0 P 0 ;0
L 1.79591998 -2.12723996 1.8396 -2.12723996 0 P 0 ;0
L 1.78818002 -2.12623996 1.84465 -2.12623996 0 P 0 ;0
L 1.82003996 -2.09123996 1.87618996 -2.09123996 0 P 0 ;0
L 1.82198996 -2.09023996 1.8762 -2.09023996 0 P 0 ;0
L 1.82325 -2.08923996 1.8762 -2.08923996 0 P 0 ;0
L 1.82411998 -2.08823996 1.87618996 -2.08823996 0 P 0 ;0
L 1.82463002 -2.08723996 1.87616998 -2.08723996 0 P 0 ;0
L 1.82488002 -2.08623996 1.87615 -2.08623996 0 P 0 ;0
L 1.82493002 -2.08523996 1.87613002 -2.08523996 0 P 0 ;0
L 1.82476998 -2.08423996 1.87611004 -2.08423996 0 P 0 ;0
L 1.64846004 -2.08295 1.73316998 -2.08295 0 P 0 ;0
L 1.64811998 -2.08195 1.73356998 -2.08195 0 P 0 ;0
L 1.64776998 -2.08095 1.73398002 -2.08095 0 P 0 ;0
L 1.64743002 -2.07995 1.73438002 -2.07995 0 P 0 ;0
L 1.64708996 -2.07895 1.73478996 -2.07895 0 P 0 ;0
L 1.64673996 -2.07795 1.7352 -2.07795 0 P 0 ;0
L 1.6464 -2.07695 1.7356 -2.07695 0 P 0 ;0
L 1.64605 -2.07595 1.73601004 -2.07595 0 P 0 ;0
L 1.64571004 -2.07495 1.73641004 -2.07495 0 P 0 ;0
L 1.64536004 -2.07395 1.73681004 -2.07395 0 P 0 ;0
L 1.64501998 -2.07295 1.73721998 -2.07295 0 P 0 ;0
L 1.64466998 -2.07195 1.73761998 -2.07195 0 P 0 ;0
L 1.64433002 -2.07095 1.73803002 -2.07095 0 P 0 ;0
L 1.64398002 -2.06995 1.69251004 -2.06995 0 P 0 ;0
L 1.69583002 -2.06995 1.73843996 -2.06995 0 P 0 ;0
L 1.64363002 -2.06895 1.69168002 -2.06895 0 P 0 ;0
L 1.69671998 -2.06895 1.73883996 -2.06895 0 P 0 ;0
L 1.64328996 -2.06795 1.69136004 -2.06795 0 P 0 ;0
L 1.69708996 -2.06795 1.73925 -2.06795 0 P 0 ;0
L 1.64293996 -2.06695 1.69108002 -2.06695 0 P 0 ;0
L 1.69738002 -2.06695 1.73965 -2.06695 0 P 0 ;0
L 1.64258996 -2.06595 1.6908 -2.06595 0 P 0 ;0
L 1.69768002 -2.06595 1.74006004 -2.06595 0 P 0 ;0
L 1.64223996 -2.06495 1.69051998 -2.06495 0 P 0 ;0
L 1.69796998 -2.06495 1.74046004 -2.06495 0 P 0 ;0
L 1.6419 -2.06395 1.69023002 -2.06395 0 P 0 ;0
L 1.69826998 -2.06395 1.74086004 -2.06395 0 P 0 ;0
L 1.64155 -2.06295 1.68996004 -2.06295 0 P 0 ;0
L 1.69856004 -2.06295 1.74126998 -2.06295 0 P 0 ;0
L 1.6412 -2.06195 1.68966998 -2.06195 0 P 0 ;0
L 1.69886004 -2.06195 1.74168002 -2.06195 0 P 0 ;0
L 1.64085 -2.06095 1.68938996 -2.06095 0 P 0 ;0
L 1.69915 -2.06095 1.74208002 -2.06095 0 P 0 ;0
L 1.6405 -2.05995 1.68911004 -2.05995 0 P 0 ;0
L 1.69945 -2.05995 1.74248002 -2.05995 0 P 0 ;0
L 1.64016004 -2.05895 1.68883002 -2.05895 0 P 0 ;0
L 1.69973996 -2.05895 1.74288996 -2.05895 0 P 0 ;0
L 1.63981004 -2.05795 1.68855 -2.05795 0 P 0 ;0
L 1.70003996 -2.05795 1.74328996 -2.05795 0 P 0 ;0
L 1.63946004 -2.05695 1.68826998 -2.05695 0 P 0 ;0
L 1.70033002 -2.05695 1.7437 -2.05695 0 P 0 ;0
L 1.63911004 -2.05595 1.68798996 -2.05595 0 P 0 ;0
L 1.70063002 -2.05595 1.7441 -2.05595 0 P 0 ;0
L 1.63876998 -2.05495 1.68771004 -2.05495 0 P 0 ;0
L 1.70091998 -2.05495 1.74451004 -2.05495 0 P 0 ;0
L 1.63841998 -2.05395 1.68741998 -2.05395 0 P 0 ;0
L 1.70121998 -2.05395 1.74491004 -2.05395 0 P 0 ;0
L 1.63806998 -2.05295 1.68713996 -2.05295 0 P 0 ;0
L 1.70151004 -2.05295 1.74531004 -2.05295 0 P 0 ;0
L 1.63771998 -2.05195 1.68686004 -2.05195 0 P 0 ;0
L 1.70181004 -2.05195 1.74571998 -2.05195 0 P 0 ;0
L 1.63738002 -2.05095 1.68658002 -2.05095 0 P 0 ;0
L 1.7021 -2.05095 1.74611998 -2.05095 0 P 0 ;0
L 1.63703002 -2.04995 1.6863 -2.04995 0 P 0 ;0
L 1.7024 -2.04995 1.74653002 -2.04995 0 P 0 ;0
L 1.63668002 -2.04895 1.68601998 -2.04895 0 P 0 ;0
L 1.70268996 -2.04895 1.74693002 -2.04895 0 P 0 ;0
L 1.63633002 -2.04795 1.68573996 -2.04795 0 P 0 ;0
L 1.70298996 -2.04795 1.74733002 -2.04795 0 P 0 ;0
L 1.63598002 -2.04695 1.68546004 -2.04695 0 P 0 ;0
L 1.70328002 -2.04695 1.74773996 -2.04695 0 P 0 ;0
L 1.63563996 -2.04595 1.68518002 -2.04595 0 P 0 ;0
L 1.70358002 -2.04595 1.74813996 -2.04595 0 P 0 ;0
L 1.63528996 -2.04495 1.6849 -2.04495 0 P 0 ;0
L 1.70386998 -2.04495 1.74855 -2.04495 0 P 0 ;0
L 1.63493996 -2.04395 1.68461004 -2.04395 0 P 0 ;0
L 1.70416998 -2.04395 1.74895 -2.04395 0 P 0 ;0
L 1.63458996 -2.04295 1.68433002 -2.04295 0 P 0 ;0
L 1.70446004 -2.04295 1.74936004 -2.04295 0 P 0 ;0
L 1.63425 -2.04195 1.68405 -2.04195 0 P 0 ;0
L 1.70475 -2.04195 1.74976004 -2.04195 0 P 0 ;0
L 1.6339 -2.04095 1.68376998 -2.04095 0 P 0 ;0
L 1.70503002 -2.04095 1.75016004 -2.04095 0 P 0 ;0
L 1.63355 -2.03995 1.68348996 -2.03995 0 P 0 ;0
L 1.70531998 -2.03995 1.75056998 -2.03995 0 P 0 ;0
L 1.6332 -2.03895 1.68321004 -2.03895 0 P 0 ;0
L 1.7056 -2.03895 1.75096998 -2.03895 0 P 0 ;0
L 1.63286004 -2.03795 1.68293002 -2.03795 0 P 0 ;0
L 1.70588996 -2.03795 1.75138002 -2.03795 0 P 0 ;0
L 1.63251004 -2.03695 1.68266004 -2.03695 0 P 0 ;0
L 1.70618002 -2.03695 1.75178002 -2.03695 0 P 0 ;0
L 1.63216004 -2.03595 1.68238002 -2.03595 0 P 0 ;0
L 1.70646998 -2.03595 1.75218996 -2.03595 0 P 0 ;0
L 1.63181004 -2.03495 1.6821 -2.03495 0 P 0 ;0
L 1.70675 -2.03495 1.75258996 -2.03495 0 P 0 ;0
L 1.63146998 -2.03395 1.68183002 -2.03395 0 P 0 ;0
L 1.70703996 -2.03395 1.75298996 -2.03395 0 P 0 ;0
L 1.63111998 -2.03295 1.68155 -2.03295 0 P 0 ;0
L 1.70733002 -2.03295 1.7534 -2.03295 0 P 0 ;0
L 1.63076998 -2.03195 1.68126998 -2.03195 0 P 0 ;0
L 1.70761004 -2.03195 1.75381004 -2.03195 0 P 0 ;0
L 1.63041998 -2.03095 1.68098996 -2.03095 0 P 0 ;0
L 1.7079 -2.03095 1.75421004 -2.03095 0 P 0 ;0
L 1.63006998 -2.02995 1.68071004 -2.02995 0 P 0 ;0
L 1.70818996 -2.02995 1.75461004 -2.02995 0 P 0 ;0
L 1.62973002 -2.02895 1.68043996 -2.02895 0 P 0 ;0
L 1.70846998 -2.02895 1.75501998 -2.02895 0 P 0 ;0
L 1.62938002 -2.02795 1.68016004 -2.02795 0 P 0 ;0
L 1.70876004 -2.02795 1.75541998 -2.02795 0 P 0 ;0
L 1.62903002 -2.02695 1.67988002 -2.02695 0 P 0 ;0
L 1.70905 -2.02695 1.75583002 -2.02695 0 P 0 ;0
L 1.62868002 -2.02595 1.6796 -2.02595 0 P 0 ;0
L 1.70933996 -2.02595 1.75623002 -2.02595 0 P 0 ;0
L 1.62831004 -2.02495 1.67933002 -2.02495 0 P 0 ;0
L 1.70961998 -2.02495 1.75663996 -2.02495 0 P 0 ;0
L 1.62793996 -2.02395 1.67905 -2.02395 0 P 0 ;0
L 1.70991004 -2.02395 1.75703996 -2.02395 0 P 0 ;0
L 1.62756998 -2.02295 1.67876998 -2.02295 0 P 0 ;0
L 1.7102 -2.02295 1.75743996 -2.02295 0 P 0 ;0
L 1.6272 -2.02195 1.6785 -2.02195 0 P 0 ;0
L 1.71048002 -2.02195 1.75785 -2.02195 0 P 0 ;0
L 1.62683002 -2.02095 1.67821998 -2.02095 0 P 0 ;0
L 1.71076004 -2.02095 1.75825 -2.02095 0 P 0 ;0
L 1.62646998 -2.01995 1.67793996 -2.01995 0 P 0 ;0
L 1.71101004 -2.01995 1.75866004 -2.01995 0 P 0 ;0
L 1.6261 -2.01895 1.67766004 -2.01895 0 P 0 ;0
L 1.71126998 -2.01895 1.75906004 -2.01895 0 P 0 ;0
L 1.62573002 -2.01795 1.67738996 -2.01795 0 P 0 ;0
L 1.71151998 -2.01795 1.75946998 -2.01795 0 P 0 ;0
L 1.62536004 -2.01695 1.67711004 -2.01695 0 P 0 ;0
L 1.71176998 -2.01695 1.75986998 -2.01695 0 P 0 ;0
L 1.62498996 -2.01595 1.67683002 -2.01595 0 P 0 ;0
L 1.71203002 -2.01595 1.76026998 -2.01595 0 P 0 ;0
L 1.62461998 -2.01495 1.67656004 -2.01495 0 P 0 ;0
L 1.71228002 -2.01495 1.76068002 -2.01495 0 P 0 ;0
L 1.62425 -2.01395 1.67628002 -2.01395 0 P 0 ;0
L 1.71253996 -2.01395 1.76108002 -2.01395 0 P 0 ;0
L 1.62388002 -2.01295 1.67601998 -2.01295 0 P 0 ;0
L 1.71278996 -2.01295 1.76148996 -2.01295 0 P 0 ;0
L 1.62351004 -2.01195 1.67576998 -2.01195 0 P 0 ;0
L 1.71305 -2.01195 1.76188996 -2.01195 0 P 0 ;0
L 1.62313996 -2.01095 1.67551998 -2.01095 0 P 0 ;0
L 1.7133 -2.01095 1.76228996 -2.01095 0 P 0 ;0
L 1.62276998 -2.00995 1.67528002 -2.00995 0 P 0 ;0
L 1.71355 -2.00995 1.7627 -2.00995 0 P 0 ;0
L 1.6224 -2.00895 1.67503002 -2.00895 0 P 0 ;0
L 1.71381004 -2.00895 1.7631 -2.00895 0 P 0 ;0
L 1.62203002 -2.00795 1.67478996 -2.00795 0 P 0 ;0
L 1.71406004 -2.00795 1.76351004 -2.00795 0 P 0 ;0
L 1.62166004 -2.00695 1.67453996 -2.00695 0 P 0 ;0
L 1.71431004 -2.00695 1.76391004 -2.00695 0 P 0 ;0
L 1.62128996 -2.00595 1.67428996 -2.00595 0 P 0 ;0
L 1.71453996 -2.00595 1.76431998 -2.00595 0 P 0 ;0
L 1.62091004 -2.00495 1.67405 -2.00495 0 P 0 ;0
L 1.71476998 -2.00495 1.76471998 -2.00495 0 P 0 ;0
L 1.62051998 -2.00395 1.6738 -2.00395 0 P 0 ;0
L 1.715 -2.00395 1.76511998 -2.00395 0 P 0 ;0
L 1.62013002 -2.00295 1.67355 -2.00295 0 P 0 ;0
L 1.71523002 -2.00295 1.76553002 -2.00295 0 P 0 ;0
L 1.61973996 -2.00195 1.67331004 -2.00195 0 P 0 ;0
L 1.71546004 -2.00195 1.76593996 -2.00195 0 P 0 ;0
L 1.61935 -2.00095 1.67306004 -2.00095 0 P 0 ;0
L 1.71568996 -2.00095 1.76633996 -2.00095 0 P 0 ;0
L 1.61896004 -1.99995 1.67283996 -1.99995 0 P 0 ;0
L 1.71591998 -1.99995 1.76673996 -1.99995 0 P 0 ;0
L 1.61856998 -1.99895 1.67261998 -1.99895 0 P 0 ;0
L 1.71613996 -1.99895 1.76715 -1.99895 0 P 0 ;0
L 1.71638002 -1.99795 1.76755 -1.99795 0 P 0 ;0
L 1.7166 -1.99695 1.76796004 -1.99695 0 P 0 ;0
L 1.71683002 -1.99595 1.76836004 -1.99595 0 P 0 ;0
L 1.71866998 -1.99495 1.76876998 -1.99495 0 P 0 ;0
L 1.78213996 -2.04823996 1.84641998 -2.04823996 0 P 0 ;0
L 1.78138002 -2.04723996 1.84498996 -2.04723996 0 P 0 ;0
L 1.78071004 -2.04623996 1.84356004 -2.04623996 0 P 0 ;0
L 1.7801 -2.04523996 1.84213996 -2.04523996 0 P 0 ;0
L 1.77956004 -2.04423996 1.84071004 -2.04423996 0 P 0 ;0
L 1.77908996 -2.04323996 1.83928002 -2.04323996 0 P 0 ;0
L 1.77866004 -2.04223996 1.83786004 -2.04223996 0 P 0 ;0
L 1.77831004 -2.04123996 1.83658996 -2.04123996 0 P 0 ;0
L 1.77796004 -2.04023996 1.83536004 -2.04023996 0 P 0 ;0
L 1.77761004 -2.03923996 1.83428002 -2.03923996 0 P 0 ;0
L 1.77733996 -2.03823996 1.83321998 -2.03823996 0 P 0 ;0
L 1.77706998 -2.03723996 1.83236998 -2.03723996 0 P 0 ;0
L 1.7768 -2.03623996 1.83171004 -2.03623996 0 P 0 ;0
L 1.7766 -2.03523996 1.83121004 -2.03523996 0 P 0 ;0
L 1.77641004 -2.03423996 1.83085 -2.03423996 0 P 0 ;0
L 1.77621004 -2.03323996 1.83071004 -2.03323996 0 P 0 ;0
L 1.77608002 -2.03223996 1.83076998 -2.03223996 0 P 0 ;0
L 1.77596004 -2.03123996 1.83106004 -2.03123996 0 P 0 ;0
L 1.77583996 -2.03023996 1.83158996 -2.03023996 0 P 0 ;0
L 1.77576004 -2.02923996 1.83238002 -2.02923996 0 P 0 ;0
L 1.7757 -2.02823996 1.83356998 -2.02823996 0 P 0 ;0
L 1.7757 -2.02723996 1.83591998 -2.02723996 0 P 0 ;0
L 1.77571998 -2.02623996 1.87495 -2.02623996 0 P 0 ;0
L 1.7758 -2.02523996 1.87485 -2.02523996 0 P 0 ;0
L 1.77588996 -2.02423996 1.87475 -2.02423996 0 P 0 ;0
L 1.77605 -2.02323996 1.87465 -2.02323996 0 P 0 ;0
L 1.77621004 -2.02223996 1.87455 -2.02223996 0 P 0 ;0
L 1.7764 -2.02123996 1.87445 -2.02123996 0 P 0 ;0
L 1.77665 -2.02023996 1.87433996 -2.02023996 0 P 0 ;0
L 1.7769 -2.01923996 1.87425 -2.01923996 0 P 0 ;0
L 1.7772 -2.01823996 1.87413996 -2.01823996 0 P 0 ;0
L 1.77753002 -2.01723996 1.87405 -2.01723996 0 P 0 ;0
L 1.77786004 -2.01623996 1.87393996 -2.01623996 0 P 0 ;0
L 1.77823002 -2.01523996 1.87383996 -2.01523996 0 P 0 ;0
L 1.77863996 -2.01423996 1.87373996 -2.01423996 0 P 0 ;0
L 1.77903996 -2.01323996 1.87363996 -2.01323996 0 P 0 ;0
L 1.7795 -2.01223996 1.87353996 -2.01223996 0 P 0 ;0
L 1.77998996 -2.01123996 1.87343996 -2.01123996 0 P 0 ;0
L 1.78046998 -2.01023996 1.87333002 -2.01023996 0 P 0 ;0
L 1.78103996 -2.00923996 1.87323002 -2.00923996 0 P 0 ;0
L 1.78161004 -2.00823996 1.87311998 -2.00823996 0 P 0 ;0
L 1.78221004 -2.00723996 1.87301998 -2.00723996 0 P 0 ;0
L 1.78288002 -2.00623996 1.87291998 -2.00623996 0 P 0 ;0
L 1.64213996 -2.14795 1.70566004 -2.14795 0 P 0 ;0
L 1.64518996 -2.14695 1.7062 -2.14695 0 P 0 ;0
L 1.64728996 -2.14595 1.70673996 -2.14595 0 P 0 ;0
L 1.64906998 -2.14495 1.70728002 -2.14495 0 P 0 ;0
L 1.65058002 -2.14395 1.70783002 -2.14395 0 P 0 ;0
L 1.6519 -2.14295 1.70836998 -2.14295 0 P 0 ;0
L 1.65311998 -2.14195 1.70881998 -2.14195 0 P 0 ;0
L 1.65416998 -2.14095 1.70926998 -2.14095 0 P 0 ;0
L 1.65508996 -2.13995 1.70973002 -2.13995 0 P 0 ;0
L 1.65588002 -2.13895 1.71018002 -2.13895 0 P 0 ;0
L 1.65658002 -2.13795 1.71063002 -2.13795 0 P 0 ;0
L 1.65726998 -2.13695 1.71108996 -2.13695 0 P 0 ;0
L 1.65791998 -2.13595 1.71153996 -2.13595 0 P 0 ;0
L 1.65853002 -2.13495 1.71198996 -2.13495 0 P 0 ;0
L 1.65913002 -2.13395 1.71245 -2.13395 0 P 0 ;0
L 1.65968002 -2.13295 1.7129 -2.13295 0 P 0 ;0
L 1.66021998 -2.13195 1.71331004 -2.13195 0 P 0 ;0
L 1.66071998 -2.13095 1.71371998 -2.13095 0 P 0 ;0
L 1.66121004 -2.12995 1.71411998 -2.12995 0 P 0 ;0
L 1.66166998 -2.12895 1.71453002 -2.12895 0 P 0 ;0
L 1.66201004 -2.12795 1.71493996 -2.12795 0 P 0 ;0
L 1.66223996 -2.12695 1.71533996 -2.12695 0 P 0 ;0
L 1.66235 -2.12595 1.71575 -2.12595 0 P 0 ;0
L 1.66236004 -2.12495 1.71615 -2.12495 0 P 0 ;0
L 1.66228002 -2.12395 1.71656004 -2.12395 0 P 0 ;0
L 1.66211998 -2.12295 1.71696004 -2.12295 0 P 0 ;0
L 1.66188002 -2.12195 1.71736004 -2.12195 0 P 0 ;0
L 1.66156004 -2.12095 1.71776998 -2.12095 0 P 0 ;0
L 1.66121004 -2.11995 1.71818002 -2.11995 0 P 0 ;0
L 1.66086998 -2.11895 1.71858002 -2.11895 0 P 0 ;0
L 1.66053002 -2.11795 1.71898996 -2.11795 0 P 0 ;0
L 1.66018002 -2.11695 1.71938996 -2.11695 0 P 0 ;0
L 1.65983996 -2.11595 1.7198 -2.11595 0 P 0 ;0
L 1.65948996 -2.11495 1.7202 -2.11495 0 P 0 ;0
L 1.65913996 -2.11395 1.72061004 -2.11395 0 P 0 ;0
L 1.6588 -2.11295 1.72101004 -2.11295 0 P 0 ;0
L 1.65846004 -2.11195 1.72141998 -2.11195 0 P 0 ;0
L 1.65811004 -2.11095 1.72181998 -2.11095 0 P 0 ;0
L 1.65776998 -2.10995 1.72223002 -2.10995 0 P 0 ;0
L 1.65741998 -2.10895 1.72263002 -2.10895 0 P 0 ;0
L 1.65708002 -2.10795 1.72303996 -2.10795 0 P 0 ;0
L 1.65673002 -2.10695 1.72343996 -2.10695 0 P 0 ;0
L 1.65638996 -2.10595 1.72385 -2.10595 0 P 0 ;0
L 1.65605 -2.10495 1.72425 -2.10495 0 P 0 ;0
L 1.6557 -2.10395 1.72466004 -2.10395 0 P 0 ;0
L 1.65536004 -2.10295 1.72506998 -2.10295 0 P 0 ;0
L 1.65501004 -2.10195 1.72546998 -2.10195 0 P 0 ;0
L 1.65466998 -2.10095 1.72588002 -2.10095 0 P 0 ;0
L 1.65431998 -2.09995 1.72628002 -2.09995 0 P 0 ;0
L 1.65398002 -2.09895 1.72668996 -2.09895 0 P 0 ;0
L 1.65363002 -2.09795 1.72708996 -2.09795 0 P 0 ;0
L 1.65328996 -2.09695 1.72748996 -2.09695 0 P 0 ;0
L 1.65293996 -2.09595 1.7279 -2.09595 0 P 0 ;0
L 1.6526 -2.09495 1.72831004 -2.09495 0 P 0 ;0
L 1.65225 -2.09395 1.72871004 -2.09395 0 P 0 ;0
L 1.65191004 -2.09295 1.72911998 -2.09295 0 P 0 ;0
L 1.65156998 -2.09195 1.72951998 -2.09195 0 P 0 ;0
L 1.65121998 -2.09095 1.72993002 -2.09095 0 P 0 ;0
L 1.65088002 -2.08995 1.73033002 -2.08995 0 P 0 ;0
L 1.65053002 -2.08895 1.73073996 -2.08895 0 P 0 ;0
L 1.65018996 -2.08795 1.73113996 -2.08795 0 P 0 ;0
L 1.64983996 -2.08695 1.73155 -2.08695 0 P 0 ;0
L 1.6495 -2.08595 1.73195 -2.08595 0 P 0 ;0
L 1.64915 -2.08495 1.73236004 -2.08495 0 P 0 ;0
L 1.64881004 -2.08395 1.73276004 -2.08395 0 P 0 ;0
L 1.81726998 -1.98915 1.81196004 -1.9899 0 P 0 ;0
L 1.81196004 -1.9899 1.80668996 -1.99096998 0 P 0 ;0
L 1.80668996 -1.99096998 1.8019 -1.99226004 0 P 0 ;0
L 1.8019 -1.99226004 1.79718996 -1.99391004 0 P 0 ;0
L 1.79718996 -1.99391004 1.79316004 -1.99568002 0 P 0 ;0
L 1.79316004 -1.99568002 1.78926998 -1.99778002 0 P 0 ;0
L 1.78926998 -1.99778002 1.78771004 -1.99878002 0 P 0 ;0
L 1.78771004 -1.99878002 1.78623002 -1.99988002 0 P 0 ;0
L 1.78623002 -1.99988002 1.78481004 -2.00108002 0 P 0 ;0
L 1.78481004 -2.00108002 1.78346998 -2.00238996 0 P 0 ;0
L 1.78346998 -2.00238996 1.78228996 -2.00371998 0 P 0 ;0
L 1.78228996 -2.00371998 1.78121004 -2.00513002 0 P 0 ;0
L 1.78121004 -2.00513002 1.78023002 -2.00661004 0 P 0 ;0
L 1.78023002 -2.00661004 1.77868002 -2.00933996 0 P 0 ;0
L 1.77868002 -2.00933996 1.77731998 -2.01216998 0 P 0 ;0
L 1.77731998 -2.01216998 1.77611004 -2.01516004 0 P 0 ;0
L 1.77611004 -2.01516004 1.77508996 -2.01823002 0 P 0 ;0
L 1.77508996 -2.01823002 1.77436998 -2.02111004 0 P 0 ;0
L 1.77436998 -2.02111004 1.77388996 -2.02406004 0 P 0 ;0
L 1.77388996 -2.02406004 1.77371998 -2.02603996 0 P 0 ;0
L 1.77371998 -2.02603996 1.77368996 -2.02801998 0 P 0 ;0
L 1.77368996 -2.02801998 1.7738 -2.03001998 0 P 0 ;0
L 1.7738 -2.03001998 1.7742 -2.03338996 0 P 0 ;0
L 1.7742 -2.03338996 1.77485 -2.03671004 0 P 0 ;0
L 1.77485 -2.03671004 1.77573002 -2.03993996 0 P 0 ;0
L 1.77573002 -2.03993996 1.77683996 -2.04308002 0 P 0 ;0
L 1.77683996 -2.04308002 1.7776 -2.04481998 0 P 0 ;0
L 1.7776 -2.04481998 1.7785 -2.04648996 0 P 0 ;0
L 1.7785 -2.04648996 1.77953002 -2.04808996 0 P 0 ;0
L 1.77953002 -2.04808996 1.78061004 -2.04953996 0 P 0 ;0
L 1.78061004 -2.04953996 1.78181004 -2.05091004 0 P 0 ;0
L 1.78181004 -2.05091004 1.78311004 -2.05218996 0 P 0 ;0
L 1.78311004 -2.05218996 1.78988996 -2.05801998 0 P 0 ;0
L 1.78988996 -2.05801998 1.79883996 -2.06491004 0 P 0 ;0
L 1.79883996 -2.06491004 1.80976998 -2.07261004 0 P 0 ;0
L 1.80976998 -2.07261004 1.81753002 -2.07823002 0 P 0 ;0
L 1.81753002 -2.07823002 1.81896998 -2.07943002 0 P 0 ;0
L 1.81896998 -2.07943002 1.82033002 -2.08073002 0 P 0 ;0
L 1.82033002 -2.08073002 1.82156998 -2.08213996 0 P 0 ;0
L 1.82156998 -2.08213996 1.82186004 -2.08251004 0 P 0 ;0
L 1.82186004 -2.08251004 1.82211004 -2.0829 0 P 0 ;0
L 1.82211004 -2.0829 1.82233002 -2.08331004 0 P 0 ;0
L 1.82233002 -2.08331004 1.82253002 -2.08373996 0 P 0 ;0
L 1.82253002 -2.08373996 1.82268002 -2.08418002 0 P 0 ;0
L 1.82268002 -2.08418002 1.82281004 -2.08463002 0 P 0 ;0
L 1.82281004 -2.08463002 1.8229 -2.0851 0 P 0 ;0
L 1.8229 -2.0851 1.82293002 -2.08533996 0 P 0 ;0
L 1.82293002 -2.08533996 1.82293996 -2.08558996 0 P 0 ;0
L 1.82293996 -2.08558996 1.82291998 -2.08583996 0 P 0 ;0
L 1.82291998 -2.08583996 1.82288002 -2.08608002 0 P 0 ;0
L 1.82288002 -2.08608002 1.82283002 -2.08631998 0 P 0 ;0
L 1.82283002 -2.08631998 1.82275 -2.08656004 0 P 0 ;0
L 1.82275 -2.08656004 1.82265 -2.08678996 0 P 0 ;0
L 1.82265 -2.08678996 1.82253996 -2.087 0 P 0 ;0
L 1.82253996 -2.087 1.8224 -2.08721004 0 P 0 ;0
L 1.8224 -2.08721004 1.82225 -2.08741004 0 P 0 ;0
L 1.82225 -2.08741004 1.82208996 -2.08758996 0 P 0 ;0
L 1.82208996 -2.08758996 1.8216 -2.08803996 0 P 0 ;0
L 1.8216 -2.08803996 1.82106998 -2.08845 0 P 0 ;0
L 1.82106998 -2.08845 1.82051004 -2.08881004 0 P 0 ;0
L 1.82051004 -2.08881004 1.81991998 -2.08911998 0 P 0 ;0
L 1.81991998 -2.08911998 1.81931004 -2.08936998 0 P 0 ;0
L 1.81931004 -2.08936998 1.81868002 -2.08958002 0 P 0 ;0
L 1.81868002 -2.08958002 1.81803002 -2.08973002 0 P 0 ;0
L 1.81803002 -2.08973002 1.81736004 -2.08981998 0 P 0 ;0
L 1.81736004 -2.08981998 1.81293002 -2.09001998 0 P 0 ;0
L 1.81293002 -2.09001998 1.80846998 -2.08986004 0 P 0 ;0
L 1.80846998 -2.08986004 1.80256998 -2.08923002 0 P 0 ;0
L 1.80256998 -2.08923002 1.79668002 -2.08818996 0 P 0 ;0
L 1.79668002 -2.08818996 1.78223002 -2.08458002 0 P 0 ;0
L 1.78223002 -2.08458002 1.77788996 -2.08338002 0 P 0 ;0
L 1.77788996 -2.08338002 1.77415 -2.08246004 0 P 0 ;0
L 1.77415 -2.08246004 1.77095 -2.08175 0 P 0 ;0
L 1.77095 -2.08175 1.7709 -2.08173996 0 P 0 ;0
L 1.7709 -2.08173996 1.77076998 -2.08173996 0 P 0 ;0
L 1.77076998 -2.08173996 1.77068996 -2.08176004 0 P 0 ;0
L 1.77068996 -2.08176004 1.77053002 -2.08183996 0 P 0 ;0
L 1.77053002 -2.08183996 1.77043002 -2.08193996 0 P 0 ;0
L 1.77043002 -2.08193996 1.77036998 -2.08201998 0 P 0 ;0
L 1.77036998 -2.08201998 1.77031998 -2.08211998 0 P 0 ;0
L 1.77031998 -2.08211998 1.7703 -2.08216998 0 P 0 ;0
L 1.7703 -2.08216998 1.77028996 -2.08223002 0 P 0 ;0
L 1.77028996 -2.08223002 1.77028002 -2.08228002 0 P 0 ;0
L 1.77028002 -2.08228002 1.77028002 -2.08238996 0 P 0 ;0
L 1.77028002 -2.08238996 1.77056998 -2.08838996 0 P 0 ;0
L 1.77056998 -2.08838996 1.77096004 -2.09526004 0 P 0 ;0
L 1.77096004 -2.09526004 1.77153996 -2.1033 0 P 0 ;0
L 1.77153996 -2.1033 1.77236004 -2.11291004 0 P 0 ;0
L 1.77236004 -2.11291004 1.77311004 -2.1194 0 P 0 ;0
L 1.77311004 -2.1194 1.77383002 -2.12398002 0 P 0 ;0
L 1.77383002 -2.12398002 1.77386004 -2.12411004 0 P 0 ;0
L 1.77386004 -2.12411004 1.7739 -2.12423002 0 P 0 ;0
L 1.7739 -2.12423002 1.77395 -2.12436004 0 P 0 ;0
L 1.77395 -2.12436004 1.77401004 -2.12448002 0 P 0 ;0
L 1.77401004 -2.12448002 1.77408002 -2.12458996 0 P 0 ;0
L 1.77408002 -2.12458996 1.77416004 -2.1247 0 P 0 ;0
L 1.77416004 -2.1247 1.77425 -2.1248 0 P 0 ;0
L 1.77425 -2.1248 1.77435 -2.12488996 0 P 0 ;0
L 1.77435 -2.12488996 1.77445 -2.12496998 0 P 0 ;0
L 1.77445 -2.12496998 1.77456998 -2.12505 0 P 0 ;0
L 1.77456998 -2.12505 1.77571004 -2.12568996 0 P 0 ;0
L 1.77571004 -2.12568996 1.7769 -2.12623996 0 P 0 ;0
L 1.7769 -2.12623996 1.77813002 -2.12668996 0 P 0 ;0
L 1.77813002 -2.12668996 1.7794 -2.12703996 0 P 0 ;0
L 1.7794 -2.12703996 1.78068996 -2.12728996 0 P 0 ;0
L 1.78068996 -2.12728996 1.79791998 -2.12951004 0 P 0 ;0
L 1.79791998 -2.12951004 1.81536004 -2.13106004 0 P 0 ;0
L 1.81536004 -2.13106004 1.82125 -2.13123996 0 P 0 ;0
L 1.82125 -2.13123996 1.82716004 -2.13098996 0 P 0 ;0
L 1.82716004 -2.13098996 1.83583996 -2.12998002 0 P 0 ;0
L 1.83583996 -2.12998002 1.84445 -2.12836004 0 P 0 ;0
L 1.84445 -2.12836004 1.84911998 -2.12711004 0 P 0 ;0
L 1.84911998 -2.12711004 1.85366004 -2.12548002 0 P 0 ;0
L 1.85366004 -2.12548002 1.85806998 -2.12348002 0 P 0 ;0
L 1.85806998 -2.12348002 1.86078996 -2.12196998 0 P 0 ;0
L 1.86078996 -2.12196998 1.8634 -2.12026998 0 P 0 ;0
L 1.8634 -2.12026998 1.86586998 -2.11836998 0 P 0 ;0
L 1.86586998 -2.11836998 1.86821004 -2.11628002 0 P 0 ;0
L 1.86821004 -2.11628002 1.87026004 -2.11413002 0 P 0 ;0
L 1.87026004 -2.11413002 1.8721 -2.11181998 0 P 0 ;0
L 1.8721 -2.11181998 1.87375 -2.10936004 0 P 0 ;0
L 1.87375 -2.10936004 1.87516998 -2.10673996 0 P 0 ;0
L 1.87516998 -2.10673996 1.87605 -2.10483996 0 P 0 ;0
L 1.87605 -2.10483996 1.87683996 -2.10291004 0 P 0 ;0
L 1.87683996 -2.10291004 1.8772 -2.10188002 0 P 0 ;0
L 1.8772 -2.10188002 1.87748996 -2.10083002 0 P 0 ;0
L 1.87748996 -2.10083002 1.87771004 -2.09976998 0 P 0 ;0
L 1.87771004 -2.09976998 1.87798002 -2.09788996 0 P 0 ;0
L 1.87798002 -2.09788996 1.87811998 -2.09601004 0 P 0 ;0
L 1.87811998 -2.09601004 1.87821004 -2.08966998 0 P 0 ;0
L 1.87821004 -2.08966998 1.8781 -2.08353996 0 P 0 ;0
L 1.8781 -2.08353996 1.87798002 -2.08166004 0 P 0 ;0
L 1.87798002 -2.08166004 1.87773002 -2.07976998 0 P 0 ;0
L 1.87773002 -2.07976998 1.87753002 -2.07873996 0 P 0 ;0
L 1.87753002 -2.07873996 1.87726998 -2.07773996 0 P 0 ;0
L 1.87726998 -2.07773996 1.87695 -2.07673996 0 P 0 ;0
L 1.87695 -2.07673996 1.87628996 -2.07505 0 P 0 ;0
L 1.87628996 -2.07505 1.87553002 -2.07338002 0 P 0 ;0
L 1.87553002 -2.07338002 1.87441004 -2.07133996 0 P 0 ;0
L 1.87441004 -2.07133996 1.87313996 -2.06938002 0 P 0 ;0
L 1.87313996 -2.06938002 1.87171004 -2.06751004 0 P 0 ;0
L 1.87171004 -2.06751004 1.8688 -2.06416004 0 P 0 ;0
L 1.8688 -2.06416004 1.86566998 -2.06095 0 P 0 ;0
L 1.86566998 -2.06095 1.86181998 -2.05741998 0 P 0 ;0
L 1.86181998 -2.05741998 1.85778002 -2.05406998 0 P 0 ;0
L 1.85778002 -2.05406998 1.84833996 -2.04715 0 P 0 ;0
L 1.84833996 -2.04715 1.83913996 -2.0407 0 P 0 ;0
L 1.83913996 -2.0407 1.83686004 -2.0389 0 P 0 ;0
L 1.83686004 -2.0389 1.83471998 -2.03691998 0 P 0 ;0
L 1.83471998 -2.03691998 1.83428002 -2.03643002 0 P 0 ;0
L 1.83428002 -2.03643002 1.83386998 -2.0359 0 P 0 ;0
L 1.83386998 -2.0359 1.83351004 -2.03535 0 P 0 ;0
L 1.83351004 -2.03535 1.83318996 -2.03476004 0 P 0 ;0
L 1.83318996 -2.03476004 1.83291998 -2.03415 0 P 0 ;0
L 1.83291998 -2.03415 1.83283996 -2.03393996 0 P 0 ;0
L 1.83283996 -2.03393996 1.83278002 -2.03371004 0 P 0 ;0
L 1.83278002 -2.03371004 1.83273002 -2.03348996 0 P 0 ;0
L 1.83273002 -2.03348996 1.83271004 -2.03326004 0 P 0 ;0
L 1.83271004 -2.03326004 1.8327 -2.03303002 0 P 0 ;0
L 1.8327 -2.03303002 1.83271004 -2.0328 0 P 0 ;0
L 1.83271004 -2.0328 1.83275 -2.03258002 0 P 0 ;0
L 1.83275 -2.03258002 1.83278996 -2.03235 0 P 0 ;0
L 1.83278996 -2.03235 1.83286004 -2.03213002 0 P 0 ;0
L 1.83286004 -2.03213002 1.83293996 -2.03191998 0 P 0 ;0
L 1.83293996 -2.03191998 1.83305 -2.03171004 0 P 0 ;0
L 1.83305 -2.03171004 1.83325 -2.03135 0 P 0 ;0
L 1.83325 -2.03135 1.83348996 -2.03101998 0 P 0 ;0
L 1.83348996 -2.03101998 1.83375 -2.03071004 0 P 0 ;0
L 1.83375 -2.03071004 1.83403002 -2.03041004 0 P 0 ;0
L 1.83403002 -2.03041004 1.83433996 -2.03015 0 P 0 ;0
L 1.83433996 -2.03015 1.83466998 -2.02991004 0 P 0 ;0
L 1.83466998 -2.02991004 1.83501998 -2.02968996 0 P 0 ;0
L 1.83501998 -2.02968996 1.83538002 -2.02951004 0 P 0 ;0
L 1.83538002 -2.02951004 1.83576004 -2.02936004 0 P 0 ;0
L 1.83576004 -2.02936004 1.83615 -2.02923996 0 P 0 ;0
L 1.83615 -2.02923996 1.83655 -2.02915 0 P 0 ;0
L 1.83655 -2.02915 1.8392 -2.02873996 0 P 0 ;0
L 1.8392 -2.02873996 1.84188002 -2.0285 0 P 0 ;0
L 1.84188002 -2.0285 1.84458002 -2.02841004 0 P 0 ;0
L 1.84458002 -2.02841004 1.84993996 -2.02858002 0 P 0 ;0
L 1.84993996 -2.02858002 1.85526998 -2.02916004 0 P 0 ;0
L 1.85526998 -2.02916004 1.86155 -2.03023002 0 P 0 ;0
L 1.86155 -2.03023002 1.86778002 -2.03158002 0 P 0 ;0
L 1.86778002 -2.03158002 1.8713 -2.03238996 0 P 0 ;0
L 1.8713 -2.03238996 1.87428996 -2.03303002 0 P 0 ;0
L 1.87428996 -2.03303002 1.8769 -2.03356004 0 P 0 ;0
L 1.8769 -2.03356004 1.87691998 -2.03356998 0 P 0 ;0
L 1.87691998 -2.03356998 1.87696004 -2.03356998 0 P 0 ;0
L 1.87696004 -2.03356998 1.87696998 -2.03356004 0 P 0 ;0
L 1.87696998 -2.03356004 1.87701004 -2.03356004 0 P 0 ;0
L 1.87701004 -2.03356004 1.87703996 -2.03353996 0 P 0 ;0
L 1.87703996 -2.03353996 1.87706004 -2.03353002 0 P 0 ;0
L 1.87706004 -2.03353002 1.87706998 -2.03351998 0 P 0 ;0
L 1.87706998 -2.03351998 1.87708996 -2.03351004 0 P 0 ;0
L 1.87708996 -2.03351004 1.8771 -2.03348996 0 P 0 ;0
L 1.8771 -2.03348996 1.87711004 -2.03348002 0 P 0 ;0
L 1.87711004 -2.03348002 1.87721998 -2.0333 0 P 0 ;0
L 1.87721998 -2.0333 1.87731998 -2.0331 0 P 0 ;0
L 1.87731998 -2.0331 1.8774 -2.0329 0 P 0 ;0
L 1.8774 -2.0329 1.87746004 -2.03268996 0 P 0 ;0
L 1.87746004 -2.03268996 1.87751004 -2.03248002 0 P 0 ;0
L 1.87751004 -2.03248002 1.87753002 -2.03226998 0 P 0 ;0
L 1.87753002 -2.03226998 1.87753996 -2.03205 0 P 0 ;0
L 1.87753996 -2.03205 1.87753002 -2.03183002 0 P 0 ;0
L 1.87753002 -2.03183002 1.87565 -2.01323996 0 P 0 ;0
L 1.87565 -2.01323996 1.87371004 -1.99451998 0 P 0 ;0
L 1.87371004 -1.99451998 1.8737 -1.99438996 0 P 0 ;0
L 1.8737 -1.99438996 1.87366998 -1.99426998 0 P 0 ;0
L 1.87366998 -1.99426998 1.87363002 -1.99415 0 P 0 ;0
L 1.87363002 -1.99415 1.87358002 -1.99403002 0 P 0 ;0
L 1.87358002 -1.99403002 1.87351998 -1.99391004 0 P 0 ;0
L 1.87351998 -1.99391004 1.87346004 -1.9938 0 P 0 ;0
L 1.87346004 -1.9938 1.87338002 -1.9937 0 P 0 ;0
L 1.87338002 -1.9937 1.87328996 -1.9936 0 P 0 ;0
L 1.87328996 -1.9936 1.8732 -1.99351004 0 P 0 ;0
L 1.8732 -1.99351004 1.8731 -1.99343002 0 P 0 ;0
L 1.8731 -1.99343002 1.87298996 -1.99335 0 P 0 ;0
L 1.87298996 -1.99335 1.87248002 -1.99305 0 P 0 ;0
L 1.87248002 -1.99305 1.87193996 -1.99278002 0 P 0 ;0
L 1.87193996 -1.99278002 1.87136998 -1.99256998 0 P 0 ;0
L 1.87136998 -1.99256998 1.87078996 -1.99241004 0 P 0 ;0
L 1.87078996 -1.99241004 1.8702 -1.9923 0 P 0 ;0
L 1.8702 -1.9923 1.85876004 -1.99076004 0 P 0 ;0
L 1.85876004 -1.99076004 1.84691998 -1.98943002 0 P 0 ;0
L 1.84691998 -1.98943002 1.83693002 -1.98876004 0 P 0 ;0
L 1.83693002 -1.98876004 1.8318 -1.98863002 0 P 0 ;0
L 1.8318 -1.98863002 1.82623002 -1.98866998 0 P 0 ;0
L 1.82623002 -1.98866998 1.82106004 -1.98883996 0 P 0 ;0
L 1.82106004 -1.98883996 1.81726998 -1.98915 0 P 0 ;0
L 1.78061004 -2.12523996 1.84838002 -2.12523996 0 P 0 ;0
L 1.77733002 -2.12423996 1.85121004 -2.12423996 0 P 0 ;0
L 1.77573996 -2.12323996 1.85376998 -2.12323996 0 P 0 ;0
L 1.77558002 -2.12223996 1.85596998 -2.12223996 0 P 0 ;0
L 1.77541998 -2.12123996 1.85798996 -2.12123996 0 P 0 ;0
L 1.77526998 -2.12023996 1.85978996 -2.12023996 0 P 0 ;0
L 1.77511004 -2.11923996 1.86131998 -2.11923996 0 P 0 ;0
L 1.77498996 -2.11823996 1.86276004 -2.11823996 0 P 0 ;0
L 1.77486998 -2.11723996 1.86406998 -2.11723996 0 P 0 ;0
L 1.77475 -2.11623996 1.86526004 -2.11623996 0 P 0 ;0
L 1.77463996 -2.11523996 1.86638002 -2.11523996 0 P 0 ;0
L 1.77451998 -2.11423996 1.8674 -2.11423996 0 P 0 ;0
L 1.77441004 -2.11323996 1.86835 -2.11323996 0 P 0 ;0
L 1.77431004 -2.11223996 1.86921004 -2.11223996 0 P 0 ;0
L 1.77421998 -2.11123996 1.87001004 -2.11123996 0 P 0 ;0
L 1.77413996 -2.11023996 1.87075 -2.11023996 0 P 0 ;0
L 1.77405 -2.10923996 1.87141998 -2.10923996 0 P 0 ;0
L 1.77396998 -2.10823996 1.87208002 -2.10823996 0 P 0 ;0
L 1.77388002 -2.10723996 1.87261998 -2.10723996 0 P 0 ;0
L 1.7738 -2.10623996 1.87316998 -2.10623996 0 P 0 ;0
L 1.77371004 -2.10523996 1.87366004 -2.10523996 0 P 0 ;0
L 1.77363002 -2.10423996 1.87411998 -2.10423996 0 P 0 ;0
L 1.77353996 -2.10323996 1.87453996 -2.10323996 0 P 0 ;0
L 1.77346998 -2.10223996 1.87495 -2.10223996 0 P 0 ;0
L 1.7734 -2.10123996 1.8753 -2.10123996 0 P 0 ;0
L 1.77333002 -2.10023996 1.87556998 -2.10023996 0 P 0 ;0
L 1.77325 -2.09923996 1.87576998 -2.09923996 0 P 0 ;0
L 1.77318002 -2.09823996 1.87591998 -2.09823996 0 P 0 ;0
L 1.77311004 -2.09723996 1.87603002 -2.09723996 0 P 0 ;0
L 1.77303996 -2.09623996 1.8761 -2.09623996 0 P 0 ;0
L 1.77296998 -2.09523996 1.87613002 -2.09523996 0 P 0 ;0
L 1.77291004 -2.09423996 1.87613996 -2.09423996 0 P 0 ;0
L 1.77285 -2.09323996 1.87616004 -2.09323996 0 P 0 ;0
L 1.77278996 -2.09223996 1.87616998 -2.09223996 0 P 0 ;0
L 1.77273002 -2.09123996 1.80256998 -2.09123996 0 P 0 ;0
L 1.77268002 -2.09023996 1.7968 -2.09023996 0 P 0 ;0
L 1.77261998 -2.08923996 1.79263002 -2.08923996 0 P 0 ;0
L 1.77256004 -2.08823996 1.78861998 -2.08823996 0 P 0 ;0
L 1.77251004 -2.08723996 1.7846 -2.08723996 0 P 0 ;0
L 1.77246004 -2.08623996 1.7807 -2.08623996 0 P 0 ;0
L 1.77241998 -2.08523996 1.77705 -2.08523996 0 P 0 ;0
L 1.77236998 -2.08423996 1.77293996 -2.08423996 0 P 0 ;0
L 1.62463996 -2.18195 1.65948996 -2.18195 0 P 0 ;0
L 1.61963996 -2.18095 1.66483002 -2.18095 0 P 0 ;0
L 1.61818002 -1.99795 1.6724 -1.99795 0 P 0 ;0
L 1.61778996 -1.99695 1.67218002 -1.99695 0 P 0 ;0
L 1.6174 -1.99595 1.67196004 -1.99595 0 P 0 ;0
L 1.61701004 -1.99495 1.67173996 -1.99495 0 P 0 ;0
L 1.61391998 -2.15695 1.70026004 -2.15695 0 P 0 ;0
L 1.61386004 -2.15595 1.70088002 -2.15595 0 P 0 ;0
L 1.61381004 -2.15495 1.70151004 -2.15495 0 P 0 ;0
L 1.61375 -2.15395 1.70213996 -2.15395 0 P 0 ;0
L 1.6137 -2.15295 1.70276004 -2.15295 0 P 0 ;0
L 1.61365 -2.15195 1.70338996 -2.15195 0 P 0 ;0
L 1.6136 -2.15095 1.70401004 -2.15095 0 P 0 ;0
L 1.61355 -2.14995 1.70456998 -2.14995 0 P 0 ;0
L 1.61348996 -2.14895 1.70511998 -2.14895 0 P 0 ;0
L 1.61343996 -2.14795 1.61738002 -2.14795 0 P 0 ;0
L 1.55341004 -2.08286998 1.60538002 -2.08286998 0 P 0 ;0
L 1.55286004 -2.08186998 1.60526998 -2.08186998 0 P 0 ;0
L 1.5521 -2.08086998 1.6051 -2.08086998 0 P 0 ;0
L 1.55126998 -2.07986998 1.6049 -2.07986998 0 P 0 ;0
L 1.55033996 -2.07886998 1.60463996 -2.07886998 0 P 0 ;0
L 1.54928996 -2.07786998 1.60433002 -2.07786998 0 P 0 ;0
L 1.54806998 -2.07686998 1.60398996 -2.07686998 0 P 0 ;0
L 1.5467 -2.07586998 1.60356998 -2.07586998 0 P 0 ;0
L 1.54531004 -2.07486998 1.6031 -2.07486998 0 P 0 ;0
L 1.54391004 -2.07386998 1.60258996 -2.07386998 0 P 0 ;0
L 1.54251004 -2.07286998 1.60201004 -2.07286998 0 P 0 ;0
L 1.54111998 -2.07186998 1.60138002 -2.07186998 0 P 0 ;0
L 1.53971998 -2.07086998 1.60068002 -2.07086998 0 P 0 ;0
L 1.53833002 -2.06986998 1.59993002 -2.06986998 0 P 0 ;0
L 1.53693002 -2.06886998 1.59908002 -2.06886998 0 P 0 ;0
L 1.53556004 -2.06786998 1.59821004 -2.06786998 0 P 0 ;0
L 1.53418996 -2.06686998 1.59733996 -2.06686998 0 P 0 ;0
L 1.53281998 -2.06586998 1.59646998 -2.06586998 0 P 0 ;0
L 1.53145 -2.06486998 1.5955 -2.06486998 0 P 0 ;0
L 1.53008002 -2.06386998 1.59453002 -2.06386998 0 P 0 ;0
L 1.52871004 -2.06286998 1.59356004 -2.06286998 0 P 0 ;0
L 1.52733996 -2.06186998 1.59253002 -2.06186998 0 P 0 ;0
L 1.52596998 -2.06086998 1.59145 -2.06086998 0 P 0 ;0
L 1.5246 -2.05986998 1.59038002 -2.05986998 0 P 0 ;0
L 1.52323002 -2.05886998 1.5893 -2.05886998 0 P 0 ;0
L 1.52186004 -2.05786998 1.58813996 -2.05786998 0 P 0 ;0
L 1.52053996 -2.05686998 1.58696004 -2.05686998 0 P 0 ;0
L 1.51935 -2.05586998 1.58576998 -2.05586998 0 P 0 ;0
L 1.51816004 -2.05486998 1.58456998 -2.05486998 0 P 0 ;0
L 1.51706998 -2.05386998 1.58321004 -2.05386998 0 P 0 ;0
L 1.51603996 -2.05286998 1.58185 -2.05286998 0 P 0 ;0
L 1.51501998 -2.05186998 1.58048996 -2.05186998 0 P 0 ;0
L 1.51408996 -2.05086998 1.57913002 -2.05086998 0 P 0 ;0
L 1.5132 -2.04986998 1.57776998 -2.04986998 0 P 0 ;0
L 1.51231998 -2.04886998 1.57641998 -2.04886998 0 P 0 ;0
L 1.51151004 -2.04786998 1.57505 -2.04786998 0 P 0 ;0
L 1.51075 -2.04686998 1.57365 -2.04686998 0 P 0 ;0
L 1.51008002 -2.04586998 1.57223002 -2.04586998 0 P 0 ;0
L 1.50945 -2.04486998 1.57081004 -2.04486998 0 P 0 ;0
L 1.50888002 -2.04386998 1.56938996 -2.04386998 0 P 0 ;0
L 1.50836004 -2.04286998 1.56796998 -2.04286998 0 P 0 ;0
L 1.5079 -2.04186998 1.56655 -2.04186998 0 P 0 ;0
L 1.50748002 -2.04086998 1.56518996 -2.04086998 0 P 0 ;0
L 1.50708996 -2.03986998 1.564 -2.03986998 0 P 0 ;0
L 1.50676004 -2.03886998 1.56296998 -2.03886998 0 P 0 ;0
L 1.50641998 -2.03786998 1.56206004 -2.03786998 0 P 0 ;0
L 1.50616998 -2.03686998 1.56125 -2.03686998 0 P 0 ;0
L 1.50591004 -2.03586998 1.56066998 -2.03586998 0 P 0 ;0
L 1.5057 -2.03486998 1.56031998 -2.03486998 0 P 0 ;0
L 1.50551998 -2.03386998 1.56016004 -2.03386998 0 P 0 ;0
L 1.50533996 -2.03286998 1.56016998 -2.03286998 0 P 0 ;0
L 1.50523996 -2.03186998 1.56036004 -2.03186998 0 P 0 ;0
L 1.50513002 -2.03086998 1.56071998 -2.03086998 0 P 0 ;0
L 1.50506998 -2.02986998 1.56131004 -2.02986998 0 P 0 ;0
L 1.50503996 -2.02886998 1.5622 -2.02886998 0 P 0 ;0
L 1.50501004 -2.02786998 1.56355 -2.02786998 0 P 0 ;0
L 1.50501998 -2.02686998 1.5657 -2.02686998 0 P 0 ;0
L 1.50506998 -2.02586998 1.60378996 -2.02586998 0 P 0 ;0
L 1.50511998 -2.02486998 1.60371004 -2.02486998 0 P 0 ;0
L 1.50521004 -2.02386998 1.60363996 -2.02386998 0 P 0 ;0
L 1.50533996 -2.02286998 1.60356998 -2.02286998 0 P 0 ;0
L 1.50546998 -2.02186998 1.6035 -2.02186998 0 P 0 ;0
L 1.50563996 -2.02086998 1.60343002 -2.02086998 0 P 0 ;0
L 1.50585 -2.01986998 1.60336004 -2.01986998 0 P 0 ;0
L 1.50606004 -2.01886998 1.60328996 -2.01886998 0 P 0 ;0
L 1.50633002 -2.01786998 1.60321998 -2.01786998 0 P 0 ;0
L 1.50661998 -2.01686998 1.60315 -2.01686998 0 P 0 ;0
L 1.50691004 -2.01586998 1.60308002 -2.01586998 0 P 0 ;0
L 1.50726998 -2.01486998 1.603 -2.01486998 0 P 0 ;0
L 1.50766004 -2.01386998 1.60293002 -2.01386998 0 P 0 ;0
L 1.50808996 -2.01286998 1.60285 -2.01286998 0 P 0 ;0
L 1.50856998 -2.01186998 1.60278002 -2.01186998 0 P 0 ;0
L 1.50908996 -2.01086998 1.6027 -2.01086998 0 P 0 ;0
L 1.50966004 -2.00986998 1.60261998 -2.00986998 0 P 0 ;0
L 1.51028996 -2.00886998 1.60255 -2.00886998 0 P 0 ;0
L 1.51096998 -2.00786998 1.60246998 -2.00786998 0 P 0 ;0
L 1.51171998 -2.00686998 1.6024 -2.00686998 0 P 0 ;0
L 1.51253996 -2.00586998 1.60233002 -2.00586998 0 P 0 ;0
L 1.51343996 -2.00486998 1.60225 -2.00486998 0 P 0 ;0
L 1.5144 -2.00386998 1.60218002 -2.00386998 0 P 0 ;0
L 1.51551998 -2.00286998 1.6021 -2.00286998 0 P 0 ;0
L 1.51663996 -2.00186998 1.60203002 -2.00186998 0 P 0 ;0
L 1.51795 -2.00086998 1.60195 -2.00086998 0 P 0 ;0
L 1.51928996 -1.99986998 1.60183996 -1.99986998 0 P 0 ;0
L 1.52086998 -1.99886998 1.60173002 -1.99886998 0 P 0 ;0
L 1.52258996 -1.99786998 1.60156998 -1.99786998 0 P 0 ;0
L 1.52451004 -1.99686998 1.60138996 -1.99686998 0 P 0 ;0
L 1.52686998 -1.99586998 1.60106998 -1.99586998 0 P 0 ;0
L 1.52976004 -1.99486998 1.59943996 -1.99486998 0 P 0 ;0
L 1.53283002 -1.99386998 1.59543002 -1.99386998 0 P 0 ;0
L 1.53678996 -1.99286998 1.59003996 -1.99286998 0 P 0 ;0
L 1.54173996 -1.99186998 1.58073996 -1.99186998 0 P 0 ;0
L 1.55036998 -1.99086998 1.56493002 -1.99086998 0 P 0 ;0
L 1.6036 -2.03086998 1.60413996 -2.03086998 0 P 0 ;0
L 1.59891004 -2.02986998 1.60406998 -2.02986998 0 P 0 ;0
L 1.59435 -2.02886998 1.604 -2.02886998 0 P 0 ;0
L 1.58838996 -2.02786998 1.60393002 -2.02786998 0 P 0 ;0
L 1.57981004 -2.02686998 1.60386004 -2.02686998 0 P 0 ;0
L 1.54575 -1.98923996 1.53931998 -1.99021998 0 P 0 ;0
L 1.53931998 -1.99021998 1.53298996 -1.99171998 0 P 0 ;0
L 1.53298996 -1.99171998 1.52678996 -1.99373996 0 P 0 ;0
L 1.52678996 -1.99373996 1.52376998 -1.995 0 P 0 ;0
L 1.52376998 -1.995 1.52086998 -1.99651004 0 P 0 ;0
L 1.52086998 -1.99651004 1.5181 -1.99826004 0 P 0 ;0
L 1.5181 -1.99826004 1.51548002 -2.00023002 0 P 0 ;0
L 1.51548002 -2.00023002 1.51301004 -2.00243002 0 P 0 ;0
L 1.51301004 -2.00243002 1.51128996 -2.00423002 0 P 0 ;0
L 1.51128996 -2.00423002 1.50971998 -2.00616004 0 P 0 ;0
L 1.50971998 -2.00616004 1.50831004 -2.00821004 0 P 0 ;0
L 1.50831004 -2.00821004 1.50706998 -2.01036998 0 P 0 ;0
L 1.50706998 -2.01036998 1.50598996 -2.01261998 0 P 0 ;0
L 1.50598996 -2.01261998 1.50508996 -2.01496998 0 P 0 ;0
L 1.50508996 -2.01496998 1.5042 -2.01801004 0 P 0 ;0
L 1.5042 -2.01801004 1.50355 -2.02111004 0 P 0 ;0
L 1.50355 -2.02111004 1.50313996 -2.02426004 0 P 0 ;0
L 1.50313996 -2.02426004 1.50298996 -2.02743002 0 P 0 ;0
L 1.50298996 -2.02743002 1.50308996 -2.03063002 0 P 0 ;0
L 1.50308996 -2.03063002 1.50338002 -2.03326998 0 P 0 ;0
L 1.50338002 -2.03326998 1.50385 -2.03588002 0 P 0 ;0
L 1.50385 -2.03588002 1.50451004 -2.03845 0 P 0 ;0
L 1.50451004 -2.03845 1.50535 -2.04096998 0 P 0 ;0
L 1.50535 -2.04096998 1.50633002 -2.0433 0 P 0 ;0
L 1.50633002 -2.0433 1.5075 -2.04553002 0 P 0 ;0
L 1.5075 -2.04553002 1.50883996 -2.04766998 0 P 0 ;0
L 1.50883996 -2.04766998 1.51036998 -2.04968996 0 P 0 ;0
L 1.51036998 -2.04968996 1.51323002 -2.05291998 0 P 0 ;0
L 1.51323002 -2.05291998 1.51631998 -2.05593996 0 P 0 ;0
L 1.51631998 -2.05593996 1.51961998 -2.05871004 0 P 0 ;0
L 1.51961998 -2.05871004 1.53591004 -2.0706 0 P 0 ;0
L 1.53591004 -2.0706 1.54668002 -2.07831004 0 P 0 ;0
L 1.54668002 -2.07831004 1.54793996 -2.07933996 0 P 0 ;0
L 1.54793996 -2.07933996 1.54911998 -2.08046998 0 P 0 ;0
L 1.54911998 -2.08046998 1.55021004 -2.08168002 0 P 0 ;0
L 1.55021004 -2.08168002 1.5512 -2.08298996 0 P 0 ;0
L 1.5512 -2.08298996 1.55136004 -2.08323002 0 P 0 ;0
L 1.55136004 -2.08323002 1.5515 -2.08348002 0 P 0 ;0
L 1.5515 -2.08348002 1.55161004 -2.08373996 0 P 0 ;0
L 1.55161004 -2.08373996 1.5517 -2.08401998 0 P 0 ;0
L 1.5517 -2.08401998 1.55176998 -2.0843 0 P 0 ;0
L 1.55176998 -2.0843 1.55181004 -2.08458002 0 P 0 ;0
L 1.55181004 -2.08458002 1.55183002 -2.08486998 0 P 0 ;0
L 1.55183002 -2.08486998 1.55181998 -2.08516004 0 P 0 ;0
L 1.55181998 -2.08516004 1.55178996 -2.08545 0 P 0 ;0
L 1.55178996 -2.08545 1.55173996 -2.08573002 0 P 0 ;0
L 1.55173996 -2.08573002 1.55166004 -2.086 0 P 0 ;0
L 1.55166004 -2.086 1.55156004 -2.08628002 0 P 0 ;0
L 1.55156004 -2.08628002 1.55136998 -2.08666998 0 P 0 ;0
L 1.55136998 -2.08666998 1.55115 -2.08703996 0 P 0 ;0
L 1.55115 -2.08703996 1.5509 -2.08738996 0 P 0 ;0
L 1.5509 -2.08738996 1.55063002 -2.08771998 0 P 0 ;0
L 1.55063002 -2.08771998 1.55033002 -2.08803002 0 P 0 ;0
L 1.55033002 -2.08803002 1.55 -2.08831004 0 P 0 ;0
L 1.55 -2.08831004 1.54966004 -2.08856004 0 P 0 ;0
L 1.54966004 -2.08856004 1.54928996 -2.08878996 0 P 0 ;0
L 1.54928996 -2.08878996 1.5489 -2.08898996 0 P 0 ;0
L 1.5489 -2.08898996 1.54786004 -2.08941004 0 P 0 ;0
L 1.54786004 -2.08941004 1.54678996 -2.08973996 0 P 0 ;0
L 1.54678996 -2.08973996 1.54568002 -2.08998002 0 P 0 ;0
L 1.54568002 -2.08998002 1.54456998 -2.09011998 0 P 0 ;0
L 1.54456998 -2.09011998 1.54343996 -2.09016998 0 P 0 ;0
L 1.54343996 -2.09016998 1.53906998 -2.09003002 0 P 0 ;0
L 1.53906998 -2.09003002 1.53468002 -2.08961998 0 P 0 ;0
L 1.53468002 -2.08961998 1.52908996 -2.08878996 0 P 0 ;0
L 1.52908996 -2.08878996 1.52351004 -2.08766004 0 P 0 ;0
L 1.52351004 -2.08766004 1.51005 -2.08418996 0 P 0 ;0
L 1.51005 -2.08418996 1.50631004 -2.08318002 0 P 0 ;0
L 1.50631004 -2.08318002 1.50308002 -2.08238996 0 P 0 ;0
L 1.50308002 -2.08238996 1.50033996 -2.08183002 0 P 0 ;0
L 1.50033996 -2.08183002 1.5003 -2.08181998 0 P 0 ;0
L 1.5003 -2.08181998 1.50016004 -2.08181998 0 P 0 ;0
L 1.50016004 -2.08181998 1.50011998 -2.08183002 0 P 0 ;0
L 1.50011998 -2.08183002 1.50006998 -2.08183996 0 P 0 ;0
L 1.50006998 -2.08183996 1.50003002 -2.08186004 0 P 0 ;0
L 1.50003002 -2.08186004 1.49998996 -2.08186998 0 P 0 ;0
L 1.49998996 -2.08186998 1.49995 -2.08188996 0 P 0 ;0
L 1.49995 -2.08188996 1.49991004 -2.08191998 0 P 0 ;0
L 1.49991004 -2.08191998 1.49988002 -2.08195 0 P 0 ;0
L 1.49988002 -2.08195 1.49983996 -2.08198002 0 P 0 ;0
L 1.49983996 -2.08198002 1.4997 -2.08213996 0 P 0 ;0
L 1.4997 -2.08213996 1.49956004 -2.08231998 0 P 0 ;0
L 1.49956004 -2.08231998 1.49943996 -2.0825 0 P 0 ;0
L 1.49943996 -2.0825 1.49933996 -2.0827 0 P 0 ;0
L 1.49933996 -2.0827 1.49925 -2.0829 0 P 0 ;0
L 1.49925 -2.0829 1.49918996 -2.08311004 0 P 0 ;0
L 1.49918996 -2.08311004 1.49913996 -2.08333002 0 P 0 ;0
L 1.49913996 -2.08333002 1.49911004 -2.08355 0 P 0 ;0
L 1.49911004 -2.08355 1.4991 -2.08376998 0 P 0 ;0
L 1.4991 -2.08376998 1.49911004 -2.08398996 0 P 0 ;0
L 1.49911004 -2.08398996 1.50071004 -2.10395 0 P 0 ;0
L 1.50071004 -2.10395 1.5024 -2.12403996 0 P 0 ;0
L 1.5024 -2.12403996 1.50241998 -2.12418002 0 P 0 ;0
L 1.50241998 -2.12418002 1.50246004 -2.12431004 0 P 0 ;0
L 1.50246004 -2.12431004 1.50248996 -2.12445 0 P 0 ;0
L 1.50248996 -2.12445 1.50255 -2.12456998 0 P 0 ;0
L 1.50255 -2.12456998 1.50261004 -2.1247 0 P 0 ;0
L 1.50261004 -2.1247 1.50276998 -2.12491998 0 P 0 ;0
L 1.50276998 -2.12491998 1.50286004 -2.12501998 0 P 0 ;0
L 1.50286004 -2.12501998 1.50296998 -2.12511998 0 P 0 ;0
L 1.50296998 -2.12511998 1.50308002 -2.12521004 0 P 0 ;0
L 1.50308002 -2.12521004 1.50318996 -2.12528002 0 P 0 ;0
L 1.50318996 -2.12528002 1.50331998 -2.12535 0 P 0 ;0
L 1.50331998 -2.12535 1.50343996 -2.1254 0 P 0 ;0
L 1.50343996 -2.1254 1.50391998 -2.12556004 0 P 0 ;0
L 1.50391998 -2.12556004 1.5044 -2.12568996 0 P 0 ;0
L 1.5044 -2.12568996 1.50848002 -2.12648996 0 P 0 ;0
L 1.50848002 -2.12648996 1.51328996 -2.12738002 0 P 0 ;0
L 1.51328996 -2.12738002 1.51873996 -2.12833996 0 P 0 ;0
L 1.51873996 -2.12833996 1.52606004 -2.12945 0 P 0 ;0
L 1.52606004 -2.12945 1.53343996 -2.13023002 0 P 0 ;0
L 1.53343996 -2.13023002 1.54886998 -2.13086998 0 P 0 ;0
L 1.54886998 -2.13086998 1.56305 -2.1303 0 P 0 ;0
L 1.56305 -2.1303 1.56666004 -2.12988996 0 P 0 ;0
L 1.56666004 -2.12988996 1.57023002 -2.12926998 0 P 0 ;0
L 1.57023002 -2.12926998 1.5738 -2.12843002 0 P 0 ;0
L 1.5738 -2.12843002 1.57945 -2.12668996 0 P 0 ;0
L 1.57945 -2.12668996 1.58498002 -2.12456998 0 P 0 ;0
L 1.58498002 -2.12456998 1.58793996 -2.12318002 0 P 0 ;0
L 1.58793996 -2.12318002 1.59078996 -2.12156004 0 P 0 ;0
L 1.59078996 -2.12156004 1.59348996 -2.11971998 0 P 0 ;0
L 1.59348996 -2.11971998 1.59525 -2.11833002 0 P 0 ;0
L 1.59525 -2.11833002 1.5969 -2.11681998 0 P 0 ;0
L 1.5969 -2.11681998 1.59846004 -2.11521004 0 P 0 ;0
L 1.59846004 -2.11521004 1.59991004 -2.11348002 0 P 0 ;0
L 1.59991004 -2.11348002 1.60175 -2.11093996 0 P 0 ;0
L 1.60175 -2.11093996 1.60338002 -2.10826998 0 P 0 ;0
L 1.60338002 -2.10826998 1.60481004 -2.10548002 0 P 0 ;0
L 1.60481004 -2.10548002 1.60573002 -2.10321004 0 P 0 ;0
L 1.60573002 -2.10321004 1.60646004 -2.10088002 0 P 0 ;0
L 1.60646004 -2.10088002 1.60698002 -2.09848996 0 P 0 ;0
L 1.60698002 -2.09848996 1.60756004 -2.09421998 0 P 0 ;0
L 1.60756004 -2.09421998 1.6078 -2.08991004 0 P 0 ;0
L 1.6078 -2.08991004 1.60768996 -2.08565 0 P 0 ;0
L 1.60768996 -2.08565 1.60723002 -2.08141998 0 P 0 ;0
L 1.60723002 -2.08141998 1.60691998 -2.07968002 0 P 0 ;0
L 1.60691998 -2.07968002 1.60646998 -2.07796998 0 P 0 ;0
L 1.60646998 -2.07796998 1.60591998 -2.0763 0 P 0 ;0
L 1.60591998 -2.0763 1.60523002 -2.07466998 0 P 0 ;0
L 1.60523002 -2.07466998 1.60411998 -2.07246998 0 P 0 ;0
L 1.60411998 -2.07246998 1.60281004 -2.07038002 0 P 0 ;0
L 1.60281004 -2.07038002 1.60131998 -2.06838996 0 P 0 ;0
L 1.60131998 -2.06838996 1.59803996 -2.06461998 0 P 0 ;0
L 1.59803996 -2.06461998 1.59455 -2.06101998 0 P 0 ;0
L 1.59455 -2.06101998 1.59031998 -2.05708996 0 P 0 ;0
L 1.59031998 -2.05708996 1.58586004 -2.05333996 0 P 0 ;0
L 1.58586004 -2.05333996 1.57588002 -2.04598996 0 P 0 ;0
L 1.57588002 -2.04598996 1.56685 -2.03963996 0 P 0 ;0
L 1.56685 -2.03963996 1.56578002 -2.03878996 0 P 0 ;0
L 1.56578002 -2.03878996 1.56476998 -2.03786004 0 P 0 ;0
L 1.56476998 -2.03786004 1.56383002 -2.03686998 0 P 0 ;0
L 1.56383002 -2.03686998 1.56295 -2.0358 0 P 0 ;0
L 1.56295 -2.0358 1.56276998 -2.03555 0 P 0 ;0
L 1.56276998 -2.03555 1.56261004 -2.03528002 0 P 0 ;0
L 1.56261004 -2.03528002 1.56246998 -2.035 0 P 0 ;0
L 1.56246998 -2.035 1.56236004 -2.03471998 0 P 0 ;0
L 1.56236004 -2.03471998 1.56226998 -2.03441998 0 P 0 ;0
L 1.56226998 -2.03441998 1.5622 -2.03411998 0 P 0 ;0
L 1.5622 -2.03411998 1.56216004 -2.03381998 0 P 0 ;0
L 1.56216004 -2.03381998 1.56213996 -2.03351004 0 P 0 ;0
L 1.56213996 -2.03351004 1.56215 -2.0332 0 P 0 ;0
L 1.56215 -2.0332 1.56218002 -2.03288996 0 P 0 ;0
L 1.56218002 -2.03288996 1.56225 -2.03253996 0 P 0 ;0
L 1.56225 -2.03253996 1.56233996 -2.03221004 0 P 0 ;0
L 1.56233996 -2.03221004 1.56246004 -2.03186998 0 P 0 ;0
L 1.56246004 -2.03186998 1.56261004 -2.03156004 0 P 0 ;0
L 1.56261004 -2.03156004 1.56278996 -2.03125 0 P 0 ;0
L 1.56278996 -2.03125 1.56298002 -2.03096004 0 P 0 ;0
L 1.56298002 -2.03096004 1.56321004 -2.03068996 0 P 0 ;0
L 1.56321004 -2.03068996 1.56345 -2.03043996 0 P 0 ;0
L 1.56345 -2.03043996 1.56371004 -2.0302 0 P 0 ;0
L 1.56371004 -2.0302 1.56416004 -2.02986004 0 P 0 ;0
L 1.56416004 -2.02986004 1.56463002 -2.02955 0 P 0 ;0
L 1.56463002 -2.02955 1.56511998 -2.02928002 0 P 0 ;0
L 1.56511998 -2.02928002 1.56561998 -2.02903002 0 P 0 ;0
L 1.56561998 -2.02903002 1.56611998 -2.02883996 0 P 0 ;0
L 1.56611998 -2.02883996 1.56663996 -2.02866998 0 P 0 ;0
L 1.56663996 -2.02866998 1.56716004 -2.02855 0 P 0 ;0
L 1.56716004 -2.02855 1.5677 -2.02846998 0 P 0 ;0
L 1.5677 -2.02846998 1.56926998 -2.02835 0 P 0 ;0
L 1.56926998 -2.02835 1.57085 -2.02833996 0 P 0 ;0
L 1.57085 -2.02833996 1.57725 -2.02866998 0 P 0 ;0
L 1.57725 -2.02866998 1.58205 -2.02906004 0 P 0 ;0
L 1.58205 -2.02906004 1.58746998 -2.02975 0 P 0 ;0
L 1.58746998 -2.02975 1.59271004 -2.03056998 0 P 0 ;0
L 1.59271004 -2.03056998 1.59681004 -2.03143002 0 P 0 ;0
L 1.59681004 -2.03143002 1.60016004 -2.03221998 0 P 0 ;0
L 1.60016004 -2.03221998 1.60308002 -2.03281004 0 P 0 ;0
L 1.60308002 -2.03281004 1.60553996 -2.03323996 0 P 0 ;0
L 1.60553996 -2.03323996 1.60568996 -2.03323996 0 P 0 ;0
L 1.60568996 -2.03323996 1.60576998 -2.03321998 0 P 0 ;0
L 1.60576998 -2.03321998 1.60586004 -2.03316004 0 P 0 ;0
L 1.60586004 -2.03316004 1.6059 -2.03313996 0 P 0 ;0
L 1.6059 -2.03313996 1.60591998 -2.03311004 0 P 0 ;0
L 1.60591998 -2.03311004 1.60598996 -2.03303996 0 P 0 ;0
L 1.60598996 -2.03303996 1.60605 -2.03296998 0 P 0 ;0
L 1.60605 -2.03296998 1.6061 -2.03288996 0 P 0 ;0
L 1.6061 -2.03288996 1.60618002 -2.03273002 0 P 0 ;0
L 1.60618002 -2.03273002 1.60621004 -2.03263002 0 P 0 ;0
L 1.60621004 -2.03263002 1.60623002 -2.03253996 0 P 0 ;0
L 1.60623002 -2.03253996 1.60625 -2.03236004 0 P 0 ;0
L 1.60625 -2.03236004 1.60623996 -2.03226004 0 P 0 ;0
L 1.60623996 -2.03226004 1.60508002 -2.01578002 0 P 0 ;0
L 1.60508002 -2.01578002 1.60393996 -2.00068002 0 P 0 ;0
L 1.60393996 -2.00068002 1.60368002 -1.99833996 0 P 0 ;0
L 1.60368002 -1.99833996 1.60326998 -1.99601004 0 P 0 ;0
L 1.60326998 -1.99601004 1.60321004 -1.99576998 0 P 0 ;0
L 1.60321004 -1.99576998 1.60313996 -1.99553002 0 P 0 ;0
L 1.60313996 -1.99553002 1.60303996 -1.9953 0 P 0 ;0
L 1.60303996 -1.9953 1.60293002 -1.99508002 0 P 0 ;0
L 1.60293002 -1.99508002 1.60281004 -1.99486004 0 P 0 ;0
L 1.60281004 -1.99486004 1.60261998 -1.9946 0 P 0 ;0
L 1.60261998 -1.9946 1.60241004 -1.99435 0 P 0 ;0
L 1.60241004 -1.99435 1.60218002 -1.99411998 0 P 0 ;0
L 1.60218002 -1.99411998 1.60191998 -1.99391004 0 P 0 ;0
L 1.60191998 -1.99391004 1.60161004 -1.99368996 0 P 0 ;0
L 1.60161004 -1.99368996 1.60128996 -1.99348996 0 P 0 ;0
L 1.60128996 -1.99348996 1.60095 -1.99331998 0 P 0 ;0
L 1.60095 -1.99331998 1.6006 -1.99316004 0 P 0 ;0
L 1.6006 -1.99316004 1.59966004 -1.99283002 0 P 0 ;0
L 1.59966004 -1.99283002 1.59871004 -1.99255 0 P 0 ;0
L 1.59871004 -1.99255 1.5933 -1.99135 0 P 0 ;0
L 1.5933 -1.99135 1.5878 -1.9905 0 P 0 ;0
L 1.5878 -1.9905 1.57285 -1.98915 0 P 0 ;0
L 1.57285 -1.98915 1.55763996 -1.98861004 0 P 0 ;0
L 1.55763996 -1.98861004 1.55171004 -1.98876004 0 P 0 ;0
L 1.55171004 -1.98876004 1.54575 -1.98923996 0 P 0 ;0
L 1.53011998 -2.12786998 1.5666 -2.12786998 0 P 0 ;0
L 1.52236004 -2.12686998 1.57168002 -2.12686998 0 P 0 ;0
L 1.51621998 -2.12586998 1.5753 -2.12586998 0 P 0 ;0
L 1.51071004 -2.12486998 1.57856004 -2.12486998 0 P 0 ;0
L 1.50553002 -2.12386998 1.58121004 -2.12386998 0 P 0 ;0
L 1.50431004 -2.12286998 1.58381998 -2.12286998 0 P 0 ;0
L 1.50423002 -2.12186998 1.58601998 -2.12186998 0 P 0 ;0
L 1.50413996 -2.12086998 1.58796004 -2.12086998 0 P 0 ;0
L 1.50406004 -2.11986998 1.58971004 -2.11986998 0 P 0 ;0
L 1.50396998 -2.11886998 1.59118002 -2.11886998 0 P 0 ;0
L 1.50388996 -2.11786998 1.5926 -2.11786998 0 P 0 ;0
L 1.50381004 -2.11686998 1.59386004 -2.11686998 0 P 0 ;0
L 1.50371998 -2.11586998 1.59496998 -2.11586998 0 P 0 ;0
L 1.50363996 -2.11486998 1.59601004 -2.11486998 0 P 0 ;0
L 1.50355 -2.11386998 1.59696998 -2.11386998 0 P 0 ;0
L 1.50346998 -2.11286998 1.59781004 -2.11286998 0 P 0 ;0
L 1.50338002 -2.11186998 1.5986 -2.11186998 0 P 0 ;0
L 1.5033 -2.11086998 1.59933002 -2.11086998 0 P 0 ;0
L 1.50321004 -2.10986998 1.60005 -2.10986998 0 P 0 ;0
L 1.50313002 -2.10886998 1.60066998 -2.10886998 0 P 0 ;0
L 1.50305 -2.10786998 1.60128002 -2.10786998 0 P 0 ;0
L 1.50296004 -2.10686998 1.60185 -2.10686998 0 P 0 ;0
L 1.50288002 -2.10586998 1.60236004 -2.10586998 0 P 0 ;0
L 1.50278996 -2.10486998 1.60286998 -2.10486998 0 P 0 ;0
L 1.50271004 -2.10386998 1.6033 -2.10386998 0 P 0 ;0
L 1.50263002 -2.10286998 1.60371004 -2.10286998 0 P 0 ;0
L 1.50255 -2.10186998 1.60405 -2.10186998 0 P 0 ;0
L 1.50246998 -2.10086998 1.60436004 -2.10086998 0 P 0 ;0
L 1.50238996 -2.09986998 1.60463002 -2.09986998 0 P 0 ;0
L 1.50231004 -2.09886998 1.60485 -2.09886998 0 P 0 ;0
L 1.50223002 -2.09786998 1.60505 -2.09786998 0 P 0 ;0
L 1.50215 -2.09686998 1.60518002 -2.09686998 0 P 0 ;0
L 1.50206998 -2.09586998 1.60531998 -2.09586998 0 P 0 ;0
L 1.50198996 -2.09486998 1.60545 -2.09486998 0 P 0 ;0
L 1.50191004 -2.09386998 1.60558002 -2.09386998 0 P 0 ;0
L 1.50183002 -2.09286998 1.60563002 -2.09286998 0 P 0 ;0
L 1.50175 -2.09186998 1.53725 -2.09186998 0 P 0 ;0
L 1.54638996 -2.09186998 1.60568996 -2.09186998 0 P 0 ;0
L 1.50166998 -2.09086998 1.5295 -2.09086998 0 P 0 ;0
L 1.54956998 -2.09086998 1.60573996 -2.09086998 0 P 0 ;0
L 1.50158996 -2.08986998 1.52436004 -2.08986998 0 P 0 ;0
L 1.55125 -2.08986998 1.60578996 -2.08986998 0 P 0 ;0
L 1.50151004 -2.08886998 1.52021004 -2.08886998 0 P 0 ;0
L 1.55226998 -2.08886998 1.60576998 -2.08886998 0 P 0 ;0
L 1.50143002 -2.08786998 1.51633002 -2.08786998 0 P 0 ;0
L 1.55298002 -2.08786998 1.60573996 -2.08786998 0 P 0 ;0
L 1.50133996 -2.08686998 1.51246004 -2.08686998 0 P 0 ;0
L 1.55346998 -2.08686998 1.60571998 -2.08686998 0 P 0 ;0
L 1.50126998 -2.08586998 1.50861998 -2.08586998 0 P 0 ;0
L 1.55375 -2.08586998 1.60568996 -2.08586998 0 P 0 ;0
L 1.50118002 -2.08486998 1.50481004 -2.08486998 0 P 0 ;0
L 1.55383002 -2.08486998 1.60558996 -2.08486998 0 P 0 ;0
L 1.55371998 -2.08386998 1.60548996 -2.08386998 0 P 0 ;0
L 1.54886998 -2.12886998 1.53358996 -2.12823996 0 P 0 ;0
L 1.53358996 -2.12823996 1.52631998 -2.12746998 0 P 0 ;0
L 1.52631998 -2.12746998 1.51906004 -2.12636998 0 P 0 ;0
L 1.51906004 -2.12636998 1.51363002 -2.12541004 0 P 0 ;0
L 1.51363002 -2.12541004 1.50886998 -2.12451998 0 P 0 ;0
L 1.50886998 -2.12451998 1.50483996 -2.12373996 0 P 0 ;0
L 1.50483996 -2.12373996 1.50448996 -2.12365 0 P 0 ;0
L 1.50448996 -2.12365 1.50438002 -2.12361004 0 P 0 ;0
L 1.50438002 -2.12361004 1.5027 -2.10378002 0 P 0 ;0
L 1.5027 -2.10378002 1.50111998 -2.08403002 0 P 0 ;0
L 1.50111998 -2.08403002 1.50263996 -2.08433996 0 P 0 ;0
L 1.50263996 -2.08433996 1.50581004 -2.08511004 0 P 0 ;0
L 1.50581004 -2.08511004 1.50955 -2.08611998 0 P 0 ;0
L 1.50955 -2.08611998 1.52306004 -2.08961004 0 P 0 ;0
L 1.52306004 -2.08961004 1.52311004 -2.08961998 0 P 0 ;0
L 1.52311004 -2.08961998 1.52875 -2.09076004 0 P 0 ;0
L 1.52875 -2.09076004 1.5288 -2.09076004 0 P 0 ;0
L 1.5288 -2.09076004 1.53443996 -2.09161004 0 P 0 ;0
L 1.53443996 -2.09161004 1.53893996 -2.09203002 0 P 0 ;0
L 1.53893996 -2.09203002 1.54346004 -2.09216998 0 P 0 ;0
L 1.54346004 -2.09216998 1.54473996 -2.09211004 0 P 0 ;0
L 1.54473996 -2.09211004 1.54603002 -2.09195 0 P 0 ;0
L 1.54603002 -2.09195 1.54728996 -2.09166998 0 P 0 ;0
L 1.54728996 -2.09166998 1.54853002 -2.09128996 0 P 0 ;0
L 1.54853002 -2.09128996 1.54973002 -2.09081004 0 P 0 ;0
L 1.54973002 -2.09081004 1.55026998 -2.09053996 0 P 0 ;0
L 1.55026998 -2.09053996 1.55076998 -2.09023002 0 P 0 ;0
L 1.55076998 -2.09023002 1.55118002 -2.08991998 0 P 0 ;0
L 1.55118002 -2.08991998 1.55118002 -2.08991004 0 P 0 ;0
L 1.55118002 -2.08991004 1.5512 -2.08991004 0 P 0 ;0
L 1.5512 -2.08991004 1.55125 -2.08986998 0 P 0 ;0
L 1.55125 -2.08986998 1.55131004 -2.08981998 0 P 0 ;0
L 1.55131004 -2.08981998 1.55126998 -2.08978002 0 P 0 ;0
L 1.55126998 -2.08978002 1.55136004 -2.08978002 0 P 0 ;0
L 1.55136004 -2.08978002 1.5517 -2.08948996 0 P 0 ;0
L 1.5517 -2.08948996 1.55206004 -2.08911998 0 P 0 ;0
L 1.55206004 -2.08911998 1.55205 -2.08911004 0 P 0 ;0
L 1.55205 -2.08911004 1.55206004 -2.08911004 0 P 0 ;0
L 1.55206004 -2.08911004 1.55211998 -2.08906004 0 P 0 ;0
L 1.55211998 -2.08906004 1.55248996 -2.08861004 0 P 0 ;0
L 1.55248996 -2.08861004 1.55283996 -2.08811998 0 P 0 ;0
L 1.55283996 -2.08811998 1.55313996 -2.08761004 0 P 0 ;0
L 1.55313996 -2.08761004 1.5534 -2.08706998 0 P 0 ;0
L 1.5534 -2.08706998 1.55356004 -2.08663002 0 P 0 ;0
L 1.55356004 -2.08663002 1.55368996 -2.08618996 0 P 0 ;0
L 1.55368996 -2.08618996 1.55376998 -2.08573996 0 P 0 ;0
L 1.55376998 -2.08573996 1.55378002 -2.08565 0 P 0 ;0
L 1.55378002 -2.08565 1.55381998 -2.08528002 0 P 0 ;0
L 1.55381998 -2.08528002 1.55383002 -2.08481998 0 P 0 ;0
L 1.55383002 -2.08481998 1.5538 -2.08436998 0 P 0 ;0
L 1.5538 -2.08436998 1.55373002 -2.08391998 0 P 0 ;0
L 1.55373002 -2.08391998 1.55361998 -2.08346998 0 P 0 ;0
L 1.55361998 -2.08346998 1.55348002 -2.08303996 0 P 0 ;0
L 1.55348002 -2.08303996 1.5533 -2.08261004 0 P 0 ;0
L 1.5533 -2.08261004 1.55308996 -2.08221004 0 P 0 ;0
L 1.55308996 -2.08221004 1.55283996 -2.08183002 0 P 0 ;0
L 1.55283996 -2.08183002 1.55175 -2.0804 0 P 0 ;0
L 1.55175 -2.0804 1.55055 -2.07908002 0 P 0 ;0
L 1.55055 -2.07908002 1.54926004 -2.07783996 0 P 0 ;0
L 1.54926004 -2.07783996 1.54788996 -2.07671998 0 P 0 ;0
L 1.54788996 -2.07671998 1.53706998 -2.06898002 0 P 0 ;0
L 1.53706998 -2.06898002 1.52085 -2.05713996 0 P 0 ;0
L 1.52085 -2.05713996 1.51766004 -2.05445 0 P 0 ;0
L 1.51766004 -2.05445 1.51468002 -2.05153996 0 P 0 ;0
L 1.51468002 -2.05153996 1.51191998 -2.04841998 0 P 0 ;0
L 1.51191998 -2.04841998 1.51048996 -2.04651998 0 P 0 ;0
L 1.51048996 -2.04651998 1.50923002 -2.04453002 0 P 0 ;0
L 1.50923002 -2.04453002 1.50813996 -2.04245 0 P 0 ;0
L 1.50813996 -2.04245 1.50721998 -2.04026004 0 P 0 ;0
L 1.50721998 -2.04026004 1.50643002 -2.03788002 0 P 0 ;0
L 1.50643002 -2.03788002 1.50581004 -2.03545 0 P 0 ;0
L 1.50581004 -2.03545 1.50536004 -2.03298996 0 P 0 ;0
L 1.50536004 -2.03298996 1.50508996 -2.0305 0 P 0 ;0
L 1.50508996 -2.0305 1.50498996 -2.02745 0 P 0 ;0
L 1.50498996 -2.02745 1.50513996 -2.02443996 0 P 0 ;0
L 1.50513996 -2.02443996 1.50551998 -2.02145 0 P 0 ;0
L 1.50551998 -2.02145 1.50613996 -2.0185 0 P 0 ;0
L 1.50613996 -2.0185 1.50698996 -2.01561004 0 P 0 ;0
L 1.50698996 -2.01561004 1.50783002 -2.01341004 0 P 0 ;0
L 1.50783002 -2.01341004 1.50883002 -2.0113 0 P 0 ;0
L 1.50883002 -2.0113 1.51 -2.00928002 0 P 0 ;0
L 1.51 -2.00928002 1.51133002 -2.00736004 0 P 0 ;0
L 1.51133002 -2.00736004 1.5128 -2.00555 0 P 0 ;0
L 1.5128 -2.00555 1.5144 -2.00386004 0 P 0 ;0
L 1.5144 -2.00386004 1.51675 -2.00176998 0 P 0 ;0
L 1.51675 -2.00176998 1.51923002 -1.9999 0 P 0 ;0
L 1.51923002 -1.9999 1.52186004 -1.99823996 0 P 0 ;0
L 1.52186004 -1.99823996 1.52461998 -1.99681004 0 P 0 ;0
L 1.52461998 -1.99681004 1.52748996 -1.99561004 0 P 0 ;0
L 1.52748996 -1.99561004 1.53353002 -1.99363996 0 P 0 ;0
L 1.53353002 -1.99363996 1.5397 -1.99218002 0 P 0 ;0
L 1.5397 -1.99218002 1.54598002 -1.99123002 0 P 0 ;0
L 1.54598002 -1.99123002 1.55181004 -1.99075 0 P 0 ;0
L 1.55181004 -1.99075 1.55763002 -1.99061998 0 P 0 ;0
L 1.55763002 -1.99061998 1.57273002 -1.99113996 0 P 0 ;0
L 1.57273002 -1.99113996 1.58755 -1.99248996 0 P 0 ;0
L 1.58755 -1.99248996 1.59293002 -1.99331998 0 P 0 ;0
L 1.59293002 -1.99331998 1.59821004 -1.99448996 0 P 0 ;0
L 1.59821004 -1.99448996 1.59905 -1.99473002 0 P 0 ;0
L 1.59905 -1.99473002 1.59986004 -1.99501998 0 P 0 ;0
L 1.59986004 -1.99501998 1.60008002 -1.99511998 0 P 0 ;0
L 1.60008002 -1.99511998 1.6003 -1.99523002 0 P 0 ;0
L 1.6003 -1.99523002 1.60051004 -1.99536004 0 P 0 ;0
L 1.60051004 -1.99536004 1.60071004 -1.9955 0 P 0 ;0
L 1.60071004 -1.9955 1.60083002 -1.99561004 0 P 0 ;0
L 1.60083002 -1.99561004 1.60093996 -1.99571004 0 P 0 ;0
L 1.60093996 -1.99571004 1.60103996 -1.99583002 0 P 0 ;0
L 1.60103996 -1.99583002 1.60111998 -1.99595 0 P 0 ;0
L 1.60111998 -1.99595 1.60116998 -1.99601998 0 P 0 ;0
L 1.60116998 -1.99601998 1.60121004 -1.99611004 0 P 0 ;0
L 1.60121004 -1.99611004 1.60125 -1.99621004 0 P 0 ;0
L 1.60125 -1.99621004 1.60128002 -1.9963 0 P 0 ;0
L 1.60128002 -1.9963 1.60131004 -1.99641004 0 P 0 ;0
L 1.60131004 -1.99641004 1.6017 -1.99861998 0 P 0 ;0
L 1.6017 -1.99861998 1.60195 -2.00086998 0 P 0 ;0
L 1.60195 -2.00086998 1.60308002 -2.01593002 0 P 0 ;0
L 1.60308002 -2.01593002 1.60415 -2.03096998 0 P 0 ;0
L 1.60415 -2.03096998 1.60345 -2.03083996 0 P 0 ;0
L 1.60345 -2.03083996 1.60058996 -2.03026004 0 P 0 ;0
L 1.60058996 -2.03026004 1.59723002 -2.02948002 0 P 0 ;0
L 1.59723002 -2.02948002 1.59721998 -2.02948002 0 P 0 ;0
L 1.59721998 -2.02948002 1.59306998 -2.0286 0 P 0 ;0
L 1.59306998 -2.0286 1.58776004 -2.02776998 0 P 0 ;0
L 1.58776004 -2.02776998 1.58226004 -2.02708002 0 P 0 ;0
L 1.58226004 -2.02708002 1.57738002 -2.02666998 0 P 0 ;0
L 1.57738002 -2.02666998 1.5709 -2.02633996 0 P 0 ;0
L 1.5709 -2.02633996 1.56918996 -2.02635 0 P 0 ;0
L 1.56918996 -2.02635 1.56746998 -2.02648996 0 P 0 ;0
L 1.56746998 -2.02648996 1.56678996 -2.02658996 0 P 0 ;0
L 1.56678996 -2.02658996 1.56611998 -2.02673996 0 P 0 ;0
L 1.56611998 -2.02673996 1.56546004 -2.02695 0 P 0 ;0
L 1.56546004 -2.02695 1.56481998 -2.0272 0 P 0 ;0
L 1.56481998 -2.0272 1.56418996 -2.0275 0 P 0 ;0
L 1.56418996 -2.0275 1.56358002 -2.02785 0 P 0 ;0
L 1.56358002 -2.02785 1.563 -2.02823002 0 P 0 ;0
L 1.563 -2.02823002 1.56245 -2.02865 0 P 0 ;0
L 1.56245 -2.02865 1.56206998 -2.02898996 0 P 0 ;0
L 1.56206998 -2.02898996 1.56171004 -2.02936004 0 P 0 ;0
L 1.56171004 -2.02936004 1.56138002 -2.02976004 0 P 0 ;0
L 1.56138002 -2.02976004 1.56108996 -2.03018996 0 P 0 ;0
L 1.56108996 -2.03018996 1.56083002 -2.03063996 0 P 0 ;0
L 1.56083002 -2.03063996 1.56061998 -2.0311 0 P 0 ;0
L 1.56061998 -2.0311 1.56043996 -2.03158996 0 P 0 ;0
L 1.56043996 -2.03158996 1.5603 -2.03208002 0 P 0 ;0
L 1.5603 -2.03208002 1.5602 -2.0326 0 P 0 ;0
L 1.5602 -2.0326 1.56015 -2.03308002 0 P 0 ;0
L 1.56015 -2.03308002 1.56013996 -2.03353996 0 P 0 ;0
L 1.56013996 -2.03353996 1.56016004 -2.03391004 0 P 0 ;0
L 1.56016004 -2.03391004 1.56048002 -2.03391004 0 P 0 ;0
L 1.56048002 -2.03391004 1.56016004 -2.03393002 0 P 0 ;0
L 1.56016004 -2.03393002 1.56016998 -2.03401004 0 P 0 ;0
L 1.56016998 -2.03401004 1.56023002 -2.03448002 0 P 0 ;0
L 1.56023002 -2.03448002 1.56025 -2.03456004 0 P 0 ;0
L 1.56025 -2.03456004 1.56033002 -2.03493002 0 P 0 ;0
L 1.56033002 -2.03493002 1.56046998 -2.03538002 0 P 0 ;0
L 1.56046998 -2.03538002 1.56063996 -2.03581998 0 P 0 ;0
L 1.56063996 -2.03581998 1.56085 -2.03623996 0 P 0 ;0
L 1.56085 -2.03623996 1.56108996 -2.03663996 0 P 0 ;0
L 1.56108996 -2.03663996 1.56136004 -2.03701998 0 P 0 ;0
L 1.56136004 -2.03701998 1.56233002 -2.03818996 0 P 0 ;0
L 1.56233002 -2.03818996 1.56336998 -2.03928996 0 P 0 ;0
L 1.56336998 -2.03928996 1.56448002 -2.04031004 0 P 0 ;0
L 1.56448002 -2.04031004 1.56566004 -2.04123996 0 P 0 ;0
L 1.56566004 -2.04123996 1.57471004 -2.04761998 0 P 0 ;0
L 1.57471004 -2.04761998 1.58461998 -2.05491004 0 P 0 ;0
L 1.58461998 -2.05491004 1.58898996 -2.05858996 0 P 0 ;0
L 1.58898996 -2.05858996 1.59315 -2.06245 0 P 0 ;0
L 1.59315 -2.06245 1.59656998 -2.06596998 0 P 0 ;0
L 1.59656998 -2.06596998 1.59976004 -2.06965 0 P 0 ;0
L 1.59976004 -2.06965 1.60116004 -2.07151004 0 P 0 ;0
L 1.60116004 -2.07151004 1.60238002 -2.07346004 0 P 0 ;0
L 1.60238002 -2.07346004 1.60341998 -2.0755 0 P 0 ;0
L 1.60341998 -2.0755 1.60403996 -2.077 0 P 0 ;0
L 1.60403996 -2.077 1.60456004 -2.07853996 0 P 0 ;0
L 1.60456004 -2.07853996 1.60496004 -2.08011004 0 P 0 ;0
L 1.60496004 -2.08011004 1.60525 -2.0817 0 P 0 ;0
L 1.60525 -2.0817 1.60568996 -2.08578002 0 P 0 ;0
L 1.60568996 -2.08578002 1.60578996 -2.08988002 0 P 0 ;0
L 1.60578996 -2.08988002 1.60556998 -2.09403002 0 P 0 ;0
L 1.60556998 -2.09403002 1.60501004 -2.09813996 0 P 0 ;0
L 1.60501004 -2.09813996 1.60451998 -2.10036998 0 P 0 ;0
L 1.60451998 -2.10036998 1.60383996 -2.10253996 0 P 0 ;0
L 1.60383996 -2.10253996 1.60298996 -2.10465 0 P 0 ;0
L 1.60298996 -2.10465 1.60163996 -2.1073 0 P 0 ;0
L 1.60163996 -2.1073 1.60008002 -2.10983002 0 P 0 ;0
L 1.60008002 -2.10983002 1.59833002 -2.11225 0 P 0 ;0
L 1.59833002 -2.11225 1.59696998 -2.11386998 0 P 0 ;0
L 1.59696998 -2.11386998 1.59551004 -2.11538996 0 P 0 ;0
L 1.59551004 -2.11538996 1.59395 -2.1168 0 P 0 ;0
L 1.59395 -2.1168 1.59231004 -2.11811004 0 P 0 ;0
L 1.59231004 -2.11811004 1.58973002 -2.11986004 0 P 0 ;0
L 1.58973002 -2.11986004 1.58701998 -2.1214 0 P 0 ;0
L 1.58701998 -2.1214 1.5842 -2.12273002 0 P 0 ;0
L 1.5842 -2.12273002 1.5788 -2.1248 0 P 0 ;0
L 1.5788 -2.1248 1.57326998 -2.12648996 0 P 0 ;0
L 1.57326998 -2.12648996 1.56983002 -2.12731004 0 P 0 ;0
L 1.56983002 -2.12731004 1.56638002 -2.12791004 0 P 0 ;0
L 1.56638002 -2.12791004 1.56288996 -2.1283 0 P 0 ;0
L 1.56288996 -2.1283 1.54886998 -2.12886998 0 P 0 ;0
L 1.35851998 -2.06545 1.47866004 -2.06545 0 P 0 ;0
L 1.35936004 -2.06445 1.47871004 -2.06445 0 P 0 ;0
L 1.36041004 -2.06345 1.47875 -2.06345 0 P 0 ;0
L 1.36163996 -2.06245 1.4788 -2.06245 0 P 0 ;0
L 1.36293996 -2.06145 1.47883996 -2.06145 0 P 0 ;0
L 1.36436004 -2.06045 1.47888996 -2.06045 0 P 0 ;0
L 1.36598002 -2.05945 1.47893996 -2.05945 0 P 0 ;0
L 1.36776004 -2.05845 1.47898996 -2.05845 0 P 0 ;0
L 1.36971004 -2.05745 1.47903002 -2.05745 0 P 0 ;0
L 1.37166004 -2.05645 1.47908002 -2.05645 0 P 0 ;0
L 1.37391004 -2.05545 1.47911998 -2.05545 0 P 0 ;0
L 1.37616998 -2.05445 1.47916998 -2.05445 0 P 0 ;0
L 1.37873002 -2.05345 1.47921004 -2.05345 0 P 0 ;0
L 1.38136004 -2.05245 1.47926004 -2.05245 0 P 0 ;0
L 1.36875 -2.03345 1.37108996 -2.03345 0 P 0 ;0
L 1.36886004 -2.03245 1.37385 -2.03245 0 P 0 ;0
L 1.36896998 -2.03145 1.37678002 -2.03145 0 P 0 ;0
L 1.36908996 -2.03045 1.3797 -2.03045 0 P 0 ;0
L 1.36921004 -2.02945 1.38261998 -2.02945 0 P 0 ;0
L 1.36933002 -2.02845 1.38638996 -2.02845 0 P 0 ;0
L 1.36946004 -2.02745 1.39023996 -2.02745 0 P 0 ;0
L 1.36958002 -2.02645 1.39503002 -2.02645 0 P 0 ;0
L 1.3697 -2.02545 1.40068002 -2.02545 0 P 0 ;0
L 1.36981998 -2.02445 1.41053996 -2.02445 0 P 0 ;0
L 1.36993996 -2.02345 1.47993996 -2.02345 0 P 0 ;0
L 1.37008002 -2.02245 1.47988002 -2.02245 0 P 0 ;0
L 1.37021004 -2.02145 1.47978002 -2.02145 0 P 0 ;0
L 1.37033996 -2.02045 1.47968002 -2.02045 0 P 0 ;0
L 1.37046998 -2.01945 1.47953002 -2.01945 0 P 0 ;0
L 1.3706 -2.01845 1.47936004 -2.01845 0 P 0 ;0
L 1.37073002 -2.01745 1.47918002 -2.01745 0 P 0 ;0
L 1.37086004 -2.01645 1.47893002 -2.01645 0 P 0 ;0
L 1.37098996 -2.01545 1.47868002 -2.01545 0 P 0 ;0
L 1.37113002 -2.01445 1.4784 -2.01445 0 P 0 ;0
L 1.37126998 -2.01345 1.47806004 -2.01345 0 P 0 ;0
L 1.3714 -2.01245 1.47773002 -2.01245 0 P 0 ;0
L 1.37153996 -2.01145 1.47733002 -2.01145 0 P 0 ;0
L 1.37168002 -2.01045 1.47691004 -2.01045 0 P 0 ;0
L 1.37181004 -2.00945 1.47641004 -2.00945 0 P 0 ;0
L 1.37195 -2.00845 1.47588996 -2.00845 0 P 0 ;0
L 1.37208002 -2.00745 1.47528002 -2.00745 0 P 0 ;0
L 1.37221004 -2.00645 1.47463996 -2.00645 0 P 0 ;0
L 1.37235 -2.00545 1.47391998 -2.00545 0 P 0 ;0
L 1.37248996 -2.00445 1.47311004 -2.00445 0 P 0 ;0
L 1.37261998 -2.00345 1.47225 -2.00345 0 P 0 ;0
L 1.37276004 -2.00245 1.47126998 -2.00245 0 P 0 ;0
L 1.3729 -2.00145 1.4702 -2.00145 0 P 0 ;0
L 1.37303002 -2.00045 1.46903996 -2.00045 0 P 0 ;0
L 1.37316998 -1.99945 1.46775 -1.99945 0 P 0 ;0
L 1.3733 -1.99845 1.46625 -1.99845 0 P 0 ;0
L 1.37343996 -1.99745 1.46455 -1.99745 0 P 0 ;0
L 1.37356998 -1.99645 1.46253996 -1.99645 0 P 0 ;0
L 1.37753002 -1.99545 1.46041004 -1.99545 0 P 0 ;0
L 1.38218996 -1.99445 1.45781004 -1.99445 0 P 0 ;0
L 1.42925 -2.08345 1.47785 -2.08345 0 P 0 ;0
L 1.42931998 -2.08245 1.47788996 -2.08245 0 P 0 ;0
L 1.42938002 -2.08145 1.47793002 -2.08145 0 P 0 ;0
L 1.42945 -2.08045 1.47796998 -2.08045 0 P 0 ;0
L 1.42951004 -2.07945 1.47801004 -2.07945 0 P 0 ;0
L 1.42958002 -2.07845 1.47806004 -2.07845 0 P 0 ;0
L 1.42963996 -2.07745 1.4781 -2.07745 0 P 0 ;0
L 1.4297 -2.07645 1.47815 -2.07645 0 P 0 ;0
L 1.42976998 -2.07545 1.4782 -2.07545 0 P 0 ;0
L 1.42983002 -2.07445 1.47825 -2.07445 0 P 0 ;0
L 1.4299 -2.07345 1.47828996 -2.07345 0 P 0 ;0
L 1.42963996 -2.07245 1.47833996 -2.07245 0 P 0 ;0
L 1.42918996 -2.07145 1.47838002 -2.07145 0 P 0 ;0
L 1.38425 -2.05145 1.47931004 -2.05145 0 P 0 ;0
L 1.38731998 -2.05045 1.47933996 -2.05045 0 P 0 ;0
L 1.39088002 -2.04945 1.47938002 -2.04945 0 P 0 ;0
L 1.3947 -2.04845 1.47941004 -2.04845 0 P 0 ;0
L 1.39851004 -2.04745 1.47945 -2.04745 0 P 0 ;0
L 1.40233002 -2.04645 1.47948002 -2.04645 0 P 0 ;0
L 1.40608002 -2.04545 1.47951004 -2.04545 0 P 0 ;0
L 1.40983002 -2.04445 1.47955 -2.04445 0 P 0 ;0
L 1.41306998 -2.04345 1.47958996 -2.04345 0 P 0 ;0
L 1.41591998 -2.04245 1.47961998 -2.04245 0 P 0 ;0
L 1.41876998 -2.04145 1.47965 -2.04145 0 P 0 ;0
L 1.42133996 -2.04045 1.47968996 -2.04045 0 P 0 ;0
L 1.42361998 -2.03945 1.47971998 -2.03945 0 P 0 ;0
L 1.42591004 -2.03845 1.47975 -2.03845 0 P 0 ;0
L 1.42805 -2.03745 1.47978002 -2.03745 0 P 0 ;0
L 1.42936004 -2.03645 1.47981004 -2.03645 0 P 0 ;0
L 1.43003002 -2.03545 1.47983002 -2.03545 0 P 0 ;0
L 1.43081998 -2.03445 1.47986004 -2.03445 0 P 0 ;0
L 1.43121004 -2.03345 1.47988002 -2.03345 0 P 0 ;0
L 1.43141998 -2.03245 1.4799 -2.03245 0 P 0 ;0
L 1.43146998 -2.03145 1.47993002 -2.03145 0 P 0 ;0
L 1.43136004 -2.03045 1.47996004 -2.03045 0 P 0 ;0
L 1.43108002 -2.02945 1.47998002 -2.02945 0 P 0 ;0
L 1.4306 -2.02845 1.48001004 -2.02845 0 P 0 ;0
L 1.42986998 -2.02745 1.48001004 -2.02745 0 P 0 ;0
L 1.42875 -2.02645 1.47998996 -2.02645 0 P 0 ;0
L 1.42658996 -2.02545 1.47996998 -2.02545 0 P 0 ;0
L 1.42203996 -2.02445 1.47996004 -2.02445 0 P 0 ;0
L 1.38748002 -1.99345 1.45483002 -1.99345 0 P 0 ;0
L 1.39331998 -1.99245 1.45108996 -1.99245 0 P 0 ;0
L 1.40051004 -1.99145 1.44503002 -1.99145 0 P 0 ;0
L 1.38096998 -2.12745 1.4051 -2.12745 0 P 0 ;0
L 1.37671004 -2.12645 1.41113996 -2.12645 0 P 0 ;0
L 1.3736 -2.12545 1.41238996 -2.12545 0 P 0 ;0
L 1.37096998 -2.12445 1.41268002 -2.12445 0 P 0 ;0
L 1.36876998 -2.12345 1.41296998 -2.12345 0 P 0 ;0
L 1.36685 -2.12245 1.41326998 -2.12245 0 P 0 ;0
L 1.36516004 -2.12145 1.41356004 -2.12145 0 P 0 ;0
L 1.36366004 -2.12045 1.41385 -2.12045 0 P 0 ;0
L 1.36225 -2.11945 1.41413996 -2.11945 0 P 0 ;0
L 1.361 -2.11845 1.41443002 -2.11845 0 P 0 ;0
L 1.35983002 -2.11745 1.41471998 -2.11745 0 P 0 ;0
L 1.35876004 -2.11645 1.41501004 -2.11645 0 P 0 ;0
L 1.42661998 -2.12445 1.47693002 -2.12445 0 P 0 ;0
L 1.42665 -2.12345 1.47693002 -2.12345 0 P 0 ;0
L 1.4267 -2.12245 1.47693002 -2.12245 0 P 0 ;0
L 1.42675 -2.12145 1.47693002 -2.12145 0 P 0 ;0
L 1.42681004 -2.12045 1.47693002 -2.12045 0 P 0 ;0
L 1.42686998 -2.11945 1.47693002 -2.11945 0 P 0 ;0
L 1.42691998 -2.11845 1.47693002 -2.11845 0 P 0 ;0
L 1.42698996 -2.11745 1.47693002 -2.11745 0 P 0 ;0
L 1.42705 -2.11645 1.47693002 -2.11645 0 P 0 ;0
L 1.42711004 -2.11545 1.47693002 -2.11545 0 P 0 ;0
L 1.42716998 -2.11445 1.47693002 -2.11445 0 P 0 ;0
L 1.42723002 -2.11345 1.47693996 -2.11345 0 P 0 ;0
L 1.4273 -2.11245 1.47695 -2.11245 0 P 0 ;0
L 1.42736998 -2.11145 1.47696004 -2.11145 0 P 0 ;0
L 1.42743996 -2.11045 1.47698002 -2.11045 0 P 0 ;0
L 1.42751004 -2.10945 1.47698996 -2.10945 0 P 0 ;0
L 1.42758002 -2.10845 1.47701004 -2.10845 0 P 0 ;0
L 1.42765 -2.10745 1.47703002 -2.10745 0 P 0 ;0
L 1.42771004 -2.10645 1.47703996 -2.10645 0 P 0 ;0
L 1.42778002 -2.10545 1.47706998 -2.10545 0 P 0 ;0
L 1.42783996 -2.10445 1.4771 -2.10445 0 P 0 ;0
L 1.42791004 -2.10345 1.47713002 -2.10345 0 P 0 ;0
L 1.42798002 -2.10245 1.47716004 -2.10245 0 P 0 ;0
L 1.42805 -2.10145 1.4772 -2.10145 0 P 0 ;0
L 1.42811004 -2.10045 1.47723002 -2.10045 0 P 0 ;0
L 1.40953002 -2.09945 1.41973002 -2.09945 0 P 0 ;0
L 1.42818002 -2.09945 1.47726004 -2.09945 0 P 0 ;0
L 1.41618002 -2.09845 1.41996998 -2.09845 0 P 0 ;0
L 1.42825 -2.09845 1.47728996 -2.09845 0 P 0 ;0
L 1.42831998 -2.09745 1.47733002 -2.09745 0 P 0 ;0
L 1.42838996 -2.09645 1.47736004 -2.09645 0 P 0 ;0
L 1.42846004 -2.09545 1.47738996 -2.09545 0 P 0 ;0
L 1.42851998 -2.09445 1.47741998 -2.09445 0 P 0 ;0
L 1.42858996 -2.09345 1.47746004 -2.09345 0 P 0 ;0
L 1.42866004 -2.09245 1.4775 -2.09245 0 P 0 ;0
L 1.42873002 -2.09145 1.47753996 -2.09145 0 P 0 ;0
L 1.42878996 -2.09045 1.47758002 -2.09045 0 P 0 ;0
L 1.42886004 -2.08945 1.47761998 -2.08945 0 P 0 ;0
L 1.42893002 -2.08845 1.47766004 -2.08845 0 P 0 ;0
L 1.42898996 -2.08745 1.4777 -2.08745 0 P 0 ;0
L 1.42906004 -2.08645 1.47773002 -2.08645 0 P 0 ;0
L 1.42911998 -2.08545 1.47776998 -2.08545 0 P 0 ;0
L 1.42918996 -2.08445 1.47781004 -2.08445 0 P 0 ;0
L 1.61686004 -2.17995 1.66846004 -2.17995 0 P 0 ;0
L 1.61591004 -2.17895 1.67158996 -2.17895 0 P 0 ;0
L 1.61553996 -2.17795 1.67431998 -2.17795 0 P 0 ;0
L 1.61526998 -2.17695 1.67675 -2.17695 0 P 0 ;0
L 1.61508002 -2.17595 1.67903996 -2.17595 0 P 0 ;0
L 1.61496998 -2.17495 1.68108002 -2.17495 0 P 0 ;0
L 1.61491004 -2.17395 1.68295 -2.17395 0 P 0 ;0
L 1.61485 -2.17295 1.68458996 -2.17295 0 P 0 ;0
L 1.61478996 -2.17195 1.6861 -2.17195 0 P 0 ;0
L 1.61473002 -2.17095 1.6875 -2.17095 0 P 0 ;0
L 1.61466998 -2.16995 1.68876998 -2.16995 0 P 0 ;0
L 1.61461004 -2.16895 1.68998002 -2.16895 0 P 0 ;0
L 1.61455 -2.16795 1.69108002 -2.16795 0 P 0 ;0
L 1.61448996 -2.16695 1.69211998 -2.16695 0 P 0 ;0
L 1.61443002 -2.16595 1.69316004 -2.16595 0 P 0 ;0
L 1.61436998 -2.16495 1.69411998 -2.16495 0 P 0 ;0
L 1.61431004 -2.16395 1.69498996 -2.16395 0 P 0 ;0
L 1.61425 -2.16295 1.69586004 -2.16295 0 P 0 ;0
L 1.61418996 -2.16195 1.69673002 -2.16195 0 P 0 ;0
L 1.61413002 -2.16095 1.69746998 -2.16095 0 P 0 ;0
L 1.61406998 -2.15995 1.6982 -2.15995 0 P 0 ;0
L 1.61401998 -2.15895 1.69893996 -2.15895 0 P 0 ;0
L 1.61396998 -2.15795 1.69963002 -2.15795 0 P 0 ;0
L 1.64433002 -2.18295 1.63151004 -2.18271004 0 P 0 ;0
L 1.63151004 -2.18271004 1.62658002 -2.18226998 0 P 0 ;0
L 1.62658002 -2.18226998 1.62168996 -2.18146998 0 P 0 ;0
L 1.62168996 -2.18146998 1.6201 -2.1811 0 P 0 ;0
L 1.6201 -2.1811 1.61853996 -2.18061004 0 P 0 ;0
L 1.61853996 -2.18061004 1.61701004 -2.18001998 0 P 0 ;0
L 1.61701004 -2.18001998 1.61686004 -2.17995 0 P 0 ;0
L 1.61686004 -2.17995 1.61671004 -2.17986998 0 P 0 ;0
L 1.61671004 -2.17986998 1.61656998 -2.17976998 0 P 0 ;0
L 1.61656998 -2.17976998 1.61643996 -2.17966998 0 P 0 ;0
L 1.61643996 -2.17966998 1.61631998 -2.17955 0 P 0 ;0
L 1.61631998 -2.17955 1.61621004 -2.17943002 0 P 0 ;0
L 1.61621004 -2.17943002 1.6161 -2.1793 0 P 0 ;0
L 1.6161 -2.1793 1.61601004 -2.17915 0 P 0 ;0
L 1.61601004 -2.17915 1.61593002 -2.179 0 P 0 ;0
L 1.61593002 -2.179 1.61586004 -2.17885 0 P 0 ;0
L 1.61586004 -2.17885 1.61553002 -2.17791004 0 P 0 ;0
L 1.61553002 -2.17791004 1.61526998 -2.17696004 0 P 0 ;0
L 1.61526998 -2.17696004 1.61508996 -2.17598996 0 P 0 ;0
L 1.61508996 -2.17598996 1.61496998 -2.17496998 0 P 0 ;0
L 1.61496998 -2.17496998 1.61408002 -2.16011004 0 P 0 ;0
L 1.61408002 -2.16011004 1.61341998 -2.14758996 0 P 0 ;0
L 1.61341998 -2.14758996 1.6202 -2.14821004 0 P 0 ;0
L 1.6202 -2.14821004 1.62023002 -2.14821004 0 P 0 ;0
L 1.62023002 -2.14821004 1.63216998 -2.14893996 0 P 0 ;0
L 1.63216998 -2.14893996 1.6349 -2.14893002 0 P 0 ;0
L 1.6349 -2.14893002 1.63761998 -2.14873002 0 P 0 ;0
L 1.63761998 -2.14873002 1.64031998 -2.14835 0 P 0 ;0
L 1.64031998 -2.14835 1.64198996 -2.14798996 0 P 0 ;0
L 1.64198996 -2.14798996 1.64363002 -2.14751998 0 P 0 ;0
L 1.64363002 -2.14751998 1.64523002 -2.14693002 0 P 0 ;0
L 1.64523002 -2.14693002 1.64678996 -2.14623002 0 P 0 ;0
L 1.64678996 -2.14623002 1.64888002 -2.14506998 0 P 0 ;0
L 1.64888002 -2.14506998 1.65086998 -2.14376004 0 P 0 ;0
L 1.65086998 -2.14376004 1.65093996 -2.14371004 0 P 0 ;0
L 1.65093996 -2.14371004 1.65275 -2.14228996 0 P 0 ;0
L 1.65275 -2.14228996 1.6539 -2.14123996 0 P 0 ;0
L 1.6539 -2.14123996 1.65496004 -2.14011004 0 P 0 ;0
L 1.65496004 -2.14011004 1.65591998 -2.13891004 0 P 0 ;0
L 1.65591998 -2.13891004 1.65755 -2.13653996 0 P 0 ;0
L 1.65755 -2.13653996 1.65901998 -2.13415 0 P 0 ;0
L 1.65901998 -2.13415 1.65903002 -2.13413002 0 P 0 ;0
L 1.65903002 -2.13413002 1.66035 -2.13171998 0 P 0 ;0
L 1.66035 -2.13171998 1.66155 -2.12925 0 P 0 ;0
L 1.66155 -2.12925 1.66183996 -2.12851998 0 P 0 ;0
L 1.66183996 -2.12851998 1.66206998 -2.12776004 0 P 0 ;0
L 1.66206998 -2.12776004 1.66223996 -2.12696998 0 P 0 ;0
L 1.66223996 -2.12696998 1.66233996 -2.12618002 0 P 0 ;0
L 1.66233996 -2.12618002 1.66236998 -2.12538996 0 P 0 ;0
L 1.66236998 -2.12538996 1.66233002 -2.12436004 0 P 0 ;0
L 1.66233002 -2.12436004 1.66221004 -2.12335 0 P 0 ;0
L 1.66221004 -2.12335 1.662 -2.12235 0 P 0 ;0
L 1.662 -2.12235 1.66171004 -2.12141004 0 P 0 ;0
L 1.66171004 -2.12141004 1.64438996 -2.07113002 0 P 0 ;0
L 1.64438996 -2.07113002 1.62871998 -2.02606004 0 P 0 ;0
L 1.62871998 -2.02606004 1.62116004 -2.00558996 0 P 0 ;0
L 1.62116004 -2.00558996 1.62116004 -2.00556998 0 P 0 ;0
L 1.62116004 -2.00556998 1.61681004 -1.99443996 0 P 0 ;0
L 1.61681004 -1.99443996 1.67163002 -1.99443996 0 P 0 ;0
L 1.67163002 -1.99443996 1.67301004 -2.00076004 0 P 0 ;0
L 1.67301004 -2.00076004 1.67613002 -2.01341998 0 P 0 ;0
L 1.67613002 -2.01341998 1.68331004 -2.03931998 0 P 0 ;0
L 1.68331004 -2.03931998 1.69153002 -2.06856998 0 P 0 ;0
L 1.69153002 -2.06856998 1.6916 -2.06876004 0 P 0 ;0
L 1.6916 -2.06876004 1.69168996 -2.06896998 0 P 0 ;0
L 1.69168996 -2.06896998 1.69181004 -2.06918002 0 P 0 ;0
L 1.69181004 -2.06918002 1.69193002 -2.06936998 0 P 0 ;0
L 1.69193002 -2.06936998 1.69208002 -2.06956004 0 P 0 ;0
L 1.69208002 -2.06956004 1.69223996 -2.06973002 0 P 0 ;0
L 1.69223996 -2.06973002 1.69241998 -2.06988002 0 P 0 ;0
L 1.69241998 -2.06988002 1.6926 -2.07001998 0 P 0 ;0
L 1.6926 -2.07001998 1.6928 -2.07015 0 P 0 ;0
L 1.6928 -2.07015 1.69301004 -2.07025 0 P 0 ;0
L 1.69301004 -2.07025 1.69323002 -2.07033996 0 P 0 ;0
L 1.69323002 -2.07033996 1.69346004 -2.07041004 0 P 0 ;0
L 1.69346004 -2.07041004 1.69368002 -2.07045 0 P 0 ;0
L 1.69368002 -2.07045 1.69391998 -2.07048002 0 P 0 ;0
L 1.69391998 -2.07048002 1.69413996 -2.07048996 0 P 0 ;0
L 1.69413996 -2.07048996 1.6944 -2.07048002 0 P 0 ;0
L 1.6944 -2.07048002 1.69465 -2.07045 0 P 0 ;0
L 1.69465 -2.07045 1.69488996 -2.07038996 0 P 0 ;0
L 1.69488996 -2.07038996 1.69513996 -2.07031998 0 P 0 ;0
L 1.69513996 -2.07031998 1.69536998 -2.07021998 0 P 0 ;0
L 1.69536998 -2.07021998 1.69558996 -2.0701 0 P 0 ;0
L 1.69558996 -2.0701 1.69581004 -2.06996998 0 P 0 ;0
L 1.69581004 -2.06996998 1.69601004 -2.06981998 0 P 0 ;0
L 1.69601004 -2.06981998 1.6962 -2.06965 0 P 0 ;0
L 1.6962 -2.06965 1.69636998 -2.06946004 0 P 0 ;0
L 1.69636998 -2.06946004 1.69653002 -2.06926004 0 P 0 ;0
L 1.69653002 -2.06926004 1.69666004 -2.06905 0 P 0 ;0
L 1.69666004 -2.06905 1.69678996 -2.06883002 0 P 0 ;0
L 1.69678996 -2.06883002 1.69688002 -2.0686 0 P 0 ;0
L 1.69688002 -2.0686 1.69695 -2.0684 0 P 0 ;0
L 1.69695 -2.0684 1.70426004 -2.04365 0 P 0 ;0
L 1.70426004 -2.04365 1.70426004 -2.04363002 0 P 0 ;0
L 1.70426004 -2.04363002 1.71066998 -2.0213 0 P 0 ;0
L 1.71066998 -2.0213 1.71068002 -2.02126004 0 P 0 ;0
L 1.71068002 -2.02126004 1.71431998 -2.00693996 0 P 0 ;0
L 1.71431998 -2.00693996 1.71706004 -1.99496998 0 P 0 ;0
L 1.71706004 -1.99496998 1.74335 -1.9947 0 P 0 ;0
L 1.74335 -1.9947 1.75403002 -1.99461004 0 P 0 ;0
L 1.75403002 -1.99461004 1.76301004 -1.99465 0 P 0 ;0
L 1.76301004 -1.99465 1.76886004 -1.99471004 0 P 0 ;0
L 1.76886004 -1.99471004 1.76883996 -1.99476004 0 P 0 ;0
L 1.76883996 -1.99476004 1.74021004 -2.06556004 0 P 0 ;0
L 1.74021004 -2.06556004 1.71298002 -2.13276998 0 P 0 ;0
L 1.71298002 -2.13276998 1.70836998 -2.14293996 0 P 0 ;0
L 1.70836998 -2.14293996 1.70413996 -2.15076004 0 P 0 ;0
L 1.70413996 -2.15076004 1.69941998 -2.15828996 0 P 0 ;0
L 1.69941998 -2.15828996 1.6967 -2.16198996 0 P 0 ;0
L 1.6967 -2.16198996 1.6937 -2.16541998 0 P 0 ;0
L 1.6937 -2.16541998 1.69041998 -2.1686 0 P 0 ;0
L 1.69041998 -2.1686 1.68793996 -2.17063002 0 P 0 ;0
L 1.68793996 -2.17063002 1.68535 -2.17248002 0 P 0 ;0
L 1.68535 -2.17248002 1.68263996 -2.17413996 0 P 0 ;0
L 1.68263996 -2.17413996 1.67981004 -2.17561004 0 P 0 ;0
L 1.67981004 -2.17561004 1.67525 -2.17761004 0 P 0 ;0
L 1.67525 -2.17761004 1.6706 -2.17931998 0 P 0 ;0
L 1.6706 -2.17931998 1.66586004 -2.18073002 0 P 0 ;0
L 1.66586004 -2.18073002 1.66141998 -2.1817 0 P 0 ;0
L 1.66141998 -2.1817 1.65691998 -2.18228996 0 P 0 ;0
L 1.65691998 -2.18228996 1.64433002 -2.18295 0 P 0 ;0
L 1.61928996 -2.00628002 1.62683996 -2.02673002 0 P 0 ;0
L 1.62683996 -2.02673002 1.6425 -2.07178002 0 P 0 ;0
L 1.6425 -2.07178002 1.65981004 -2.12201998 0 P 0 ;0
L 1.65981004 -2.12201998 1.66006004 -2.12283996 0 P 0 ;0
L 1.66006004 -2.12283996 1.66023002 -2.12368002 0 P 0 ;0
L 1.66023002 -2.12368002 1.66033996 -2.12451998 0 P 0 ;0
L 1.66033996 -2.12451998 1.66036998 -2.12538002 0 P 0 ;0
L 1.66036998 -2.12538002 1.66033996 -2.12601004 0 P 0 ;0
L 1.66033996 -2.12601004 1.66026998 -2.12663996 0 P 0 ;0
L 1.66026998 -2.12663996 1.66013996 -2.12725 0 P 0 ;0
L 1.66013996 -2.12725 1.65995 -2.12786004 0 P 0 ;0
L 1.65995 -2.12786004 1.65971004 -2.12843996 0 P 0 ;0
L 1.65971004 -2.12843996 1.65856998 -2.1308 0 P 0 ;0
L 1.65856998 -2.1308 1.6573 -2.13313002 0 P 0 ;0
L 1.6573 -2.13313002 1.65586998 -2.13545 0 P 0 ;0
L 1.65586998 -2.13545 1.65431004 -2.13771998 0 P 0 ;0
L 1.65431004 -2.13771998 1.65343996 -2.1388 0 P 0 ;0
L 1.65343996 -2.1388 1.65248996 -2.13981998 0 P 0 ;0
L 1.65248996 -2.13981998 1.65146004 -2.14076004 0 P 0 ;0
L 1.65146004 -2.14076004 1.64971004 -2.14213002 0 P 0 ;0
L 1.64971004 -2.14213002 1.64785 -2.14336004 0 P 0 ;0
L 1.64785 -2.14336004 1.64588996 -2.14443996 0 P 0 ;0
L 1.64588996 -2.14443996 1.64446998 -2.14508002 0 P 0 ;0
L 1.64446998 -2.14508002 1.64301004 -2.14561998 0 P 0 ;0
L 1.64301004 -2.14561998 1.64151004 -2.14605 0 P 0 ;0
L 1.64151004 -2.14605 1.63996998 -2.14636998 0 P 0 ;0
L 1.63996998 -2.14636998 1.63741004 -2.14673996 0 P 0 ;0
L 1.63741004 -2.14673996 1.63483002 -2.14693002 0 P 0 ;0
L 1.63483002 -2.14693002 1.63223002 -2.14693996 0 P 0 ;0
L 1.63223002 -2.14693996 1.62036004 -2.14621998 0 P 0 ;0
L 1.62036004 -2.14621998 1.6113 -2.14538002 0 P 0 ;0
L 1.6113 -2.14538002 1.61208996 -2.16023002 0 P 0 ;0
L 1.61208996 -2.16023002 1.61298002 -2.17515 0 P 0 ;0
L 1.61298002 -2.17515 1.6131 -2.17628002 0 P 0 ;0
L 1.6131 -2.17628002 1.61331998 -2.17741004 0 P 0 ;0
L 1.61331998 -2.17741004 1.61361998 -2.17851004 0 P 0 ;0
L 1.61361998 -2.17851004 1.614 -2.17958996 0 P 0 ;0
L 1.614 -2.17958996 1.61413996 -2.17988996 0 P 0 ;0
L 1.61413996 -2.17988996 1.61428996 -2.18018002 0 P 0 ;0
L 1.61428996 -2.18018002 1.61446998 -2.18045 0 P 0 ;0
L 1.61446998 -2.18045 1.61466998 -2.18071004 0 P 0 ;0
L 1.61466998 -2.18071004 1.61488996 -2.18095 0 P 0 ;0
L 1.61488996 -2.18095 1.61511998 -2.18116998 0 P 0 ;0
L 1.61511998 -2.18116998 1.61538002 -2.18138002 0 P 0 ;0
L 1.61538002 -2.18138002 1.61565 -2.18156004 0 P 0 ;0
L 1.61565 -2.18156004 1.61593002 -2.18173002 0 P 0 ;0
L 1.61593002 -2.18173002 1.61623002 -2.18186004 0 P 0 ;0
L 1.61623002 -2.18186004 1.61788002 -2.1825 0 P 0 ;0
L 1.61788002 -2.1825 1.61956998 -2.18301998 0 P 0 ;0
L 1.61956998 -2.18301998 1.6213 -2.18343002 0 P 0 ;0
L 1.6213 -2.18343002 1.62633002 -2.18426004 0 P 0 ;0
L 1.62633002 -2.18426004 1.6314 -2.18471004 0 P 0 ;0
L 1.6314 -2.18471004 1.64436004 -2.18495 0 P 0 ;0
L 1.64436004 -2.18495 1.65711004 -2.18428002 0 P 0 ;0
L 1.65711004 -2.18428002 1.66176998 -2.18366998 0 P 0 ;0
L 1.66176998 -2.18366998 1.66636004 -2.18266998 0 P 0 ;0
L 1.66636004 -2.18266998 1.67123002 -2.18121004 0 P 0 ;0
L 1.67123002 -2.18121004 1.676 -2.17946998 0 P 0 ;0
L 1.676 -2.17946998 1.68068002 -2.17741998 0 P 0 ;0
L 1.68068002 -2.17741998 1.68361998 -2.17588002 0 P 0 ;0
L 1.68361998 -2.17588002 1.68646004 -2.17415 0 P 0 ;0
L 1.68646004 -2.17415 1.68916004 -2.17221998 0 P 0 ;0
L 1.68916004 -2.17221998 1.69175 -2.17008996 0 P 0 ;0
L 1.69175 -2.17008996 1.69515 -2.1668 0 P 0 ;0
L 1.69515 -2.1668 1.69826004 -2.16323996 0 P 0 ;0
L 1.69826004 -2.16323996 1.70108002 -2.15941998 0 P 0 ;0
L 1.70108002 -2.15941998 1.70586004 -2.15176998 0 P 0 ;0
L 1.70586004 -2.15176998 1.71016004 -2.14383002 0 P 0 ;0
L 1.71016004 -2.14383002 1.71481998 -2.13356004 0 P 0 ;0
L 1.71481998 -2.13356004 1.74206998 -2.06631004 0 P 0 ;0
L 1.74206998 -2.06631004 1.77071004 -1.99548002 0 P 0 ;0
L 1.77071004 -1.99548002 1.77088002 -1.99498996 0 P 0 ;0
L 1.77088002 -1.99498996 1.77101998 -1.99448996 0 P 0 ;0
L 1.77101998 -1.99448996 1.77111998 -1.99398996 0 P 0 ;0
L 1.77111998 -1.99398996 1.77118002 -1.99346998 0 P 0 ;0
L 1.77118002 -1.99346998 1.7712 -1.99295 0 P 0 ;0
L 1.7712 -1.99295 1.7712 -1.99293002 0 P 0 ;0
L 1.7712 -1.99293002 1.77118996 -1.99286998 0 P 0 ;0
L 1.77118996 -1.99286998 1.77118002 -1.99286004 0 P 0 ;0
L 1.77118002 -1.99286004 1.77118002 -1.99283996 0 P 0 ;0
L 1.77118002 -1.99283996 1.77111004 -1.99276998 0 P 0 ;0
L 1.77111004 -1.99276998 1.77106998 -1.99275 0 P 0 ;0
L 1.77106998 -1.99275 1.77106004 -1.99273996 0 P 0 ;0
L 1.77106004 -1.99273996 1.771 -1.99273002 0 P 0 ;0
L 1.771 -1.99273002 1.77098002 -1.99273002 0 P 0 ;0
L 1.77098002 -1.99273002 1.76301004 -1.99265 0 P 0 ;0
L 1.76301004 -1.99265 1.75401998 -1.99261004 0 P 0 ;0
L 1.75401998 -1.99261004 1.74333002 -1.9927 0 P 0 ;0
L 1.74333002 -1.9927 1.71546004 -1.99298996 0 P 0 ;0
L 1.71546004 -1.99298996 1.71236998 -2.00646998 0 P 0 ;0
L 1.71236998 -2.00646998 1.70873996 -2.02078002 0 P 0 ;0
L 1.70873996 -2.02078002 1.70233996 -2.04308002 0 P 0 ;0
L 1.70233996 -2.04308002 1.69505 -2.0678 0 P 0 ;0
L 1.69505 -2.0678 1.69501998 -2.06788002 0 P 0 ;0
L 1.69501998 -2.06788002 1.69498996 -2.06795 0 P 0 ;0
L 1.69498996 -2.06795 1.69495 -2.06801998 0 P 0 ;0
L 1.69495 -2.06801998 1.69485 -2.06816004 0 P 0 ;0
L 1.69485 -2.06816004 1.69478996 -2.06821998 0 P 0 ;0
L 1.69478996 -2.06821998 1.69466998 -2.06831998 0 P 0 ;0
L 1.69466998 -2.06831998 1.69453002 -2.0684 0 P 0 ;0
L 1.69453002 -2.0684 1.69445 -2.06843002 0 P 0 ;0
L 1.69445 -2.06843002 1.69438002 -2.06846004 0 P 0 ;0
L 1.69438002 -2.06846004 1.69428996 -2.06846998 0 P 0 ;0
L 1.69428996 -2.06846998 1.69421004 -2.06848996 0 P 0 ;0
L 1.69421004 -2.06848996 1.69406998 -2.06848996 0 P 0 ;0
L 1.69406998 -2.06848996 1.69395 -2.06846998 0 P 0 ;0
L 1.69395 -2.06846998 1.69383002 -2.06843002 0 P 0 ;0
L 1.69383002 -2.06843002 1.69373002 -2.06836998 0 P 0 ;0
L 1.69373002 -2.06836998 1.69363002 -2.06828996 0 P 0 ;0
L 1.69363002 -2.06828996 1.69358996 -2.06823996 0 P 0 ;0
L 1.69358996 -2.06823996 1.69355 -2.0682 0 P 0 ;0
L 1.69355 -2.0682 1.69351998 -2.06815 0 P 0 ;0
L 1.69351998 -2.06815 1.69346004 -2.06803996 0 P 0 ;0
L 1.69346004 -2.06803996 1.69343996 -2.06798002 0 P 0 ;0
L 1.69343996 -2.06798002 1.68523002 -2.03878002 0 P 0 ;0
L 1.68523002 -2.03878002 1.67806998 -2.01291998 0 P 0 ;0
L 1.67806998 -2.01291998 1.67496004 -2.00031004 0 P 0 ;0
L 1.67496004 -2.00031004 1.67323002 -1.99243996 0 P 0 ;0
L 1.67323002 -1.99243996 1.61388002 -1.99243996 0 P 0 ;0
L 1.61388002 -1.99243996 1.61928996 -2.00628002 0 P 0 ;0
L 1.35018002 -2.08345 1.39488996 -2.08345 0 P 0 ;0
L 1.35026004 -2.08245 1.39586004 -2.08245 0 P 0 ;0
L 1.35041004 -2.08145 1.39708996 -2.08145 0 P 0 ;0
L 1.35058996 -2.08045 1.39853002 -2.08045 0 P 0 ;0
L 1.35083996 -2.07945 1.40031998 -2.07945 0 P 0 ;0
L 1.35116998 -2.07845 1.40271004 -2.07845 0 P 0 ;0
L 1.35158002 -2.07745 1.40561998 -2.07745 0 P 0 ;0
L 1.35203002 -2.07645 1.4092 -2.07645 0 P 0 ;0
L 1.35248002 -2.07545 1.41288996 -2.07545 0 P 0 ;0
L 1.35293002 -2.07445 1.4164 -2.07445 0 P 0 ;0
L 1.35338996 -2.07345 1.41975 -2.07345 0 P 0 ;0
L 1.35393996 -2.07245 1.42293996 -2.07245 0 P 0 ;0
L 1.35448996 -2.07145 1.42606998 -2.07145 0 P 0 ;0
L 1.35505 -2.07045 1.47843002 -2.07045 0 P 0 ;0
L 1.3557 -2.06945 1.47846998 -2.06945 0 P 0 ;0
L 1.35635 -2.06845 1.47851998 -2.06845 0 P 0 ;0
L 1.35701998 -2.06745 1.47856998 -2.06745 0 P 0 ;0
L 1.35776998 -2.06645 1.47861004 -2.06645 0 P 0 ;0
L 1.29346998 -2.00516004 1.33388996 -2.00516004 0 P 0 ;0
L 1.29448996 -2.00416004 1.33385 -2.00416004 0 P 0 ;0
L 1.29551004 -2.00316004 1.33381004 -2.00316004 0 P 0 ;0
L 1.29653996 -2.00216004 1.33376004 -2.00216004 0 P 0 ;0
L 1.29756004 -2.00116004 1.33371004 -2.00116004 0 P 0 ;0
L 1.29861998 -2.00016004 1.33366004 -2.00016004 0 P 0 ;0
L 1.29973002 -1.99916004 1.3336 -1.99916004 0 P 0 ;0
L 1.30101004 -1.99816004 1.33355 -1.99816004 0 P 0 ;0
L 1.30238996 -1.99716004 1.3335 -1.99716004 0 P 0 ;0
L 1.30393996 -1.99616004 1.33345 -1.99616004 0 P 0 ;0
L 1.30571004 -1.99516004 1.33338996 -1.99516004 0 P 0 ;0
L 1.3077 -1.99416004 1.33333002 -1.99416004 0 P 0 ;0
L 1.31001004 -1.99316004 1.33328002 -1.99316004 0 P 0 ;0
L 1.31288002 -1.99216004 1.33321998 -1.99216004 0 P 0 ;0
L 1.31688996 -1.99116004 1.33316004 -1.99116004 0 P 0 ;0
L 1.39798996 -1.98971998 1.39326998 -1.99043002 0 P 0 ;0
L 1.39326998 -1.99043002 1.38806998 -1.9913 0 P 0 ;0
L 1.38806998 -1.9913 1.38316004 -1.9922 0 P 0 ;0
L 1.38316004 -1.9922 1.37946004 -1.99296998 0 P 0 ;0
L 1.37946004 -1.99296998 1.3718 -1.99466998 0 P 0 ;0
L 1.3718 -1.99466998 1.36896004 -2.01553996 0 P 0 ;0
L 1.36896004 -2.01553996 1.36791004 -2.02358996 0 P 0 ;0
L 1.36791004 -2.02358996 1.36708002 -2.03043002 0 P 0 ;0
L 1.36708002 -2.03043002 1.36638996 -2.03646004 0 P 0 ;0
L 1.36638996 -2.03646004 1.36638002 -2.03648996 0 P 0 ;0
L 1.36638002 -2.03648996 1.36638996 -2.03653002 0 P 0 ;0
L 1.36638996 -2.03653002 1.36638996 -2.03656998 0 P 0 ;0
L 1.36638996 -2.03656998 1.3664 -2.03663996 0 P 0 ;0
L 1.3664 -2.03663996 1.36641998 -2.03666998 0 P 0 ;0
L 1.36641998 -2.03666998 1.36643002 -2.03671004 0 P 0 ;0
L 1.36643002 -2.03671004 1.36648996 -2.0368 0 P 0 ;0
L 1.36648996 -2.0368 1.36656004 -2.03686004 0 P 0 ;0
L 1.36656004 -2.03686004 1.3666 -2.03688996 0 P 0 ;0
L 1.3666 -2.03688996 1.36663002 -2.03691004 0 P 0 ;0
L 1.36663002 -2.03691004 1.36666004 -2.03691004 0 P 0 ;0
L 1.36666004 -2.03691004 1.36671004 -2.03693002 0 P 0 ;0
L 1.36671004 -2.03693002 1.36676998 -2.03693002 0 P 0 ;0
L 1.36676998 -2.03693002 1.36685 -2.03691998 0 P 0 ;0
L 1.36685 -2.03691998 1.36895 -2.03628002 0 P 0 ;0
L 1.36895 -2.03628002 1.37143002 -2.03545 0 P 0 ;0
L 1.37143002 -2.03545 1.37428996 -2.03441004 0 P 0 ;0
L 1.37428996 -2.03441004 1.38346004 -2.03126998 0 P 0 ;0
L 1.38346004 -2.03126998 1.39251998 -2.02891998 0 P 0 ;0
L 1.39251998 -2.02891998 1.40156004 -2.02731998 0 P 0 ;0
L 1.40156004 -2.02731998 1.41068002 -2.02643996 0 P 0 ;0
L 1.41068002 -2.02643996 1.41566998 -2.02628002 0 P 0 ;0
L 1.41566998 -2.02628002 1.42066004 -2.02633996 0 P 0 ;0
L 1.42066004 -2.02633996 1.42221004 -2.02646998 0 P 0 ;0
L 1.42221004 -2.02646998 1.42375 -2.02671998 0 P 0 ;0
L 1.42375 -2.02671998 1.42525 -2.0271 0 P 0 ;0
L 1.42525 -2.0271 1.42671998 -2.02761004 0 P 0 ;0
L 1.42671998 -2.02761004 1.42706004 -2.02776004 0 P 0 ;0
L 1.42706004 -2.02776004 1.42738002 -2.02793002 0 P 0 ;0
L 1.42738002 -2.02793002 1.42768002 -2.02813996 0 P 0 ;0
L 1.42768002 -2.02813996 1.42796998 -2.02836004 0 P 0 ;0
L 1.42796998 -2.02836004 1.42823002 -2.02861004 0 P 0 ;0
L 1.42823002 -2.02861004 1.42848002 -2.02888996 0 P 0 ;0
L 1.42848002 -2.02888996 1.4287 -2.02918002 0 P 0 ;0
L 1.4287 -2.02918002 1.42888996 -2.02948996 0 P 0 ;0
L 1.42888996 -2.02948996 1.42906004 -2.02981004 0 P 0 ;0
L 1.42906004 -2.02981004 1.4292 -2.03015 0 P 0 ;0
L 1.4292 -2.03015 1.42931998 -2.0305 0 P 0 ;0
L 1.42931998 -2.0305 1.4294 -2.03086004 0 P 0 ;0
L 1.4294 -2.03086004 1.42945 -2.03121998 0 P 0 ;0
L 1.42945 -2.03121998 1.42946998 -2.03158002 0 P 0 ;0
L 1.42946998 -2.03158002 1.42946004 -2.03195 0 P 0 ;0
L 1.42946004 -2.03195 1.42941998 -2.03231004 0 P 0 ;0
L 1.42941998 -2.03231004 1.42935 -2.03266998 0 P 0 ;0
L 1.42935 -2.03266998 1.42925 -2.03301998 0 P 0 ;0
L 1.42925 -2.03301998 1.42911998 -2.03336004 0 P 0 ;0
L 1.42911998 -2.03336004 1.42896004 -2.03368996 0 P 0 ;0
L 1.42896004 -2.03368996 1.42875 -2.03405 0 P 0 ;0
L 1.42875 -2.03405 1.42851004 -2.03438996 0 P 0 ;0
L 1.42851004 -2.03438996 1.42825 -2.03471004 0 P 0 ;0
L 1.42825 -2.03471004 1.42796004 -2.03501004 0 P 0 ;0
L 1.42796004 -2.03501004 1.42765 -2.03528996 0 P 0 ;0
L 1.42765 -2.03528996 1.42731998 -2.03553996 0 P 0 ;0
L 1.42731998 -2.03553996 1.42696998 -2.03576004 0 P 0 ;0
L 1.42696998 -2.03576004 1.4266 -2.03596004 0 P 0 ;0
L 1.4266 -2.03596004 1.41951004 -2.03906004 0 P 0 ;0
L 1.41951004 -2.03906004 1.4109 -2.04208996 0 P 0 ;0
L 1.4109 -2.04208996 1.40178002 -2.04451998 0 P 0 ;0
L 1.40178002 -2.04451998 1.3878 -2.04818996 0 P 0 ;0
L 1.3878 -2.04818996 1.38176998 -2.05015 0 P 0 ;0
L 1.38176998 -2.05015 1.3758 -2.05243002 0 P 0 ;0
L 1.3758 -2.05243002 1.37086998 -2.0546 0 P 0 ;0
L 1.37086998 -2.0546 1.36603996 -2.05708002 0 P 0 ;0
L 1.36603996 -2.05708002 1.36356004 -2.05856004 0 P 0 ;0
L 1.36356004 -2.05856004 1.36118996 -2.06023002 0 P 0 ;0
L 1.36118996 -2.06023002 1.35895 -2.06206004 0 P 0 ;0
L 1.35895 -2.06206004 1.35805 -2.06291004 0 P 0 ;0
L 1.35805 -2.06291004 1.35721998 -2.06385 0 P 0 ;0
L 1.35721998 -2.06385 1.35518996 -2.06655 0 P 0 ;0
L 1.35518996 -2.06655 1.3532 -2.06961998 0 P 0 ;0
L 1.3532 -2.06961998 1.35156004 -2.07263002 0 P 0 ;0
L 1.35156004 -2.07263002 1.34951004 -2.07718002 0 P 0 ;0
L 1.34951004 -2.07718002 1.34911004 -2.07825 0 P 0 ;0
L 1.34911004 -2.07825 1.34878996 -2.07935 0 P 0 ;0
L 1.34878996 -2.07935 1.34853002 -2.08046998 0 P 0 ;0
L 1.34853002 -2.08046998 1.34825 -2.08238002 0 P 0 ;0
L 1.34825 -2.08238002 1.34811998 -2.08431004 0 P 0 ;0
L 1.34811998 -2.08431004 1.348 -2.09128996 0 P 0 ;0
L 1.348 -2.09128996 1.3481 -2.09761004 0 P 0 ;0
L 1.3481 -2.09761004 1.34823002 -2.09961004 0 P 0 ;0
L 1.34823002 -2.09961004 1.34846998 -2.10161004 0 P 0 ;0
L 1.34846998 -2.10161004 1.34876998 -2.10321998 0 P 0 ;0
L 1.34876998 -2.10321998 1.3492 -2.10478996 0 P 0 ;0
L 1.3492 -2.10478996 1.3498 -2.10648996 0 P 0 ;0
L 1.3498 -2.10648996 1.3505 -2.10815 0 P 0 ;0
L 1.3505 -2.10815 1.35178996 -2.11066004 0 P 0 ;0
L 1.35178996 -2.11066004 1.35328002 -2.11305 0 P 0 ;0
L 1.35328002 -2.11305 1.35496998 -2.1153 0 P 0 ;0
L 1.35496998 -2.1153 1.35685 -2.1174 0 P 0 ;0
L 1.35685 -2.1174 1.35891998 -2.11933996 0 P 0 ;0
L 1.35891998 -2.11933996 1.36126998 -2.12121998 0 P 0 ;0
L 1.36126998 -2.12121998 1.36373996 -2.12293002 0 P 0 ;0
L 1.36373996 -2.12293002 1.36633002 -2.12446004 0 P 0 ;0
L 1.36633002 -2.12446004 1.36901004 -2.1258 0 P 0 ;0
L 1.36901004 -2.1258 1.3718 -2.12695 0 P 0 ;0
L 1.3718 -2.12695 1.37578996 -2.12828002 0 P 0 ;0
L 1.37578996 -2.12828002 1.37986998 -2.12928996 0 P 0 ;0
L 1.37986998 -2.12928996 1.38401998 -2.12998996 0 P 0 ;0
L 1.38401998 -2.12998996 1.3882 -2.13036004 0 P 0 ;0
L 1.3882 -2.13036004 1.39443002 -2.13045 0 P 0 ;0
L 1.39443002 -2.13045 1.40066004 -2.13006998 0 P 0 ;0
L 1.40066004 -2.13006998 1.40685 -2.12923002 0 P 0 ;0
L 1.40685 -2.12923002 1.41371004 -2.12801998 0 P 0 ;0
L 1.41371004 -2.12801998 1.41583002 -2.12081004 0 P 0 ;0
L 1.41583002 -2.12081004 1.41953996 -2.10798996 0 P 0 ;0
L 1.41953996 -2.10798996 1.42135 -2.10126998 0 P 0 ;0
L 1.42135 -2.10126998 1.42236998 -2.097 0 P 0 ;0
L 1.42236998 -2.097 1.42238996 -2.09691004 0 P 0 ;0
L 1.42238996 -2.09691004 1.4224 -2.09681998 0 P 0 ;0
L 1.4224 -2.09681998 1.4224 -2.09673996 0 P 0 ;0
L 1.4224 -2.09673996 1.42238002 -2.09656004 0 P 0 ;0
L 1.42238002 -2.09656004 1.42235 -2.09648002 0 P 0 ;0
L 1.42235 -2.09648002 1.42233002 -2.09638996 0 P 0 ;0
L 1.42233002 -2.09638996 1.42225 -2.09623002 0 P 0 ;0
L 1.42225 -2.09623002 1.4222 -2.09616004 0 P 0 ;0
L 1.4222 -2.09616004 1.42213996 -2.09608996 0 P 0 ;0
L 1.42213996 -2.09608996 1.42208996 -2.09601998 0 P 0 ;0
L 1.42208996 -2.09601998 1.42203996 -2.09598996 0 P 0 ;0
L 1.42203996 -2.09598996 1.42198996 -2.09595 0 P 0 ;0
L 1.42198996 -2.09595 1.42188996 -2.09588996 0 P 0 ;0
L 1.42188996 -2.09588996 1.42183002 -2.09586004 0 P 0 ;0
L 1.42183002 -2.09586004 1.42178002 -2.09585 0 P 0 ;0
L 1.42178002 -2.09585 1.42171998 -2.09583002 0 P 0 ;0
L 1.42171998 -2.09583002 1.42166004 -2.09581998 0 P 0 ;0
L 1.42166004 -2.09581998 1.42153996 -2.09581998 0 P 0 ;0
L 1.42153996 -2.09581998 1.41978002 -2.09591004 0 P 0 ;0
L 1.41978002 -2.09591004 1.41763996 -2.09615 0 P 0 ;0
L 1.41763996 -2.09615 1.41521998 -2.09658002 0 P 0 ;0
L 1.41521998 -2.09658002 1.4107 -2.09733002 0 P 0 ;0
L 1.4107 -2.09733002 1.40613002 -2.09775 0 P 0 ;0
L 1.40613002 -2.09775 1.40481004 -2.09778002 0 P 0 ;0
L 1.40481004 -2.09778002 1.40348996 -2.09771998 0 P 0 ;0
L 1.40348996 -2.09771998 1.40216998 -2.09756004 0 P 0 ;0
L 1.40216998 -2.09756004 1.40086998 -2.0973 0 P 0 ;0
L 1.40086998 -2.0973 1.39958996 -2.09695 0 P 0 ;0
L 1.39958996 -2.09695 1.39895 -2.09671998 0 P 0 ;0
L 1.39895 -2.09671998 1.39831998 -2.09643002 0 P 0 ;0
L 1.39831998 -2.09643002 1.39773002 -2.0961 0 P 0 ;0
L 1.39773002 -2.0961 1.39716004 -2.09571004 0 P 0 ;0
L 1.39716004 -2.09571004 1.39663002 -2.09528002 0 P 0 ;0
L 1.39663002 -2.09528002 1.39613996 -2.0948 0 P 0 ;0
L 1.39613996 -2.0948 1.39568002 -2.09428002 0 P 0 ;0
L 1.39568002 -2.09428002 1.39533996 -2.09381998 0 P 0 ;0
L 1.39533996 -2.09381998 1.39505 -2.09333996 0 P 0 ;0
L 1.39505 -2.09333996 1.39478996 -2.09281998 0 P 0 ;0
L 1.39478996 -2.09281998 1.39456998 -2.09228996 0 P 0 ;0
L 1.39456998 -2.09228996 1.3944 -2.09173996 0 P 0 ;0
L 1.3944 -2.09173996 1.39428002 -2.09118996 0 P 0 ;0
L 1.39428002 -2.09118996 1.39421004 -2.09061998 0 P 0 ;0
L 1.39421004 -2.09061998 1.39418002 -2.09003996 0 P 0 ;0
L 1.39418002 -2.09003996 1.39421004 -2.08943002 0 P 0 ;0
L 1.39421004 -2.08943002 1.39428002 -2.08883002 0 P 0 ;0
L 1.39428002 -2.08883002 1.39441004 -2.08823002 0 P 0 ;0
L 1.39441004 -2.08823002 1.3946 -2.08765 0 P 0 ;0
L 1.3946 -2.08765 1.39483002 -2.08708002 0 P 0 ;0
L 1.39483002 -2.08708002 1.39511004 -2.08653996 0 P 0 ;0
L 1.39511004 -2.08653996 1.39555 -2.08583996 0 P 0 ;0
L 1.39555 -2.08583996 1.39603996 -2.08518002 0 P 0 ;0
L 1.39603996 -2.08518002 1.39658002 -2.08456004 0 P 0 ;0
L 1.39658002 -2.08456004 1.39716004 -2.08396998 0 P 0 ;0
L 1.39716004 -2.08396998 1.39778002 -2.08343002 0 P 0 ;0
L 1.39778002 -2.08343002 1.39878996 -2.08266998 0 P 0 ;0
L 1.39878996 -2.08266998 1.39985 -2.08196998 0 P 0 ;0
L 1.39985 -2.08196998 1.40096004 -2.08135 0 P 0 ;0
L 1.40096004 -2.08135 1.40211998 -2.08081004 0 P 0 ;0
L 1.40211998 -2.08081004 1.40503002 -2.07971004 0 P 0 ;0
L 1.40503002 -2.07971004 1.40801998 -2.07881998 0 P 0 ;0
L 1.40801998 -2.07881998 1.41128996 -2.07796004 0 P 0 ;0
L 1.41128996 -2.07796004 1.41506004 -2.07691998 0 P 0 ;0
L 1.41506004 -2.07691998 1.41871998 -2.07585 0 P 0 ;0
L 1.41871998 -2.07585 1.42165 -2.07495 0 P 0 ;0
L 1.42165 -2.07495 1.42791998 -2.07295 0 P 0 ;0
L 1.42791998 -2.07295 1.42731998 -2.08241004 0 P 0 ;0
L 1.42731998 -2.08241004 1.42701004 -2.08708002 0 P 0 ;0
L 1.42701004 -2.08708002 1.42658002 -2.09353996 0 P 0 ;0
L 1.42658002 -2.09353996 1.4261 -2.10055 0 P 0 ;0
L 1.4261 -2.10055 1.42566998 -2.10706004 0 P 0 ;0
L 1.42566998 -2.10706004 1.42525 -2.11306004 0 P 0 ;0
L 1.42525 -2.11306004 1.42491998 -2.11851998 0 P 0 ;0
L 1.42491998 -2.11851998 1.42466004 -2.1231 0 P 0 ;0
L 1.42466004 -2.1231 1.42461004 -2.12471004 0 P 0 ;0
L 1.42461004 -2.12471004 1.4246 -2.12716004 0 P 0 ;0
L 1.4246 -2.12716004 1.47893002 -2.12716004 0 P 0 ;0
L 1.47893002 -2.12716004 1.47893002 -2.11358002 0 P 0 ;0
L 1.47893002 -2.11358002 1.47905 -2.10616998 0 P 0 ;0
L 1.47905 -2.10616998 1.47943996 -2.09385 0 P 0 ;0
L 1.47943996 -2.09385 1.48 -2.07968996 0 P 0 ;0
L 1.48 -2.07968996 1.48066004 -2.0655 0 P 0 ;0
L 1.48066004 -2.0655 1.4813 -2.05168996 0 P 0 ;0
L 1.4813 -2.05168996 1.48175 -2.03873996 0 P 0 ;0
L 1.48175 -2.03873996 1.48201998 -2.02785 0 P 0 ;0
L 1.48201998 -2.02785 1.48191998 -2.02286004 0 P 0 ;0
L 1.48191998 -2.02286004 1.48165 -2.01995 0 P 0 ;0
L 1.48165 -2.01995 1.48115 -2.01708002 0 P 0 ;0
L 1.48115 -2.01708002 1.48043996 -2.01425 0 P 0 ;0
L 1.48043996 -2.01425 1.47951004 -2.01146998 0 P 0 ;0
L 1.47951004 -2.01146998 1.47866998 -2.00946998 0 P 0 ;0
L 1.47866998 -2.00946998 1.47768002 -2.00753996 0 P 0 ;0
L 1.47768002 -2.00753996 1.47655 -2.00568002 0 P 0 ;0
L 1.47655 -2.00568002 1.47528002 -2.00391998 0 P 0 ;0
L 1.47528002 -2.00391998 1.47388002 -2.00225 0 P 0 ;0
L 1.47388002 -2.00225 1.47228996 -2.00063002 0 P 0 ;0
L 1.47228996 -2.00063002 1.4706 -1.99911998 0 P 0 ;0
L 1.4706 -1.99911998 1.4688 -1.99773002 0 P 0 ;0
L 1.4688 -1.99773002 1.46691004 -1.99648002 0 P 0 ;0
L 1.46691004 -1.99648002 1.46491998 -1.99535 0 P 0 ;0
L 1.46491998 -1.99535 1.46098996 -1.99351004 0 P 0 ;0
L 1.46098996 -1.99351004 1.45693002 -1.99196998 0 P 0 ;0
L 1.45693002 -1.99196998 1.45276004 -1.99076004 0 P 0 ;0
L 1.45276004 -1.99076004 1.44953996 -1.99006004 0 P 0 ;0
L 1.44953996 -1.99006004 1.44628996 -1.98956004 0 P 0 ;0
L 1.44628996 -1.98956004 1.44298002 -1.98923996 0 P 0 ;0
L 1.44298002 -1.98923996 1.42695 -1.98856998 0 P 0 ;0
L 1.42695 -1.98856998 1.41038996 -1.98865 0 P 0 ;0
L 1.41038996 -1.98865 1.4042 -1.98901004 0 P 0 ;0
L 1.4042 -1.98901004 1.39798996 -1.98971998 0 P 0 ;0
L 1.35778996 -2.11545 1.4153 -2.11545 0 P 0 ;0
L 1.35688996 -2.11445 1.41558996 -2.11445 0 P 0 ;0
L 1.35608002 -2.11345 1.41588002 -2.11345 0 P 0 ;0
L 1.35533002 -2.11245 1.41616998 -2.11245 0 P 0 ;0
L 1.35463996 -2.11145 1.41646004 -2.11145 0 P 0 ;0
L 1.35401004 -2.11045 1.41675 -2.11045 0 P 0 ;0
L 1.35341004 -2.10945 1.41703996 -2.10945 0 P 0 ;0
L 1.3529 -2.10845 1.41733002 -2.10845 0 P 0 ;0
L 1.35238002 -2.10745 1.41761998 -2.10745 0 P 0 ;0
L 1.35195 -2.10645 1.41788002 -2.10645 0 P 0 ;0
L 1.35155 -2.10545 1.41816004 -2.10545 0 P 0 ;0
L 1.3512 -2.10445 1.41841998 -2.10445 0 P 0 ;0
L 1.35091004 -2.10345 1.41868996 -2.10345 0 P 0 ;0
L 1.35066004 -2.10245 1.41896004 -2.10245 0 P 0 ;0
L 1.35046998 -2.10145 1.41923002 -2.10145 0 P 0 ;0
L 1.35033996 -2.10045 1.41948996 -2.10045 0 P 0 ;0
L 1.35021998 -2.09945 1.40141004 -2.09945 0 P 0 ;0
L 1.35016004 -2.09845 1.39791004 -2.09845 0 P 0 ;0
L 1.3501 -2.09745 1.39616004 -2.09745 0 P 0 ;0
L 1.35008002 -2.09645 1.39496004 -2.09645 0 P 0 ;0
L 1.35006998 -2.09545 1.39406004 -2.09545 0 P 0 ;0
L 1.35005 -2.09445 1.39338002 -2.09445 0 P 0 ;0
L 1.35003996 -2.09345 1.39288002 -2.09345 0 P 0 ;0
L 1.35001998 -2.09245 1.39253002 -2.09245 0 P 0 ;0
L 1.35001004 -2.09145 1.3923 -2.09145 0 P 0 ;0
L 1.35001998 -2.09045 1.3922 -2.09045 0 P 0 ;0
L 1.35003002 -2.08945 1.3922 -2.08945 0 P 0 ;0
L 1.35005 -2.08845 1.39231998 -2.08845 0 P 0 ;0
L 1.35006998 -2.08745 1.39256004 -2.08745 0 P 0 ;0
L 1.35008002 -2.08645 1.39293002 -2.08645 0 P 0 ;0
L 1.3501 -2.08545 1.39343002 -2.08545 0 P 0 ;0
L 1.35011004 -2.08445 1.39408996 -2.08445 0 P 0 ;0
L 1.39438002 -2.12845 1.3883 -2.12836004 0 P 0 ;0
L 1.3883 -2.12836004 1.38426998 -2.128 0 P 0 ;0
L 1.38426998 -2.128 1.38028002 -2.12733002 0 P 0 ;0
L 1.38028002 -2.12733002 1.37635 -2.12636004 0 P 0 ;0
L 1.37635 -2.12636004 1.37248996 -2.12508002 0 P 0 ;0
L 1.37248996 -2.12508002 1.36983996 -2.12398002 0 P 0 ;0
L 1.36983996 -2.12398002 1.36728996 -2.1227 0 P 0 ;0
L 1.36728996 -2.1227 1.36481998 -2.12123996 0 P 0 ;0
L 1.36481998 -2.12123996 1.36246004 -2.11961004 0 P 0 ;0
L 1.36246004 -2.11961004 1.36023002 -2.11781998 0 P 0 ;0
L 1.36023002 -2.11781998 1.35828996 -2.116 0 P 0 ;0
L 1.35828996 -2.116 1.35651998 -2.11403002 0 P 0 ;0
L 1.35651998 -2.11403002 1.35493002 -2.11191004 0 P 0 ;0
L 1.35493002 -2.11191004 1.35353002 -2.10966998 0 P 0 ;0
L 1.35353002 -2.10966998 1.35231004 -2.10731004 0 P 0 ;0
L 1.35231004 -2.10731004 1.35166998 -2.10576998 0 P 0 ;0
L 1.35166998 -2.10576998 1.35111004 -2.1042 0 P 0 ;0
L 1.35111004 -2.1042 1.35071998 -2.10276004 0 P 0 ;0
L 1.35071998 -2.10276004 1.35045 -2.1013 0 P 0 ;0
L 1.35045 -2.1013 1.35021998 -2.09943002 0 P 0 ;0
L 1.35021998 -2.09943002 1.3501 -2.09753002 0 P 0 ;0
L 1.3501 -2.09753002 1.35001004 -2.09128002 0 P 0 ;0
L 1.35001004 -2.09128002 1.35011998 -2.0844 0 P 0 ;0
L 1.35011998 -2.0844 1.35023996 -2.08258996 0 P 0 ;0
L 1.35023996 -2.08258996 1.3505 -2.08083996 0 P 0 ;0
L 1.3505 -2.08083996 1.35071998 -2.07985 0 P 0 ;0
L 1.35071998 -2.07985 1.35101004 -2.07888002 0 P 0 ;0
L 1.35101004 -2.07888002 1.35136004 -2.07793002 0 P 0 ;0
L 1.35136004 -2.07793002 1.35335 -2.07351998 0 P 0 ;0
L 1.35335 -2.07351998 1.35491998 -2.07065 0 P 0 ;0
L 1.35491998 -2.07065 1.35683002 -2.0677 0 P 0 ;0
L 1.35683002 -2.0677 1.35876998 -2.06511004 0 P 0 ;0
L 1.35876998 -2.06511004 1.35948996 -2.0643 0 P 0 ;0
L 1.35948996 -2.0643 1.36026998 -2.06356004 0 P 0 ;0
L 1.36026998 -2.06356004 1.3624 -2.06181998 0 P 0 ;0
L 1.3624 -2.06181998 1.36465 -2.06023996 0 P 0 ;0
L 1.36465 -2.06023996 1.36701004 -2.05883002 0 P 0 ;0
L 1.36701004 -2.05883002 1.37173002 -2.05641004 0 P 0 ;0
L 1.37173002 -2.05641004 1.37656004 -2.05426998 0 P 0 ;0
L 1.37656004 -2.05426998 1.38243002 -2.05203996 0 P 0 ;0
L 1.38243002 -2.05203996 1.38836004 -2.0501 0 P 0 ;0
L 1.38836004 -2.0501 1.4023 -2.04645 0 P 0 ;0
L 1.4023 -2.04645 1.41148996 -2.044 0 P 0 ;0
L 1.41148996 -2.044 1.42016998 -2.04095 0 P 0 ;0
L 1.42016998 -2.04095 1.42016998 -2.04093996 0 P 0 ;0
L 1.42016998 -2.04093996 1.42021004 -2.04093996 0 P 0 ;0
L 1.42021004 -2.04093996 1.42023996 -2.04093002 0 P 0 ;0
L 1.42023996 -2.04093002 1.42746998 -2.03776004 0 P 0 ;0
L 1.42746998 -2.03776004 1.42753002 -2.03773002 0 P 0 ;0
L 1.42753002 -2.03773002 1.42796998 -2.03748996 0 P 0 ;0
L 1.42796998 -2.03748996 1.42846004 -2.03718996 0 P 0 ;0
L 1.42846004 -2.03718996 1.42891998 -2.03683996 0 P 0 ;0
L 1.42891998 -2.03683996 1.42935 -2.03646004 0 P 0 ;0
L 1.42935 -2.03646004 1.42975 -2.03603996 0 P 0 ;0
L 1.42975 -2.03603996 1.43011004 -2.0356 0 P 0 ;0
L 1.43011004 -2.0356 1.43016004 -2.03553002 0 P 0 ;0
L 1.43016004 -2.03553002 1.4299 -2.03535 0 P 0 ;0
L 1.4299 -2.03535 1.43028002 -2.03535 0 P 0 ;0
L 1.43028002 -2.03535 1.43043996 -2.03513002 0 P 0 ;0
L 1.43043996 -2.03513002 1.43048002 -2.03506004 0 P 0 ;0
L 1.43048002 -2.03506004 1.43041998 -2.03501998 0 P 0 ;0
L 1.43041998 -2.03501998 1.4305 -2.03501998 0 P 0 ;0
L 1.4305 -2.03501998 1.43073002 -2.03463002 0 P 0 ;0
L 1.43073002 -2.03463002 1.43096004 -2.03415 0 P 0 ;0
L 1.43096004 -2.03415 1.43115 -2.03365 0 P 0 ;0
L 1.43115 -2.03365 1.4313 -2.03313002 0 P 0 ;0
L 1.4313 -2.03313002 1.4314 -2.03261004 0 P 0 ;0
L 1.4314 -2.03261004 1.43146004 -2.03208002 0 P 0 ;0
L 1.43146004 -2.03208002 1.43146998 -2.03155 0 P 0 ;0
L 1.43146998 -2.03155 1.43143996 -2.03101004 0 P 0 ;0
L 1.43143996 -2.03101004 1.43143002 -2.03093002 0 P 0 ;0
L 1.43143002 -2.03093002 1.43136004 -2.03048996 0 P 0 ;0
L 1.43136004 -2.03048996 1.43125 -2.02996998 0 P 0 ;0
L 1.43125 -2.02996998 1.43108002 -2.02946004 0 P 0 ;0
L 1.43108002 -2.02946004 1.43086998 -2.02896004 0 P 0 ;0
L 1.43086998 -2.02896004 1.43063002 -2.02848996 0 P 0 ;0
L 1.43063002 -2.02848996 1.43033996 -2.02803996 0 P 0 ;0
L 1.43033996 -2.02803996 1.43001998 -2.02761004 0 P 0 ;0
L 1.43001998 -2.02761004 1.42966004 -2.02721004 0 P 0 ;0
L 1.42966004 -2.02721004 1.42928002 -2.02685 0 P 0 ;0
L 1.42928002 -2.02685 1.42886004 -2.02651998 0 P 0 ;0
L 1.42886004 -2.02651998 1.42841998 -2.02623002 0 P 0 ;0
L 1.42841998 -2.02623002 1.42795 -2.02596998 0 P 0 ;0
L 1.42795 -2.02596998 1.42746004 -2.02575 0 P 0 ;0
L 1.42746004 -2.02575 1.42583002 -2.02518002 0 P 0 ;0
L 1.42583002 -2.02518002 1.42416004 -2.02476004 0 P 0 ;0
L 1.42416004 -2.02476004 1.42245 -2.02448002 0 P 0 ;0
L 1.42245 -2.02448002 1.42075 -2.02435 0 P 0 ;0
L 1.42075 -2.02435 1.41565 -2.02428002 0 P 0 ;0
L 1.41565 -2.02428002 1.4156 -2.02428002 0 P 0 ;0
L 1.4156 -2.02428002 1.41055 -2.02445 0 P 0 ;0
L 1.41055 -2.02445 1.41048002 -2.02445 0 P 0 ;0
L 1.41048002 -2.02445 1.40128996 -2.02533996 0 P 0 ;0
L 1.40128996 -2.02533996 1.39208996 -2.02696998 0 P 0 ;0
L 1.39208996 -2.02696998 1.38288002 -2.02936004 0 P 0 ;0
L 1.38288002 -2.02936004 1.37363002 -2.03251998 0 P 0 ;0
L 1.37363002 -2.03251998 1.37076998 -2.03356004 0 P 0 ;0
L 1.37076998 -2.03356004 1.36865 -2.03426998 0 P 0 ;0
L 1.36865 -2.03426998 1.36906004 -2.03066998 0 P 0 ;0
L 1.36906004 -2.03066998 1.36988996 -2.02383996 0 P 0 ;0
L 1.36988996 -2.02383996 1.37095 -2.01581004 0 P 0 ;0
L 1.37095 -2.01581004 1.37358996 -1.99631998 0 P 0 ;0
L 1.37358996 -1.99631998 1.37988002 -1.99491998 0 P 0 ;0
L 1.37988002 -1.99491998 1.38353996 -1.99416998 0 P 0 ;0
L 1.38353996 -1.99416998 1.38841998 -1.99326998 0 P 0 ;0
L 1.38841998 -1.99326998 1.39358002 -1.9924 0 P 0 ;0
L 1.39358002 -1.9924 1.39825 -1.9917 0 P 0 ;0
L 1.39825 -1.9917 1.40436998 -1.991 0 P 0 ;0
L 1.40436998 -1.991 1.41045 -1.99065 0 P 0 ;0
L 1.41045 -1.99065 1.42691004 -1.99056998 0 P 0 ;0
L 1.42691004 -1.99056998 1.44283996 -1.99123996 0 P 0 ;0
L 1.44283996 -1.99123996 1.44603996 -1.99153996 0 P 0 ;0
L 1.44603996 -1.99153996 1.44918002 -1.99203002 0 P 0 ;0
L 1.44918002 -1.99203002 1.45226004 -1.9927 0 P 0 ;0
L 1.45226004 -1.9927 1.4563 -1.99386998 0 P 0 ;0
L 1.4563 -1.99386998 1.46021004 -1.99535 0 P 0 ;0
L 1.46021004 -1.99535 1.464 -1.99713002 0 P 0 ;0
L 1.464 -1.99713002 1.46586004 -1.99818996 0 P 0 ;0
L 1.46586004 -1.99818996 1.46763996 -1.99936004 0 P 0 ;0
L 1.46763996 -1.99936004 1.46931998 -2.00066004 0 P 0 ;0
L 1.46931998 -2.00066004 1.47091004 -2.00206998 0 P 0 ;0
L 1.47091004 -2.00206998 1.47238996 -2.00358996 0 P 0 ;0
L 1.47238996 -2.00358996 1.4737 -2.00515 0 P 0 ;0
L 1.4737 -2.00515 1.47488002 -2.00678996 0 P 0 ;0
L 1.47488002 -2.00678996 1.47593996 -2.00851004 0 P 0 ;0
L 1.47593996 -2.00851004 1.47686004 -2.01031004 0 P 0 ;0
L 1.47686004 -2.01031004 1.47763996 -2.01216998 0 P 0 ;0
L 1.47763996 -2.01216998 1.47851998 -2.01481004 0 P 0 ;0
L 1.47851998 -2.01481004 1.47918996 -2.01748996 0 P 0 ;0
L 1.47918996 -2.01748996 1.47966004 -2.02021998 0 P 0 ;0
L 1.47966004 -2.02021998 1.47993002 -2.02296998 0 P 0 ;0
L 1.47993002 -2.02296998 1.48001998 -2.02783996 0 P 0 ;0
L 1.48001998 -2.02783996 1.47975 -2.03868996 0 P 0 ;0
L 1.47975 -2.03868996 1.4793 -2.05161004 0 P 0 ;0
L 1.4793 -2.05161004 1.47866004 -2.06543002 0 P 0 ;0
L 1.47866004 -2.06543002 1.47801004 -2.07961004 0 P 0 ;0
L 1.47801004 -2.07961004 1.47743996 -2.09378996 0 P 0 ;0
L 1.47743996 -2.09378996 1.47705 -2.10613002 0 P 0 ;0
L 1.47705 -2.10613002 1.47693002 -2.11356004 0 P 0 ;0
L 1.47693002 -2.11356004 1.47693002 -2.12516004 0 P 0 ;0
L 1.47693002 -2.12516004 1.42661004 -2.12516004 0 P 0 ;0
L 1.42661004 -2.12516004 1.42661004 -2.12473996 0 P 0 ;0
L 1.42661004 -2.12473996 1.42666004 -2.12318002 0 P 0 ;0
L 1.42666004 -2.12318002 1.42691004 -2.11863996 0 P 0 ;0
L 1.42691004 -2.11863996 1.42725 -2.1132 0 P 0 ;0
L 1.42725 -2.1132 1.42766004 -2.1072 0 P 0 ;0
L 1.42766004 -2.1072 1.42766004 -2.10718996 0 P 0 ;0
L 1.42766004 -2.10718996 1.4281 -2.10068996 0 P 0 ;0
L 1.4281 -2.10068996 1.42858002 -2.09368002 0 P 0 ;0
L 1.42858002 -2.09368002 1.42901004 -2.08721004 0 P 0 ;0
L 1.42901004 -2.08721004 1.42901004 -2.0872 0 P 0 ;0
L 1.42901004 -2.0872 1.42931004 -2.08256004 0 P 0 ;0
L 1.42931004 -2.08256004 1.42991998 -2.07308002 0 P 0 ;0
L 1.42991998 -2.07308002 1.42916004 -2.07136998 0 P 0 ;0
L 1.42916004 -2.07136998 1.42731998 -2.07105 0 P 0 ;0
L 1.42731998 -2.07105 1.42105 -2.07303996 0 P 0 ;0
L 1.42105 -2.07303996 1.41815 -2.07393002 0 P 0 ;0
L 1.41815 -2.07393002 1.41451004 -2.075 0 P 0 ;0
L 1.41451004 -2.075 1.41076004 -2.07603002 0 P 0 ;0
L 1.41076004 -2.07603002 1.40748002 -2.0769 0 P 0 ;0
L 1.40748002 -2.0769 1.40438996 -2.07781004 0 P 0 ;0
L 1.40438996 -2.07781004 1.40431998 -2.07783996 0 P 0 ;0
L 1.40431998 -2.07783996 1.40133996 -2.07896998 0 P 0 ;0
L 1.40133996 -2.07896998 1.40005 -2.07956998 0 P 0 ;0
L 1.40005 -2.07956998 1.39881998 -2.08026004 0 P 0 ;0
L 1.39881998 -2.08026004 1.39763996 -2.08103002 0 P 0 ;0
L 1.39763996 -2.08103002 1.39651998 -2.08188002 0 P 0 ;0
L 1.39651998 -2.08188002 1.39578996 -2.08251004 0 P 0 ;0
L 1.39578996 -2.08251004 1.39573996 -2.08256004 0 P 0 ;0
L 1.39573996 -2.08256004 1.3951 -2.08318996 0 P 0 ;0
L 1.3951 -2.08318996 1.39446998 -2.08393002 0 P 0 ;0
L 1.39446998 -2.08393002 1.3939 -2.08471004 0 P 0 ;0
L 1.3939 -2.08471004 1.39336998 -2.08553996 0 P 0 ;0
L 1.39336998 -2.08553996 1.39301004 -2.08623996 0 P 0 ;0
L 1.39301004 -2.08623996 1.39271004 -2.08696998 0 P 0 ;0
L 1.39271004 -2.08696998 1.39248002 -2.08771998 0 P 0 ;0
L 1.39248002 -2.08771998 1.39231004 -2.08848996 0 P 0 ;0
L 1.39231004 -2.08848996 1.39221004 -2.08926004 0 P 0 ;0
L 1.39221004 -2.08926004 1.39218002 -2.09003996 0 P 0 ;0
L 1.39218002 -2.09003996 1.39221004 -2.0908 0 P 0 ;0
L 1.39221004 -2.0908 1.39231004 -2.09153002 0 P 0 ;0
L 1.39231004 -2.09153002 1.39246998 -2.09226004 0 P 0 ;0
L 1.39246998 -2.09226004 1.39268996 -2.09296998 0 P 0 ;0
L 1.39268996 -2.09296998 1.39296004 -2.09365 0 P 0 ;0
L 1.39296004 -2.09365 1.3933 -2.09431004 0 P 0 ;0
L 1.3933 -2.09431004 1.39368996 -2.09493996 0 P 0 ;0
L 1.39368996 -2.09493996 1.39411998 -2.09553996 0 P 0 ;0
L 1.39411998 -2.09553996 1.39468996 -2.09618002 0 P 0 ;0
L 1.39468996 -2.09618002 1.3953 -2.09678002 0 P 0 ;0
L 1.3953 -2.09678002 1.39596004 -2.09731998 0 P 0 ;0
L 1.39596004 -2.09731998 1.39666998 -2.0978 0 P 0 ;0
L 1.39666998 -2.0978 1.39673996 -2.09783996 0 P 0 ;0
L 1.39673996 -2.09783996 1.39741004 -2.09821998 0 P 0 ;0
L 1.39741004 -2.09821998 1.39748996 -2.09825 0 P 0 ;0
L 1.39748996 -2.09825 1.39818996 -2.09856998 0 P 0 ;0
L 1.39818996 -2.09856998 1.39898996 -2.09886004 0 P 0 ;0
L 1.39898996 -2.09886004 1.39906998 -2.09888002 0 P 0 ;0
L 1.39906998 -2.09888002 1.40043996 -2.09888002 0 P 0 ;0
L 1.40043996 -2.09888002 1.40033996 -2.09923002 0 P 0 ;0
L 1.40033996 -2.09923002 1.40041998 -2.09925 0 P 0 ;0
L 1.40041998 -2.09925 1.40186004 -2.09953002 0 P 0 ;0
L 1.40186004 -2.09953002 1.40331004 -2.09971004 0 P 0 ;0
L 1.40331004 -2.09971004 1.40478002 -2.09978002 0 P 0 ;0
L 1.40478002 -2.09978002 1.40625 -2.09975 0 P 0 ;0
L 1.40625 -2.09975 1.41096004 -2.09931004 0 P 0 ;0
L 1.41096004 -2.09931004 1.41556998 -2.09855 0 P 0 ;0
L 1.41556998 -2.09855 1.41791998 -2.09813002 0 P 0 ;0
L 1.41791998 -2.09813002 1.41995 -2.09791004 0 P 0 ;0
L 1.41995 -2.09791004 1.4201 -2.0979 0 P 0 ;0
L 1.4201 -2.0979 1.41941004 -2.10078002 0 P 0 ;0
L 1.41941004 -2.10078002 1.41761004 -2.10745 0 P 0 ;0
L 1.41761004 -2.10745 1.41391004 -2.12025 0 P 0 ;0
L 1.41391004 -2.12025 1.41215 -2.12626998 0 P 0 ;0
L 1.41215 -2.12626998 1.40655 -2.12725 0 P 0 ;0
L 1.40655 -2.12725 1.40046004 -2.12808002 0 P 0 ;0
L 1.40046004 -2.12808002 1.39438002 -2.12845 0 P 0 ;0
L 1.15303002 -2.08283002 1.20788996 -2.08283002 0 P 0 ;0
L 1.15398996 -2.08183002 1.20795 -2.08183002 0 P 0 ;0
L 1.15483002 -2.08083002 1.208 -2.08083002 0 P 0 ;0
L 1.15555 -2.07983002 1.20805 -2.07983002 0 P 0 ;0
L 1.15621998 -2.07883002 1.2081 -2.07883002 0 P 0 ;0
L 1.15681998 -2.07783002 1.20816004 -2.07783002 0 P 0 ;0
L 1.15733002 -2.07683002 1.20821004 -2.07683002 0 P 0 ;0
L 1.15778996 -2.07583002 1.20826004 -2.07583002 0 P 0 ;0
L 1.15818002 -2.07483002 1.20831004 -2.07483002 0 P 0 ;0
L 1.15853996 -2.07383002 1.20836998 -2.07383002 0 P 0 ;0
L 1.15881998 -2.07283002 1.20841998 -2.07283002 0 P 0 ;0
L 1.1591 -2.07183002 1.20846998 -2.07183002 0 P 0 ;0
L 1.15938002 -2.07083002 1.20853002 -2.07083002 0 P 0 ;0
L 1.1596 -2.06983002 1.20858002 -2.06983002 0 P 0 ;0
L 1.15981004 -2.06883002 1.20863996 -2.06883002 0 P 0 ;0
L 1.16001004 -2.06783002 1.20868996 -2.06783002 0 P 0 ;0
L 1.1602 -2.06683002 1.20875 -2.06683002 0 P 0 ;0
L 1.16033996 -2.06583002 1.2088 -2.06583002 0 P 0 ;0
L 1.16048996 -2.06483002 1.20886004 -2.06483002 0 P 0 ;0
L 1.16063996 -2.06383002 1.20891998 -2.06383002 0 P 0 ;0
L 1.16078002 -2.06283002 1.20896998 -2.06283002 0 P 0 ;0
L 1.16088996 -2.06183002 1.20903002 -2.06183002 0 P 0 ;0
L 1.16098996 -2.06083002 1.20908002 -2.06083002 0 P 0 ;0
L 1.16108996 -2.05983002 1.20913996 -2.05983002 0 P 0 ;0
L 1.16118002 -2.05883002 1.20918996 -2.05883002 0 P 0 ;0
L 1.16128002 -2.05783002 1.20925 -2.05783002 0 P 0 ;0
L 1.16133996 -2.05683002 1.2093 -2.05683002 0 P 0 ;0
L 1.1614 -2.05583002 1.20936004 -2.05583002 0 P 0 ;0
L 1.16146004 -2.05483002 1.20941004 -2.05483002 0 P 0 ;0
L 1.16151998 -2.05383002 1.20946998 -2.05383002 0 P 0 ;0
L 1.16158002 -2.05283002 1.20951998 -2.05283002 0 P 0 ;0
L 1.16163996 -2.05183002 1.20958002 -2.05183002 0 P 0 ;0
L 1.1617 -2.05083002 1.20963996 -2.05083002 0 P 0 ;0
L 1.16175 -2.04983002 1.2097 -2.04983002 0 P 0 ;0
L 1.16181004 -2.04883002 1.20975 -2.04883002 0 P 0 ;0
L 1.16186998 -2.04783002 1.20981004 -2.04783002 0 P 0 ;0
L 1.16193002 -2.04683002 1.20986998 -2.04683002 0 P 0 ;0
L 1.16198996 -2.04583002 1.20993002 -2.04583002 0 P 0 ;0
L 1.16205 -2.04483002 1.20998996 -2.04483002 0 P 0 ;0
L 1.16211004 -2.04383002 1.21005 -2.04383002 0 P 0 ;0
L 1.16215 -2.04283002 1.2101 -2.04283002 0 P 0 ;0
L 1.1622 -2.04183002 1.21016004 -2.04183002 0 P 0 ;0
L 1.16225 -2.04083002 1.21021998 -2.04083002 0 P 0 ;0
L 1.16228996 -2.03983002 1.21028002 -2.03983002 0 P 0 ;0
L 1.16233996 -2.03883002 1.21033996 -2.03883002 0 P 0 ;0
L 1.16238002 -2.03783002 1.2104 -2.03783002 0 P 0 ;0
L 1.16243002 -2.03683002 1.21046004 -2.03683002 0 P 0 ;0
L 1.16246998 -2.03583002 1.21051004 -2.03583002 0 P 0 ;0
L 1.16251998 -2.03483002 1.21056998 -2.03483002 0 P 0 ;0
L 1.16256998 -2.03383002 1.21063996 -2.03383002 0 P 0 ;0
L 1.16261004 -2.03283002 1.2107 -2.03283002 0 P 0 ;0
L 1.16266004 -2.03183002 1.21076004 -2.03183002 0 P 0 ;0
L 1.1627 -2.03083002 1.21083002 -2.03083002 0 P 0 ;0
L 1.16015 -1.97631004 1.17066004 -1.97631004 0 P 0 ;0
L 1.15961998 -1.97531004 1.17026004 -1.97531004 0 P 0 ;0
L 1.1591 -1.97431004 1.16986998 -1.97431004 0 P 0 ;0
L 1.15856998 -1.97331004 1.16946998 -1.97331004 0 P 0 ;0
L 1.15803996 -1.97231004 1.16903002 -1.97231004 0 P 0 ;0
L 1.15746998 -1.97131004 1.16858996 -1.97131004 0 P 0 ;0
L 1.1569 -1.97031004 1.16815 -1.97031004 0 P 0 ;0
L 1.15631998 -1.96931004 1.16771004 -1.96931004 0 P 0 ;0
L 1.15573996 -1.96831004 1.16726998 -1.96831004 0 P 0 ;0
L 1.15516004 -1.96731004 1.16681998 -1.96731004 0 P 0 ;0
L 1.15458996 -1.96631004 1.16638002 -1.96631004 0 P 0 ;0
L 1.15398002 -1.96531004 1.16593996 -1.96531004 0 P 0 ;0
L 1.1533 -1.96431004 1.16548996 -1.96431004 0 P 0 ;0
L 1.15261998 -1.96331004 1.16503002 -1.96331004 0 P 0 ;0
L 1.15193996 -1.96231004 1.16448002 -1.96231004 0 P 0 ;0
L 1.15126004 -1.96131004 1.16393002 -1.96131004 0 P 0 ;0
L 1.15058002 -1.96031004 1.16338002 -1.96031004 0 P 0 ;0
L 1.1499 -1.95931004 1.16283002 -1.95931004 0 P 0 ;0
L 1.1491 -1.95831004 1.16228996 -1.95831004 0 P 0 ;0
L 1.14831004 -1.95731004 1.16173996 -1.95731004 0 P 0 ;0
L 1.14751004 -1.95631004 1.16118996 -1.95631004 0 P 0 ;0
L 1.14671004 -1.95531004 1.16063996 -1.95531004 0 P 0 ;0
L 1.14591998 -1.95431004 1.16008996 -1.95431004 0 P 0 ;0
L 1.14511998 -1.95331004 1.15943996 -1.95331004 0 P 0 ;0
L 1.1442 -1.95231004 1.15878002 -1.95231004 0 P 0 ;0
L 1.14326998 -1.95131004 1.15811004 -1.95131004 0 P 0 ;0
L 1.14233996 -1.95031004 1.15745 -1.95031004 0 P 0 ;0
L 1.14141004 -1.94931004 1.15678002 -1.94931004 0 P 0 ;0
L 1.14048996 -1.94831004 1.15611998 -1.94831004 0 P 0 ;0
L 1.1395 -1.94731004 1.15545 -1.94731004 0 P 0 ;0
L 1.13843002 -1.94631004 1.15478996 -1.94631004 0 P 0 ;0
L 1.13736004 -1.94531004 1.15411998 -1.94531004 0 P 0 ;0
L 1.13628996 -1.94431004 1.15333002 -1.94431004 0 P 0 ;0
L 1.13521004 -1.94331004 1.15253002 -1.94331004 0 P 0 ;0
L 1.13413996 -1.94231004 1.15173996 -1.94231004 0 P 0 ;0
L 1.13306998 -1.94131004 1.15093996 -1.94131004 0 P 0 ;0
L 1.132 -1.94031004 1.15013996 -1.94031004 0 P 0 ;0
L 1.13081004 -1.93931004 1.14935 -1.93931004 0 P 0 ;0
L 1.12958002 -1.93831004 1.14855 -1.93831004 0 P 0 ;0
L 1.12833996 -1.93731004 1.14775 -1.93731004 0 P 0 ;0
L 1.1271 -1.93631004 1.14688996 -1.93631004 0 P 0 ;0
L 1.12586004 -1.93531004 1.14593996 -1.93531004 0 P 0 ;0
L 1.12461998 -1.93431004 1.14498996 -1.93431004 0 P 0 ;0
L 1.12338002 -1.93331004 1.14405 -1.93331004 0 P 0 ;0
L 1.12203002 -1.93231004 1.1431 -1.93231004 0 P 0 ;0
L 1.1206 -1.93131004 1.14216004 -1.93131004 0 P 0 ;0
L 1.11916004 -1.93031004 1.14121004 -1.93031004 0 P 0 ;0
L 1.11771998 -1.92931004 1.14026998 -1.92931004 0 P 0 ;0
L 1.11628996 -1.92831004 1.13931998 -1.92831004 0 P 0 ;0
L 1.11483996 -1.92731004 1.13838002 -1.92731004 0 P 0 ;0
L 1.11338996 -1.92631004 1.13743002 -1.92631004 0 P 0 ;0
L 1.11171998 -1.92531004 1.13648996 -1.92531004 0 P 0 ;0
L 1.11005 -1.92431004 1.13538002 -1.92431004 0 P 0 ;0
L 1.10838002 -1.92331004 1.13426998 -1.92331004 0 P 0 ;0
L 1.1067 -1.92231004 1.13315 -1.92231004 0 P 0 ;0
L 1.10503002 -1.92131004 1.13203002 -1.92131004 0 P 0 ;0
L 1.10336004 -1.92031004 1.13091998 -1.92031004 0 P 0 ;0
L 1.1015 -1.91931004 1.1298 -1.91931004 0 P 0 ;0
L 1.09955 -1.91831004 1.12868002 -1.91831004 0 P 0 ;0
L 1.16275 -2.02983002 1.21088996 -2.02983002 0 P 0 ;0
L 1.16278996 -2.02883002 1.21095 -2.02883002 0 P 0 ;0
L 1.16283996 -2.02783002 1.21101004 -2.02783002 0 P 0 ;0
L 1.16226998 -2.02683002 1.21108002 -2.02683002 0 P 0 ;0
L 1.16153996 -2.02583002 1.21113996 -2.02583002 0 P 0 ;0
L 1.15846004 -2.02483002 1.2112 -2.02483002 0 P 0 ;0
L 1.10036004 -2.00383002 1.21255 -2.00383002 0 P 0 ;0
L 1.10226004 -2.00283002 1.2126 -2.00283002 0 P 0 ;0
L 1.10433996 -2.00183002 1.21266998 -2.00183002 0 P 0 ;0
L 1.1065 -2.00083002 1.21273002 -2.00083002 0 P 0 ;0
L 1.10886998 -1.99983002 1.21278996 -1.99983002 0 P 0 ;0
L 1.11138002 -1.99883002 1.21285 -1.99883002 0 P 0 ;0
L 1.11436998 -1.99783002 1.21288002 -1.99783002 0 P 0 ;0
L 1.11748996 -1.99683002 1.21255 -1.99683002 0 P 0 ;0
L 1.12061998 -1.99583002 1.2089 -1.99583002 0 P 0 ;0
L 1.12433996 -1.99483002 1.2036 -1.99483002 0 P 0 ;0
L 1.12863996 -1.99383002 1.19728002 -1.99383002 0 P 0 ;0
L 1.13295 -1.99283002 1.19096998 -1.99283002 0 P 0 ;0
L 1.13985 -1.99183002 1.18111998 -1.99183002 0 P 0 ;0
L 1.14948002 -1.99083002 1.1651 -1.99083002 0 P 0 ;0
L 1.24218002 -2.08316004 1.29143996 -2.08316004 0 P 0 ;0
L 1.24223002 -2.08216004 1.29151004 -2.08216004 0 P 0 ;0
L 1.24228002 -2.08116004 1.29158996 -2.08116004 0 P 0 ;0
L 1.24233996 -2.08016004 1.29166004 -2.08016004 0 P 0 ;0
L 1.24238996 -2.07916004 1.29173002 -2.07916004 0 P 0 ;0
L 1.24245 -2.07816004 1.29181004 -2.07816004 0 P 0 ;0
L 1.2425 -2.07716004 1.29188002 -2.07716004 0 P 0 ;0
L 1.24256004 -2.07616004 1.29195 -2.07616004 0 P 0 ;0
L 1.24261004 -2.07516004 1.29203002 -2.07516004 0 P 0 ;0
L 1.24266998 -2.07416004 1.2921 -2.07416004 0 P 0 ;0
L 1.24271998 -2.07316004 1.29216998 -2.07316004 0 P 0 ;0
L 1.24278002 -2.07216004 1.29223996 -2.07216004 0 P 0 ;0
L 1.24283002 -2.07116004 1.29231998 -2.07116004 0 P 0 ;0
L 1.24288002 -2.07016004 1.29238996 -2.07016004 0 P 0 ;0
L 1.24293002 -2.06916004 1.29246004 -2.06916004 0 P 0 ;0
L 1.24296998 -2.06816004 1.29253002 -2.06816004 0 P 0 ;0
L 1.24301998 -2.06716004 1.29261004 -2.06716004 0 P 0 ;0
L 1.24306004 -2.06616004 1.2927 -2.06616004 0 P 0 ;0
L 1.24311004 -2.06516004 1.29281004 -2.06516004 0 P 0 ;0
L 1.24315 -2.06416004 1.29291998 -2.06416004 0 P 0 ;0
L 1.2432 -2.06316004 1.29303002 -2.06316004 0 P 0 ;0
L 1.24323996 -2.06216004 1.29315 -2.06216004 0 P 0 ;0
L 1.24328996 -2.06116004 1.29331998 -2.06116004 0 P 0 ;0
L 1.24333002 -2.06016004 1.2935 -2.06016004 0 P 0 ;0
L 1.24338002 -2.05916004 1.29366998 -2.05916004 0 P 0 ;0
L 1.24341998 -2.05816004 1.29385 -2.05816004 0 P 0 ;0
L 1.24346998 -2.05716004 1.29408996 -2.05716004 0 P 0 ;0
L 1.24351004 -2.05616004 1.29433996 -2.05616004 0 P 0 ;0
L 1.24355 -2.05516004 1.29458996 -2.05516004 0 P 0 ;0
L 1.2436 -2.05416004 1.29485 -2.05416004 0 P 0 ;0
L 1.24363996 -2.05316004 1.29516998 -2.05316004 0 P 0 ;0
L 1.24368996 -2.05216004 1.29551998 -2.05216004 0 P 0 ;0
L 1.24373002 -2.05116004 1.29586004 -2.05116004 0 P 0 ;0
L 1.24378002 -2.05016004 1.29621004 -2.05016004 0 P 0 ;0
L 1.24383002 -2.04916004 1.29663996 -2.04916004 0 P 0 ;0
L 1.24386998 -2.04816004 1.29708002 -2.04816004 0 P 0 ;0
L 1.24391004 -2.04716004 1.29753002 -2.04716004 0 P 0 ;0
L 1.24396004 -2.04616004 1.29796998 -2.04616004 0 P 0 ;0
L 1.244 -2.04516004 1.29851004 -2.04516004 0 P 0 ;0
L 1.24405 -2.04416004 1.2991 -2.04416004 0 P 0 ;0
L 1.24408996 -2.04316004 1.29975 -2.04316004 0 P 0 ;0
L 1.24413996 -2.04216004 1.3005 -2.04216004 0 P 0 ;0
L 1.24418002 -2.04116004 1.30131998 -2.04116004 0 P 0 ;0
L 1.24423002 -2.04016004 1.30223002 -2.04016004 0 P 0 ;0
L 1.24426998 -2.03916004 1.30326998 -2.03916004 0 P 0 ;0
L 1.24431998 -2.03816004 1.30446004 -2.03816004 0 P 0 ;0
L 1.24436004 -2.03716004 1.30581998 -2.03716004 0 P 0 ;0
L 1.24441004 -2.03616004 1.30738002 -2.03616004 0 P 0 ;0
L 1.24445 -2.03516004 1.30923002 -2.03516004 0 P 0 ;0
L 1.24448996 -2.03416004 1.31156004 -2.03416004 0 P 0 ;0
L 1.24453996 -2.03316004 1.31478996 -2.03316004 0 P 0 ;0
L 1.24458996 -2.03216004 1.32013002 -2.03216004 0 P 0 ;0
L 1.24461998 -2.03116004 1.33481004 -2.03116004 0 P 0 ;0
L 1.24463996 -2.03016004 1.33478002 -2.03016004 0 P 0 ;0
L 1.24466004 -2.02916004 1.33473996 -2.02916004 0 P 0 ;0
L 1.24468002 -2.02816004 1.33471004 -2.02816004 0 P 0 ;0
L 1.2447 -2.02716004 1.33468002 -2.02716004 0 P 0 ;0
L 1.24471998 -2.02616004 1.33463996 -2.02616004 0 P 0 ;0
L 1.24473996 -2.02516004 1.3346 -2.02516004 0 P 0 ;0
L 1.24476004 -2.02416004 1.33456998 -2.02416004 0 P 0 ;0
L 1.24478002 -2.02316004 1.33453002 -2.02316004 0 P 0 ;0
L 1.2448 -2.02216004 1.3345 -2.02216004 0 P 0 ;0
L 1.24481998 -2.02116004 1.33446998 -2.02116004 0 P 0 ;0
L 1.24483996 -2.02016004 1.33443002 -2.02016004 0 P 0 ;0
L 1.24486004 -2.01916004 1.3344 -2.01916004 0 P 0 ;0
L 1.24488002 -2.01816004 1.33436004 -2.01816004 0 P 0 ;0
L 1.2449 -2.01716004 1.33433002 -2.01716004 0 P 0 ;0
L 1.24491998 -2.01616004 1.33428996 -2.01616004 0 P 0 ;0
L 1.24493996 -2.01516004 1.33426004 -2.01516004 0 P 0 ;0
L 1.24496004 -2.01416004 1.33421998 -2.01416004 0 P 0 ;0
L 1.24498002 -2.01316004 1.33418996 -2.01316004 0 P 0 ;0
L 1.245 -2.01216004 1.33415 -2.01216004 0 P 0 ;0
L 1.24501998 -2.01116004 1.33411998 -2.01116004 0 P 0 ;0
L 1.24503996 -2.01016004 1.33408002 -2.01016004 0 P 0 ;0
L 1.24506004 -2.00916004 1.33403996 -2.00916004 0 P 0 ;0
L 1.24508002 -2.00816004 1.334 -2.00816004 0 P 0 ;0
L 1.2451 -2.00716004 1.33396004 -2.00716004 0 P 0 ;0
L 1.24511998 -2.00616004 1.33393002 -2.00616004 0 P 0 ;0
L 1.24513996 -2.00516004 1.29098996 -2.00516004 0 P 0 ;0
L 1.24513996 -2.00416004 1.29033002 -2.00416004 0 P 0 ;0
L 1.24513996 -2.00316004 1.29005 -2.00316004 0 P 0 ;0
L 1.24513996 -2.00216004 1.29005 -2.00216004 0 P 0 ;0
L 1.24513996 -2.00116004 1.29005 -2.00116004 0 P 0 ;0
L 1.24515 -2.00016004 1.29005 -2.00016004 0 P 0 ;0
L 1.24515 -1.99916004 1.29005 -1.99916004 0 P 0 ;0
L 1.24515 -1.99816004 1.29005 -1.99816004 0 P 0 ;0
L 1.24515 -1.99716004 1.29005 -1.99716004 0 P 0 ;0
L 1.24515 -1.99616004 1.29005 -1.99616004 0 P 0 ;0
L 1.24515 -1.99516004 1.29005 -1.99516004 0 P 0 ;0
L 1.16085 -2.02753002 1.1601 -2.04393002 0 P 0 ;0
L 1.1601 -2.04393002 1.15928996 -2.05771998 0 P 0 ;0
L 1.15928996 -2.05771998 1.15883996 -2.06228002 0 P 0 ;0
L 1.15883996 -2.06228002 1.15818002 -2.06681998 0 P 0 ;0
L 1.15818002 -2.06681998 1.15751004 -2.07006998 0 P 0 ;0
L 1.15751004 -2.07006998 1.15661004 -2.07328996 0 P 0 ;0
L 1.15661004 -2.07328996 1.15616004 -2.07453996 0 P 0 ;0
L 1.15616004 -2.07453996 1.15563002 -2.07576998 0 P 0 ;0
L 1.15563002 -2.07576998 1.15501998 -2.07696004 0 P 0 ;0
L 1.15501998 -2.07696004 1.15433002 -2.0781 0 P 0 ;0
L 1.15433002 -2.0781 1.1534 -2.07941998 0 P 0 ;0
L 1.1534 -2.07941998 1.15236004 -2.08066004 0 P 0 ;0
L 1.15236004 -2.08066004 1.15123002 -2.08181998 0 P 0 ;0
L 1.15123002 -2.08181998 1.15001004 -2.08286998 0 P 0 ;0
L 1.15001004 -2.08286998 1.14871004 -2.08383002 0 P 0 ;0
L 1.14871004 -2.08383002 1.14733002 -2.08468002 0 P 0 ;0
L 1.14733002 -2.08468002 1.14591004 -2.0854 0 P 0 ;0
L 1.14591004 -2.0854 1.14443996 -2.086 0 P 0 ;0
L 1.14443996 -2.086 1.14291004 -2.08648002 0 P 0 ;0
L 1.14291004 -2.08648002 1.14136004 -2.08683002 0 P 0 ;0
L 1.14136004 -2.08683002 1.13976998 -2.08703996 0 P 0 ;0
L 1.13976998 -2.08703996 1.13816004 -2.08713002 0 P 0 ;0
L 1.13816004 -2.08713002 1.13656998 -2.08708002 0 P 0 ;0
L 1.13656998 -2.08708002 1.13498996 -2.0869 0 P 0 ;0
L 1.13498996 -2.0869 1.13341998 -2.08658996 0 P 0 ;0
L 1.13341998 -2.08658996 1.13188996 -2.08615 0 P 0 ;0
L 1.13188996 -2.08615 1.1304 -2.08558996 0 P 0 ;0
L 1.1304 -2.08558996 1.12895 -2.08488996 0 P 0 ;0
L 1.12895 -2.08488996 1.12756998 -2.08408002 0 P 0 ;0
L 1.12756998 -2.08408002 1.12625 -2.08315 0 P 0 ;0
L 1.12625 -2.08315 1.12501004 -2.08211998 0 P 0 ;0
L 1.12501004 -2.08211998 1.12386004 -2.081 0 P 0 ;0
L 1.12386004 -2.081 1.12281004 -2.07978002 0 P 0 ;0
L 1.12281004 -2.07978002 1.12183996 -2.07846998 0 P 0 ;0
L 1.12183996 -2.07846998 1.1211 -2.07726004 0 P 0 ;0
L 1.1211 -2.07726004 1.12046998 -2.07598996 0 P 0 ;0
L 1.12046998 -2.07598996 1.11996004 -2.07466998 0 P 0 ;0
L 1.11996004 -2.07466998 1.11955 -2.07331004 0 P 0 ;0
L 1.11955 -2.07331004 1.11926998 -2.07191004 0 P 0 ;0
L 1.11926998 -2.07191004 1.11868002 -2.06693996 0 P 0 ;0
L 1.11868002 -2.06693996 1.11848002 -2.06191004 0 P 0 ;0
L 1.11848002 -2.06191004 1.11871004 -2.05668002 0 P 0 ;0
L 1.11871004 -2.05668002 1.11936004 -2.05148002 0 P 0 ;0
L 1.11936004 -2.05148002 1.11978996 -2.04936998 0 P 0 ;0
L 1.11978996 -2.04936998 1.12036998 -2.0473 0 P 0 ;0
L 1.12036998 -2.0473 1.12108996 -2.04528002 0 P 0 ;0
L 1.12108996 -2.04528002 1.12196004 -2.04331998 0 P 0 ;0
L 1.12196004 -2.04331998 1.1229 -2.04153996 0 P 0 ;0
L 1.1229 -2.04153996 1.12396998 -2.03985 0 P 0 ;0
L 1.12396998 -2.03985 1.12516998 -2.03823002 0 P 0 ;0
L 1.12516998 -2.03823002 1.12735 -2.03573996 0 P 0 ;0
L 1.12735 -2.03573996 1.12973002 -2.03345 0 P 0 ;0
L 1.12973002 -2.03345 1.13223996 -2.03141998 0 P 0 ;0
L 1.13223996 -2.03141998 1.13491998 -2.02961004 0 P 0 ;0
L 1.13491998 -2.02961004 1.13611004 -2.02893002 0 P 0 ;0
L 1.13611004 -2.02893002 1.13735 -2.02833996 0 P 0 ;0
L 1.13735 -2.02833996 1.13861998 -2.02781998 0 P 0 ;0
L 1.13861998 -2.02781998 1.13993996 -2.0274 0 P 0 ;0
L 1.13993996 -2.0274 1.14191004 -2.02693002 0 P 0 ;0
L 1.14191004 -2.02693002 1.14391004 -2.02663002 0 P 0 ;0
L 1.14391004 -2.02663002 1.14935 -2.02626004 0 P 0 ;0
L 1.14935 -2.02626004 1.15471004 -2.0263 0 P 0 ;0
L 1.15471004 -2.0263 1.15591004 -2.02638996 0 P 0 ;0
L 1.15591004 -2.02638996 1.1571 -2.02656998 0 P 0 ;0
L 1.1571 -2.02656998 1.15828002 -2.02683996 0 P 0 ;0
L 1.15828002 -2.02683996 1.16085 -2.02753002 0 P 0 ;0
L 1.13876998 -2.14783002 1.20233002 -2.14783002 0 P 0 ;0
L 1.14236998 -2.14683002 1.20266004 -2.14683002 0 P 0 ;0
L 1.14481004 -2.14583002 1.20296004 -2.14583002 0 P 0 ;0
L 1.1467 -2.14483002 1.20325 -2.14483002 0 P 0 ;0
L 1.14826004 -2.14383002 1.20353002 -2.14383002 0 P 0 ;0
L 1.1496 -2.14283002 1.20373996 -2.14283002 0 P 0 ;0
L 1.15078996 -2.14183002 1.20395 -2.14183002 0 P 0 ;0
L 1.15186004 -2.14083002 1.20415 -2.14083002 0 P 0 ;0
L 1.15278996 -2.13983002 1.20431998 -2.13983002 0 P 0 ;0
L 1.15361998 -2.13883002 1.20446004 -2.13883002 0 P 0 ;0
L 1.15436004 -2.13783002 1.20458002 -2.13783002 0 P 0 ;0
L 1.155 -2.13683002 1.20466998 -2.13683002 0 P 0 ;0
L 1.15556998 -2.13583002 1.20475 -2.13583002 0 P 0 ;0
L 1.15608996 -2.13483002 1.20481998 -2.13483002 0 P 0 ;0
L 1.15653996 -2.13383002 1.20488996 -2.13383002 0 P 0 ;0
L 1.15691004 -2.13283002 1.20496004 -2.13283002 0 P 0 ;0
L 1.15723996 -2.13183002 1.20503002 -2.13183002 0 P 0 ;0
L 1.15751998 -2.13083002 1.2051 -2.13083002 0 P 0 ;0
L 1.15773002 -2.12983002 1.20516004 -2.12983002 0 P 0 ;0
L 1.15793002 -2.12883002 1.20523002 -2.12883002 0 P 0 ;0
L 1.15806004 -2.12783002 1.2053 -2.12783002 0 P 0 ;0
L 1.15816998 -2.12683002 1.20536998 -2.12683002 0 P 0 ;0
L 1.15821004 -2.12583002 1.20543996 -2.12583002 0 P 0 ;0
L 1.11716004 -2.12483002 1.12726004 -2.12483002 0 P 0 ;0
L 1.15823996 -2.12483002 1.20551004 -2.12483002 0 P 0 ;0
L 1.10911998 -2.12383002 1.1352 -2.12383002 0 P 0 ;0
L 1.15821998 -2.12383002 1.20556998 -2.12383002 0 P 0 ;0
L 1.10468996 -2.12283002 1.14018996 -2.12283002 0 P 0 ;0
L 1.1582 -2.12283002 1.20563996 -2.12283002 0 P 0 ;0
L 1.10131004 -2.12183002 1.14366998 -2.12183002 0 P 0 ;0
L 1.15818002 -2.12183002 1.2057 -2.12183002 0 P 0 ;0
L 1.15808996 -2.12083002 1.20576004 -2.12083002 0 P 0 ;0
L 1.15781004 -2.11983002 1.20583002 -2.11983002 0 P 0 ;0
L 1.15721004 -2.11883002 1.20588002 -2.11883002 0 P 0 ;0
L 1.14146004 -2.08883002 1.20758002 -2.08883002 0 P 0 ;0
L 1.14525 -2.08783002 1.20763002 -2.08783002 0 P 0 ;0
L 1.14751004 -2.08683002 1.20768002 -2.08683002 0 P 0 ;0
L 1.14928002 -2.08583002 1.20773002 -2.08583002 0 P 0 ;0
L 1.15073002 -2.08483002 1.20778996 -2.08483002 0 P 0 ;0
L 1.15196004 -2.08383002 1.20783996 -2.08383002 0 P 0 ;0
L 1.13818996 -2.08913002 1.13826998 -2.08913002 0 P 0 ;0
L 1.13826998 -2.08913002 1.13988002 -2.08903996 0 P 0 ;0
L 1.13988002 -2.08903996 1.13996004 -2.08903996 0 P 0 ;0
L 1.13996004 -2.08903996 1.14001004 -2.08903002 0 P 0 ;0
L 1.14001004 -2.08903002 1.14005 -2.08901998 0 P 0 ;0
L 1.14005 -2.08901998 1.14163002 -2.08881004 0 P 0 ;0
L 1.14163002 -2.08881004 1.14166998 -2.0888 0 P 0 ;0
L 1.14166998 -2.0888 1.14171004 -2.0888 0 P 0 ;0
L 1.14171004 -2.0888 1.14178996 -2.08878002 0 P 0 ;0
L 1.14178996 -2.08878002 1.14335 -2.08843002 0 P 0 ;0
L 1.14335 -2.08843002 1.14351004 -2.08838996 0 P 0 ;0
L 1.14351004 -2.08838996 1.14503002 -2.08791004 0 P 0 ;0
L 1.14503002 -2.08791004 1.14511004 -2.08788996 0 P 0 ;0
L 1.14511004 -2.08788996 1.14515 -2.08786998 0 P 0 ;0
L 1.14515 -2.08786998 1.14518996 -2.08786004 0 P 0 ;0
L 1.14518996 -2.08786004 1.14666004 -2.08725 0 P 0 ;0
L 1.14666004 -2.08725 1.14673996 -2.08721998 0 P 0 ;0
L 1.14673996 -2.08721998 1.14678002 -2.0872 0 P 0 ;0
L 1.14678002 -2.0872 1.14681998 -2.08718996 0 P 0 ;0
L 1.14681998 -2.08718996 1.14823996 -2.08646998 0 P 0 ;0
L 1.14823996 -2.08646998 1.14826998 -2.08645 0 P 0 ;0
L 1.14826998 -2.08645 1.14835 -2.08641004 0 P 0 ;0
L 1.14835 -2.08641004 1.14838002 -2.08638002 0 P 0 ;0
L 1.14838002 -2.08638002 1.14976004 -2.08553002 0 P 0 ;0
L 1.14976004 -2.08553002 1.14978996 -2.08551004 0 P 0 ;0
L 1.14978996 -2.08551004 1.14983002 -2.08548996 0 P 0 ;0
L 1.14983002 -2.08548996 1.14988996 -2.08543996 0 P 0 ;0
L 1.14988996 -2.08543996 1.1512 -2.08448996 0 P 0 ;0
L 1.1512 -2.08448996 1.15126004 -2.08443996 0 P 0 ;0
L 1.15126004 -2.08443996 1.15128996 -2.08441004 0 P 0 ;0
L 1.15128996 -2.08441004 1.15131998 -2.08438996 0 P 0 ;0
L 1.15131998 -2.08438996 1.15253996 -2.08333002 0 P 0 ;0
L 1.15253996 -2.08333002 1.15256998 -2.0833 0 P 0 ;0
L 1.15256998 -2.0833 1.1526 -2.08328002 0 P 0 ;0
L 1.1526 -2.08328002 1.15263002 -2.08323996 0 P 0 ;0
L 1.15263002 -2.08323996 1.15266004 -2.08321998 0 P 0 ;0
L 1.15266004 -2.08321998 1.15378996 -2.08206004 0 P 0 ;0
L 1.15378996 -2.08206004 1.15376004 -2.08203996 0 P 0 ;0
L 1.15376004 -2.08203996 1.15381998 -2.08203996 0 P 0 ;0
L 1.15381998 -2.08203996 1.15383996 -2.082 0 P 0 ;0
L 1.15383996 -2.082 1.15386998 -2.08196998 0 P 0 ;0
L 1.15386998 -2.08196998 1.1539 -2.08195 0 P 0 ;0
L 1.1539 -2.08195 1.15493002 -2.08071004 0 P 0 ;0
L 1.15493002 -2.08071004 1.15493002 -2.0807 0 P 0 ;0
L 1.15493002 -2.0807 1.15496004 -2.08066998 0 P 0 ;0
L 1.15496004 -2.08066998 1.15498002 -2.08063996 0 P 0 ;0
L 1.15498002 -2.08063996 1.15501004 -2.08061004 0 P 0 ;0
L 1.15501004 -2.08061004 1.15503002 -2.08058002 0 P 0 ;0
L 1.15503002 -2.08058002 1.15596004 -2.07926004 0 P 0 ;0
L 1.15596004 -2.07926004 1.15603996 -2.07913996 0 P 0 ;0
L 1.15603996 -2.07913996 1.15673002 -2.07798996 0 P 0 ;0
L 1.15673002 -2.07798996 1.15676998 -2.07793002 0 P 0 ;0
L 1.15676998 -2.07793002 1.15678996 -2.07786998 0 P 0 ;0
L 1.15678996 -2.07786998 1.15741004 -2.07668996 0 P 0 ;0
L 1.15741004 -2.07668996 1.15743996 -2.07663002 0 P 0 ;0
L 1.15743996 -2.07663002 1.15746004 -2.07656998 0 P 0 ;0
L 1.15746004 -2.07656998 1.15746998 -2.07656998 0 P 0 ;0
L 1.15746998 -2.07656998 1.158 -2.07533996 0 P 0 ;0
L 1.158 -2.07533996 1.15801004 -2.07531004 0 P 0 ;0
L 1.15801004 -2.07531004 1.15803002 -2.07528002 0 P 0 ;0
L 1.15803002 -2.07528002 1.15805 -2.07521998 0 P 0 ;0
L 1.15805 -2.07521998 1.15848996 -2.07396004 0 P 0 ;0
L 1.15848996 -2.07396004 1.15841004 -2.07393002 0 P 0 ;0
L 1.15841004 -2.07393002 1.15851004 -2.07393002 0 P 0 ;0
L 1.15851004 -2.07393002 1.15851998 -2.0739 0 P 0 ;0
L 1.15851998 -2.0739 1.15853002 -2.07386004 0 P 0 ;0
L 1.15853002 -2.07386004 1.15853996 -2.07383002 0 P 0 ;0
L 1.15853996 -2.07383002 1.15943996 -2.07061004 0 P 0 ;0
L 1.15943996 -2.07061004 1.15945 -2.07058002 0 P 0 ;0
L 1.15945 -2.07058002 1.15946004 -2.07053996 0 P 0 ;0
L 1.15946004 -2.07053996 1.15946998 -2.07051004 0 P 0 ;0
L 1.15946998 -2.07051004 1.15946998 -2.07046998 0 P 0 ;0
L 1.15946998 -2.07046998 1.16013996 -2.06723002 0 P 0 ;0
L 1.16013996 -2.06723002 1.16013996 -2.0672 0 P 0 ;0
L 1.16013996 -2.0672 1.16016004 -2.06713996 0 P 0 ;0
L 1.16016004 -2.06713996 1.16016004 -2.06711004 0 P 0 ;0
L 1.16016004 -2.06711004 1.16081998 -2.06256004 0 P 0 ;0
L 1.16081998 -2.06256004 1.16081998 -2.06253996 0 P 0 ;0
L 1.16081998 -2.06253996 1.16083002 -2.0625 0 P 0 ;0
L 1.16083002 -2.0625 1.16083002 -2.06246998 0 P 0 ;0
L 1.16083002 -2.06246998 1.16126998 -2.05791004 0 P 0 ;0
L 1.16126998 -2.05791004 1.16128002 -2.0579 0 P 0 ;0
L 1.16128002 -2.0579 1.16128002 -2.05783996 0 P 0 ;0
L 1.16128002 -2.05783996 1.1621 -2.04405 0 P 0 ;0
L 1.1621 -2.04405 1.1621 -2.04401998 0 P 0 ;0
L 1.1621 -2.04401998 1.16285 -2.02761998 0 P 0 ;0
L 1.16285 -2.02761998 1.16136998 -2.0256 0 P 0 ;0
L 1.16136998 -2.0256 1.15878996 -2.02491004 0 P 0 ;0
L 1.15878996 -2.02491004 1.15878002 -2.0249 0 P 0 ;0
L 1.15878002 -2.0249 1.15871998 -2.02488996 0 P 0 ;0
L 1.15871998 -2.02488996 1.15755 -2.02461998 0 P 0 ;0
L 1.15755 -2.02461998 1.15746998 -2.0246 0 P 0 ;0
L 1.15746998 -2.0246 1.1574 -2.0246 0 P 0 ;0
L 1.1574 -2.0246 1.15621004 -2.02441004 0 P 0 ;0
L 1.15621004 -2.02441004 1.15616998 -2.02441004 0 P 0 ;0
L 1.15616998 -2.02441004 1.1561 -2.0244 0 P 0 ;0
L 1.1561 -2.0244 1.15606004 -2.02438996 0 P 0 ;0
L 1.15606004 -2.02438996 1.15486004 -2.0243 0 P 0 ;0
L 1.15486004 -2.0243 1.15471998 -2.0243 0 P 0 ;0
L 1.15471998 -2.0243 1.14936004 -2.02426004 0 P 0 ;0
L 1.14936004 -2.02426004 1.14928996 -2.02426004 0 P 0 ;0
L 1.14928996 -2.02426004 1.14925 -2.02426998 0 P 0 ;0
L 1.14925 -2.02426998 1.14921004 -2.02426998 0 P 0 ;0
L 1.14921004 -2.02426998 1.14376998 -2.02463996 0 P 0 ;0
L 1.14376998 -2.02463996 1.1437 -2.02463996 0 P 0 ;0
L 1.1437 -2.02463996 1.14365 -2.02465 0 P 0 ;0
L 1.14365 -2.02465 1.14361004 -2.02465 0 P 0 ;0
L 1.14361004 -2.02465 1.14161998 -2.02495 0 P 0 ;0
L 1.14161998 -2.02495 1.14161004 -2.02495 0 P 0 ;0
L 1.14161004 -2.02495 1.14153002 -2.02496998 0 P 0 ;0
L 1.14153002 -2.02496998 1.14148996 -2.02496998 0 P 0 ;0
L 1.14148996 -2.02496998 1.14143996 -2.02498996 0 P 0 ;0
L 1.14143996 -2.02498996 1.13946998 -2.02545 0 P 0 ;0
L 1.13946998 -2.02545 1.13943996 -2.02546998 0 P 0 ;0
L 1.13943996 -2.02546998 1.1394 -2.02546998 0 P 0 ;0
L 1.1394 -2.02546998 1.13933002 -2.0255 0 P 0 ;0
L 1.13933002 -2.0255 1.13801004 -2.02591998 0 P 0 ;0
L 1.13801004 -2.02591998 1.13798002 -2.02593002 0 P 0 ;0
L 1.13798002 -2.02593002 1.13793996 -2.02593996 0 P 0 ;0
L 1.13793996 -2.02593996 1.13788002 -2.02596998 0 P 0 ;0
L 1.13788002 -2.02596998 1.1366 -2.02648002 0 P 0 ;0
L 1.1366 -2.02648002 1.13653996 -2.0265 0 P 0 ;0
L 1.13653996 -2.0265 1.13648002 -2.02653002 0 P 0 ;0
L 1.13648002 -2.02653002 1.13523996 -2.02713002 0 P 0 ;0
L 1.13523996 -2.02713002 1.13518002 -2.02716004 0 P 0 ;0
L 1.13518002 -2.02716004 1.13515 -2.02716998 0 P 0 ;0
L 1.13515 -2.02716998 1.13511998 -2.02718996 0 P 0 ;0
L 1.13511998 -2.02718996 1.13393002 -2.02786998 0 P 0 ;0
L 1.13393002 -2.02786998 1.13388996 -2.02788996 0 P 0 ;0
L 1.13388996 -2.02788996 1.1338 -2.02795 0 P 0 ;0
L 1.1338 -2.02795 1.13111998 -2.02976004 0 P 0 ;0
L 1.13111998 -2.02976004 1.13105 -2.02981004 0 P 0 ;0
L 1.13105 -2.02981004 1.13101004 -2.02983996 0 P 0 ;0
L 1.13101004 -2.02983996 1.13098002 -2.02986004 0 P 0 ;0
L 1.13098002 -2.02986004 1.12846998 -2.03188996 0 P 0 ;0
L 1.12846998 -2.03188996 1.12838002 -2.03198002 0 P 0 ;0
L 1.12838002 -2.03198002 1.12833996 -2.03201004 0 P 0 ;0
L 1.12833996 -2.03201004 1.12596004 -2.0343 0 P 0 ;0
L 1.12596004 -2.0343 1.12593996 -2.03433002 0 P 0 ;0
L 1.12593996 -2.03433002 1.1259 -2.03436004 0 P 0 ;0
L 1.1259 -2.03436004 1.12588002 -2.03438996 0 P 0 ;0
L 1.12588002 -2.03438996 1.12585 -2.03443002 0 P 0 ;0
L 1.12585 -2.03443002 1.12366998 -2.03691004 0 P 0 ;0
L 1.12366998 -2.03691004 1.12363996 -2.03695 0 P 0 ;0
L 1.12363996 -2.03695 1.12361998 -2.03698002 0 P 0 ;0
L 1.12361998 -2.03698002 1.12358996 -2.03701004 0 P 0 ;0
L 1.12358996 -2.03701004 1.12356998 -2.03703996 0 P 0 ;0
L 1.12356998 -2.03703996 1.12236998 -2.03865 0 P 0 ;0
L 1.12236998 -2.03865 1.12233996 -2.03868996 0 P 0 ;0
L 1.12233996 -2.03868996 1.12233002 -2.03871004 0 P 0 ;0
L 1.12233002 -2.03871004 1.12228996 -2.03878002 0 P 0 ;0
L 1.12228996 -2.03878002 1.12121004 -2.04046998 0 P 0 ;0
L 1.12121004 -2.04046998 1.12118996 -2.0405 0 P 0 ;0
L 1.12118996 -2.0405 1.12116998 -2.04053996 0 P 0 ;0
L 1.12116998 -2.04053996 1.12115 -2.04056998 0 P 0 ;0
L 1.12115 -2.04056998 1.12113996 -2.04061004 0 P 0 ;0
L 1.12113996 -2.04061004 1.12018996 -2.04238002 0 P 0 ;0
L 1.12018996 -2.04238002 1.12016004 -2.04245 0 P 0 ;0
L 1.12016004 -2.04245 1.12013996 -2.04248002 0 P 0 ;0
L 1.12013996 -2.04248002 1.12013002 -2.04251004 0 P 0 ;0
L 1.12013002 -2.04251004 1.11926004 -2.04446998 0 P 0 ;0
L 1.11926004 -2.04446998 1.11925 -2.0445 0 P 0 ;0
L 1.11925 -2.0445 1.11923002 -2.04453996 0 P 0 ;0
L 1.11923002 -2.04453996 1.11921998 -2.04458002 0 P 0 ;0
L 1.11921998 -2.04458002 1.11921004 -2.04461004 0 P 0 ;0
L 1.11921004 -2.04461004 1.11848002 -2.04663002 0 P 0 ;0
L 1.11848002 -2.04663002 1.11846998 -2.04666004 0 P 0 ;0
L 1.11846998 -2.04666004 1.11846004 -2.0467 0 P 0 ;0
L 1.11846004 -2.0467 1.11843996 -2.04676998 0 P 0 ;0
L 1.11843996 -2.04676998 1.11786004 -2.04883996 0 P 0 ;0
L 1.11786004 -2.04883996 1.11785 -2.04886998 0 P 0 ;0
L 1.11785 -2.04886998 1.11783996 -2.04891004 0 P 0 ;0
L 1.11783996 -2.04891004 1.11783996 -2.04893996 0 P 0 ;0
L 1.11783996 -2.04893996 1.11783002 -2.04896998 0 P 0 ;0
L 1.11783002 -2.04896998 1.11783002 -2.04898002 0 P 0 ;0
L 1.11783002 -2.04898002 1.1174 -2.05108002 0 P 0 ;0
L 1.1174 -2.05108002 1.1174 -2.05111998 0 P 0 ;0
L 1.1174 -2.05111998 1.11738996 -2.05116004 0 P 0 ;0
L 1.11738996 -2.05116004 1.11738002 -2.05118996 0 P 0 ;0
L 1.11738002 -2.05118996 1.11738002 -2.05123002 0 P 0 ;0
L 1.11738002 -2.05123002 1.11673002 -2.05643002 0 P 0 ;0
L 1.11673002 -2.05643002 1.11671998 -2.05646998 0 P 0 ;0
L 1.11671998 -2.05646998 1.11671998 -2.05655 0 P 0 ;0
L 1.11671998 -2.05655 1.11671004 -2.05658996 0 P 0 ;0
L 1.11671004 -2.05658996 1.11648996 -2.06181998 0 P 0 ;0
L 1.11648996 -2.06181998 1.11648002 -2.06186998 0 P 0 ;0
L 1.11648002 -2.06186998 1.11648002 -2.06195 0 P 0 ;0
L 1.11648002 -2.06195 1.11648996 -2.06198996 0 P 0 ;0
L 1.11648996 -2.06198996 1.11668002 -2.06696998 0 P 0 ;0
L 1.11668002 -2.06696998 1.11768002 -2.06696998 0 P 0 ;0
L 1.11768002 -2.06696998 1.11668002 -2.06701004 0 P 0 ;0
L 1.11668002 -2.06701004 1.11668002 -2.06713002 0 P 0 ;0
L 1.11668002 -2.06713002 1.11668996 -2.06716998 0 P 0 ;0
L 1.11668996 -2.06716998 1.11728002 -2.07215 0 P 0 ;0
L 1.11728002 -2.07215 1.11728996 -2.07218996 0 P 0 ;0
L 1.11728996 -2.07218996 1.11728996 -2.07223002 0 P 0 ;0
L 1.11728996 -2.07223002 1.11731004 -2.07231004 0 P 0 ;0
L 1.11731004 -2.07231004 1.11758996 -2.07371004 0 P 0 ;0
L 1.11758996 -2.07371004 1.1176 -2.07375 0 P 0 ;0
L 1.1176 -2.07375 1.11761004 -2.0738 0 P 0 ;0
L 1.11761004 -2.0738 1.11761998 -2.07383996 0 P 0 ;0
L 1.11761998 -2.07383996 1.11763996 -2.07388002 0 P 0 ;0
L 1.11763996 -2.07388002 1.11803996 -2.07523996 0 P 0 ;0
L 1.11803996 -2.07523996 1.11806004 -2.07531998 0 P 0 ;0
L 1.11806004 -2.07531998 1.11808002 -2.07536004 0 P 0 ;0
L 1.11808002 -2.07536004 1.11808996 -2.07541004 0 P 0 ;0
L 1.11808996 -2.07541004 1.11861004 -2.07673002 0 P 0 ;0
L 1.11861004 -2.07673002 1.11863996 -2.07681004 0 P 0 ;0
L 1.11863996 -2.07681004 1.11866004 -2.07683996 0 P 0 ;0
L 1.11866004 -2.07683996 1.11868002 -2.07688002 0 P 0 ;0
L 1.11868002 -2.07688002 1.11931004 -2.07815 0 P 0 ;0
L 1.11931004 -2.07815 1.11935 -2.07823002 0 P 0 ;0
L 1.11935 -2.07823002 1.1194 -2.0783 0 P 0 ;0
L 1.1194 -2.0783 1.12013996 -2.07951998 0 P 0 ;0
L 1.12013996 -2.07951998 1.12021004 -2.07961998 0 P 0 ;0
L 1.12021004 -2.07961998 1.12023002 -2.07965 0 P 0 ;0
L 1.12023002 -2.07965 1.12023002 -2.07966004 0 P 0 ;0
L 1.12023002 -2.07966004 1.1212 -2.08096998 0 P 0 ;0
L 1.1212 -2.08096998 1.12123996 -2.08103002 0 P 0 ;0
L 1.12123996 -2.08103002 1.12126998 -2.08106004 0 P 0 ;0
L 1.12126998 -2.08106004 1.12128996 -2.08108996 0 P 0 ;0
L 1.12128996 -2.08108996 1.12235 -2.08231004 0 P 0 ;0
L 1.12235 -2.08231004 1.12238002 -2.08233996 0 P 0 ;0
L 1.12238002 -2.08233996 1.1224 -2.08236998 0 P 0 ;0
L 1.1224 -2.08236998 1.12246004 -2.08243002 0 P 0 ;0
L 1.12246004 -2.08243002 1.12361004 -2.08355 0 P 0 ;0
L 1.12361004 -2.08355 1.12366998 -2.08361004 0 P 0 ;0
L 1.12366998 -2.08361004 1.1237 -2.08363002 0 P 0 ;0
L 1.1237 -2.08363002 1.12373002 -2.08366004 0 P 0 ;0
L 1.12373002 -2.08366004 1.12496998 -2.08468996 0 P 0 ;0
L 1.12496998 -2.08468996 1.125 -2.08471004 0 P 0 ;0
L 1.125 -2.08471004 1.12503002 -2.08473996 0 P 0 ;0
L 1.12503002 -2.08473996 1.12506998 -2.08476004 0 P 0 ;0
L 1.12506998 -2.08476004 1.1251 -2.08478996 0 P 0 ;0
L 1.1251 -2.08478996 1.12641998 -2.08571004 0 P 0 ;0
L 1.12641998 -2.08571004 1.12645 -2.08573002 0 P 0 ;0
L 1.12645 -2.08573002 1.12648002 -2.08576004 0 P 0 ;0
L 1.12648002 -2.08576004 1.12651004 -2.08578002 0 P 0 ;0
L 1.12651004 -2.08578002 1.12655 -2.0858 0 P 0 ;0
L 1.12655 -2.0858 1.12793996 -2.08661004 0 P 0 ;0
L 1.12793996 -2.08661004 1.12801004 -2.08665 0 P 0 ;0
L 1.12801004 -2.08665 1.12805 -2.08666998 0 P 0 ;0
L 1.12805 -2.08666998 1.12808002 -2.08668996 0 P 0 ;0
L 1.12808002 -2.08668996 1.12808996 -2.08668996 0 P 0 ;0
L 1.12808996 -2.08668996 1.12953996 -2.08738996 0 P 0 ;0
L 1.12953996 -2.08738996 1.12961998 -2.08743002 0 P 0 ;0
L 1.12961998 -2.08743002 1.12965 -2.08743996 0 P 0 ;0
L 1.12965 -2.08743996 1.1297 -2.08746004 0 P 0 ;0
L 1.1297 -2.08746004 1.13118002 -2.08801998 0 P 0 ;0
L 1.13118002 -2.08801998 1.13133996 -2.08808002 0 P 0 ;0
L 1.13133996 -2.08808002 1.13286998 -2.08851004 0 P 0 ;0
L 1.13286998 -2.08851004 1.13295 -2.08853996 0 P 0 ;0
L 1.13295 -2.08853996 1.13303996 -2.08855 0 P 0 ;0
L 1.13303996 -2.08855 1.1346 -2.08886004 0 P 0 ;0
L 1.1346 -2.08886004 1.13471998 -2.08888996 0 P 0 ;0
L 1.13471998 -2.08888996 1.13476004 -2.08888996 0 P 0 ;0
L 1.13476004 -2.08888996 1.13633996 -2.08906998 0 P 0 ;0
L 1.13633996 -2.08906998 1.13638996 -2.08908002 0 P 0 ;0
L 1.13638996 -2.08908002 1.13651004 -2.08908002 0 P 0 ;0
L 1.13651004 -2.08908002 1.1381 -2.08913002 0 P 0 ;0
L 1.1381 -2.08913002 1.13818996 -2.08913002 0 P 0 ;0
L 1.31623996 -1.98923996 1.3135 -1.98988002 0 P 0 ;0
L 1.3135 -1.98988002 1.31078996 -1.99071004 0 P 0 ;0
L 1.31078996 -1.99071004 1.30813002 -1.99175 0 P 0 ;0
L 1.30813002 -1.99175 1.30553996 -1.99296998 0 P 0 ;0
L 1.30553996 -1.99296998 1.30308996 -1.99431998 0 P 0 ;0
L 1.30308996 -1.99431998 1.30073996 -1.99585 0 P 0 ;0
L 1.30073996 -1.99585 1.29863996 -1.99746004 0 P 0 ;0
L 1.29863996 -1.99746004 1.29666004 -1.99923996 0 P 0 ;0
L 1.29666004 -1.99923996 1.29205 -2.00375 0 P 0 ;0
L 1.29205 -2.00375 1.29205 -1.99243996 0 P 0 ;0
L 1.29205 -1.99243996 1.24316004 -1.99243996 0 P 0 ;0
L 1.24316004 -1.99243996 1.24313996 -2.00521004 0 P 0 ;0
L 1.24313996 -2.00521004 1.24261004 -2.03151004 0 P 0 ;0
L 1.24261004 -2.03151004 1.24086998 -2.07046004 0 P 0 ;0
L 1.24086998 -2.07046004 1.23873996 -2.10921004 0 P 0 ;0
L 1.23873996 -2.10921004 1.23811998 -2.11641998 0 P 0 ;0
L 1.23811998 -2.11641998 1.23711998 -2.12361998 0 P 0 ;0
L 1.23711998 -2.12361998 1.23655 -2.12716004 0 P 0 ;0
L 1.23655 -2.12716004 1.29205 -2.12716004 0 P 0 ;0
L 1.29205 -2.12716004 1.29206998 -2.11766004 0 P 0 ;0
L 1.29206998 -2.11766004 1.29238996 -2.10283996 0 P 0 ;0
L 1.29238996 -2.10283996 1.29336004 -2.08431004 0 P 0 ;0
L 1.29336004 -2.08431004 1.29463996 -2.06673002 0 P 0 ;0
L 1.29463996 -2.06673002 1.29511004 -2.06253002 0 P 0 ;0
L 1.29511004 -2.06253002 1.29583996 -2.05836004 0 P 0 ;0
L 1.29583996 -2.05836004 1.29683002 -2.05446998 0 P 0 ;0
L 1.29683002 -2.05446998 1.29813996 -2.05068996 0 P 0 ;0
L 1.29813996 -2.05068996 1.29978002 -2.04701998 0 P 0 ;0
L 1.29978002 -2.04701998 1.30056998 -2.04556998 0 P 0 ;0
L 1.30056998 -2.04556998 1.30146998 -2.04418996 0 P 0 ;0
L 1.30146998 -2.04418996 1.30246998 -2.04288002 0 P 0 ;0
L 1.30246998 -2.04288002 1.30356998 -2.04165 0 P 0 ;0
L 1.30356998 -2.04165 1.30475 -2.0405 0 P 0 ;0
L 1.30475 -2.0405 1.30603996 -2.03945 0 P 0 ;0
L 1.30603996 -2.03945 1.30773996 -2.03826004 0 P 0 ;0
L 1.30773996 -2.03826004 1.30953002 -2.03723002 0 P 0 ;0
L 1.30953002 -2.03723002 1.31141004 -2.03635 0 P 0 ;0
L 1.31141004 -2.03635 1.31335 -2.03563002 0 P 0 ;0
L 1.31335 -2.03563002 1.31535 -2.03508002 0 P 0 ;0
L 1.31535 -2.03508002 1.31973996 -2.03423002 0 P 0 ;0
L 1.31973996 -2.03423002 1.32416004 -2.03366998 0 P 0 ;0
L 1.32416004 -2.03366998 1.32863002 -2.0334 0 P 0 ;0
L 1.32863002 -2.0334 1.33688002 -2.03318002 0 P 0 ;0
L 1.33688002 -2.03318002 1.33613002 -2.01151004 0 P 0 ;0
L 1.33613002 -2.01151004 1.33581004 -2.00315 0 P 0 ;0
L 1.33581004 -2.00315 1.33543996 -1.99596004 0 P 0 ;0
L 1.33543996 -1.99596004 1.33508002 -1.98971004 0 P 0 ;0
L 1.33508002 -1.98971004 1.33503996 -1.98945 0 P 0 ;0
L 1.33503996 -1.98945 1.335 -1.98931998 0 P 0 ;0
L 1.335 -1.98931998 1.33496004 -1.9892 0 P 0 ;0
L 1.33496004 -1.9892 1.3349 -1.98908002 0 P 0 ;0
L 1.3349 -1.98908002 1.33483996 -1.98896998 0 P 0 ;0
L 1.33483996 -1.98896998 1.33476998 -1.98886004 0 P 0 ;0
L 1.33476998 -1.98886004 1.33468996 -1.98876004 0 P 0 ;0
L 1.33468996 -1.98876004 1.3346 -1.98866998 0 P 0 ;0
L 1.3346 -1.98866998 1.33451004 -1.98858996 0 P 0 ;0
L 1.33451004 -1.98858996 1.3344 -1.98851998 0 P 0 ;0
L 1.3344 -1.98851998 1.3343 -1.98845 0 P 0 ;0
L 1.3343 -1.98845 1.33418002 -1.98838996 0 P 0 ;0
L 1.33418002 -1.98838996 1.33406998 -1.98833996 0 P 0 ;0
L 1.33406998 -1.98833996 1.33395 -1.9883 0 P 0 ;0
L 1.33395 -1.9883 1.33383002 -1.98828002 0 P 0 ;0
L 1.33383002 -1.98828002 1.3337 -1.98826004 0 P 0 ;0
L 1.3337 -1.98826004 1.33356998 -1.98825 0 P 0 ;0
L 1.33356998 -1.98825 1.32756998 -1.98823002 0 P 0 ;0
L 1.32756998 -1.98823002 1.32135 -1.98853996 0 P 0 ;0
L 1.32135 -1.98853996 1.31878996 -1.98881998 0 P 0 ;0
L 1.31878996 -1.98881998 1.31623996 -1.98923996 0 P 0 ;0
L 1.2389 -2.12516004 1.29006004 -2.12516004 0 P 0 ;0
L 1.23906998 -2.12416004 1.29006004 -2.12416004 0 P 0 ;0
L 1.23921004 -2.12316004 1.29006004 -2.12316004 0 P 0 ;0
L 1.23933996 -2.12216004 1.29006004 -2.12216004 0 P 0 ;0
L 1.23948996 -2.12116004 1.29006004 -2.12116004 0 P 0 ;0
L 1.23961998 -2.12016004 1.29006998 -2.12016004 0 P 0 ;0
L 1.23976004 -2.11916004 1.29006998 -2.11916004 0 P 0 ;0
L 1.2399 -2.11816004 1.29006998 -2.11816004 0 P 0 ;0
L 1.24003996 -2.11716004 1.29008002 -2.11716004 0 P 0 ;0
L 1.24015 -2.11616004 1.2901 -2.11616004 0 P 0 ;0
L 1.24023996 -2.11516004 1.29011998 -2.11516004 0 P 0 ;0
L 1.24033002 -2.11416004 1.29013996 -2.11416004 0 P 0 ;0
L 1.24041004 -2.11316004 1.29016004 -2.11316004 0 P 0 ;0
L 1.24048996 -2.11216004 1.29018996 -2.11216004 0 P 0 ;0
L 1.24058002 -2.11116004 1.29021004 -2.11116004 0 P 0 ;0
L 1.24066998 -2.11016004 1.29023002 -2.11016004 0 P 0 ;0
L 1.24075 -2.10916004 1.29025 -2.10916004 0 P 0 ;0
L 1.2408 -2.10816004 1.29026998 -2.10816004 0 P 0 ;0
L 1.24086004 -2.10716004 1.29028996 -2.10716004 0 P 0 ;0
L 1.24091004 -2.10616004 1.29031998 -2.10616004 0 P 0 ;0
L 1.24096998 -2.10516004 1.29033996 -2.10516004 0 P 0 ;0
L 1.24101998 -2.10416004 1.29036004 -2.10416004 0 P 0 ;0
L 1.24108002 -2.10316004 1.29038002 -2.10316004 0 P 0 ;0
L 1.24113002 -2.10216004 1.29041998 -2.10216004 0 P 0 ;0
L 1.24118002 -2.10116004 1.29046998 -2.10116004 0 P 0 ;0
L 1.24123996 -2.10016004 1.29053002 -2.10016004 0 P 0 ;0
L 1.24128996 -2.09916004 1.29058002 -2.09916004 0 P 0 ;0
L 1.24135 -2.09816004 1.29063002 -2.09816004 0 P 0 ;0
L 1.2414 -2.09716004 1.29068002 -2.09716004 0 P 0 ;0
L 1.24146004 -2.09616004 1.29073996 -2.09616004 0 P 0 ;0
L 1.24151004 -2.09516004 1.29078996 -2.09516004 0 P 0 ;0
L 1.24156998 -2.09416004 1.29083996 -2.09416004 0 P 0 ;0
L 1.24161998 -2.09316004 1.2909 -2.09316004 0 P 0 ;0
L 1.24168002 -2.09216004 1.29095 -2.09216004 0 P 0 ;0
L 1.24173002 -2.09116004 1.291 -2.09116004 0 P 0 ;0
L 1.24178996 -2.09016004 1.29105 -2.09016004 0 P 0 ;0
L 1.24183996 -2.08916004 1.2911 -2.08916004 0 P 0 ;0
L 1.2419 -2.08816004 1.29116004 -2.08816004 0 P 0 ;0
L 1.24196004 -2.08716004 1.29121004 -2.08716004 0 P 0 ;0
L 1.24201004 -2.08616004 1.29126998 -2.08616004 0 P 0 ;0
L 1.24206998 -2.08516004 1.29131998 -2.08516004 0 P 0 ;0
L 1.24211998 -2.08416004 1.29136998 -2.08416004 0 P 0 ;0
L 1.2389 -2.12516004 1.2391 -2.12393002 0 P 0 ;0
L 1.2391 -2.12393002 1.2391 -2.1239 0 P 0 ;0
L 1.2391 -2.1239 1.24011004 -2.11665 0 P 0 ;0
L 1.24011004 -2.11665 1.24073002 -2.10935 0 P 0 ;0
L 1.24073002 -2.10935 1.24073996 -2.10931998 0 P 0 ;0
L 1.24073996 -2.10931998 1.24286004 -2.07056004 0 P 0 ;0
L 1.24286004 -2.07056004 1.24461004 -2.03158002 0 P 0 ;0
L 1.24461004 -2.03158002 1.24513996 -2.00523002 0 P 0 ;0
L 1.24513996 -2.00523002 1.24515 -1.99443996 0 P 0 ;0
L 1.24515 -1.99443996 1.29005 -1.99443996 0 P 0 ;0
L 1.29005 -1.99443996 1.29005 -2.00375 0 P 0 ;0
L 1.29005 -2.00375 1.29128002 -2.0056 0 P 0 ;0
L 1.29128002 -2.0056 1.29345 -2.00518002 0 P 0 ;0
L 1.29345 -2.00518002 1.29803002 -2.0007 0 P 0 ;0
L 1.29803002 -2.0007 1.29991998 -1.999 0 P 0 ;0
L 1.29991998 -1.999 1.30188996 -1.99748996 0 P 0 ;0
L 1.30188996 -1.99748996 1.30411998 -1.99603996 0 P 0 ;0
L 1.30411998 -1.99603996 1.30645 -1.99475 0 P 0 ;0
L 1.30645 -1.99475 1.30891998 -1.99358996 0 P 0 ;0
L 1.30891998 -1.99358996 1.31145 -1.9926 0 P 0 ;0
L 1.31145 -1.9926 1.31401998 -1.99181004 0 P 0 ;0
L 1.31401998 -1.99181004 1.31663996 -1.9912 0 P 0 ;0
L 1.31663996 -1.9912 1.31906004 -1.9908 0 P 0 ;0
L 1.31906004 -1.9908 1.32151004 -1.99053002 0 P 0 ;0
L 1.32151004 -1.99053002 1.32761998 -1.99023002 0 P 0 ;0
L 1.32761998 -1.99023002 1.3331 -1.99025 0 P 0 ;0
L 1.3331 -1.99025 1.33345 -1.99608002 0 P 0 ;0
L 1.33345 -1.99608002 1.33381004 -2.00323002 0 P 0 ;0
L 1.33381004 -2.00323002 1.33413002 -2.01158996 0 P 0 ;0
L 1.33413002 -2.01158996 1.33413002 -2.0116 0 P 0 ;0
L 1.33413002 -2.0116 1.33481998 -2.03123002 0 P 0 ;0
L 1.33481998 -2.03123002 1.32853996 -2.0314 0 P 0 ;0
L 1.32853996 -2.0314 1.32398002 -2.03166998 0 P 0 ;0
L 1.32398002 -2.03166998 1.31941998 -2.03225 0 P 0 ;0
L 1.31941998 -2.03225 1.31488996 -2.03313002 0 P 0 ;0
L 1.31488996 -2.03313002 1.31273996 -2.03373002 0 P 0 ;0
L 1.31273996 -2.03373002 1.31063996 -2.0345 0 P 0 ;0
L 1.31063996 -2.0345 1.3086 -2.03545 0 P 0 ;0
L 1.3086 -2.03545 1.30666004 -2.03656998 0 P 0 ;0
L 1.30666004 -2.03656998 1.30658996 -2.03661998 0 P 0 ;0
L 1.30658996 -2.03661998 1.30483002 -2.03786004 0 P 0 ;0
L 1.30483002 -2.03786004 1.30341998 -2.03901004 0 P 0 ;0
L 1.30341998 -2.03901004 1.30336998 -2.03906004 0 P 0 ;0
L 1.30336998 -2.03906004 1.30211998 -2.04026004 0 P 0 ;0
L 1.30211998 -2.04026004 1.30093002 -2.0416 0 P 0 ;0
L 1.30093002 -2.0416 1.29983002 -2.04303996 0 P 0 ;0
L 1.29983002 -2.04303996 1.29978996 -2.0431 0 P 0 ;0
L 1.29978996 -2.0431 1.29885 -2.04453996 0 P 0 ;0
L 1.29885 -2.04453996 1.29798996 -2.04613002 0 P 0 ;0
L 1.29798996 -2.04613002 1.29631998 -2.04986998 0 P 0 ;0
L 1.29631998 -2.04986998 1.29628002 -2.04995 0 P 0 ;0
L 1.29628002 -2.04995 1.29625 -2.05003002 0 P 0 ;0
L 1.29625 -2.05003002 1.29491998 -2.0539 0 P 0 ;0
L 1.29491998 -2.0539 1.29388996 -2.05793996 0 P 0 ;0
L 1.29388996 -2.05793996 1.29386998 -2.05801998 0 P 0 ;0
L 1.29386998 -2.05801998 1.29313996 -2.06221004 0 P 0 ;0
L 1.29313996 -2.06221004 1.29313002 -2.06223996 0 P 0 ;0
L 1.29313002 -2.06223996 1.29311998 -2.0623 0 P 0 ;0
L 1.29311998 -2.0623 1.29265 -2.06655 0 P 0 ;0
L 1.29265 -2.06655 1.29136998 -2.08418996 0 P 0 ;0
L 1.29136998 -2.08418996 1.29038996 -2.10276998 0 P 0 ;0
L 1.29038996 -2.10276998 1.29006998 -2.11763002 0 P 0 ;0
L 1.29006998 -2.11763002 1.29006004 -2.12516004 0 P 0 ;0
L 1.29006004 -2.12516004 1.2389 -2.12516004 0 P 0 ;0
L 1.09846998 -2.00483002 1.21248002 -2.00483002 0 P 0 ;0
L 1.09838002 -2.12083002 1.14708002 -2.12083002 0 P 0 ;0
L 1.11933002 -2.18283002 1.15161998 -2.18283002 0 P 0 ;0
L 1.11001998 -2.18183002 1.15838002 -2.18183002 0 P 0 ;0
L 1.10246998 -2.18083002 1.16333996 -2.18083002 0 P 0 ;0
L 1.04061004 -1.89731004 1.09978002 -1.89731004 0 P 0 ;0
L 1.03565 -1.89631004 1.09821004 -1.89631004 0 P 0 ;0
L 1.03068996 -1.89531004 1.09661004 -1.89531004 0 P 0 ;0
L 1.02573002 -1.89431004 1.09475 -1.89431004 0 P 0 ;0
L 1.019 -1.89331004 1.09288002 -1.89331004 0 P 0 ;0
L 1.01163996 -1.89231004 1.09101998 -1.89231004 0 P 0 ;0
L 0.99518996 -1.89131004 1.08916004 -1.89131004 0 P 0 ;0
L 0.87011998 -1.88331004 1.07278996 -1.88331004 0 P 0 ;0
L 0.86963996 -1.88231004 1.07053002 -1.88231004 0 P 0 ;0
L 0.86916004 -1.88131004 1.06828002 -1.88131004 0 P 0 ;0
L 0.86863002 -1.88031004 1.06603002 -1.88031004 0 P 0 ;0
L 0.86806998 -1.87931004 1.06351004 -1.87931004 0 P 0 ;0
L 0.8675 -1.87831004 1.06076998 -1.87831004 0 P 0 ;0
L 0.86693002 -1.87731004 1.05803996 -1.87731004 0 P 0 ;0
L 0.86631004 -1.87631004 1.05531004 -1.87631004 0 P 0 ;0
L 0.86563996 -1.87531004 1.05256998 -1.87531004 0 P 0 ;0
L 0.86498002 -1.87431004 1.04983996 -1.87431004 0 P 0 ;0
L 0.86431998 -1.87331004 1.0471 -1.87331004 0 P 0 ;0
L 0.86356004 -1.87231004 1.04376004 -1.87231004 0 P 0 ;0
L 0.86278996 -1.87131004 1.04041998 -1.87131004 0 P 0 ;0
L 0.86203002 -1.87031004 1.03708002 -1.87031004 0 P 0 ;0
L 0.86118996 -1.86931004 1.03373996 -1.86931004 0 P 0 ;0
L 0.8603 -1.86831004 1.0304 -1.86831004 0 P 0 ;0
L 0.85941004 -1.86731004 1.02656998 -1.86731004 0 P 0 ;0
L 0.8585 -1.86631004 1.02231998 -1.86631004 0 P 0 ;0
L 0.85756998 -1.86531004 1.01806998 -1.86531004 0 P 0 ;0
L 0.85663002 -1.86431004 1.01381998 -1.86431004 0 P 0 ;0
L 0.85568996 -1.86331004 1.00931998 -1.86331004 0 P 0 ;0
L 0.85481004 -1.86231004 1.00335 -1.86231004 0 P 0 ;0
L 0.85916998 -1.86131004 0.99738002 -1.86131004 0 P 0 ;0
L 0.86716998 -1.86031004 0.99141998 -1.86031004 0 P 0 ;0
L 0.87476998 -1.89731004 0.89943002 -1.89731004 0 P 0 ;0
L 0.87453996 -1.89631004 0.90426004 -1.89631004 0 P 0 ;0
L 0.87431004 -1.89531004 0.9097 -1.89531004 0 P 0 ;0
L 0.87406998 -1.89431004 0.91608002 -1.89431004 0 P 0 ;0
L 0.87383002 -1.89331004 0.92246004 -1.89331004 0 P 0 ;0
L 0.87355 -1.89231004 0.93086004 -1.89231004 0 P 0 ;0
L 0.87323002 -1.89131004 0.95553002 -1.89131004 0 P 0 ;0
L 0.87291004 -1.89031004 1.08728996 -1.89031004 0 P 0 ;0
L 0.87258996 -1.88931004 1.08543002 -1.88931004 0 P 0 ;0
L 0.87223002 -1.88831004 1.08356998 -1.88831004 0 P 0 ;0
L 0.87183002 -1.88731004 1.0817 -1.88731004 0 P 0 ;0
L 0.87143002 -1.88631004 1.07955 -1.88631004 0 P 0 ;0
L 0.87103002 -1.88531004 1.07728996 -1.88531004 0 P 0 ;0
L 0.8706 -1.88431004 1.07503996 -1.88431004 0 P 0 ;0
L 0.87525 -1.85931004 0.98545 -1.85931004 0 P 0 ;0
L 0.88421004 -1.85831004 0.97621004 -1.85831004 0 P 0 ;0
L 0.89393002 -1.85731004 0.96606998 -1.85731004 0 P 0 ;0
L 0.9106 -1.85631004 0.95203002 -1.85631004 0 P 0 ;0
L 1.08716004 -1.91231004 1.12151004 -1.91231004 0 P 0 ;0
L 1.08486004 -1.91131004 1.12018996 -1.91131004 0 P 0 ;0
L 1.08256004 -1.91031004 1.11886004 -1.91031004 0 P 0 ;0
L 1.08023002 -1.90931004 1.11753996 -1.90931004 0 P 0 ;0
L 1.07738002 -1.90831004 1.11621004 -1.90831004 0 P 0 ;0
L 1.07453002 -1.90731004 1.11488996 -1.90731004 0 P 0 ;0
L 1.07168996 -1.90631004 1.11356998 -1.90631004 0 P 0 ;0
L 1.06883996 -1.90531004 1.11223996 -1.90531004 0 P 0 ;0
L 1.066 -1.90431004 1.11076998 -1.90431004 0 P 0 ;0
L 1.06315 -1.90331004 1.1092 -1.90331004 0 P 0 ;0
L 1.0599 -1.90231004 1.10763002 -1.90231004 0 P 0 ;0
L 1.05611998 -1.90131004 1.10606004 -1.90131004 0 P 0 ;0
L 1.05235 -1.90031004 1.10448996 -1.90031004 0 P 0 ;0
L 1.04856998 -1.89931004 1.10291998 -1.89931004 0 P 0 ;0
L 1.04478996 -1.89831004 1.10135 -1.89831004 0 P 0 ;0
L 0.98815 -2.08316004 1.03726998 -2.08316004 0 P 0 ;0
L 0.98818002 -2.08216004 1.03731004 -2.08216004 0 P 0 ;0
L 0.98821998 -2.08116004 1.03735 -2.08116004 0 P 0 ;0
L 0.98825 -2.08016004 1.03738996 -2.08016004 0 P 0 ;0
L 0.98828002 -2.07916004 1.03743002 -2.07916004 0 P 0 ;0
L 0.98831998 -2.07816004 1.03746998 -2.07816004 0 P 0 ;0
L 0.98835 -2.07716004 1.03751004 -2.07716004 0 P 0 ;0
L 0.98838002 -2.07616004 1.03755 -2.07616004 0 P 0 ;0
L 0.98841998 -2.07516004 1.03758002 -2.07516004 0 P 0 ;0
L 0.98845 -2.07416004 1.03761004 -2.07416004 0 P 0 ;0
L 0.98848002 -2.07316004 1.03763996 -2.07316004 0 P 0 ;0
L 0.98851004 -2.07216004 1.03768002 -2.07216004 0 P 0 ;0
L 0.98855 -2.07116004 1.03771004 -2.07116004 0 P 0 ;0
L 0.98858002 -2.07016004 1.03773996 -2.07016004 0 P 0 ;0
L 0.98858996 -2.06916004 1.03776998 -2.06916004 0 P 0 ;0
L 0.98858996 -2.06816004 1.0378 -2.06816004 0 P 0 ;0
L 0.98858996 -2.06716004 1.03783002 -2.06716004 0 P 0 ;0
L 0.98858002 -2.06616004 1.03786004 -2.06616004 0 P 0 ;0
L 0.98856998 -2.06516004 1.0379 -2.06516004 0 P 0 ;0
L 0.98856998 -2.06416004 1.03793002 -2.06416004 0 P 0 ;0
L 0.98856998 -2.06316004 1.03796004 -2.06316004 0 P 0 ;0
L 0.98856004 -2.06216004 1.03798996 -2.06216004 0 P 0 ;0
L 0.98855 -2.06116004 1.03801998 -2.06116004 0 P 0 ;0
L 0.98855 -2.06016004 1.03805 -2.06016004 0 P 0 ;0
L 0.98853996 -2.05916004 1.03808002 -2.05916004 0 P 0 ;0
L 0.98853996 -2.05816004 1.0381 -2.05816004 0 P 0 ;0
L 0.98853002 -2.05716004 1.03811998 -2.05716004 0 P 0 ;0
L 0.98848002 -2.05616004 1.03815 -2.05616004 0 P 0 ;0
L 0.98841004 -2.05516004 1.03818002 -2.05516004 0 P 0 ;0
L 0.98835 -2.05416004 1.0382 -2.05416004 0 P 0 ;0
L 0.98828002 -2.05316004 1.03821998 -2.05316004 0 P 0 ;0
L 0.98821004 -2.05216004 1.03825 -2.05216004 0 P 0 ;0
L 0.98815 -2.05116004 1.03826998 -2.05116004 0 P 0 ;0
L 0.98808996 -2.05016004 1.03828996 -2.05016004 0 P 0 ;0
L 0.98801998 -2.04916004 1.03831998 -2.04916004 0 P 0 ;0
L 0.98796004 -2.04816004 1.03833996 -2.04816004 0 P 0 ;0
L 0.98788996 -2.04716004 1.03836004 -2.04716004 0 P 0 ;0
L 0.98783002 -2.04616004 1.03838996 -2.04616004 0 P 0 ;0
L 0.98768996 -2.04516004 1.0384 -2.04516004 0 P 0 ;0
L 0.98756004 -2.04416004 1.03841004 -2.04416004 0 P 0 ;0
L 0.98738002 -2.04316004 1.03841998 -2.04316004 0 P 0 ;0
L 0.98716004 -2.04216004 1.03843002 -2.04216004 0 P 0 ;0
L 0.98691998 -2.04116004 1.03843996 -2.04116004 0 P 0 ;0
L 0.98661998 -2.04016004 1.03845 -2.04016004 0 P 0 ;0
L 0.98631998 -2.03916004 1.03846004 -2.03916004 0 P 0 ;0
L 0.98593996 -2.03816004 1.03846998 -2.03816004 0 P 0 ;0
L 0.98546998 -2.03716004 1.03848002 -2.03716004 0 P 0 ;0
L 0.98491004 -2.03616004 1.03846998 -2.03616004 0 P 0 ;0
L 0.98425 -2.03516004 1.03846004 -2.03516004 0 P 0 ;0
L 0.98346004 -2.03416004 1.03846004 -2.03416004 0 P 0 ;0
L 0.98251998 -2.03316004 1.03843996 -2.03316004 0 P 0 ;0
L 0.98138002 -2.03216004 1.03843002 -2.03216004 0 P 0 ;0
L 0.97998996 -2.03116004 1.03841998 -2.03116004 0 P 0 ;0
L 0.97813996 -2.03016004 1.03841004 -2.03016004 0 P 0 ;0
L 0.97491004 -2.02916004 1.0384 -2.02916004 0 P 0 ;0
L 0.94763996 -2.00716004 1.03293996 -2.00716004 0 P 0 ;0
L 0.94978996 -2.00616004 1.03231998 -2.00616004 0 P 0 ;0
L 0.95081004 -2.00516004 1.0317 -2.00516004 0 P 0 ;0
L 0.95183002 -2.00416004 1.03098002 -2.00416004 0 P 0 ;0
L 0.95285 -2.00316004 1.03023002 -2.00316004 0 P 0 ;0
L 0.95388996 -2.00216004 1.02936004 -2.00216004 0 P 0 ;0
L 0.95498002 -2.00116004 1.02841998 -2.00116004 0 P 0 ;0
L 0.95621998 -2.00016004 1.02738996 -2.00016004 0 P 0 ;0
L 0.95761998 -1.99916004 1.0262 -1.99916004 0 P 0 ;0
L 0.9592 -1.99816004 1.02486004 -1.99816004 0 P 0 ;0
L 0.96083996 -1.99716004 1.02335 -1.99716004 0 P 0 ;0
L 0.9627 -1.99616004 1.02161004 -1.99616004 0 P 0 ;0
L 0.96468996 -1.99516004 1.01951998 -1.99516004 0 P 0 ;0
L 0.96685 -1.99416004 1.01683002 -1.99416004 0 P 0 ;0
L 0.96936998 -1.99316004 1.01378002 -1.99316004 0 P 0 ;0
L 0.97236998 -1.99216004 1.00981004 -1.99216004 0 P 0 ;0
L 0.97676004 -1.99116004 1.00456998 -1.99116004 0 P 0 ;0
L 1.06713996 -2.08283002 1.12288002 -2.08283002 0 P 0 ;0
L 1.06698996 -2.08183002 1.12193996 -2.08183002 0 P 0 ;0
L 1.06686004 -2.08083002 1.12108996 -2.08083002 0 P 0 ;0
L 1.06673996 -2.07983002 1.12036004 -2.07983002 0 P 0 ;0
L 1.06661998 -2.07883002 1.11971998 -2.07883002 0 P 0 ;0
L 1.06653002 -2.07783002 1.11916004 -2.07783002 0 P 0 ;0
L 1.06648002 -2.07683002 1.11866004 -2.07683002 0 P 0 ;0
L 1.06641998 -2.07583002 1.11826004 -2.07583002 0 P 0 ;0
L 1.06636998 -2.07483002 1.11791998 -2.07483002 0 P 0 ;0
L 1.06631998 -2.07383002 1.11761998 -2.07383002 0 P 0 ;0
L 1.06626004 -2.07283002 1.11741998 -2.07283002 0 P 0 ;0
L 1.06621004 -2.07183002 1.11723996 -2.07183002 0 P 0 ;0
L 1.06616004 -2.07083002 1.11711998 -2.07083002 0 P 0 ;0
L 1.06616004 -2.06983002 1.11701004 -2.06983002 0 P 0 ;0
L 1.06616004 -2.06883002 1.11688996 -2.06883002 0 P 0 ;0
L 1.06616998 -2.06783002 1.11676998 -2.06783002 0 P 0 ;0
L 1.06618002 -2.06683002 1.11666998 -2.06683002 0 P 0 ;0
L 1.06618996 -2.06583002 1.11663002 -2.06583002 0 P 0 ;0
L 1.0662 -2.06483002 1.11658996 -2.06483002 0 P 0 ;0
L 1.06621004 -2.06383002 1.11656004 -2.06383002 0 P 0 ;0
L 1.06623002 -2.06283002 1.11651998 -2.06283002 0 P 0 ;0
L 1.06631004 -2.06183002 1.11648996 -2.06183002 0 P 0 ;0
L 1.06638002 -2.06083002 1.11653002 -2.06083002 0 P 0 ;0
L 1.06645 -2.05983002 1.11656998 -2.05983002 0 P 0 ;0
L 1.06651998 -2.05883002 1.11661998 -2.05883002 0 P 0 ;0
L 1.06658996 -2.05783002 1.11666004 -2.05783002 0 P 0 ;0
L 1.06666998 -2.05683002 1.11671004 -2.05683002 0 P 0 ;0
L 1.06673996 -2.05583002 1.11681004 -2.05583002 0 P 0 ;0
L 1.06686004 -2.05483002 1.11693002 -2.05483002 0 P 0 ;0
L 1.067 -2.05383002 1.11705 -2.05383002 0 P 0 ;0
L 1.06713996 -2.05283002 1.11718002 -2.05283002 0 P 0 ;0
L 1.06728002 -2.05183002 1.11731004 -2.05183002 0 P 0 ;0
L 1.06741998 -2.05083002 1.11746004 -2.05083002 0 P 0 ;0
L 1.06756004 -2.04983002 1.11766004 -2.04983002 0 P 0 ;0
L 1.0677 -2.04883002 1.11786004 -2.04883002 0 P 0 ;0
L 1.06786004 -2.04783002 1.11813996 -2.04783002 0 P 0 ;0
L 1.06806998 -2.04683002 1.11841998 -2.04683002 0 P 0 ;0
L 1.06828002 -2.04583002 1.11876998 -2.04583002 0 P 0 ;0
L 1.06848996 -2.04483002 1.11913002 -2.04483002 0 P 0 ;0
L 1.06871004 -2.04383002 1.11955 -2.04383002 0 P 0 ;0
L 1.06898996 -2.04283002 1.11998996 -2.04283002 0 P 0 ;0
L 1.06928002 -2.04183002 1.12048002 -2.04183002 0 P 0 ;0
L 1.06956004 -2.04083002 1.12101004 -2.04083002 0 P 0 ;0
L 1.06985 -2.03983002 1.12161998 -2.03983002 0 P 0 ;0
L 1.07021004 -2.03883002 1.12225 -2.03883002 0 P 0 ;0
L 1.07056998 -2.03783002 1.12298002 -2.03783002 0 P 0 ;0
L 1.07093002 -2.03683002 1.12373996 -2.03683002 0 P 0 ;0
L 1.07128996 -2.03583002 1.12461998 -2.03583002 0 P 0 ;0
L 1.07173002 -2.03483002 1.12548996 -2.03483002 0 P 0 ;0
L 1.07216998 -2.03383002 1.12646004 -2.03383002 0 P 0 ;0
L 1.07261998 -2.03283002 1.12748996 -2.03283002 0 P 0 ;0
L 1.07308002 -2.03183002 1.12855 -2.03183002 0 P 0 ;0
L 1.07361998 -2.03083002 1.12978996 -2.03083002 0 P 0 ;0
L 1.09761004 -1.91731004 1.12756998 -1.91731004 0 P 0 ;0
L 1.09566004 -1.91631004 1.12645 -1.91631004 0 P 0 ;0
L 1.09371004 -1.91531004 1.12533002 -1.91531004 0 P 0 ;0
L 1.09176004 -1.91431004 1.12416004 -1.91431004 0 P 0 ;0
L 1.08946004 -1.91331004 1.12283996 -1.91331004 0 P 0 ;0
L 1.07415 -2.02983002 1.13101998 -2.02983002 0 P 0 ;0
L 1.07468996 -2.02883002 1.13248996 -2.02883002 0 P 0 ;0
L 1.07528996 -2.02783002 1.134 -2.02783002 0 P 0 ;0
L 1.07591998 -2.02683002 1.13586004 -2.02683002 0 P 0 ;0
L 1.07656004 -2.02583002 1.13828996 -2.02583002 0 P 0 ;0
L 1.07721004 -2.02483002 1.14243002 -2.02483002 0 P 0 ;0
L 1.07795 -2.02383002 1.21126998 -2.02383002 0 P 0 ;0
L 1.07868002 -2.02283002 1.21133002 -2.02283002 0 P 0 ;0
L 1.07941998 -2.02183002 1.2114 -2.02183002 0 P 0 ;0
L 1.08021004 -2.02083002 1.21146004 -2.02083002 0 P 0 ;0
L 1.08103996 -2.01983002 1.21153002 -2.01983002 0 P 0 ;0
L 1.08186998 -2.01883002 1.2116 -2.01883002 0 P 0 ;0
L 1.08273002 -2.01783002 1.21166004 -2.01783002 0 P 0 ;0
L 1.08366998 -2.01683002 1.21173002 -2.01683002 0 P 0 ;0
L 1.0846 -2.01583002 1.2118 -2.01583002 0 P 0 ;0
L 1.08555 -2.01483002 1.21186004 -2.01483002 0 P 0 ;0
L 1.08661004 -2.01383002 1.21193002 -2.01383002 0 P 0 ;0
L 1.08766998 -2.01283002 1.21198996 -2.01283002 0 P 0 ;0
L 1.08873002 -2.01183002 1.21205 -2.01183002 0 P 0 ;0
L 1.0898 -2.01083002 1.21211998 -2.01083002 0 P 0 ;0
L 1.09098996 -2.00983002 1.21218002 -2.00983002 0 P 0 ;0
L 1.09225 -2.00883002 1.21223996 -2.00883002 0 P 0 ;0
L 1.09358996 -2.00783002 1.2123 -2.00783002 0 P 0 ;0
L 1.09506998 -2.00683002 1.21236004 -2.00683002 0 P 0 ;0
L 1.09668996 -2.00583002 1.21241998 -2.00583002 0 P 0 ;0
L 0.98546998 -2.12516004 1.03548996 -2.12516004 0 P 0 ;0
L 0.98558996 -2.12416004 1.03553996 -2.12416004 0 P 0 ;0
L 0.9857 -2.12316004 1.03558002 -2.12316004 0 P 0 ;0
L 0.98581004 -2.12216004 1.03561998 -2.12216004 0 P 0 ;0
L 0.98591004 -2.12116004 1.03566998 -2.12116004 0 P 0 ;0
L 0.98598996 -2.12016004 1.03571004 -2.12016004 0 P 0 ;0
L 0.98608002 -2.11916004 1.03575 -2.11916004 0 P 0 ;0
L 0.98616998 -2.11816004 1.0358 -2.11816004 0 P 0 ;0
L 0.98625 -2.11716004 1.03583996 -2.11716004 0 P 0 ;0
L 0.98633996 -2.11616004 1.03588002 -2.11616004 0 P 0 ;0
L 0.98641998 -2.11516004 1.03593002 -2.11516004 0 P 0 ;0
L 0.98651004 -2.11416004 1.03596998 -2.11416004 0 P 0 ;0
L 0.9866 -2.11316004 1.03601004 -2.11316004 0 P 0 ;0
L 0.98668002 -2.11216004 1.03605 -2.11216004 0 P 0 ;0
L 0.98676998 -2.11116004 1.0361 -2.11116004 0 P 0 ;0
L 0.98685 -2.11016004 1.03613996 -2.11016004 0 P 0 ;0
L 0.98693996 -2.10916004 1.03618002 -2.10916004 0 P 0 ;0
L 0.987 -2.10816004 1.03623002 -2.10816004 0 P 0 ;0
L 0.98705 -2.10716004 1.03626998 -2.10716004 0 P 0 ;0
L 0.9871 -2.10616004 1.03631004 -2.10616004 0 P 0 ;0
L 0.98716004 -2.10516004 1.03636004 -2.10516004 0 P 0 ;0
L 0.9872 -2.10416004 1.0364 -2.10416004 0 P 0 ;0
L 0.98725 -2.10316004 1.03643996 -2.10316004 0 P 0 ;0
L 0.98731004 -2.10216004 1.03648002 -2.10216004 0 P 0 ;0
L 0.98735 -2.10116004 1.03653002 -2.10116004 0 P 0 ;0
L 0.9874 -2.10016004 1.03656998 -2.10016004 0 P 0 ;0
L 0.98746004 -2.09916004 1.03661004 -2.09916004 0 P 0 ;0
L 0.98751004 -2.09816004 1.03666004 -2.09816004 0 P 0 ;0
L 0.98755 -2.09716004 1.0367 -2.09716004 0 P 0 ;0
L 0.9876 -2.09616004 1.03673996 -2.09616004 0 P 0 ;0
L 0.98766004 -2.09516004 1.03678996 -2.09516004 0 P 0 ;0
L 0.9877 -2.09416004 1.03683002 -2.09416004 0 P 0 ;0
L 0.98775 -2.09316004 1.03686998 -2.09316004 0 P 0 ;0
L 0.98781004 -2.09216004 1.03691998 -2.09216004 0 P 0 ;0
L 0.98785 -2.09116004 1.03696004 -2.09116004 0 P 0 ;0
L 0.9879 -2.09016004 1.037 -2.09016004 0 P 0 ;0
L 0.98796004 -2.08916004 1.03703996 -2.08916004 0 P 0 ;0
L 0.98798996 -2.08816004 1.03706998 -2.08816004 0 P 0 ;0
L 0.98801998 -2.08716004 1.03711004 -2.08716004 0 P 0 ;0
L 0.98805 -2.08616004 1.03715 -2.08616004 0 P 0 ;0
L 0.98808996 -2.08516004 1.03718996 -2.08516004 0 P 0 ;0
L 0.98811998 -2.08416004 1.03723002 -2.08416004 0 P 0 ;0
L 1.08216998 -2.15683002 1.19803996 -2.15683002 0 P 0 ;0
L 1.0821 -2.15583002 1.19861004 -2.15583002 0 P 0 ;0
L 1.08201998 -2.15483002 1.19918002 -2.15483002 0 P 0 ;0
L 1.08195 -2.15383002 1.1997 -2.15383002 0 P 0 ;0
L 1.08188996 -2.15283002 1.20018002 -2.15283002 0 P 0 ;0
L 1.08183002 -2.15183002 1.20066004 -2.15183002 0 P 0 ;0
L 1.08176998 -2.15083002 1.20113996 -2.15083002 0 P 0 ;0
L 1.08171998 -2.14983002 1.20153996 -2.14983002 0 P 0 ;0
L 1.08166004 -2.14883002 1.20193002 -2.14883002 0 P 0 ;0
L 1.0816 -2.14783002 1.11538996 -2.14783002 0 P 0 ;0
L 1.08155 -2.14683002 1.10903002 -2.14683002 0 P 0 ;0
L 1.0815 -2.14583002 1.10415 -2.14583002 0 P 0 ;0
L 1.08146004 -2.14483002 1.09953002 -2.14483002 0 P 0 ;0
L 1.08141004 -2.14383002 1.09563996 -2.14383002 0 P 0 ;0
L 1.08136004 -2.14283002 1.09183996 -2.14283002 0 P 0 ;0
L 1.08131004 -2.14183002 1.08821004 -2.14183002 0 P 0 ;0
L 1.08133002 -2.14083002 1.08471998 -2.14083002 0 P 0 ;0
L 1.09586998 -2.11983002 1.14965 -2.11983002 0 P 0 ;0
L 1.09361998 -2.11883002 1.15221998 -2.11883002 0 P 0 ;0
L 1.09158996 -2.11783002 1.20595 -2.11783002 0 P 0 ;0
L 1.08988002 -2.11683002 1.20601004 -2.11683002 0 P 0 ;0
L 1.08823996 -2.11583002 1.20606998 -2.11583002 0 P 0 ;0
L 1.08678996 -2.11483002 1.20613002 -2.11483002 0 P 0 ;0
L 1.08541004 -2.11383002 1.20618996 -2.11383002 0 P 0 ;0
L 1.08416998 -2.11283002 1.20625 -2.11283002 0 P 0 ;0
L 1.08295 -2.11183002 1.20631004 -2.11183002 0 P 0 ;0
L 1.08188002 -2.11083002 1.20638002 -2.11083002 0 P 0 ;0
L 1.08081998 -2.10983002 1.20643996 -2.10983002 0 P 0 ;0
L 1.07986004 -2.10883002 1.2065 -2.10883002 0 P 0 ;0
L 1.07895 -2.10783002 1.20656004 -2.10783002 0 P 0 ;0
L 1.07803002 -2.10683002 1.20661998 -2.10683002 0 P 0 ;0
L 1.07723996 -2.10583002 1.20666998 -2.10583002 0 P 0 ;0
L 1.07646004 -2.10483002 1.20671998 -2.10483002 0 P 0 ;0
L 1.07568002 -2.10383002 1.20678002 -2.10383002 0 P 0 ;0
L 1.075 -2.10283002 1.20683002 -2.10283002 0 P 0 ;0
L 1.07433002 -2.10183002 1.20688002 -2.10183002 0 P 0 ;0
L 1.07366998 -2.10083002 1.20693996 -2.10083002 0 P 0 ;0
L 1.07308996 -2.09983002 1.20698996 -2.09983002 0 P 0 ;0
L 1.07253002 -2.09883002 1.20705 -2.09883002 0 P 0 ;0
L 1.07198002 -2.09783002 1.2071 -2.09783002 0 P 0 ;0
L 1.07146998 -2.09683002 1.20715 -2.09683002 0 P 0 ;0
L 1.07101998 -2.09583002 1.2072 -2.09583002 0 P 0 ;0
L 1.07056998 -2.09483002 1.20726004 -2.09483002 0 P 0 ;0
L 1.07013002 -2.09383002 1.20731004 -2.09383002 0 P 0 ;0
L 1.06976998 -2.09283002 1.20736004 -2.09283002 0 P 0 ;0
L 1.06941998 -2.09183002 1.20741998 -2.09183002 0 P 0 ;0
L 1.06906004 -2.09083002 1.20746998 -2.09083002 0 P 0 ;0
L 1.06876004 -2.08983002 1.20753002 -2.08983002 0 P 0 ;0
L 1.06848996 -2.08883002 1.13443002 -2.08883002 0 P 0 ;0
L 1.06821998 -2.08783002 1.13068002 -2.08783002 0 P 0 ;0
L 1.06795 -2.08683002 1.12836998 -2.08683002 0 P 0 ;0
L 1.06771998 -2.08583002 1.1266 -2.08583002 0 P 0 ;0
L 1.06753002 -2.08483002 1.12516004 -2.08483002 0 P 0 ;0
L 1.06733002 -2.08383002 1.12393996 -2.08383002 0 P 0 ;0
L 0.90273996 -1.85456998 0.89068996 -1.85558002 0 P 0 ;0
L 0.89068996 -1.85558002 0.87421004 -1.85741998 0 P 0 ;0
L 0.87421004 -1.85741998 0.85783002 -1.85946998 0 P 0 ;0
L 0.85783002 -1.85946998 0.85526998 -1.8599 0 P 0 ;0
L 0.85526998 -1.8599 0.85276004 -1.86055 0 P 0 ;0
L 0.85276004 -1.86055 0.85255 -1.86063996 0 P 0 ;0
L 0.85255 -1.86063996 0.85248996 -1.86068996 0 P 0 ;0
L 0.85248996 -1.86068996 0.85243002 -1.86073002 0 P 0 ;0
L 0.85243002 -1.86073002 0.85238002 -1.86078002 0 P 0 ;0
L 0.85238002 -1.86078002 0.85233002 -1.86083996 0 P 0 ;0
L 0.85233002 -1.86083996 0.85225 -1.86096004 0 P 0 ;0
L 0.85225 -1.86096004 0.85218002 -1.8611 0 P 0 ;0
L 0.85218002 -1.8611 0.85216004 -1.86116998 0 P 0 ;0
L 0.85216004 -1.86116998 0.85215 -1.86123996 0 P 0 ;0
L 0.85215 -1.86123996 0.85213996 -1.86136998 0 P 0 ;0
L 0.85213996 -1.86136998 0.85213002 -1.86148996 0 P 0 ;0
L 0.85213002 -1.86148996 0.85213996 -1.86161998 0 P 0 ;0
L 0.85213996 -1.86161998 0.85215 -1.86173996 0 P 0 ;0
L 0.85215 -1.86173996 0.85218002 -1.86186998 0 P 0 ;0
L 0.85218002 -1.86186998 0.85221004 -1.86198996 0 P 0 ;0
L 0.85221004 -1.86198996 0.85225 -1.8621 0 P 0 ;0
L 0.85225 -1.8621 0.85231004 -1.86221998 0 P 0 ;0
L 0.85231004 -1.86221998 0.85236998 -1.86233002 0 P 0 ;0
L 0.85236998 -1.86233002 0.85281998 -1.863 0 P 0 ;0
L 0.85281998 -1.863 0.8533 -1.86363996 0 P 0 ;0
L 0.8533 -1.86363996 0.85383002 -1.86425 0 P 0 ;0
L 0.85383002 -1.86425 0.85736004 -1.86801998 0 P 0 ;0
L 0.85736004 -1.86801998 0.86013002 -1.87113002 0 P 0 ;0
L 0.86013002 -1.87113002 0.86266004 -1.87443002 0 P 0 ;0
L 0.86266004 -1.87443002 0.86501004 -1.87798996 0 P 0 ;0
L 0.86501004 -1.87798996 0.86711998 -1.88171004 0 P 0 ;0
L 0.86711998 -1.88171004 0.86896998 -1.88553996 0 P 0 ;0
L 0.86896998 -1.88553996 0.87055 -1.8895 0 P 0 ;0
L 0.87055 -1.8895 0.8718 -1.89343002 0 P 0 ;0
L 0.8718 -1.89343002 0.87276004 -1.89745 0 P 0 ;0
L 0.87276004 -1.89745 0.87371004 -1.90195 0 P 0 ;0
L 0.87371004 -1.90195 0.87383002 -1.90236004 0 P 0 ;0
L 0.87383002 -1.90236004 0.87396998 -1.90276004 0 P 0 ;0
L 0.87396998 -1.90276004 0.87416004 -1.90313996 0 P 0 ;0
L 0.87416004 -1.90313996 0.87436998 -1.90351004 0 P 0 ;0
L 0.87436998 -1.90351004 0.87443002 -1.9036 0 P 0 ;0
L 0.87443002 -1.9036 0.87456998 -1.90376004 0 P 0 ;0
L 0.87456998 -1.90376004 0.87465 -1.90381998 0 P 0 ;0
L 0.87465 -1.90381998 0.87473002 -1.90388996 0 P 0 ;0
L 0.87473002 -1.90388996 0.87481998 -1.90393996 0 P 0 ;0
L 0.87481998 -1.90393996 0.87491998 -1.90398996 0 P 0 ;0
L 0.87491998 -1.90398996 0.87501004 -1.90403002 0 P 0 ;0
L 0.87501004 -1.90403002 0.87521004 -1.90408996 0 P 0 ;0
L 0.87521004 -1.90408996 0.87531998 -1.9041 0 P 0 ;0
L 0.87531998 -1.9041 0.87573002 -1.90413002 0 P 0 ;0
L 0.87573002 -1.90413002 0.87613996 -1.90411998 0 P 0 ;0
L 0.87613996 -1.90411998 0.87653996 -1.90408002 0 P 0 ;0
L 0.87653996 -1.90408002 0.87695 -1.90401004 0 P 0 ;0
L 0.87695 -1.90401004 0.90756004 -1.89766998 0 P 0 ;0
L 0.90756004 -1.89766998 0.92603996 -1.89478002 0 P 0 ;0
L 0.92603996 -1.89478002 0.93486004 -1.89393996 0 P 0 ;0
L 0.93486004 -1.89393996 0.94371004 -1.8935 0 P 0 ;0
L 0.94371004 -1.8935 0.97045 -1.89308002 0 P 0 ;0
L 0.97045 -1.89308002 0.99468996 -1.89328996 0 P 0 ;0
L 0.99468996 -1.89328996 1.01021004 -1.89413996 0 P 0 ;0
L 1.01021004 -1.89413996 1.0241 -1.89601998 0 P 0 ;0
L 1.0241 -1.89601998 1.04188002 -1.89961004 0 P 0 ;0
L 1.04188002 -1.89961004 1.06095 -1.90466004 0 P 0 ;0
L 1.06095 -1.90466004 1.07963996 -1.91123002 0 P 0 ;0
L 1.07963996 -1.91123002 1.09093996 -1.91613002 0 P 0 ;0
L 1.09093996 -1.91613002 1.10186998 -1.92175 0 P 0 ;0
L 1.10186998 -1.92175 1.11243996 -1.92806998 0 P 0 ;0
L 1.11243996 -1.92806998 1.12163002 -1.93446998 0 P 0 ;0
L 1.12163002 -1.93446998 1.13033002 -1.94148996 0 P 0 ;0
L 1.13033002 -1.94148996 1.1385 -1.94911004 0 P 0 ;0
L 1.1385 -1.94911004 1.14358996 -1.9546 0 P 0 ;0
L 1.14358996 -1.9546 1.14825 -1.96045 0 P 0 ;0
L 1.14825 -1.96045 1.15246998 -1.96663002 0 P 0 ;0
L 1.15246998 -1.96663002 1.15623002 -1.97316004 0 P 0 ;0
L 1.15623002 -1.97316004 1.15895 -1.97831004 0 P 0 ;0
L 1.15895 -1.97831004 1.17358996 -1.97831004 0 P 0 ;0
L 1.17358996 -1.97831004 1.17135 -1.9726 0 P 0 ;0
L 1.17135 -1.9726 1.16696004 -1.96266998 0 P 0 ;0
L 1.16696004 -1.96266998 1.16171998 -1.95313002 0 P 0 ;0
L 1.16171998 -1.95313002 1.1557 -1.94406998 0 P 0 ;0
L 1.1557 -1.94406998 1.14885 -1.93548002 0 P 0 ;0
L 1.14885 -1.93548002 1.13778996 -1.92378002 0 P 0 ;0
L 1.13778996 -1.92378002 1.12576998 -1.91301998 0 P 0 ;0
L 1.12576998 -1.91301998 1.11283996 -1.90326004 0 P 0 ;0
L 1.11283996 -1.90326004 1.09783002 -1.89368996 0 P 0 ;0
L 1.09783002 -1.89368996 1.08213002 -1.88526998 0 P 0 ;0
L 1.08213002 -1.88526998 1.06576998 -1.87801004 0 P 0 ;0
L 1.06576998 -1.87801004 1.04776004 -1.87141998 0 P 0 ;0
L 1.04776004 -1.87141998 1.02938002 -1.86591998 0 P 0 ;0
L 1.02938002 -1.86591998 1.01058002 -1.8615 0 P 0 ;0
L 1.01058002 -1.8615 0.98441998 -1.85711004 0 P 0 ;0
L 0.98441998 -1.85711004 0.95781004 -1.85448996 0 P 0 ;0
L 0.95781004 -1.85448996 0.93061004 -1.85366004 0 P 0 ;0
L 0.93061004 -1.85366004 0.90273996 -1.85456998 0 P 0 ;0
L 1.16015 -1.97631004 1.15798002 -1.97218996 0 P 0 ;0
L 1.15798002 -1.97218996 1.15796004 -1.97216004 0 P 0 ;0
L 1.15796004 -1.97216004 1.15416004 -1.96556998 0 P 0 ;0
L 1.15416004 -1.96556998 1.15411998 -1.96551004 0 P 0 ;0
L 1.15411998 -1.96551004 1.14986004 -1.95926004 0 P 0 ;0
L 1.14986004 -1.95926004 1.14981998 -1.95921004 0 P 0 ;0
L 1.14981998 -1.95921004 1.14511004 -1.9533 0 P 0 ;0
L 1.14511004 -1.9533 1.13991998 -1.9477 0 P 0 ;0
L 1.13991998 -1.9477 1.13986004 -1.94765 0 P 0 ;0
L 1.13986004 -1.94765 1.13163996 -1.93998002 0 P 0 ;0
L 1.13163996 -1.93998002 1.12283002 -1.93286004 0 P 0 ;0
L 1.12283002 -1.93286004 1.11351998 -1.92638996 0 P 0 ;0
L 1.11351998 -1.92638996 1.10283996 -1.92 0 P 0 ;0
L 1.10283996 -1.92 1.0918 -1.91433002 0 P 0 ;0
L 1.0918 -1.91433002 1.08036998 -1.90936004 0 P 0 ;0
L 1.08036998 -1.90936004 1.06153002 -1.90273996 0 P 0 ;0
L 1.06153002 -1.90273996 1.06146004 -1.90273002 0 P 0 ;0
L 1.06146004 -1.90273002 1.04233002 -1.89766004 0 P 0 ;0
L 1.04233002 -1.89766004 1.02443002 -1.89405 0 P 0 ;0
L 1.02443002 -1.89405 1.0104 -1.89213996 0 P 0 ;0
L 1.0104 -1.89213996 0.99475 -1.89128996 0 P 0 ;0
L 0.99475 -1.89128996 0.97045 -1.89108002 0 P 0 ;0
L 0.97045 -1.89108002 0.94365 -1.8915 0 P 0 ;0
L 0.94365 -1.8915 0.94361998 -1.8915 0 P 0 ;0
L 0.94361998 -1.8915 0.93471998 -1.89195 0 P 0 ;0
L 0.93471998 -1.89195 0.92578996 -1.89278996 0 P 0 ;0
L 0.92578996 -1.89278996 0.9072 -1.89571004 0 P 0 ;0
L 0.9072 -1.89571004 0.87656998 -1.90203996 0 P 0 ;0
L 0.87656998 -1.90203996 0.87626998 -1.9021 0 P 0 ;0
L 0.87626998 -1.9021 0.87601998 -1.90211998 0 P 0 ;0
L 0.87601998 -1.90211998 0.87588996 -1.90213002 0 P 0 ;0
L 0.87588996 -1.90213002 0.87583002 -1.90198996 0 P 0 ;0
L 0.87583002 -1.90198996 0.87573002 -1.90175 0 P 0 ;0
L 0.87573002 -1.90175 0.87566004 -1.90146998 0 P 0 ;0
L 0.87566004 -1.90146998 0.87471004 -1.89701004 0 P 0 ;0
L 0.87471004 -1.89701004 0.8747 -1.89698996 0 P 0 ;0
L 0.8747 -1.89698996 0.87373002 -1.89288996 0 P 0 ;0
L 0.87373002 -1.89288996 0.87243002 -1.88881998 0 P 0 ;0
L 0.87243002 -1.88881998 0.8724 -1.88876004 0 P 0 ;0
L 0.8724 -1.88876004 0.8708 -1.88473996 0 P 0 ;0
L 0.8708 -1.88473996 0.8689 -1.88078002 0 P 0 ;0
L 0.8689 -1.88078002 0.86671998 -1.87693996 0 P 0 ;0
L 0.86671998 -1.87693996 0.86428996 -1.87326004 0 P 0 ;0
L 0.86428996 -1.87326004 0.86166998 -1.86985 0 P 0 ;0
L 0.86166998 -1.86985 0.85883996 -1.86668002 0 P 0 ;0
L 0.85883996 -1.86668002 0.85883002 -1.86666004 0 P 0 ;0
L 0.85883002 -1.86666004 0.85531998 -1.86291004 0 P 0 ;0
L 0.85531998 -1.86291004 0.85486004 -1.86238002 0 P 0 ;0
L 0.85486004 -1.86238002 0.85466004 -1.86211998 0 P 0 ;0
L 0.85466004 -1.86211998 0.8557 -1.86186004 0 P 0 ;0
L 0.8557 -1.86186004 0.85811998 -1.86145 0 P 0 ;0
L 0.85811998 -1.86145 0.87443996 -1.85941004 0 P 0 ;0
L 0.87443996 -1.85941004 0.89088996 -1.85756998 0 P 0 ;0
L 0.89088996 -1.85756998 0.90286004 -1.85656998 0 P 0 ;0
L 0.90286004 -1.85656998 0.93061004 -1.85566004 0 P 0 ;0
L 0.93061004 -1.85566004 0.95768002 -1.85648996 0 P 0 ;0
L 0.95768002 -1.85648996 0.98416004 -1.8591 0 P 0 ;0
L 0.98416004 -1.8591 1.01018996 -1.86346004 0 P 0 ;0
L 1.01018996 -1.86346004 1.02886004 -1.86785 0 P 0 ;0
L 1.02886004 -1.86785 1.04711998 -1.87331998 0 P 0 ;0
L 1.04711998 -1.87331998 1.06501004 -1.87986004 0 P 0 ;0
L 1.06501004 -1.87986004 1.08125 -1.88706998 0 P 0 ;0
L 1.08125 -1.88706998 1.09681004 -1.89541998 0 P 0 ;0
L 1.09681004 -1.89541998 1.1117 -1.9049 0 P 0 ;0
L 1.1117 -1.9049 1.1245 -1.91456998 0 P 0 ;0
L 1.1245 -1.91456998 1.13638996 -1.92521004 0 P 0 ;0
L 1.13638996 -1.92521004 1.14733996 -1.93678996 0 P 0 ;0
L 1.14733996 -1.93678996 1.15408002 -1.94525 0 P 0 ;0
L 1.15408002 -1.94525 1.16001004 -1.95416998 0 P 0 ;0
L 1.16001004 -1.95416998 1.16516004 -1.96355 0 P 0 ;0
L 1.16516004 -1.96355 1.1695 -1.97336998 0 P 0 ;0
L 1.1695 -1.97336998 1.17066004 -1.97631004 0 P 0 ;0
L 1.17066004 -1.97631004 1.16015 -1.97631004 0 P 0 ;0
L 0.87563002 -1.90131004 0.8801 -1.90131004 0 P 0 ;0
L 0.87541004 -1.90031004 0.88493996 -1.90031004 0 P 0 ;0
L 0.8752 -1.89931004 0.88976998 -1.89931004 0 P 0 ;0
L 0.87498996 -1.89831004 0.8946 -1.89831004 0 P 0 ;0
L 0.89423002 -2.08316004 0.94355 -2.08316004 0 P 0 ;0
L 0.89428996 -2.08216004 0.9436 -2.08216004 0 P 0 ;0
L 0.89435 -2.08116004 0.94365 -2.08116004 0 P 0 ;0
L 0.89441004 -2.08016004 0.9437 -2.08016004 0 P 0 ;0
L 0.89446004 -2.07916004 0.94375 -2.07916004 0 P 0 ;0
L 0.89451998 -2.07816004 0.94378996 -2.07816004 0 P 0 ;0
L 0.89458002 -2.07716004 0.94383996 -2.07716004 0 P 0 ;0
L 0.89463996 -2.07616004 0.94388996 -2.07616004 0 P 0 ;0
L 0.8947 -2.07516004 0.94393996 -2.07516004 0 P 0 ;0
L 0.89475 -2.07416004 0.94398002 -2.07416004 0 P 0 ;0
L 0.89481004 -2.07316004 0.94403002 -2.07316004 0 P 0 ;0
L 0.89486998 -2.07216004 0.94408002 -2.07216004 0 P 0 ;0
L 0.89493002 -2.07116004 0.94415 -2.07116004 0 P 0 ;0
L 0.89498996 -2.07016004 0.94426004 -2.07016004 0 P 0 ;0
L 0.89505 -2.06916004 0.94436998 -2.06916004 0 P 0 ;0
L 0.8951 -2.06816004 0.94448002 -2.06816004 0 P 0 ;0
L 0.89516004 -2.06716004 0.94458996 -2.06716004 0 P 0 ;0
L 0.89521998 -2.06616004 0.9447 -2.06616004 0 P 0 ;0
L 0.89526998 -2.06516004 0.94481004 -2.06516004 0 P 0 ;0
L 0.89531004 -2.06416004 0.94491998 -2.06416004 0 P 0 ;0
L 0.89535 -2.06316004 0.94503002 -2.06316004 0 P 0 ;0
L 0.8954 -2.06216004 0.94513996 -2.06216004 0 P 0 ;0
L 0.89543996 -2.06116004 0.94531998 -2.06116004 0 P 0 ;0
L 0.89548996 -2.06016004 0.94551004 -2.06016004 0 P 0 ;0
L 0.89553002 -2.05916004 0.9457 -2.05916004 0 P 0 ;0
L 0.89558002 -2.05816004 0.94588996 -2.05816004 0 P 0 ;0
L 0.89561998 -2.05716004 0.94608002 -2.05716004 0 P 0 ;0
L 0.89566998 -2.05616004 0.94626998 -2.05616004 0 P 0 ;0
L 0.89571004 -2.05516004 0.94646998 -2.05516004 0 P 0 ;0
L 0.89575 -2.05416004 0.94666004 -2.05416004 0 P 0 ;0
L 0.8958 -2.05316004 0.94685 -2.05316004 0 P 0 ;0
L 0.89583996 -2.05216004 0.94708002 -2.05216004 0 P 0 ;0
L 0.89588996 -2.05116004 0.94735 -2.05116004 0 P 0 ;0
L 0.89593996 -2.05016004 0.94761998 -2.05016004 0 P 0 ;0
L 0.89598002 -2.04916004 0.9479 -2.04916004 0 P 0 ;0
L 0.89601998 -2.04816004 0.94825 -2.04816004 0 P 0 ;0
L 0.89606998 -2.04716004 0.94858996 -2.04716004 0 P 0 ;0
L 0.89611004 -2.04616004 0.94893002 -2.04616004 0 P 0 ;0
L 0.89616004 -2.04516004 0.94935 -2.04516004 0 P 0 ;0
L 0.8962 -2.04416004 0.94976998 -2.04416004 0 P 0 ;0
L 0.89625 -2.04316004 0.9502 -2.04316004 0 P 0 ;0
L 0.89628002 -2.04216004 0.95068996 -2.04216004 0 P 0 ;0
L 0.89631004 -2.04116004 0.95118996 -2.04116004 0 P 0 ;0
L 0.89633996 -2.04016004 0.95168996 -2.04016004 0 P 0 ;0
L 0.89638002 -2.03916004 0.95228002 -2.03916004 0 P 0 ;0
L 0.89641004 -2.03816004 0.95291004 -2.03816004 0 P 0 ;0
L 0.89643996 -2.03716004 0.95363002 -2.03716004 0 P 0 ;0
L 0.89646998 -2.03616004 0.95445 -2.03616004 0 P 0 ;0
L 0.89651004 -2.03516004 0.95535 -2.03516004 0 P 0 ;0
L 0.89653996 -2.03416004 0.95636998 -2.03416004 0 P 0 ;0
L 0.89656998 -2.03316004 0.95756998 -2.03316004 0 P 0 ;0
L 0.8966 -2.03216004 0.95893996 -2.03216004 0 P 0 ;0
L 0.89663996 -2.03116004 0.96055 -2.03116004 0 P 0 ;0
L 0.89666998 -2.03016004 0.96278002 -2.03016004 0 P 0 ;0
L 0.8967 -2.02916004 0.96676004 -2.02916004 0 P 0 ;0
L 0.89673996 -2.02816004 1.03838996 -2.02816004 0 P 0 ;0
L 0.89676998 -2.02716004 1.03838002 -2.02716004 0 P 0 ;0
L 0.8968 -2.02616004 1.03833996 -2.02616004 0 P 0 ;0
L 0.89683996 -2.02516004 1.03828996 -2.02516004 0 P 0 ;0
L 0.89686998 -2.02416004 1.03823002 -2.02416004 0 P 0 ;0
L 0.8969 -2.02316004 1.03816004 -2.02316004 0 P 0 ;0
L 0.89693996 -2.02216004 1.0381 -2.02216004 0 P 0 ;0
L 0.89696998 -2.02116004 1.03803996 -2.02116004 0 P 0 ;0
L 0.897 -2.02016004 1.0379 -2.02016004 0 P 0 ;0
L 0.89703002 -2.01916004 1.03773996 -2.01916004 0 P 0 ;0
L 0.89706004 -2.01816004 1.03751998 -2.01816004 0 P 0 ;0
L 0.89708996 -2.01716004 1.03728002 -2.01716004 0 P 0 ;0
L 0.89711998 -2.01616004 1.03698996 -2.01616004 0 P 0 ;0
L 0.89713996 -2.01516004 1.03668002 -2.01516004 0 P 0 ;0
L 0.89716998 -2.01416004 1.03631004 -2.01416004 0 P 0 ;0
L 0.8972 -2.01316004 1.03591998 -2.01316004 0 P 0 ;0
L 0.89721998 -2.01216004 1.03548996 -2.01216004 0 P 0 ;0
L 0.89725 -2.01116004 1.03505 -2.01116004 0 P 0 ;0
L 0.89726998 -2.01016004 1.03458002 -2.01016004 0 P 0 ;0
L 0.8973 -2.00916004 1.03405 -2.00916004 0 P 0 ;0
L 0.89733002 -2.00816004 1.03351998 -2.00816004 0 P 0 ;0
L 0.89736004 -2.00716004 0.94676004 -2.00716004 0 P 0 ;0
L 0.89738002 -2.00616004 0.9461 -2.00616004 0 P 0 ;0
L 0.89741004 -2.00516004 0.94563996 -2.00516004 0 P 0 ;0
L 0.89743996 -2.00416004 0.94563996 -2.00416004 0 P 0 ;0
L 0.89746004 -2.00316004 0.94563996 -2.00316004 0 P 0 ;0
L 0.89748996 -2.00216004 0.94563996 -2.00216004 0 P 0 ;0
L 0.89751004 -2.00116004 0.94563996 -2.00116004 0 P 0 ;0
L 0.89753996 -2.00016004 0.94563996 -2.00016004 0 P 0 ;0
L 0.89756998 -1.99916004 0.94563996 -1.99916004 0 P 0 ;0
L 0.8976 -1.99816004 0.94563996 -1.99816004 0 P 0 ;0
L 0.89761998 -1.99716004 0.94563996 -1.99716004 0 P 0 ;0
L 0.89765 -1.99616004 0.94563996 -1.99616004 0 P 0 ;0
L 0.89768002 -1.99516004 0.94563996 -1.99516004 0 P 0 ;0
L 0.97546998 -1.98933996 0.97236998 -1.99006004 0 P 0 ;0
L 0.97236998 -1.99006004 0.96931998 -1.99103002 0 P 0 ;0
L 0.96931998 -1.99103002 0.96603002 -1.99233002 0 P 0 ;0
L 0.96603002 -1.99233002 0.96281004 -1.99383002 0 P 0 ;0
L 0.96281004 -1.99383002 0.95976004 -1.99546998 0 P 0 ;0
L 0.95976004 -1.99546998 0.95681004 -1.99728996 0 P 0 ;0
L 0.95681004 -1.99728996 0.95521004 -1.99841004 0 P 0 ;0
L 0.95521004 -1.99841004 0.95368996 -1.99963002 0 P 0 ;0
L 0.95368996 -1.99963002 0.95223996 -2.00095 0 P 0 ;0
L 0.95223996 -2.00095 0.94763996 -2.00546998 0 P 0 ;0
L 0.94763996 -2.00546998 0.94763996 -1.99243996 0 P 0 ;0
L 0.94763996 -1.99243996 0.89575 -1.99243996 0 P 0 ;0
L 0.89575 -1.99243996 0.89505 -2.01878002 0 P 0 ;0
L 0.89505 -2.01878002 0.89423996 -2.04316004 0 P 0 ;0
L 0.89423996 -2.04316004 0.89321998 -2.0661 0 P 0 ;0
L 0.89321998 -2.0661 0.89198996 -2.08728996 0 P 0 ;0
L 0.89198996 -2.08728996 0.89055 -2.1063 0 P 0 ;0
L 0.89055 -2.1063 0.88993996 -2.11358002 0 P 0 ;0
L 0.88993996 -2.11358002 0.88943002 -2.11988002 0 P 0 ;0
L 0.88943002 -2.11988002 0.88898996 -2.12533996 0 P 0 ;0
L 0.88898996 -2.12533996 0.88896004 -2.12613002 0 P 0 ;0
L 0.88896004 -2.12613002 0.88896998 -2.12621004 0 P 0 ;0
L 0.88896998 -2.12621004 0.88898002 -2.12625 0 P 0 ;0
L 0.88898002 -2.12625 0.88898996 -2.12628002 0 P 0 ;0
L 0.88898996 -2.12628002 0.88901998 -2.12636004 0 P 0 ;0
L 0.88901998 -2.12636004 0.88903996 -2.12638996 0 P 0 ;0
L 0.88903996 -2.12638996 0.88906998 -2.12641998 0 P 0 ;0
L 0.88906998 -2.12641998 0.88908996 -2.12645 0 P 0 ;0
L 0.88908996 -2.12645 0.88911998 -2.12646998 0 P 0 ;0
L 0.88911998 -2.12646998 0.88915 -2.1265 0 P 0 ;0
L 0.88915 -2.1265 0.88921004 -2.12653996 0 P 0 ;0
L 0.88921004 -2.12653996 0.88925 -2.12655 0 P 0 ;0
L 0.88925 -2.12655 0.88928002 -2.12656004 0 P 0 ;0
L 0.88928002 -2.12656004 0.88931998 -2.12658002 0 P 0 ;0
L 0.88931998 -2.12658002 0.8894 -2.12658002 0 P 0 ;0
L 0.8894 -2.12658002 0.89648002 -2.12686998 0 P 0 ;0
L 0.89648002 -2.12686998 0.90518996 -2.1271 0 P 0 ;0
L 0.90518996 -2.1271 0.9165 -2.12716004 0 P 0 ;0
L 0.9165 -2.12716004 0.94403996 -2.12716004 0 P 0 ;0
L 0.94403996 -2.12716004 0.94468996 -2.10135 0 P 0 ;0
L 0.94468996 -2.10135 0.9461 -2.07171998 0 P 0 ;0
L 0.9461 -2.07171998 0.94713002 -2.06233002 0 P 0 ;0
L 0.94713002 -2.06233002 0.9489 -2.05308002 0 P 0 ;0
L 0.9489 -2.05308002 0.94975 -2.04995 0 P 0 ;0
L 0.94975 -2.04995 0.9508 -2.04688996 0 P 0 ;0
L 0.9508 -2.04688996 0.95205 -2.0439 0 P 0 ;0
L 0.95205 -2.0439 0.95351004 -2.041 0 P 0 ;0
L 0.95351004 -2.041 0.9544 -2.03951004 0 P 0 ;0
L 0.9544 -2.03951004 0.95541998 -2.03811004 0 P 0 ;0
L 0.95541998 -2.03811004 0.95655 -2.03678996 0 P 0 ;0
L 0.95655 -2.03678996 0.95778996 -2.03556998 0 P 0 ;0
L 0.95778996 -2.03556998 0.95911998 -2.03446998 0 P 0 ;0
L 0.95911998 -2.03446998 0.96056998 -2.03346998 0 P 0 ;0
L 0.96056998 -2.03346998 0.96151004 -2.03291004 0 P 0 ;0
L 0.96151004 -2.03291004 0.96248996 -2.03243002 0 P 0 ;0
L 0.96248996 -2.03243002 0.96351004 -2.03201998 0 P 0 ;0
L 0.96351004 -2.03201998 0.96455 -2.03168996 0 P 0 ;0
L 0.96455 -2.03168996 0.96613002 -2.0313 0 P 0 ;0
L 0.96613002 -2.0313 0.96773002 -2.03101998 0 P 0 ;0
L 0.96773002 -2.03101998 0.96935 -2.03086004 0 P 0 ;0
L 0.96935 -2.03086004 0.97095 -2.03081004 0 P 0 ;0
L 0.97095 -2.03081004 0.97255 -2.03086998 0 P 0 ;0
L 0.97255 -2.03086998 0.97413002 -2.03105 0 P 0 ;0
L 0.97413002 -2.03105 0.97513002 -2.03123996 0 P 0 ;0
L 0.97513002 -2.03123996 0.9761 -2.03151004 0 P 0 ;0
L 0.9761 -2.03151004 0.97706004 -2.03186004 0 P 0 ;0
L 0.97706004 -2.03186004 0.97796998 -2.0323 0 P 0 ;0
L 0.97796998 -2.0323 0.97885 -2.0328 0 P 0 ;0
L 0.97885 -2.0328 0.97968002 -2.03336998 0 P 0 ;0
L 0.97968002 -2.03336998 0.98046998 -2.03398996 0 P 0 ;0
L 0.98046998 -2.03398996 0.98121998 -2.03468002 0 P 0 ;0
L 0.98121998 -2.03468002 0.98191004 -2.03541998 0 P 0 ;0
L 0.98191004 -2.03541998 0.98253996 -2.0362 0 P 0 ;0
L 0.98253996 -2.0362 0.9831 -2.03703002 0 P 0 ;0
L 0.9831 -2.03703002 0.9836 -2.03788996 0 P 0 ;0
L 0.9836 -2.03788996 0.98403996 -2.0388 0 P 0 ;0
L 0.98403996 -2.0388 0.9844 -2.03973996 0 P 0 ;0
L 0.9844 -2.03973996 0.98505 -2.04188996 0 P 0 ;0
L 0.98505 -2.04188996 0.98553002 -2.04408002 0 P 0 ;0
L 0.98553002 -2.04408002 0.98583002 -2.0463 0 P 0 ;0
L 0.98583002 -2.0463 0.98653002 -2.05705 0 P 0 ;0
L 0.98653002 -2.05705 0.9866 -2.06961004 0 P 0 ;0
L 0.9866 -2.06961004 0.98596004 -2.08908002 0 P 0 ;0
L 0.98596004 -2.08908002 0.98498002 -2.10858002 0 P 0 ;0
L 0.98498002 -2.10858002 0.98388002 -2.12146998 0 P 0 ;0
L 0.98388002 -2.12146998 0.98323002 -2.12716004 0 P 0 ;0
L 0.98323002 -2.12716004 1.03741004 -2.12716004 0 P 0 ;0
L 1.03741004 -2.12716004 1.03896004 -2.09103002 0 P 0 ;0
L 1.03896004 -2.09103002 1.03956004 -2.0759 0 P 0 ;0
L 1.03956004 -2.0759 1.04005 -2.06025 0 P 0 ;0
L 1.04005 -2.06025 1.04038996 -2.04626004 0 P 0 ;0
L 1.04038996 -2.04626004 1.04048002 -2.03698996 0 P 0 ;0
L 1.04048002 -2.03698996 1.04036998 -2.02651998 0 P 0 ;0
L 1.04036998 -2.02651998 1.04003996 -2.02096998 0 P 0 ;0
L 1.04003996 -2.02096998 1.03975 -2.01895 0 P 0 ;0
L 1.03975 -2.01895 1.0393 -2.01693996 0 P 0 ;0
L 1.0393 -2.01693996 1.03868996 -2.01483996 0 P 0 ;0
L 1.03868996 -2.01483996 1.03793996 -2.01278002 0 P 0 ;0
L 1.03793996 -2.01278002 1.03658996 -2.00968002 0 P 0 ;0
L 1.03658996 -2.00968002 1.03501004 -2.00668996 0 P 0 ;0
L 1.03501004 -2.00668996 1.0332 -2.0038 0 P 0 ;0
L 1.0332 -2.0038 1.03186998 -2.002 0 P 0 ;0
L 1.03186998 -2.002 1.0304 -2.0003 0 P 0 ;0
L 1.0304 -2.0003 1.0288 -1.99873002 0 P 0 ;0
L 1.0288 -1.99873002 1.02708002 -1.99728996 0 P 0 ;0
L 1.02708002 -1.99728996 1.02518002 -1.99593002 0 P 0 ;0
L 1.02518002 -1.99593002 1.02318002 -1.99471998 0 P 0 ;0
L 1.02318002 -1.99471998 1.0211 -1.99365 0 P 0 ;0
L 1.0211 -1.99365 1.01893002 -1.99273996 0 P 0 ;0
L 1.01893002 -1.99273996 1.01358996 -1.99098996 0 P 0 ;0
L 1.01358996 -1.99098996 1.0081 -1.98971004 0 P 0 ;0
L 1.0081 -1.98971004 1.00428996 -1.98908996 0 P 0 ;0
L 1.00428996 -1.98908996 1.00043996 -1.98868002 0 P 0 ;0
L 1.00043996 -1.98868002 0.99138002 -1.98826004 0 P 0 ;0
L 0.99138002 -1.98826004 0.98251998 -1.98846998 0 P 0 ;0
L 0.98251998 -1.98846998 0.97898996 -1.98878996 0 P 0 ;0
L 0.97898996 -1.98878996 0.97546998 -1.98933996 0 P 0 ;0
L 0.91651004 -2.12516004 0.94208996 -2.12516004 0 P 0 ;0
L 0.8911 -2.12416004 0.94211004 -2.12416004 0 P 0 ;0
L 0.89118002 -2.12316004 0.94213996 -2.12316004 0 P 0 ;0
L 0.89125 -2.12216004 0.94216004 -2.12216004 0 P 0 ;0
L 0.89133002 -2.12116004 0.94218996 -2.12116004 0 P 0 ;0
L 0.89141004 -2.12016004 0.94221004 -2.12016004 0 P 0 ;0
L 0.89148996 -2.11916004 0.94223996 -2.11916004 0 P 0 ;0
L 0.89156998 -2.11816004 0.94226998 -2.11816004 0 P 0 ;0
L 0.89166004 -2.11716004 0.94228996 -2.11716004 0 P 0 ;0
L 0.89173996 -2.11616004 0.94231004 -2.11616004 0 P 0 ;0
L 0.89181998 -2.11516004 0.94233996 -2.11516004 0 P 0 ;0
L 0.8919 -2.11416004 0.94236004 -2.11416004 0 P 0 ;0
L 0.89198002 -2.11316004 0.94238996 -2.11316004 0 P 0 ;0
L 0.89206998 -2.11216004 0.94241998 -2.11216004 0 P 0 ;0
L 0.89215 -2.11116004 0.94243996 -2.11116004 0 P 0 ;0
L 0.89223002 -2.11016004 0.94246998 -2.11016004 0 P 0 ;0
L 0.89231998 -2.10916004 0.94248996 -2.10916004 0 P 0 ;0
L 0.8924 -2.10816004 0.94251998 -2.10816004 0 P 0 ;0
L 0.89248002 -2.10716004 0.94255 -2.10716004 0 P 0 ;0
L 0.89256998 -2.10616004 0.94256998 -2.10616004 0 P 0 ;0
L 0.89263996 -2.10516004 0.94258996 -2.10516004 0 P 0 ;0
L 0.89271004 -2.10416004 0.94261998 -2.10416004 0 P 0 ;0
L 0.89278996 -2.10316004 0.94263996 -2.10316004 0 P 0 ;0
L 0.89286998 -2.10216004 0.94266998 -2.10216004 0 P 0 ;0
L 0.89293996 -2.10116004 0.9427 -2.10116004 0 P 0 ;0
L 0.89301998 -2.10016004 0.94275 -2.10016004 0 P 0 ;0
L 0.89308996 -2.09916004 0.94278996 -2.09916004 0 P 0 ;0
L 0.89316998 -2.09816004 0.94283996 -2.09816004 0 P 0 ;0
L 0.89325 -2.09716004 0.94288996 -2.09716004 0 P 0 ;0
L 0.89331998 -2.09616004 0.94293996 -2.09616004 0 P 0 ;0
L 0.8934 -2.09516004 0.94298002 -2.09516004 0 P 0 ;0
L 0.89346998 -2.09416004 0.94303002 -2.09416004 0 P 0 ;0
L 0.89355 -2.09316004 0.94308002 -2.09316004 0 P 0 ;0
L 0.89361998 -2.09216004 0.94313002 -2.09216004 0 P 0 ;0
L 0.8937 -2.09116004 0.94318002 -2.09116004 0 P 0 ;0
L 0.89378002 -2.09016004 0.94321998 -2.09016004 0 P 0 ;0
L 0.89385 -2.08916004 0.94326998 -2.08916004 0 P 0 ;0
L 0.89393002 -2.08816004 0.94331998 -2.08816004 0 P 0 ;0
L 0.894 -2.08716004 0.94336004 -2.08716004 0 P 0 ;0
L 0.89406004 -2.08616004 0.94341004 -2.08616004 0 P 0 ;0
L 0.89411998 -2.08516004 0.94346004 -2.08516004 0 P 0 ;0
L 0.89418002 -2.08416004 0.94351004 -2.08416004 0 P 0 ;0
L 0.91651004 -2.12516004 0.90521998 -2.1251 0 P 0 ;0
L 0.90521998 -2.1251 0.89655 -2.12486998 0 P 0 ;0
L 0.89655 -2.12486998 0.89106004 -2.12465 0 P 0 ;0
L 0.89106004 -2.12465 0.89141998 -2.12003996 0 P 0 ;0
L 0.89141998 -2.12003996 0.89193996 -2.11373996 0 P 0 ;0
L 0.89193996 -2.11373996 0.89253996 -2.10645 0 P 0 ;0
L 0.89253996 -2.10645 0.89398002 -2.08741998 0 P 0 ;0
L 0.89398002 -2.08741998 0.89521998 -2.06621998 0 P 0 ;0
L 0.89521998 -2.06621998 0.89521998 -2.06618996 0 P 0 ;0
L 0.89521998 -2.06618996 0.89623996 -2.04323002 0 P 0 ;0
L 0.89623996 -2.04323002 0.89703996 -2.01883002 0 P 0 ;0
L 0.89703996 -2.01883002 0.8977 -1.99443996 0 P 0 ;0
L 0.8977 -1.99443996 0.94563996 -1.99443996 0 P 0 ;0
L 0.94563996 -1.99443996 0.94563996 -2.00546998 0 P 0 ;0
L 0.94563996 -2.00546998 0.94686004 -2.00731004 0 P 0 ;0
L 0.94686004 -2.00731004 0.94903002 -2.00688996 0 P 0 ;0
L 0.94903002 -2.00688996 0.95361998 -2.00241004 0 P 0 ;0
L 0.95361998 -2.00241004 0.95498996 -2.00115 0 P 0 ;0
L 0.95498996 -2.00115 0.95641998 -2.00001004 0 P 0 ;0
L 0.95641998 -2.00001004 0.9579 -1.99896004 0 P 0 ;0
L 0.9579 -1.99896004 0.96076004 -1.9972 0 P 0 ;0
L 0.96076004 -1.9972 0.9637 -1.99561998 0 P 0 ;0
L 0.9637 -1.99561998 0.96683002 -1.99416998 0 P 0 ;0
L 0.96683002 -1.99416998 0.96998996 -1.99291998 0 P 0 ;0
L 0.96998996 -1.99291998 0.9729 -1.99198996 0 P 0 ;0
L 0.9729 -1.99198996 0.97586004 -1.9913 0 P 0 ;0
L 0.97586004 -1.9913 0.97923002 -1.99076998 0 P 0 ;0
L 0.97923002 -1.99076998 0.98263002 -1.99046998 0 P 0 ;0
L 0.98263002 -1.99046998 0.99136004 -1.99026004 0 P 0 ;0
L 0.99136004 -1.99026004 1.00028996 -1.99066998 0 P 0 ;0
L 1.00028996 -1.99066998 1.00403002 -1.99108002 0 P 0 ;0
L 1.00403002 -1.99108002 1.00771004 -1.99166998 0 P 0 ;0
L 1.00771004 -1.99166998 1.01305 -1.99291998 0 P 0 ;0
L 1.01305 -1.99291998 1.01823002 -1.99461998 0 P 0 ;0
L 1.01823002 -1.99461998 1.02026004 -1.99546998 0 P 0 ;0
L 1.02026004 -1.99546998 1.02221004 -1.99646998 0 P 0 ;0
L 1.02221004 -1.99646998 1.02408002 -1.9976 0 P 0 ;0
L 1.02408002 -1.9976 1.02585 -1.99886998 0 P 0 ;0
L 1.02585 -1.99886998 1.02746004 -2.00021004 0 P 0 ;0
L 1.02746004 -2.00021004 1.02893996 -2.00166998 0 P 0 ;0
L 1.02893996 -2.00166998 1.03031004 -2.00325 0 P 0 ;0
L 1.03031004 -2.00325 1.03155 -2.00493002 0 P 0 ;0
L 1.03155 -2.00493002 1.03326998 -2.00768002 0 P 0 ;0
L 1.03326998 -2.00768002 1.03478002 -2.01055 0 P 0 ;0
L 1.03478002 -2.01055 1.03608002 -2.01351998 0 P 0 ;0
L 1.03608002 -2.01351998 1.03678996 -2.01546998 0 P 0 ;0
L 1.03678996 -2.01546998 1.03736004 -2.01743002 0 P 0 ;0
L 1.03736004 -2.01743002 1.03778002 -2.0193 0 P 0 ;0
L 1.03778002 -2.0193 1.03805 -2.02116998 0 P 0 ;0
L 1.03805 -2.02116998 1.03836998 -2.02658996 0 P 0 ;0
L 1.03836998 -2.02658996 1.03848002 -2.03698996 0 P 0 ;0
L 1.03848002 -2.03698996 1.03838996 -2.04623002 0 P 0 ;0
L 1.03838996 -2.04623002 1.03805 -2.06018996 0 P 0 ;0
L 1.03805 -2.06018996 1.03756004 -2.07583002 0 P 0 ;0
L 1.03756004 -2.07583002 1.03696998 -2.09095 0 P 0 ;0
L 1.03696998 -2.09095 1.03548996 -2.12516004 0 P 0 ;0
L 1.03548996 -2.12516004 0.98546998 -2.12516004 0 P 0 ;0
L 0.98546998 -2.12516004 0.98586998 -2.12166004 0 P 0 ;0
L 0.98586998 -2.12166004 0.98696998 -2.10871998 0 P 0 ;0
L 0.98696998 -2.10871998 0.98796004 -2.08916004 0 P 0 ;0
L 0.98796004 -2.08916004 0.9886 -2.06963002 0 P 0 ;0
L 0.9886 -2.06963002 0.98853002 -2.05698002 0 P 0 ;0
L 0.98853002 -2.05698002 0.98781998 -2.0461 0 P 0 ;0
L 0.98781998 -2.0461 0.9875 -2.04373002 0 P 0 ;0
L 0.9875 -2.04373002 0.98748002 -2.04365 0 P 0 ;0
L 0.98748002 -2.04365 0.98698996 -2.04138996 0 P 0 ;0
L 0.98698996 -2.04138996 0.9863 -2.03908002 0 P 0 ;0
L 0.9863 -2.03908002 0.98588002 -2.038 0 P 0 ;0
L 0.98588002 -2.038 0.98538002 -2.03696004 0 P 0 ;0
L 0.98538002 -2.03696004 0.9848 -2.03596004 0 P 0 ;0
L 0.9848 -2.03596004 0.98413996 -2.03501004 0 P 0 ;0
L 0.98413996 -2.03501004 0.98341998 -2.03411004 0 P 0 ;0
L 0.98341998 -2.03411004 0.98336998 -2.03405 0 P 0 ;0
L 0.98336998 -2.03405 0.98263002 -2.03326004 0 P 0 ;0
L 0.98263002 -2.03326004 0.98176998 -2.03246998 0 P 0 ;0
L 0.98176998 -2.03246998 0.98086998 -2.03175 0 P 0 ;0
L 0.98086998 -2.03175 0.97991004 -2.0311 0 P 0 ;0
L 0.97991004 -2.0311 0.9789 -2.03051998 0 P 0 ;0
L 0.9789 -2.03051998 0.97783002 -2.03001998 0 P 0 ;0
L 0.97783002 -2.03001998 0.97673002 -2.02961004 0 P 0 ;0
L 0.97673002 -2.02961004 0.97663996 -2.02958002 0 P 0 ;0
L 0.97663996 -2.02958002 0.97558996 -2.02928996 0 P 0 ;0
L 0.97558996 -2.02928996 0.97443002 -2.02906998 0 P 0 ;0
L 0.97443002 -2.02906998 0.9727 -2.02888002 0 P 0 ;0
L 0.9727 -2.02888002 0.97261998 -2.02886998 0 P 0 ;0
L 0.97261998 -2.02886998 0.97096004 -2.02881004 0 P 0 ;0
L 0.97096004 -2.02881004 0.96921004 -2.02886004 0 P 0 ;0
L 0.96921004 -2.02886004 0.96745 -2.02903996 0 P 0 ;0
L 0.96745 -2.02903996 0.96571004 -2.02933996 0 P 0 ;0
L 0.96571004 -2.02933996 0.964 -2.02976004 0 P 0 ;0
L 0.964 -2.02976004 0.96283002 -2.03013996 0 P 0 ;0
L 0.96283002 -2.03013996 0.96168002 -2.0306 0 P 0 ;0
L 0.96168002 -2.0306 0.96056998 -2.03115 0 P 0 ;0
L 0.96056998 -2.03115 0.95948996 -2.03178002 0 P 0 ;0
L 0.95948996 -2.03178002 0.95791004 -2.03286998 0 P 0 ;0
L 0.95791004 -2.03286998 0.95645 -2.03408996 0 P 0 ;0
L 0.95645 -2.03408996 0.95508996 -2.03541998 0 P 0 ;0
L 0.95508996 -2.03541998 0.95383996 -2.03686998 0 P 0 ;0
L 0.95383996 -2.03686998 0.9538 -2.03693002 0 P 0 ;0
L 0.9538 -2.03693002 0.95273002 -2.03841004 0 P 0 ;0
L 0.95273002 -2.03841004 0.95175 -2.04003996 0 P 0 ;0
L 0.95175 -2.04003996 0.95023002 -2.04306004 0 P 0 ;0
L 0.95023002 -2.04306004 0.94896004 -2.04611004 0 P 0 ;0
L 0.94896004 -2.04611004 0.94893002 -2.04616998 0 P 0 ;0
L 0.94893002 -2.04616998 0.94783002 -2.04936004 0 P 0 ;0
L 0.94783002 -2.04936004 0.94695 -2.05263002 0 P 0 ;0
L 0.94695 -2.05263002 0.94515 -2.06203002 0 P 0 ;0
L 0.94515 -2.06203002 0.9441 -2.07156004 0 P 0 ;0
L 0.9441 -2.07156004 0.9427 -2.10128002 0 P 0 ;0
L 0.9427 -2.10128002 0.94208996 -2.12516004 0 P 0 ;0
L 0.94208996 -2.12516004 0.91651004 -2.12516004 0 P 0 ;0
L 0.93143002 -2.21261998 1.00578996 -2.21261998 0 P 0 ;0
L 0.94051004 -2.21161998 1.00803002 -2.21161998 0 P 0 ;0
L 0.94941998 -2.21061998 1.01026004 -2.21061998 0 P 0 ;0
L 0.9555 -2.20961998 1.0125 -2.20961998 0 P 0 ;0
L 0.96158002 -2.20861998 1.01473996 -2.20861998 0 P 0 ;0
L 0.96766004 -2.20761998 1.01696998 -2.20761998 0 P 0 ;0
L 0.97373002 -2.20661998 1.01921004 -2.20661998 0 P 0 ;0
L 0.97981004 -2.20561998 1.02145 -2.20561998 0 P 0 ;0
L 0.98498996 -2.20461998 1.02368996 -2.20461998 0 P 0 ;0
L 0.98973996 -2.20361998 1.02591998 -2.20361998 0 P 0 ;0
L 0.99448996 -2.20261998 1.02816004 -2.20261998 0 P 0 ;0
L 0.99923996 -2.20161998 1.0304 -2.20161998 0 P 0 ;0
L 1.00398996 -2.20061998 1.03243996 -2.20061998 0 P 0 ;0
L 1.00875 -2.19961998 1.0344 -2.19961998 0 P 0 ;0
L 1.01348996 -2.19861998 1.03636998 -2.19861998 0 P 0 ;0
L 1.0178 -2.19761998 1.03833996 -2.19761998 0 P 0 ;0
L 1.02168996 -2.19661998 1.04031004 -2.19661998 0 P 0 ;0
L 1.02558002 -2.19561998 1.04228002 -2.19561998 0 P 0 ;0
L 1.02946998 -2.19461998 1.04415 -2.19461998 0 P 0 ;0
L 1.03336004 -2.19361998 1.04596998 -2.19361998 0 P 0 ;0
L 1.03725 -2.19261998 1.04778996 -2.19261998 0 P 0 ;0
L 1.04113996 -2.19161998 1.0496 -2.19161998 0 P 0 ;0
L 1.14356998 -1.98926998 1.13261004 -1.99086004 0 P 0 ;0
L 1.13261004 -1.99086004 1.12165 -1.9934 0 P 0 ;0
L 1.12165 -1.9934 1.11125 -1.99673002 0 P 0 ;0
L 1.11125 -1.99673002 1.10658002 -1.99858996 0 P 0 ;0
L 1.10658002 -1.99858996 1.10198996 -2.00071004 0 P 0 ;0
L 1.10198996 -2.00071004 1.09653002 -2.00358996 0 P 0 ;0
L 1.09653002 -2.00358996 1.09436998 -2.00488996 0 P 0 ;0
L 1.09436998 -2.00488996 1.09226004 -2.00631004 0 P 0 ;0
L 1.09226004 -2.00631004 1.09028002 -2.00781004 0 P 0 ;0
L 1.09028002 -2.00781004 1.08836998 -2.00941998 0 P 0 ;0
L 1.08836998 -2.00941998 1.08405 -2.0135 0 P 0 ;0
L 1.08405 -2.0135 1.08096998 -2.01678996 0 P 0 ;0
L 1.08096998 -2.01678996 1.07808002 -2.02026998 0 P 0 ;0
L 1.07808002 -2.02026998 1.0754 -2.02393002 0 P 0 ;0
L 1.0754 -2.02393002 1.07313996 -2.02748002 0 P 0 ;0
L 1.07313996 -2.02748002 1.07116004 -2.03118996 0 P 0 ;0
L 1.07116004 -2.03118996 1.06943996 -2.03505 0 P 0 ;0
L 1.06943996 -2.03505 1.06795 -2.03918996 0 P 0 ;0
L 1.06795 -2.03918996 1.06673996 -2.04343996 0 P 0 ;0
L 1.06673996 -2.04343996 1.06583002 -2.04778002 0 P 0 ;0
L 1.06583002 -2.04778002 1.06476998 -2.05538996 0 P 0 ;0
L 1.06476998 -2.05538996 1.06421004 -2.06306004 0 P 0 ;0
L 1.06421004 -2.06306004 1.06415 -2.07076004 0 P 0 ;0
L 1.06415 -2.07076004 1.06456998 -2.0785 0 P 0 ;0
L 1.06456998 -2.0785 1.06508996 -2.08276004 0 P 0 ;0
L 1.06508996 -2.08276004 1.06591004 -2.08696004 0 P 0 ;0
L 1.06591004 -2.08696004 1.06703002 -2.09108002 0 P 0 ;0
L 1.06703002 -2.09108002 1.06833002 -2.09473002 0 P 0 ;0
L 1.06833002 -2.09473002 1.06991998 -2.09823996 0 P 0 ;0
L 1.06991998 -2.09823996 1.0718 -2.10161998 0 P 0 ;0
L 1.0718 -2.10161998 1.07398002 -2.10491998 0 P 0 ;0
L 1.07398002 -2.10491998 1.07641998 -2.10803002 0 P 0 ;0
L 1.07641998 -2.10803002 1.07908996 -2.11095 0 P 0 ;0
L 1.07908996 -2.11095 1.08175 -2.11345 0 P 0 ;0
L 1.08175 -2.11345 1.08458996 -2.11573996 0 P 0 ;0
L 1.08458996 -2.11573996 1.08758996 -2.1178 0 P 0 ;0
L 1.08758996 -2.1178 1.09073002 -2.11963996 0 P 0 ;0
L 1.09073002 -2.11963996 1.094 -2.12123996 0 P 0 ;0
L 1.094 -2.12123996 1.0986 -2.12306998 0 P 0 ;0
L 1.0986 -2.12306998 1.10331004 -2.12456004 0 P 0 ;0
L 1.10331004 -2.12456004 1.10811004 -2.12568996 0 P 0 ;0
L 1.10811004 -2.12568996 1.11298002 -2.12646998 0 P 0 ;0
L 1.11298002 -2.12646998 1.1182 -2.12693002 0 P 0 ;0
L 1.1182 -2.12693002 1.12343996 -2.12703002 0 P 0 ;0
L 1.12343996 -2.12703002 1.12866998 -2.12676004 0 P 0 ;0
L 1.12866998 -2.12676004 1.13388002 -2.12613002 0 P 0 ;0
L 1.13388002 -2.12613002 1.14086004 -2.12473996 0 P 0 ;0
L 1.14086004 -2.12473996 1.1477 -2.12273996 0 P 0 ;0
L 1.1477 -2.12273996 1.15433996 -2.12015 0 P 0 ;0
L 1.15433996 -2.12015 1.1545 -2.12008996 0 P 0 ;0
L 1.1545 -2.12008996 1.15466004 -2.12003996 0 P 0 ;0
L 1.15466004 -2.12003996 1.15483002 -2.12001004 0 P 0 ;0
L 1.15483002 -2.12001004 1.15498996 -2.11998996 0 P 0 ;0
L 1.15498996 -2.11998996 1.15533002 -2.11998996 0 P 0 ;0
L 1.15533002 -2.11998996 1.15538996 -2.12 0 P 0 ;0
L 1.15538996 -2.12 1.15545 -2.12001998 0 P 0 ;0
L 1.15545 -2.12001998 1.15551004 -2.12003002 0 P 0 ;0
L 1.15551004 -2.12003002 1.15556004 -2.12006004 0 P 0 ;0
L 1.15556004 -2.12006004 1.15561004 -2.12008002 0 P 0 ;0
L 1.15561004 -2.12008002 1.15566004 -2.12011004 0 P 0 ;0
L 1.15566004 -2.12011004 1.15571004 -2.12015 0 P 0 ;0
L 1.15571004 -2.12015 1.15575 -2.12018996 0 P 0 ;0
L 1.15575 -2.12018996 1.15578996 -2.12023996 0 P 0 ;0
L 1.15578996 -2.12023996 1.15583002 -2.12028002 0 P 0 ;0
L 1.15583002 -2.12028002 1.15586004 -2.12033996 0 P 0 ;0
L 1.15586004 -2.12033996 1.15588002 -2.12038996 0 P 0 ;0
L 1.15588002 -2.12038996 1.15591004 -2.12043996 0 P 0 ;0
L 1.15591004 -2.12043996 1.15601998 -2.12076004 0 P 0 ;0
L 1.15601998 -2.12076004 1.1561 -2.12108002 0 P 0 ;0
L 1.1561 -2.12108002 1.15616004 -2.12141998 0 P 0 ;0
L 1.15616004 -2.12141998 1.15618002 -2.12175 0 P 0 ;0
L 1.15618002 -2.12175 1.15623996 -2.12505 0 P 0 ;0
L 1.15623996 -2.12505 1.15616004 -2.12688002 0 P 0 ;0
L 1.15616004 -2.12688002 1.15593002 -2.12871004 0 P 0 ;0
L 1.15593002 -2.12871004 1.15553996 -2.13051998 0 P 0 ;0
L 1.15553996 -2.13051998 1.15516004 -2.1318 0 P 0 ;0
L 1.15516004 -2.1318 1.1547 -2.13305 0 P 0 ;0
L 1.1547 -2.13305 1.15415 -2.13426004 0 P 0 ;0
L 1.15415 -2.13426004 1.15351004 -2.13545 0 P 0 ;0
L 1.15351004 -2.13545 1.15278996 -2.1366 0 P 0 ;0
L 1.15278996 -2.1366 1.15198002 -2.13768996 0 P 0 ;0
L 1.15198002 -2.13768996 1.15111004 -2.13873002 0 P 0 ;0
L 1.15111004 -2.13873002 1.15016004 -2.13971004 0 P 0 ;0
L 1.15016004 -2.13971004 1.14876004 -2.14096004 0 P 0 ;0
L 1.14876004 -2.14096004 1.14726004 -2.1421 0 P 0 ;0
L 1.14726004 -2.1421 1.14566998 -2.14311004 0 P 0 ;0
L 1.14566998 -2.14311004 1.144 -2.144 0 P 0 ;0
L 1.144 -2.144 1.14226004 -2.14476004 0 P 0 ;0
L 1.14226004 -2.14476004 1.14046004 -2.14536998 0 P 0 ;0
L 1.14046004 -2.14536998 1.13863002 -2.14583002 0 P 0 ;0
L 1.13863002 -2.14583002 1.13676004 -2.14613996 0 P 0 ;0
L 1.13676004 -2.14613996 1.13041998 -2.14663996 0 P 0 ;0
L 1.13041998 -2.14663996 1.12403996 -2.1466 0 P 0 ;0
L 1.12403996 -2.1466 1.11621998 -2.14593996 0 P 0 ;0
L 1.11621998 -2.14593996 1.10843996 -2.14471004 0 P 0 ;0
L 1.10843996 -2.14471004 1.09946998 -2.14276998 0 P 0 ;0
L 1.09946998 -2.14276998 1.0905 -2.14041004 0 P 0 ;0
L 1.0905 -2.14041004 1.07963996 -2.13728996 0 P 0 ;0
L 1.07963996 -2.13728996 1.07936004 -2.1401 0 P 0 ;0
L 1.07936004 -2.1401 1.07931004 -2.14103996 0 P 0 ;0
L 1.07931004 -2.14103996 1.07931998 -2.14198002 0 P 0 ;0
L 1.07931998 -2.14198002 1.07956998 -2.14735 0 P 0 ;0
L 1.07956998 -2.14735 1.07993996 -2.15375 0 P 0 ;0
L 1.07993996 -2.15375 1.08045 -2.16081998 0 P 0 ;0
L 1.08045 -2.16081998 1.08181004 -2.17873002 0 P 0 ;0
L 1.08181004 -2.17873002 1.08996004 -2.18061004 0 P 0 ;0
L 1.08996004 -2.18061004 1.09951004 -2.18246004 0 P 0 ;0
L 1.09951004 -2.18246004 1.11243996 -2.18416998 0 P 0 ;0
L 1.11243996 -2.18416998 1.1254 -2.18543002 0 P 0 ;0
L 1.1254 -2.18543002 1.13508002 -2.18583002 0 P 0 ;0
L 1.13508002 -2.18583002 1.14765 -2.18528996 0 P 0 ;0
L 1.14765 -2.18528996 1.15368002 -2.18461004 0 P 0 ;0
L 1.15368002 -2.18461004 1.15971004 -2.18363996 0 P 0 ;0
L 1.15971004 -2.18363996 1.16521004 -2.18248002 0 P 0 ;0
L 1.16521004 -2.18248002 1.17063996 -2.18103002 0 P 0 ;0
L 1.17063996 -2.18103002 1.17528996 -2.17946998 0 P 0 ;0
L 1.17528996 -2.17946998 1.17978002 -2.17753996 0 P 0 ;0
L 1.17978002 -2.17753996 1.18216998 -2.1763 0 P 0 ;0
L 1.18216998 -2.1763 1.18446004 -2.17488996 0 P 0 ;0
L 1.18446004 -2.17488996 1.18663996 -2.17331004 0 P 0 ;0
L 1.18663996 -2.17331004 1.18871004 -2.17156004 0 P 0 ;0
L 1.18871004 -2.17156004 1.19161004 -2.16871998 0 P 0 ;0
L 1.19161004 -2.16871998 1.19431004 -2.16568996 0 P 0 ;0
L 1.19431004 -2.16568996 1.19678996 -2.16246998 0 P 0 ;0
L 1.19678996 -2.16246998 1.19908996 -2.15901998 0 P 0 ;0
L 1.19908996 -2.15901998 1.20113996 -2.15543996 0 P 0 ;0
L 1.20113996 -2.15543996 1.20295 -2.15171004 0 P 0 ;0
L 1.20295 -2.15171004 1.20435 -2.14815 0 P 0 ;0
L 1.20435 -2.14815 1.20543996 -2.14448996 0 P 0 ;0
L 1.20543996 -2.14448996 1.20621004 -2.14073996 0 P 0 ;0
L 1.20621004 -2.14073996 1.20651998 -2.13855 0 P 0 ;0
L 1.20651998 -2.13855 1.20671998 -2.13633996 0 P 0 ;0
L 1.20671998 -2.13633996 1.20761998 -2.12321004 0 P 0 ;0
L 1.20761998 -2.12321004 1.20858002 -2.10753996 0 P 0 ;0
L 1.20858002 -2.10753996 1.20951004 -2.09021998 0 P 0 ;0
L 1.20951004 -2.09021998 1.21048002 -2.07166004 0 P 0 ;0
L 1.21048002 -2.07166004 1.21156004 -2.05228002 0 P 0 ;0
L 1.21156004 -2.05228002 1.21258002 -2.03478996 0 P 0 ;0
L 1.21258002 -2.03478996 1.21333002 -2.02286004 0 P 0 ;0
L 1.21333002 -2.02286004 1.21393996 -2.01373996 0 P 0 ;0
L 1.21393996 -2.01373996 1.21443996 -2.00568996 0 P 0 ;0
L 1.21443996 -2.00568996 1.21485 -1.99883996 0 P 0 ;0
L 1.21485 -1.99883996 1.2149 -1.99721004 0 P 0 ;0
L 1.2149 -1.99721004 1.21488996 -1.99703996 0 P 0 ;0
L 1.21488996 -1.99703996 1.21486998 -1.99686004 0 P 0 ;0
L 1.21486998 -1.99686004 1.21483996 -1.99668996 0 P 0 ;0
L 1.21483996 -1.99668996 1.21478996 -1.99653002 0 P 0 ;0
L 1.21478996 -1.99653002 1.21473002 -1.99636998 0 P 0 ;0
L 1.21473002 -1.99636998 1.21466004 -1.99621004 0 P 0 ;0
L 1.21466004 -1.99621004 1.21458002 -1.99606004 0 P 0 ;0
L 1.21458002 -1.99606004 1.21448002 -1.99591004 0 P 0 ;0
L 1.21448002 -1.99591004 1.21433002 -1.99571998 0 P 0 ;0
L 1.21433002 -1.99571998 1.21416998 -1.99553996 0 P 0 ;0
L 1.21416998 -1.99553996 1.21398996 -1.99538002 0 P 0 ;0
L 1.21398996 -1.99538002 1.21378996 -1.99523996 0 P 0 ;0
L 1.21378996 -1.99523996 1.21358002 -1.99511004 0 P 0 ;0
L 1.21358002 -1.99511004 1.21336004 -1.995 0 P 0 ;0
L 1.21336004 -1.995 1.21261004 -1.99468996 0 P 0 ;0
L 1.21261004 -1.99468996 1.21183996 -1.99443996 0 P 0 ;0
L 1.21183996 -1.99443996 1.21105 -1.99423002 0 P 0 ;0
L 1.21105 -1.99423002 1.20593996 -1.99318002 0 P 0 ;0
L 1.20593996 -1.99318002 1.18996998 -1.99065 0 P 0 ;0
L 1.18996998 -1.99065 1.17318996 -1.98908002 0 P 0 ;0
L 1.17318996 -1.98908002 1.15718996 -1.98858002 0 P 0 ;0
L 1.15718996 -1.98858002 1.1504 -1.98876004 0 P 0 ;0
L 1.1504 -1.98876004 1.14356998 -1.98926998 0 P 0 ;0
L 1.04503996 -2.19061998 1.05141998 -2.19061998 0 P 0 ;0
L 1.04893002 -2.18961998 1.05323002 -2.18961998 0 P 0 ;0
L 1.05263002 -2.18861998 1.05503996 -2.18861998 0 P 0 ;0
L 1.05628996 -2.18761998 1.05676004 -2.18761998 0 P 0 ;0
L 1.09645 -2.17983002 1.16738002 -2.17983002 0 P 0 ;0
L 1.09126004 -2.17883002 1.17091004 -2.17883002 0 P 0 ;0
L 1.0868 -2.17783002 1.17386998 -2.17783002 0 P 0 ;0
L 1.08368002 -2.17683002 1.17636004 -2.17683002 0 P 0 ;0
L 1.0836 -2.17583002 1.1787 -2.17583002 0 P 0 ;0
L 1.08351998 -2.17483002 1.18066998 -2.17483002 0 P 0 ;0
L 1.08345 -2.17383002 1.18236998 -2.17383002 0 P 0 ;0
L 1.08336998 -2.17283002 1.1839 -2.17283002 0 P 0 ;0
L 1.08328996 -2.17183002 1.18526998 -2.17183002 0 P 0 ;0
L 1.08321998 -2.17083002 1.18646998 -2.17083002 0 P 0 ;0
L 1.08313996 -2.16983002 1.18761998 -2.16983002 0 P 0 ;0
L 1.08306998 -2.16883002 1.18863996 -2.16883002 0 P 0 ;0
L 1.08298996 -2.16783002 1.18966004 -2.16783002 0 P 0 ;0
L 1.08291998 -2.16683002 1.19061004 -2.16683002 0 P 0 ;0
L 1.08283996 -2.16583002 1.1915 -2.16583002 0 P 0 ;0
L 1.08276004 -2.16483002 1.19238996 -2.16483002 0 P 0 ;0
L 1.08268996 -2.16383002 1.19321004 -2.16383002 0 P 0 ;0
L 1.08261004 -2.16283002 1.19398002 -2.16283002 0 P 0 ;0
L 1.08253002 -2.16183002 1.19476004 -2.16183002 0 P 0 ;0
L 1.08246004 -2.16083002 1.19548002 -2.16083002 0 P 0 ;0
L 1.08238002 -2.15983002 1.19613996 -2.15983002 0 P 0 ;0
L 1.08231004 -2.15883002 1.19681004 -2.15883002 0 P 0 ;0
L 1.08223996 -2.15783002 1.19746004 -2.15783002 0 P 0 ;0
L 1.13506998 -2.18383002 1.12553002 -2.18343996 0 P 0 ;0
L 1.12553002 -2.18343996 1.11266004 -2.18218002 0 P 0 ;0
L 1.11266004 -2.18218002 1.09983002 -2.18048002 0 P 0 ;0
L 1.09983002 -2.18048002 1.09036998 -2.17866004 0 P 0 ;0
L 1.09036998 -2.17866004 1.0837 -2.17711004 0 P 0 ;0
L 1.0837 -2.17711004 1.08245 -2.16066998 0 P 0 ;0
L 1.08245 -2.16066998 1.08193996 -2.15361998 0 P 0 ;0
L 1.08193996 -2.15361998 1.08156998 -2.14726004 0 P 0 ;0
L 1.08156998 -2.14726004 1.08131998 -2.14191004 0 P 0 ;0
L 1.08131998 -2.14191004 1.08131004 -2.14108996 0 P 0 ;0
L 1.08131004 -2.14108996 1.08136004 -2.14026004 0 P 0 ;0
L 1.08136004 -2.14026004 1.0814 -2.13986998 0 P 0 ;0
L 1.0814 -2.13986998 1.08996004 -2.14233002 0 P 0 ;0
L 1.08996004 -2.14233002 1.08996998 -2.14233996 0 P 0 ;0
L 1.08996998 -2.14233996 1.08998996 -2.14233996 0 P 0 ;0
L 1.08998996 -2.14233996 1.099 -2.14471998 0 P 0 ;0
L 1.099 -2.14471998 1.10806998 -2.14668002 0 P 0 ;0
L 1.10806998 -2.14668002 1.11598002 -2.14791998 0 P 0 ;0
L 1.11598002 -2.14791998 1.12395 -2.1486 0 P 0 ;0
L 1.12395 -2.1486 1.13048996 -2.14863996 0 P 0 ;0
L 1.13048996 -2.14863996 1.137 -2.14811998 0 P 0 ;0
L 1.137 -2.14811998 1.13903002 -2.14778996 0 P 0 ;0
L 1.13903002 -2.14778996 1.14103002 -2.14728996 0 P 0 ;0
L 1.14103002 -2.14728996 1.14298002 -2.14661998 0 P 0 ;0
L 1.14298002 -2.14661998 1.14486998 -2.14581004 0 P 0 ;0
L 1.14486998 -2.14581004 1.14668002 -2.14483996 0 P 0 ;0
L 1.14668002 -2.14483996 1.1484 -2.14373996 0 P 0 ;0
L 1.1484 -2.14373996 1.15003002 -2.1425 0 P 0 ;0
L 1.15003002 -2.1425 1.15155 -2.14115 0 P 0 ;0
L 1.15155 -2.14115 1.1526 -2.14006998 0 P 0 ;0
L 1.1526 -2.14006998 1.15263996 -2.14001998 0 P 0 ;0
L 1.15263996 -2.14001998 1.15356004 -2.13893002 0 P 0 ;0
L 1.15356004 -2.13893002 1.15443996 -2.13771998 0 P 0 ;0
L 1.15443996 -2.13771998 1.15523002 -2.13646004 0 P 0 ;0
L 1.15523002 -2.13646004 1.15593996 -2.13515 0 P 0 ;0
L 1.15593996 -2.13515 1.15655 -2.13381004 0 P 0 ;0
L 1.15655 -2.13381004 1.15706004 -2.13243002 0 P 0 ;0
L 1.15706004 -2.13243002 1.15748002 -2.13101004 0 P 0 ;0
L 1.15748002 -2.13101004 1.1579 -2.12905 0 P 0 ;0
L 1.1579 -2.12905 1.15816004 -2.12706004 0 P 0 ;0
L 1.15816004 -2.12706004 1.15825 -2.12506998 0 P 0 ;0
L 1.15825 -2.12506998 1.15818002 -2.12165 0 P 0 ;0
L 1.15818002 -2.12165 1.15813996 -2.12118002 0 P 0 ;0
L 1.15813996 -2.12118002 1.15813002 -2.1211 0 P 0 ;0
L 1.15813002 -2.1211 1.15806004 -2.12068002 0 P 0 ;0
L 1.15806004 -2.12068002 1.15793996 -2.12018996 0 P 0 ;0
L 1.15793996 -2.12018996 1.15778002 -2.11973002 0 P 0 ;0
L 1.15778002 -2.11973002 1.1577 -2.11953002 0 P 0 ;0
L 1.1577 -2.11953002 1.15758996 -2.11933002 0 P 0 ;0
L 1.15758996 -2.11933002 1.15746998 -2.11913996 0 P 0 ;0
L 1.15746998 -2.11913996 1.15733002 -2.11895 0 P 0 ;0
L 1.15733002 -2.11895 1.15716998 -2.11878002 0 P 0 ;0
L 1.15716998 -2.11878002 1.157 -2.11863002 0 P 0 ;0
L 1.157 -2.11863002 1.15681998 -2.11848996 0 P 0 ;0
L 1.15681998 -2.11848996 1.15663002 -2.11836004 0 P 0 ;0
L 1.15663002 -2.11836004 1.15641998 -2.11825 0 P 0 ;0
L 1.15641998 -2.11825 1.15621004 -2.11816004 0 P 0 ;0
L 1.15621004 -2.11816004 1.15598996 -2.11808996 0 P 0 ;0
L 1.15598996 -2.11808996 1.15576998 -2.11803996 0 P 0 ;0
L 1.15576998 -2.11803996 1.15553002 -2.118 0 P 0 ;0
L 1.15553002 -2.118 1.15518002 -2.11798002 0 P 0 ;0
L 1.15518002 -2.11798002 1.15483996 -2.11798996 0 P 0 ;0
L 1.15483996 -2.11798996 1.15451004 -2.11803002 0 P 0 ;0
L 1.15451004 -2.11803002 1.15418002 -2.1181 0 P 0 ;0
L 1.15418002 -2.1181 1.15386004 -2.1182 0 P 0 ;0
L 1.15386004 -2.1182 1.15361004 -2.11828996 0 P 0 ;0
L 1.15361004 -2.11828996 1.14705 -2.12083996 0 P 0 ;0
L 1.14705 -2.12083996 1.14038996 -2.12278996 0 P 0 ;0
L 1.14038996 -2.12278996 1.13356004 -2.12416004 0 P 0 ;0
L 1.13356004 -2.12416004 1.1285 -2.12476998 0 P 0 ;0
L 1.1285 -2.12476998 1.12341004 -2.12501998 0 P 0 ;0
L 1.12341004 -2.12501998 1.11831004 -2.12493002 0 P 0 ;0
L 1.11831004 -2.12493002 1.11323002 -2.12448996 0 P 0 ;0
L 1.11323002 -2.12448996 1.10848996 -2.12373002 0 P 0 ;0
L 1.10848996 -2.12373002 1.10383996 -2.12263002 0 P 0 ;0
L 1.10383996 -2.12263002 1.09926998 -2.12118996 0 P 0 ;0
L 1.09926998 -2.12118996 1.09481004 -2.11941004 0 P 0 ;0
L 1.09481004 -2.11941004 1.09168002 -2.11788002 0 P 0 ;0
L 1.09168002 -2.11788002 1.08866004 -2.11611998 0 P 0 ;0
L 1.08866004 -2.11611998 1.08578002 -2.11413002 0 P 0 ;0
L 1.08578002 -2.11413002 1.08306998 -2.11193996 0 P 0 ;0
L 1.08306998 -2.11193996 1.08051998 -2.10955 0 P 0 ;0
L 1.08051998 -2.10955 1.07793996 -2.10673002 0 P 0 ;0
L 1.07793996 -2.10673002 1.07561004 -2.10373996 0 P 0 ;0
L 1.07561004 -2.10373996 1.07351004 -2.10058002 0 P 0 ;0
L 1.07351004 -2.10058002 1.07171004 -2.09733996 0 P 0 ;0
L 1.07171004 -2.09733996 1.07018002 -2.09396998 0 P 0 ;0
L 1.07018002 -2.09396998 1.06893996 -2.09048002 0 P 0 ;0
L 1.06893996 -2.09048002 1.06786004 -2.0865 0 P 0 ;0
L 1.06786004 -2.0865 1.06706004 -2.08243996 0 P 0 ;0
L 1.06706004 -2.08243996 1.06656004 -2.07833002 0 P 0 ;0
L 1.06656004 -2.07833002 1.06615 -2.07071004 0 P 0 ;0
L 1.06615 -2.07071004 1.06621004 -2.06313996 0 P 0 ;0
L 1.06621004 -2.06313996 1.06675 -2.0556 0 P 0 ;0
L 1.06675 -2.0556 1.0678 -2.04813002 0 P 0 ;0
L 1.0678 -2.04813002 1.06868996 -2.04391998 0 P 0 ;0
L 1.06868996 -2.04391998 1.06985 -2.03981004 0 P 0 ;0
L 1.06985 -2.03981004 1.0713 -2.03578996 0 P 0 ;0
L 1.0713 -2.03578996 1.07296004 -2.03206998 0 P 0 ;0
L 1.07296004 -2.03206998 1.07486998 -2.02848996 0 P 0 ;0
L 1.07486998 -2.02848996 1.07705 -2.02506004 0 P 0 ;0
L 1.07705 -2.02506004 1.07966004 -2.0215 0 P 0 ;0
L 1.07966004 -2.0215 1.08246998 -2.01811004 0 P 0 ;0
L 1.08246998 -2.01811004 1.08546998 -2.01491004 0 P 0 ;0
L 1.08546998 -2.01491004 1.0897 -2.01091004 0 P 0 ;0
L 1.0897 -2.01091004 1.09153002 -2.00936998 0 P 0 ;0
L 1.09153002 -2.00936998 1.09341998 -2.00793996 0 P 0 ;0
L 1.09341998 -2.00793996 1.09545 -2.00658002 0 P 0 ;0
L 1.09545 -2.00658002 1.09751004 -2.00533996 0 P 0 ;0
L 1.09751004 -2.00533996 1.10288002 -2.0025 0 P 0 ;0
L 1.10288002 -2.0025 1.10736998 -2.00043002 0 P 0 ;0
L 1.10736998 -2.00043002 1.11193002 -1.99861004 0 P 0 ;0
L 1.11193002 -1.99861004 1.12218002 -1.99533002 0 P 0 ;0
L 1.12218002 -1.99533002 1.13298002 -1.99281998 0 P 0 ;0
L 1.13298002 -1.99281998 1.14378996 -1.99126004 0 P 0 ;0
L 1.14378996 -1.99126004 1.1505 -1.99075 0 P 0 ;0
L 1.1505 -1.99075 1.15718002 -1.99058996 0 P 0 ;0
L 1.15718002 -1.99058996 1.17306998 -1.99108002 0 P 0 ;0
L 1.17306998 -1.99108002 1.18971998 -1.99263002 0 P 0 ;0
L 1.18971998 -1.99263002 1.20558002 -1.99515 0 P 0 ;0
L 1.20558002 -1.99515 1.21058996 -1.99618002 0 P 0 ;0
L 1.21058996 -1.99618002 1.21126998 -1.99636004 0 P 0 ;0
L 1.21126998 -1.99636004 1.21191998 -1.99656998 0 P 0 ;0
L 1.21191998 -1.99656998 1.21253002 -1.99681998 0 P 0 ;0
L 1.21253002 -1.99681998 1.21261004 -1.99686004 0 P 0 ;0
L 1.21261004 -1.99686004 1.21266004 -1.99688996 0 P 0 ;0
L 1.21266004 -1.99688996 1.21271998 -1.99693002 0 P 0 ;0
L 1.21271998 -1.99693002 1.21281998 -1.99703002 0 P 0 ;0
L 1.21281998 -1.99703002 1.21286004 -1.99708996 0 P 0 ;0
L 1.21286004 -1.99708996 1.21288002 -1.99711004 0 P 0 ;0
L 1.21288002 -1.99711004 1.21288002 -1.99711998 0 P 0 ;0
L 1.21288002 -1.99711998 1.21288996 -1.99715 0 P 0 ;0
L 1.21288996 -1.99715 1.2129 -1.99716998 0 P 0 ;0
L 1.2129 -1.99716998 1.2129 -1.99721998 0 P 0 ;0
L 1.2129 -1.99721998 1.21285 -1.99875 0 P 0 ;0
L 1.21285 -1.99875 1.21243996 -2.00556998 0 P 0 ;0
L 1.21243996 -2.00556998 1.21193996 -2.01361004 0 P 0 ;0
L 1.21193996 -2.01361004 1.21133996 -2.02273002 0 P 0 ;0
L 1.21133996 -2.02273002 1.21133996 -2.02273996 0 P 0 ;0
L 1.21133996 -2.02273996 1.21058996 -2.03468002 0 P 0 ;0
L 1.21058996 -2.03468002 1.20956004 -2.05216998 0 P 0 ;0
L 1.20956004 -2.05216998 1.20848996 -2.07156004 0 P 0 ;0
L 1.20848996 -2.07156004 1.20848996 -2.07156998 0 P 0 ;0
L 1.20848996 -2.07156998 1.20751004 -2.09011004 0 P 0 ;0
L 1.20751004 -2.09011004 1.20658996 -2.10743996 0 P 0 ;0
L 1.20658996 -2.10743996 1.20561998 -2.12308996 0 P 0 ;0
L 1.20561998 -2.12308996 1.20473002 -2.13618996 0 P 0 ;0
L 1.20473002 -2.13618996 1.20453002 -2.13831998 0 P 0 ;0
L 1.20453002 -2.13831998 1.20423996 -2.14041004 0 P 0 ;0
L 1.20423996 -2.14041004 1.2035 -2.144 0 P 0 ;0
L 1.2035 -2.144 1.20246004 -2.1475 0 P 0 ;0
L 1.20246004 -2.1475 1.20111998 -2.1509 0 P 0 ;0
L 1.20111998 -2.1509 1.19936998 -2.1545 0 P 0 ;0
L 1.19936998 -2.1545 1.19738002 -2.15796998 0 P 0 ;0
L 1.19738002 -2.15796998 1.19516004 -2.1613 0 P 0 ;0
L 1.19516004 -2.1613 1.19276998 -2.16441004 0 P 0 ;0
L 1.19276998 -2.16441004 1.19016004 -2.16733996 0 P 0 ;0
L 1.19016004 -2.16733996 1.18736004 -2.17008002 0 P 0 ;0
L 1.18736004 -2.17008002 1.1854 -2.17173996 0 P 0 ;0
L 1.1854 -2.17173996 1.18335 -2.17323002 0 P 0 ;0
L 1.18335 -2.17323002 1.18118002 -2.17456004 0 P 0 ;0
L 1.18118002 -2.17456004 1.17893002 -2.17573002 0 P 0 ;0
L 1.17893002 -2.17573002 1.17456998 -2.1776 0 P 0 ;0
L 1.17456998 -2.1776 1.17006998 -2.17911998 0 P 0 ;0
L 1.17006998 -2.17911998 1.16473996 -2.18053002 0 P 0 ;0
L 1.16473996 -2.18053002 1.15935 -2.18166998 0 P 0 ;0
L 1.15935 -2.18166998 1.15341998 -2.18263002 0 P 0 ;0
L 1.15341998 -2.18263002 1.1475 -2.18328996 0 P 0 ;0
L 1.1475 -2.18328996 1.13506998 -2.18383002 0 P 0 ;0
L 0.90491998 -2.21461998 1.00131004 -2.21461998 0 P 0 ;0
L 0.92235 -2.21361998 1.00355 -2.21361998 0 P 0 ;0
L 0.76925 -1.8965 0.85586998 -1.8965 0 P 0 ;0
L 0.76958996 -1.8955 0.85556004 -1.8955 0 P 0 ;0
L 0.76995 -1.8945 0.85521004 -1.8945 0 P 0 ;0
L 0.77031004 -1.8935 0.85486004 -1.8935 0 P 0 ;0
L 0.77071004 -1.8925 0.85443996 -1.8925 0 P 0 ;0
L 0.77115 -1.8915 0.85401004 -1.8915 0 P 0 ;0
L 0.7716 -1.8905 0.85355 -1.8905 0 P 0 ;0
L 0.77206004 -1.8895 0.85303002 -1.8895 0 P 0 ;0
L 0.7726 -1.8885 0.85251004 -1.8885 0 P 0 ;0
L 0.77313996 -1.8875 0.85198996 -1.8875 0 P 0 ;0
L 0.77368996 -1.8865 0.85138002 -1.8865 0 P 0 ;0
L 0.77433002 -1.8855 0.85073996 -1.8855 0 P 0 ;0
L 0.77496004 -1.8845 0.85011004 -1.8845 0 P 0 ;0
L 0.77561998 -1.8835 0.84943002 -1.8835 0 P 0 ;0
L 0.77636004 -1.8825 0.84866998 -1.8825 0 P 0 ;0
L 0.77711004 -1.8815 0.84791004 -1.8815 0 P 0 ;0
L 0.7779 -1.8805 0.84713002 -1.8805 0 P 0 ;0
L 0.77876998 -1.8795 0.84623002 -1.8795 0 P 0 ;0
L 0.77963996 -1.8785 0.84533002 -1.8785 0 P 0 ;0
L 0.7806 -1.8775 0.8444 -1.8775 0 P 0 ;0
L 0.78161004 -1.8765 0.84335 -1.8765 0 P 0 ;0
L 0.78265 -1.8755 0.84228996 -1.8755 0 P 0 ;0
L 0.78381998 -1.8745 0.84108996 -1.8745 0 P 0 ;0
L 0.78498996 -1.8735 0.83986998 -1.8735 0 P 0 ;0
L 0.78635 -1.8725 0.83848002 -1.8725 0 P 0 ;0
L 0.78773002 -1.8715 0.83706004 -1.8715 0 P 0 ;0
L 0.78933002 -1.8705 0.83541998 -1.8705 0 P 0 ;0
L 0.791 -1.8695 0.83366004 -1.8695 0 P 0 ;0
L 0.793 -1.8685 0.83171998 -1.8685 0 P 0 ;0
L 0.79525 -1.8675 0.82941998 -1.8675 0 P 0 ;0
L 0.79791998 -1.8665 0.82671004 -1.8665 0 P 0 ;0
L 0.80143996 -1.8655 0.82328996 -1.8655 0 P 0 ;0
L 0.80705 -1.8645 0.81776004 -1.8645 0 P 0 ;0
L 0.74543002 -1.89661998 0.75033002 -1.89661998 0 P 0 ;0
L 0.74751004 -1.89561998 0.75058996 -1.89561998 0 P 0 ;0
L 0.74958996 -1.89461998 0.75086004 -1.89461998 0 P 0 ;0
L 0.76733996 -1.9125 0.85751998 -1.9125 0 P 0 ;0
L 0.76728996 -1.9115 0.85756004 -1.9115 0 P 0 ;0
L 0.76723996 -1.9105 0.85758996 -1.9105 0 P 0 ;0
L 0.76721998 -1.9095 0.85763002 -1.9095 0 P 0 ;0
L 0.76725 -1.9085 0.85761004 -1.9085 0 P 0 ;0
L 0.76728002 -1.9075 0.85756998 -1.9075 0 P 0 ;0
L 0.76731004 -1.9065 0.85753002 -1.9065 0 P 0 ;0
L 0.76741998 -1.9055 0.85748996 -1.9055 0 P 0 ;0
L 0.76753996 -1.9045 0.85738002 -1.9045 0 P 0 ;0
L 0.76766004 -1.9035 0.85726004 -1.9035 0 P 0 ;0
L 0.76781998 -1.9025 0.85713996 -1.9025 0 P 0 ;0
L 0.76801998 -1.9015 0.85701004 -1.9015 0 P 0 ;0
L 0.76821004 -1.9005 0.85683002 -1.9005 0 P 0 ;0
L 0.76841998 -1.8995 0.85661998 -1.8995 0 P 0 ;0
L 0.7687 -1.8985 0.85641004 -1.8985 0 P 0 ;0
L 0.76896998 -1.8975 0.85613996 -1.8975 0 P 0 ;0
L 0.76751004 -2.08325 0.8416 -2.08325 0 P 0 ;0
L 0.76761998 -2.08225 0.84161998 -2.08225 0 P 0 ;0
L 0.76773996 -2.08125 0.84166998 -2.08125 0 P 0 ;0
L 0.76786004 -2.08025 0.84171998 -2.08025 0 P 0 ;0
L 0.76796998 -2.07925 0.84176998 -2.07925 0 P 0 ;0
L 0.76808002 -2.07825 0.84181004 -2.07825 0 P 0 ;0
L 0.76818002 -2.07725 0.84186004 -2.07725 0 P 0 ;0
L 0.76828996 -2.07625 0.8419 -2.07625 0 P 0 ;0
L 0.76838996 -2.07525 0.84195 -2.07525 0 P 0 ;0
L 0.76848996 -2.07425 0.842 -2.07425 0 P 0 ;0
L 0.7686 -2.07325 0.84205 -2.07325 0 P 0 ;0
L 0.7687 -2.07225 0.84208996 -2.07225 0 P 0 ;0
L 0.7688 -2.07125 0.84213996 -2.07125 0 P 0 ;0
L 0.7689 -2.07025 0.84218002 -2.07025 0 P 0 ;0
L 0.76901004 -2.06925 0.84223002 -2.06925 0 P 0 ;0
L 0.76911004 -2.06825 0.84228002 -2.06825 0 P 0 ;0
L 0.76921004 -2.06725 0.84233002 -2.06725 0 P 0 ;0
L 0.76931998 -2.06625 0.84236998 -2.06625 0 P 0 ;0
L 0.76941998 -2.06525 0.84241998 -2.06525 0 P 0 ;0
L 0.76948996 -2.06425 0.84246004 -2.06425 0 P 0 ;0
L 0.76956004 -2.06325 0.84251004 -2.06325 0 P 0 ;0
L 0.76963002 -2.06225 0.84256004 -2.06225 0 P 0 ;0
L 0.7697 -2.06125 0.8426 -2.06125 0 P 0 ;0
L 0.76976998 -2.06025 0.84265 -2.06025 0 P 0 ;0
L 0.76983996 -2.05925 0.8427 -2.05925 0 P 0 ;0
L 0.76991004 -2.05825 0.84273996 -2.05825 0 P 0 ;0
L 0.76996998 -2.05725 0.84278996 -2.05725 0 P 0 ;0
L 0.77001004 -2.05625 0.84283996 -2.05625 0 P 0 ;0
L 0.77003996 -2.05525 0.84288002 -2.05525 0 P 0 ;0
L 0.77008002 -2.05425 0.84295 -2.05425 0 P 0 ;0
L 0.77011998 -2.05325 0.84303996 -2.05325 0 P 0 ;0
L 0.77016004 -2.05225 0.84311998 -2.05225 0 P 0 ;0
L 0.77018996 -2.05125 0.84321004 -2.05125 0 P 0 ;0
L 0.77023002 -2.05025 0.8433 -2.05025 0 P 0 ;0
L 0.77026998 -2.04925 0.84338002 -2.04925 0 P 0 ;0
L 0.77031004 -2.04825 0.84346998 -2.04825 0 P 0 ;0
L 0.77033996 -2.04725 0.84356004 -2.04725 0 P 0 ;0
L 0.77038002 -2.04625 0.84363996 -2.04625 0 P 0 ;0
L 0.77041004 -2.04525 0.84373002 -2.04525 0 P 0 ;0
L 0.77043996 -2.04425 0.84381004 -2.04425 0 P 0 ;0
L 0.77046004 -2.04325 0.8439 -2.04325 0 P 0 ;0
L 0.77048002 -2.04225 0.84398996 -2.04225 0 P 0 ;0
L 0.77051004 -2.04125 0.84406998 -2.04125 0 P 0 ;0
L 0.77053002 -2.04025 0.84416004 -2.04025 0 P 0 ;0
L 0.77055 -2.03925 0.84425 -2.03925 0 P 0 ;0
L 0.77058002 -2.03825 0.84433002 -2.03825 0 P 0 ;0
L 0.7706 -2.03725 0.84441998 -2.03725 0 P 0 ;0
L 0.77061998 -2.03625 0.84451004 -2.03625 0 P 0 ;0
L 0.77065 -2.03525 0.84458996 -2.03525 0 P 0 ;0
L 0.77066998 -2.03425 0.84468002 -2.03425 0 P 0 ;0
L 0.7707 -2.03325 0.84476998 -2.03325 0 P 0 ;0
L 0.77071998 -2.03225 0.84485 -2.03225 0 P 0 ;0
L 0.77073002 -2.03125 0.84493996 -2.03125 0 P 0 ;0
L 0.77073996 -2.03025 0.84503002 -2.03025 0 P 0 ;0
L 0.79986004 -1.8638 0.79643996 -1.86486998 0 P 0 ;0
L 0.79643996 -1.86486998 0.79311998 -1.86621004 0 P 0 ;0
L 0.79311998 -1.86621004 0.78991004 -1.86781004 0 P 0 ;0
L 0.78991004 -1.86781004 0.78683996 -1.86966998 0 P 0 ;0
L 0.78683996 -1.86966998 0.78391998 -1.87178002 0 P 0 ;0
L 0.78391998 -1.87178002 0.78111998 -1.87416998 0 P 0 ;0
L 0.78111998 -1.87416998 0.7785 -1.87676004 0 P 0 ;0
L 0.7785 -1.87676004 0.77608002 -1.87953996 0 P 0 ;0
L 0.77608002 -1.87953996 0.77386998 -1.8825 0 P 0 ;0
L 0.77386998 -1.8825 0.77188002 -1.88561998 0 P 0 ;0
L 0.77188002 -1.88561998 0.77013996 -1.88886004 0 P 0 ;0
L 0.77013996 -1.88886004 0.76863996 -1.89221004 0 P 0 ;0
L 0.76863996 -1.89221004 0.7674 -1.89566998 0 P 0 ;0
L 0.7674 -1.89566998 0.76643002 -1.89921004 0 P 0 ;0
L 0.76643002 -1.89921004 0.76571004 -1.90283996 0 P 0 ;0
L 0.76571004 -1.90283996 0.76531004 -1.90636004 0 P 0 ;0
L 0.76531004 -1.90636004 0.7652 -1.90991004 0 P 0 ;0
L 0.7652 -1.90991004 0.76538996 -1.91345 0 P 0 ;0
L 0.76538996 -1.91345 0.76586998 -1.91696998 0 P 0 ;0
L 0.76586998 -1.91696998 0.76663996 -1.92046004 0 P 0 ;0
L 0.76663996 -1.92046004 0.76803002 -1.92493996 0 P 0 ;0
L 0.76803002 -1.92493996 0.76978002 -1.9293 0 P 0 ;0
L 0.76978002 -1.9293 0.77106998 -1.93193996 0 P 0 ;0
L 0.77106998 -1.93193996 0.77253002 -1.93448002 0 P 0 ;0
L 0.77253002 -1.93448002 0.77416004 -1.93693996 0 P 0 ;0
L 0.77416004 -1.93693996 0.77593002 -1.93923002 0 P 0 ;0
L 0.77593002 -1.93923002 0.77783996 -1.94141004 0 P 0 ;0
L 0.77783996 -1.94141004 0.77988996 -1.94345 0 P 0 ;0
L 0.77988996 -1.94345 0.78216004 -1.94545 0 P 0 ;0
L 0.78216004 -1.94545 0.78453996 -1.9473 0 P 0 ;0
L 0.78453996 -1.9473 0.78703002 -1.94901998 0 P 0 ;0
L 0.78703002 -1.94901998 0.79016998 -1.95088002 0 P 0 ;0
L 0.79016998 -1.95088002 0.79343996 -1.95248996 0 P 0 ;0
L 0.79343996 -1.95248996 0.79683002 -1.95383996 0 P 0 ;0
L 0.79683002 -1.95383996 0.80031998 -1.95491998 0 P 0 ;0
L 0.80031998 -1.95491998 0.80391004 -1.95573996 0 P 0 ;0
L 0.80391004 -1.95573996 0.80751998 -1.95626004 0 P 0 ;0
L 0.80751998 -1.95626004 0.81116004 -1.9565 0 P 0 ;0
L 0.81116004 -1.9565 0.81481004 -1.95646004 0 P 0 ;0
L 0.81481004 -1.95646004 0.81843996 -1.95613002 0 P 0 ;0
L 0.81843996 -1.95613002 0.82205 -1.95551004 0 P 0 ;0
L 0.82205 -1.95551004 0.82561998 -1.95461004 0 P 0 ;0
L 0.82561998 -1.95461004 0.82911004 -1.95345 0 P 0 ;0
L 0.82911004 -1.95345 0.83248996 -1.95201004 0 P 0 ;0
L 0.83248996 -1.95201004 0.83576004 -1.95031998 0 P 0 ;0
L 0.83576004 -1.95031998 0.83891998 -1.94836004 0 P 0 ;0
L 0.83891998 -1.94836004 0.84191998 -1.94616998 0 P 0 ;0
L 0.84191998 -1.94616998 0.84475 -1.94375 0 P 0 ;0
L 0.84475 -1.94375 0.84738996 -1.94113996 0 P 0 ;0
L 0.84738996 -1.94113996 0.84983002 -1.93833996 0 P 0 ;0
L 0.84983002 -1.93833996 0.85206998 -1.93533996 0 P 0 ;0
L 0.85206998 -1.93533996 0.8536 -1.93291998 0 P 0 ;0
L 0.8536 -1.93291998 0.85496004 -1.93041004 0 P 0 ;0
L 0.85496004 -1.93041004 0.85613996 -1.9278 0 P 0 ;0
L 0.85613996 -1.9278 0.85711998 -1.92511004 0 P 0 ;0
L 0.85711998 -1.92511004 0.85823002 -1.92123002 0 P 0 ;0
L 0.85823002 -1.92123002 0.85901998 -1.91726998 0 P 0 ;0
L 0.85901998 -1.91726998 0.85948996 -1.91323996 0 P 0 ;0
L 0.85948996 -1.91323996 0.85963996 -1.90918002 0 P 0 ;0
L 0.85963996 -1.90918002 0.85946998 -1.90513002 0 P 0 ;0
L 0.85946998 -1.90513002 0.85898002 -1.9011 0 P 0 ;0
L 0.85898002 -1.9011 0.85841998 -1.89826004 0 P 0 ;0
L 0.85841998 -1.89826004 0.85766004 -1.89546004 0 P 0 ;0
L 0.85766004 -1.89546004 0.85671004 -1.89273002 0 P 0 ;0
L 0.85671004 -1.89273002 0.85556998 -1.89006004 0 P 0 ;0
L 0.85556998 -1.89006004 0.85361998 -1.88631004 0 P 0 ;0
L 0.85361998 -1.88631004 0.85136004 -1.88273996 0 P 0 ;0
L 0.85136004 -1.88273996 0.84881004 -1.87938002 0 P 0 ;0
L 0.84881004 -1.87938002 0.84596998 -1.87623002 0 P 0 ;0
L 0.84596998 -1.87623002 0.84355 -1.87393996 0 P 0 ;0
L 0.84355 -1.87393996 0.84096998 -1.87181998 0 P 0 ;0
L 0.84096998 -1.87181998 0.83826004 -1.86988996 0 P 0 ;0
L 0.83826004 -1.86988996 0.83541004 -1.86815 0 P 0 ;0
L 0.83541004 -1.86815 0.83243996 -1.86661004 0 P 0 ;0
L 0.83243996 -1.86661004 0.82938996 -1.86531004 0 P 0 ;0
L 0.82938996 -1.86531004 0.82625 -1.86423002 0 P 0 ;0
L 0.82625 -1.86423002 0.82303996 -1.86336004 0 P 0 ;0
L 0.82303996 -1.86336004 0.81978002 -1.86273002 0 P 0 ;0
L 0.81978002 -1.86273002 0.81646998 -1.86233002 0 P 0 ;0
L 0.81646998 -1.86233002 0.81228996 -1.86215 0 P 0 ;0
L 0.81228996 -1.86215 0.80811004 -1.86233996 0 P 0 ;0
L 0.80811004 -1.86233996 0.80396004 -1.86288996 0 P 0 ;0
L 0.80396004 -1.86288996 0.79986004 -1.8638 0 P 0 ;0
L 0.80308996 -1.9535 0.82186004 -1.9535 0 P 0 ;0
L 0.79926004 -1.9525 0.82563996 -1.9525 0 P 0 ;0
L 0.79636004 -1.9515 0.82856998 -1.9515 0 P 0 ;0
L 0.79393002 -1.9505 0.83093996 -1.9505 0 P 0 ;0
L 0.7919 -1.9495 0.83298996 -1.9495 0 P 0 ;0
L 0.79008002 -1.9485 0.8349 -1.9485 0 P 0 ;0
L 0.78838996 -1.9475 0.83651004 -1.9475 0 P 0 ;0
L 0.7869 -1.9465 0.83806998 -1.9465 0 P 0 ;0
L 0.78548002 -1.9455 0.83943996 -1.9455 0 P 0 ;0
L 0.7842 -1.9445 0.84078996 -1.9445 0 P 0 ;0
L 0.78298002 -1.9435 0.84196998 -1.9435 0 P 0 ;0
L 0.78183996 -1.9425 0.84313996 -1.9425 0 P 0 ;0
L 0.78076998 -1.9415 0.84418996 -1.9415 0 P 0 ;0
L 0.77976004 -1.9405 0.8452 -1.9405 0 P 0 ;0
L 0.77883002 -1.9395 0.84616998 -1.9395 0 P 0 ;0
L 0.77793996 -1.9385 0.84703996 -1.9385 0 P 0 ;0
L 0.77711998 -1.9375 0.84791004 -1.9375 0 P 0 ;0
L 0.77635 -1.9365 0.84871004 -1.9365 0 P 0 ;0
L 0.77561004 -1.9355 0.84945 -1.9355 0 P 0 ;0
L 0.77493996 -1.9345 0.8502 -1.9345 0 P 0 ;0
L 0.77428002 -1.9335 0.85086998 -1.9335 0 P 0 ;0
L 0.7737 -1.9325 0.8515 -1.9325 0 P 0 ;0
L 0.77311998 -1.9315 0.8521 -1.9315 0 P 0 ;0
L 0.77258996 -1.9305 0.85263996 -1.9305 0 P 0 ;0
L 0.7721 -1.9295 0.85318002 -1.9295 0 P 0 ;0
L 0.77161004 -1.9285 0.85363002 -1.9285 0 P 0 ;0
L 0.77121004 -1.9275 0.85408002 -1.9275 0 P 0 ;0
L 0.77081004 -1.9265 0.85448002 -1.9265 0 P 0 ;0
L 0.77041004 -1.9255 0.85485 -1.9255 0 P 0 ;0
L 0.77001004 -1.9245 0.85521998 -1.9245 0 P 0 ;0
L 0.76968002 -1.9235 0.8555 -1.9235 0 P 0 ;0
L 0.76936998 -1.9225 0.85578996 -1.9225 0 P 0 ;0
L 0.76906004 -1.9215 0.85606998 -1.9215 0 P 0 ;0
L 0.76875 -1.9205 0.85633002 -1.9205 0 P 0 ;0
L 0.76848002 -1.9195 0.85653002 -1.9195 0 P 0 ;0
L 0.76826004 -1.9185 0.85673002 -1.9185 0 P 0 ;0
L 0.76803002 -1.9175 0.85693002 -1.9175 0 P 0 ;0
L 0.76783002 -1.9165 0.85708996 -1.9165 0 P 0 ;0
L 0.76768996 -1.9155 0.85721004 -1.9155 0 P 0 ;0
L 0.76755 -1.9145 0.85733002 -1.9145 0 P 0 ;0
L 0.76741998 -1.9135 0.85745 -1.9135 0 P 0 ;0
L 0.81121004 -1.9545 0.80773002 -1.95426998 0 P 0 ;0
L 0.80773002 -1.95426998 0.80426998 -1.95376998 0 P 0 ;0
L 0.80426998 -1.95376998 0.80083996 -1.95298996 0 P 0 ;0
L 0.80083996 -1.95298996 0.7975 -1.95195 0 P 0 ;0
L 0.7975 -1.95195 0.79426004 -1.95066004 0 P 0 ;0
L 0.79426004 -1.95066004 0.79111998 -1.94911998 0 P 0 ;0
L 0.79111998 -1.94911998 0.78811004 -1.94733002 0 P 0 ;0
L 0.78811004 -1.94733002 0.78573002 -1.94568996 0 P 0 ;0
L 0.78573002 -1.94568996 0.78343996 -1.9439 0 P 0 ;0
L 0.78343996 -1.9439 0.78126004 -1.94198996 0 P 0 ;0
L 0.78126004 -1.94198996 0.7793 -1.94003996 0 P 0 ;0
L 0.7793 -1.94003996 0.77746998 -1.93796004 0 P 0 ;0
L 0.77746998 -1.93796004 0.77578996 -1.93576998 0 P 0 ;0
L 0.77578996 -1.93576998 0.77423002 -1.93343002 0 P 0 ;0
L 0.77423002 -1.93343002 0.77283996 -1.931 0 P 0 ;0
L 0.77283996 -1.931 0.77161004 -1.92848996 0 P 0 ;0
L 0.77161004 -1.92848996 0.76991998 -1.92426998 0 P 0 ;0
L 0.76991998 -1.92426998 0.76858002 -1.91993996 0 P 0 ;0
L 0.76858002 -1.91993996 0.76783996 -1.91661998 0 P 0 ;0
L 0.76783996 -1.91661998 0.76738002 -1.91326998 0 P 0 ;0
L 0.76738002 -1.91326998 0.76721004 -1.90988996 0 P 0 ;0
L 0.76721004 -1.90988996 0.76731004 -1.90651004 0 P 0 ;0
L 0.76731004 -1.90651004 0.7677 -1.90315 0 P 0 ;0
L 0.7677 -1.90315 0.76838002 -1.89966998 0 P 0 ;0
L 0.76838002 -1.89966998 0.76931004 -1.89626998 0 P 0 ;0
L 0.76931004 -1.89626998 0.7705 -1.89296004 0 P 0 ;0
L 0.7705 -1.89296004 0.77193996 -1.88973996 0 P 0 ;0
L 0.77193996 -1.88973996 0.7736 -1.88663996 0 P 0 ;0
L 0.7736 -1.88663996 0.77551004 -1.88363996 0 P 0 ;0
L 0.77551004 -1.88363996 0.77763002 -1.8808 0 P 0 ;0
L 0.77763002 -1.8808 0.77996004 -1.87813002 0 P 0 ;0
L 0.77996004 -1.87813002 0.78246998 -1.87565 0 P 0 ;0
L 0.78246998 -1.87565 0.78516004 -1.87336004 0 P 0 ;0
L 0.78516004 -1.87336004 0.78795 -1.87133996 0 P 0 ;0
L 0.78795 -1.87133996 0.79088002 -1.86956004 0 P 0 ;0
L 0.79088002 -1.86956004 0.79393996 -1.86803002 0 P 0 ;0
L 0.79393996 -1.86803002 0.79711004 -1.86675 0 P 0 ;0
L 0.79711004 -1.86675 0.80038002 -1.86573002 0 P 0 ;0
L 0.80038002 -1.86573002 0.80431004 -1.86486004 0 P 0 ;0
L 0.80431004 -1.86486004 0.80828996 -1.86433996 0 P 0 ;0
L 0.80828996 -1.86433996 0.8123 -1.86416004 0 P 0 ;0
L 0.8123 -1.86416004 0.81631004 -1.86431998 0 P 0 ;0
L 0.81631004 -1.86431998 0.81946998 -1.86471004 0 P 0 ;0
L 0.81946998 -1.86471004 0.82258996 -1.86531004 0 P 0 ;0
L 0.82258996 -1.86531004 0.82566004 -1.86613996 0 P 0 ;0
L 0.82566004 -1.86613996 0.82866998 -1.86718002 0 P 0 ;0
L 0.82866998 -1.86718002 0.83158996 -1.86843002 0 P 0 ;0
L 0.83158996 -1.86843002 0.83443002 -1.86988996 0 P 0 ;0
L 0.83443002 -1.86988996 0.83716004 -1.87156004 0 P 0 ;0
L 0.83716004 -1.87156004 0.83976004 -1.87341004 0 P 0 ;0
L 0.83976004 -1.87341004 0.84223002 -1.87543996 0 P 0 ;0
L 0.84223002 -1.87543996 0.84453996 -1.87763002 0 P 0 ;0
L 0.84453996 -1.87763002 0.84726998 -1.88065 0 P 0 ;0
L 0.84726998 -1.88065 0.84971998 -1.88388002 0 P 0 ;0
L 0.84971998 -1.88388002 0.85188996 -1.88731004 0 P 0 ;0
L 0.85188996 -1.88731004 0.85376004 -1.89091004 0 P 0 ;0
L 0.85376004 -1.89091004 0.85483996 -1.89345 0 P 0 ;0
L 0.85483996 -1.89345 0.85575 -1.89605 0 P 0 ;0
L 0.85575 -1.89605 0.85646998 -1.89871004 0 P 0 ;0
L 0.85646998 -1.89871004 0.857 -1.90141004 0 P 0 ;0
L 0.857 -1.90141004 0.85748002 -1.9053 0 P 0 ;0
L 0.85748002 -1.9053 0.85763996 -1.90918996 0 P 0 ;0
L 0.85763996 -1.90918996 0.8575 -1.91308002 0 P 0 ;0
L 0.8575 -1.91308002 0.85703996 -1.91696004 0 P 0 ;0
L 0.85703996 -1.91696004 0.85628002 -1.92076004 0 P 0 ;0
L 0.85628002 -1.92076004 0.85521998 -1.92448996 0 P 0 ;0
L 0.85521998 -1.92448996 0.85428002 -1.92705 0 P 0 ;0
L 0.85428002 -1.92705 0.85316998 -1.92951998 0 P 0 ;0
L 0.85316998 -1.92951998 0.85188002 -1.93191004 0 P 0 ;0
L 0.85188002 -1.93191004 0.85041998 -1.9342 0 P 0 ;0
L 0.85041998 -1.9342 0.84826998 -1.93708002 0 P 0 ;0
L 0.84826998 -1.93708002 0.84593002 -1.93976998 0 P 0 ;0
L 0.84593002 -1.93976998 0.8434 -1.94228002 0 P 0 ;0
L 0.8434 -1.94228002 0.84068002 -1.9446 0 P 0 ;0
L 0.84068002 -1.9446 0.8378 -1.9467 0 P 0 ;0
L 0.8378 -1.9467 0.83476998 -1.94858002 0 P 0 ;0
L 0.83476998 -1.94858002 0.83163996 -1.9502 0 P 0 ;0
L 0.83163996 -1.9502 0.8284 -1.95158002 0 P 0 ;0
L 0.8284 -1.95158002 0.82506004 -1.95268996 0 P 0 ;0
L 0.82506004 -1.95268996 0.82163996 -1.95356004 0 P 0 ;0
L 0.82163996 -1.95356004 0.81818002 -1.95413996 0 P 0 ;0
L 0.81818002 -1.95413996 0.8147 -1.95446004 0 P 0 ;0
L 0.8147 -1.95446004 0.81121004 -1.9545 0 P 0 ;0
L 0.77075 -2.02925 0.84511004 -2.02925 0 P 0 ;0
L 0.77076004 -2.02825 0.8452 -2.02825 0 P 0 ;0
L 0.77076998 -2.02725 0.84528996 -2.02725 0 P 0 ;0
L 0.77078002 -2.02625 0.84536998 -2.02625 0 P 0 ;0
L 0.77078996 -2.02525 0.84548996 -2.02525 0 P 0 ;0
L 0.7708 -2.02425 0.84561998 -2.02425 0 P 0 ;0
L 0.77081004 -2.02325 0.84575 -2.02325 0 P 0 ;0
L 0.77081998 -2.02225 0.84588002 -2.02225 0 P 0 ;0
L 0.77083002 -2.02125 0.84601004 -2.02125 0 P 0 ;0
L 0.77083996 -2.02025 0.84613996 -2.02025 0 P 0 ;0
L 0.77085 -2.01925 0.84626004 -2.01925 0 P 0 ;0
L 0.77085 -2.01825 0.84638996 -2.01825 0 P 0 ;0
L 0.77085 -2.01725 0.84651998 -2.01725 0 P 0 ;0
L 0.77086004 -2.01625 0.84663996 -2.01625 0 P 0 ;0
L 0.77086004 -2.01525 0.84676998 -2.01525 0 P 0 ;0
L 0.77086004 -2.01425 0.8469 -2.01425 0 P 0 ;0
L 0.77086004 -2.01325 0.84703002 -2.01325 0 P 0 ;0
L 0.77086004 -2.01225 0.84716004 -2.01225 0 P 0 ;0
L 0.77086004 -2.01125 0.84728996 -2.01125 0 P 0 ;0
L 0.77086004 -2.01025 0.84741004 -2.01025 0 P 0 ;0
L 0.77086998 -2.00925 0.84753996 -2.00925 0 P 0 ;0
L 0.77086998 -2.00825 0.84766998 -2.00825 0 P 0 ;0
L 0.77086998 -2.00725 0.84778996 -2.00725 0 P 0 ;0
L 0.77086998 -2.00625 0.84791998 -2.00625 0 P 0 ;0
L 0.77086998 -2.00525 0.84805 -2.00525 0 P 0 ;0
L 0.77086998 -2.00425 0.84818002 -2.00425 0 P 0 ;0
L 0.77088002 -2.00325 0.84831004 -2.00325 0 P 0 ;0
L 0.77088002 -2.00225 0.84843996 -2.00225 0 P 0 ;0
L 0.77088002 -2.00125 0.84856004 -2.00125 0 P 0 ;0
L 0.77088002 -2.00025 0.84868996 -2.00025 0 P 0 ;0
L 0.77088002 -1.99925 0.84881998 -1.99925 0 P 0 ;0
L 0.77088002 -1.99825 0.84896004 -1.99825 0 P 0 ;0
L 0.77088002 -1.99725 0.84911004 -1.99725 0 P 0 ;0
L 0.77088996 -1.99625 0.84926998 -1.99625 0 P 0 ;0
L 0.77088996 -1.99525 0.84941998 -1.99525 0 P 0 ;0
L 0.77088996 -1.99425 0.84956998 -1.99425 0 P 0 ;0
L 0.77088996 -1.99325 0.84971998 -1.99325 0 P 0 ;0
L 0.77088996 -1.99225 0.84986998 -1.99225 0 P 0 ;0
L 0.77088996 -1.99125 0.85003002 -1.99125 0 P 0 ;0
L 0.7709 -1.99025 0.85018002 -1.99025 0 P 0 ;0
L 0.7709 -1.98925 0.85033002 -1.98925 0 P 0 ;0
L 0.76885 -2.01878002 0.76871998 -2.03201998 0 P 0 ;0
L 0.76871998 -2.03201998 0.7684 -2.04553996 0 P 0 ;0
L 0.7684 -2.04553996 0.76796004 -2.05751004 0 P 0 ;0
L 0.76796004 -2.05751004 0.76741004 -2.06523002 0 P 0 ;0
L 0.76741004 -2.06523002 0.76596004 -2.07933996 0 P 0 ;0
L 0.76596004 -2.07933996 0.7636 -2.09918002 0 P 0 ;0
L 0.7636 -2.09918002 0.76116004 -2.119 0 P 0 ;0
L 0.76116004 -2.119 0.76011998 -2.12526004 0 P 0 ;0
L 0.76011998 -2.12526004 0.75948996 -2.12825 0 P 0 ;0
L 0.75948996 -2.12825 0.84418002 -2.12825 0 P 0 ;0
L 0.84418002 -2.12825 0.84361998 -2.10788002 0 P 0 ;0
L 0.84361998 -2.10788002 0.8436 -2.08276004 0 P 0 ;0
L 0.8436 -2.08276004 0.8449 -2.05491998 0 P 0 ;0
L 0.8449 -2.05491998 0.84736004 -2.02641004 0 P 0 ;0
L 0.84736004 -2.02641004 0.85083996 -1.99923002 0 P 0 ;0
L 0.85083996 -1.99923002 0.85268996 -1.987 0 P 0 ;0
L 0.85268996 -1.987 0.7689 -1.987 0 P 0 ;0
L 0.7689 -1.987 0.76885 -2.01878002 0 P 0 ;0
L 0.76195 -2.12625 0.84211998 -2.12625 0 P 0 ;0
L 0.76213996 -2.12525 0.8421 -2.12525 0 P 0 ;0
L 0.76231004 -2.12425 0.84206998 -2.12425 0 P 0 ;0
L 0.76248002 -2.12325 0.84203996 -2.12325 0 P 0 ;0
L 0.76263996 -2.12225 0.84201004 -2.12225 0 P 0 ;0
L 0.76281004 -2.12125 0.84198996 -2.12125 0 P 0 ;0
L 0.76296998 -2.12025 0.84196004 -2.12025 0 P 0 ;0
L 0.76313996 -2.11925 0.84193002 -2.11925 0 P 0 ;0
L 0.76326998 -2.11825 0.8419 -2.11825 0 P 0 ;0
L 0.76338996 -2.11725 0.84188002 -2.11725 0 P 0 ;0
L 0.76351004 -2.11625 0.84185 -2.11625 0 P 0 ;0
L 0.76363996 -2.11525 0.84181998 -2.11525 0 P 0 ;0
L 0.76376004 -2.11425 0.84178996 -2.11425 0 P 0 ;0
L 0.76388002 -2.11325 0.84176998 -2.11325 0 P 0 ;0
L 0.76401004 -2.11225 0.84173996 -2.11225 0 P 0 ;0
L 0.76413002 -2.11125 0.84171004 -2.11125 0 P 0 ;0
L 0.76425 -2.11025 0.84168002 -2.11025 0 P 0 ;0
L 0.76438002 -2.10925 0.84166004 -2.10925 0 P 0 ;0
L 0.7645 -2.10825 0.84163002 -2.10825 0 P 0 ;0
L 0.76461998 -2.10725 0.84161998 -2.10725 0 P 0 ;0
L 0.76475 -2.10625 0.84161998 -2.10625 0 P 0 ;0
L 0.76486998 -2.10525 0.84161998 -2.10525 0 P 0 ;0
L 0.76498996 -2.10425 0.84161998 -2.10425 0 P 0 ;0
L 0.76511998 -2.10325 0.84161998 -2.10325 0 P 0 ;0
L 0.76523996 -2.10225 0.84161998 -2.10225 0 P 0 ;0
L 0.76536004 -2.10125 0.84161998 -2.10125 0 P 0 ;0
L 0.76548996 -2.10025 0.84161998 -2.10025 0 P 0 ;0
L 0.76561004 -2.09925 0.84161998 -2.09925 0 P 0 ;0
L 0.76573002 -2.09825 0.84161004 -2.09825 0 P 0 ;0
L 0.76583996 -2.09725 0.84161004 -2.09725 0 P 0 ;0
L 0.76596998 -2.09625 0.84161004 -2.09625 0 P 0 ;0
L 0.76608996 -2.09525 0.84161004 -2.09525 0 P 0 ;0
L 0.7662 -2.09425 0.84161004 -2.09425 0 P 0 ;0
L 0.76631998 -2.09325 0.84161004 -2.09325 0 P 0 ;0
L 0.76643996 -2.09225 0.84161004 -2.09225 0 P 0 ;0
L 0.76656004 -2.09125 0.84161004 -2.09125 0 P 0 ;0
L 0.76668002 -2.09025 0.84161004 -2.09025 0 P 0 ;0
L 0.76678996 -2.08925 0.84161004 -2.08925 0 P 0 ;0
L 0.76691998 -2.08825 0.84161004 -2.08825 0 P 0 ;0
L 0.76703002 -2.08725 0.84161004 -2.08725 0 P 0 ;0
L 0.76715 -2.08625 0.8416 -2.08625 0 P 0 ;0
L 0.76726998 -2.08525 0.8416 -2.08525 0 P 0 ;0
L 0.76738996 -2.08425 0.8416 -2.08425 0 P 0 ;0
L 0.76195 -2.12625 0.76208002 -2.12561998 0 P 0 ;0
L 0.76208002 -2.12561998 0.76313996 -2.11928996 0 P 0 ;0
L 0.76313996 -2.11928996 0.76558996 -2.09941998 0 P 0 ;0
L 0.76558996 -2.09941998 0.76558996 -2.09941004 0 P 0 ;0
L 0.76558996 -2.09941004 0.76793996 -2.07956004 0 P 0 ;0
L 0.76793996 -2.07956004 0.7694 -2.0654 0 P 0 ;0
L 0.7694 -2.0654 0.76941004 -2.06536004 0 P 0 ;0
L 0.76941004 -2.06536004 0.76996004 -2.05761998 0 P 0 ;0
L 0.76996004 -2.05761998 0.76996004 -2.05758996 0 P 0 ;0
L 0.76996004 -2.05758996 0.7704 -2.0456 0 P 0 ;0
L 0.7704 -2.0456 0.77071998 -2.03206004 0 P 0 ;0
L 0.77071998 -2.03206004 0.77085 -2.01878002 0 P 0 ;0
L 0.77085 -2.01878002 0.7709 -1.989 0 P 0 ;0
L 0.7709 -1.989 0.85036004 -1.989 0 P 0 ;0
L 0.85036004 -1.989 0.84886004 -1.99895 0 P 0 ;0
L 0.84886004 -1.99895 0.84538002 -2.02618996 0 P 0 ;0
L 0.84538002 -2.02618996 0.8429 -2.05478996 0 P 0 ;0
L 0.8429 -2.05478996 0.8416 -2.08271004 0 P 0 ;0
L 0.8416 -2.08271004 0.84161998 -2.10791004 0 P 0 ;0
L 0.84161998 -2.10791004 0.84211998 -2.12625 0 P 0 ;0
L 0.84211998 -2.12625 0.76195 -2.12625 0 P 0 ;0
L 0.71628996 -1.91261998 0.74938002 -1.91261998 0 P 0 ;0
L 0.71783002 -1.91161998 0.74933002 -1.91161998 0 P 0 ;0
L 0.71953002 -1.91061998 0.74931004 -1.91061998 0 P 0 ;0
L 0.72133002 -1.90961998 0.74928996 -1.90961998 0 P 0 ;0
L 0.72313996 -1.90861998 0.74926998 -1.90861998 0 P 0 ;0
L 0.72493996 -1.90761998 0.74928996 -1.90761998 0 P 0 ;0
L 0.72673996 -1.90661998 0.74931998 -1.90661998 0 P 0 ;0
L 0.72855 -1.90561998 0.74935 -1.90561998 0 P 0 ;0
L 0.73035 -1.90461998 0.74938996 -1.90461998 0 P 0 ;0
L 0.73215 -1.90361998 0.74946998 -1.90361998 0 P 0 ;0
L 0.73396004 -1.90261998 0.74953996 -1.90261998 0 P 0 ;0
L 0.73576004 -1.90161998 0.74961998 -1.90161998 0 P 0 ;0
L 0.73756998 -1.90061998 0.74973996 -1.90061998 0 P 0 ;0
L 0.73943002 -1.89961998 0.74986004 -1.89961998 0 P 0 ;0
L 0.74141998 -1.89861998 0.74998996 -1.89861998 0 P 0 ;0
L 0.74341004 -1.89761998 0.75015 -1.89761998 0 P 0 ;0
L 0.59843002 -2.08361998 0.6754 -2.08361998 0 P 0 ;0
L 0.59846004 -2.08261998 0.67538996 -2.08261998 0 P 0 ;0
L 0.59848002 -2.08161998 0.67538002 -2.08161998 0 P 0 ;0
L 0.59851004 -2.08061998 0.67538002 -2.08061998 0 P 0 ;0
L 0.59853002 -2.07961998 0.67546004 -2.07961998 0 P 0 ;0
L 0.59856004 -2.07861998 0.67553996 -2.07861998 0 P 0 ;0
L 0.59861998 -2.07761998 0.67561004 -2.07761998 0 P 0 ;0
L 0.5987 -2.07661998 0.67568996 -2.07661998 0 P 0 ;0
L 0.59878002 -2.07561998 0.67576004 -2.07561998 0 P 0 ;0
L 0.59885 -2.07461998 0.67583996 -2.07461998 0 P 0 ;0
L 0.59893002 -2.07361998 0.67591998 -2.07361998 0 P 0 ;0
L 0.59901004 -2.07261998 0.67598996 -2.07261998 0 P 0 ;0
L 0.59908002 -2.07161998 0.67606998 -2.07161998 0 P 0 ;0
L 0.59916004 -2.07061998 0.67613996 -2.07061998 0 P 0 ;0
L 0.59923002 -2.06961998 0.67621004 -2.06961998 0 P 0 ;0
L 0.59936004 -2.06861998 0.6763 -2.06861998 0 P 0 ;0
L 0.59948996 -2.06761998 0.67645 -2.06761998 0 P 0 ;0
L 0.59963002 -2.06661998 0.6766 -2.06661998 0 P 0 ;0
L 0.59976998 -2.06561998 0.67676004 -2.06561998 0 P 0 ;0
L 0.5999 -2.06461998 0.67691998 -2.06461998 0 P 0 ;0
L 0.60003002 -2.06361998 0.67706998 -2.06361998 0 P 0 ;0
L 0.60016998 -2.06261998 0.6773 -2.06261998 0 P 0 ;0
L 0.60031004 -2.06161998 0.67753002 -2.06161998 0 P 0 ;0
L 0.60051004 -2.06061998 0.67776004 -2.06061998 0 P 0 ;0
L 0.60071004 -2.05961998 0.67798996 -2.05961998 0 P 0 ;0
L 0.60091998 -2.05861998 0.67823002 -2.05861998 0 P 0 ;0
L 0.60111998 -2.05761998 0.67853002 -2.05761998 0 P 0 ;0
L 0.60133002 -2.05661998 0.67883996 -2.05661998 0 P 0 ;0
L 0.60153996 -2.05561998 0.67913996 -2.05561998 0 P 0 ;0
L 0.60173996 -2.05461998 0.67945 -2.05461998 0 P 0 ;0
L 0.60195 -2.05361998 0.67975 -2.05361998 0 P 0 ;0
L 0.60223002 -2.05261998 0.68006004 -2.05261998 0 P 0 ;0
L 0.60251004 -2.05161998 0.68036004 -2.05161998 0 P 0 ;0
L 0.60278996 -2.05061998 0.68066998 -2.05061998 0 P 0 ;0
L 0.60306004 -2.04961998 0.68096998 -2.04961998 0 P 0 ;0
L 0.60333996 -2.04861998 0.68135 -2.04861998 0 P 0 ;0
L 0.60361998 -2.04761998 0.68173002 -2.04761998 0 P 0 ;0
L 0.6039 -2.04661998 0.68211004 -2.04661998 0 P 0 ;0
L 0.60418002 -2.04561998 0.68248996 -2.04561998 0 P 0 ;0
L 0.60453002 -2.04461998 0.68288002 -2.04461998 0 P 0 ;0
L 0.60488002 -2.04361998 0.68326004 -2.04361998 0 P 0 ;0
L 0.60523002 -2.04261998 0.68363996 -2.04261998 0 P 0 ;0
L 0.60556998 -2.04161998 0.68401998 -2.04161998 0 P 0 ;0
L 0.60591998 -2.04061998 0.6844 -2.04061998 0 P 0 ;0
L 0.60626998 -2.03961998 0.68486004 -2.03961998 0 P 0 ;0
L 0.60661998 -2.03861998 0.68531998 -2.03861998 0 P 0 ;0
L 0.60698996 -2.03761998 0.68578002 -2.03761998 0 P 0 ;0
L 0.60743002 -2.03661998 0.68623996 -2.03661998 0 P 0 ;0
L 0.60786004 -2.03561998 0.6867 -2.03561998 0 P 0 ;0
L 0.60828996 -2.03461998 0.68716004 -2.03461998 0 P 0 ;0
L 0.60873002 -2.03361998 0.68761998 -2.03361998 0 P 0 ;0
L 0.60916004 -2.03261998 0.68808996 -2.03261998 0 P 0 ;0
L 0.60958996 -2.03161998 0.68856998 -2.03161998 0 P 0 ;0
L 0.61003002 -2.03061998 0.68911004 -2.03061998 0 P 0 ;0
L 0.61046004 -2.02961998 0.68965 -2.02961998 0 P 0 ;0
L 0.61088996 -2.02861998 0.69018996 -2.02861998 0 P 0 ;0
L 0.61133002 -2.02761998 0.69073002 -2.02761998 0 P 0 ;0
L 0.61176004 -2.02661998 0.69126998 -2.02661998 0 P 0 ;0
L 0.6122 -2.02561998 0.69181004 -2.02561998 0 P 0 ;0
L 0.61263002 -2.02461998 0.69235 -2.02461998 0 P 0 ;0
L 0.61306004 -2.02361998 0.69288002 -2.02361998 0 P 0 ;0
L 0.61348996 -2.02261998 0.69346998 -2.02261998 0 P 0 ;0
L 0.61393002 -2.02161998 0.69408996 -2.02161998 0 P 0 ;0
L 0.61436004 -2.02061998 0.6947 -2.02061998 0 P 0 ;0
L 0.61478996 -2.01961998 0.69531998 -2.01961998 0 P 0 ;0
L 0.61531004 -2.01861998 0.69593996 -2.01861998 0 P 0 ;0
L 0.61583996 -2.01761998 0.69656004 -2.01761998 0 P 0 ;0
L 0.61636004 -2.01661998 0.69718002 -2.01661998 0 P 0 ;0
L 0.61688002 -2.01561998 0.69778996 -2.01561998 0 P 0 ;0
L 0.6174 -2.01461998 0.69841998 -2.01461998 0 P 0 ;0
L 0.61791998 -2.01361998 0.69911998 -2.01361998 0 P 0 ;0
L 0.61843996 -2.01261998 0.69981998 -2.01261998 0 P 0 ;0
L 0.61896004 -2.01161998 0.70051998 -2.01161998 0 P 0 ;0
L 0.61948002 -2.01061998 0.70123002 -2.01061998 0 P 0 ;0
L 0.62 -2.00961998 0.70193002 -2.00961998 0 P 0 ;0
L 0.62051998 -2.00861998 0.70263002 -2.00861998 0 P 0 ;0
L 0.62103996 -2.00761998 0.70333002 -2.00761998 0 P 0 ;0
L 0.62163996 -2.00661998 0.70403996 -2.00661998 0 P 0 ;0
L 0.62225 -2.00561998 0.70483002 -2.00561998 0 P 0 ;0
L 0.62285 -2.00461998 0.70565 -2.00461998 0 P 0 ;0
L 0.62346004 -2.00361998 0.70646004 -2.00361998 0 P 0 ;0
L 0.62406004 -2.00261998 0.70726998 -2.00261998 0 P 0 ;0
L 0.62466004 -2.00161998 0.70808996 -2.00161998 0 P 0 ;0
L 0.62526998 -2.00061998 0.7089 -2.00061998 0 P 0 ;0
L 0.62586998 -1.99961998 0.70971004 -1.99961998 0 P 0 ;0
L 0.62648002 -1.99861998 0.71053002 -1.99861998 0 P 0 ;0
L 0.62708002 -1.99761998 0.71133996 -1.99761998 0 P 0 ;0
L 0.62768996 -1.99661998 0.71216004 -1.99661998 0 P 0 ;0
L 0.62831998 -1.99561998 0.71296998 -1.99561998 0 P 0 ;0
L 0.62901004 -1.99461998 0.71378996 -1.99461998 0 P 0 ;0
L 0.62971004 -1.99361998 0.71466004 -1.99361998 0 P 0 ;0
L 0.6304 -1.99261998 0.71561004 -1.99261998 0 P 0 ;0
L 0.6311 -1.99161998 0.71656998 -1.99161998 0 P 0 ;0
L 0.63178996 -1.99061998 0.71753002 -1.99061998 0 P 0 ;0
L 0.63248996 -1.98961998 0.71848996 -1.98961998 0 P 0 ;0
L 0.63318002 -1.98861998 0.71945 -1.98861998 0 P 0 ;0
L 0.63388002 -1.98761998 0.72041004 -1.98761998 0 P 0 ;0
L 0.63456998 -1.98661998 0.72136998 -1.98661998 0 P 0 ;0
L 0.63526998 -1.98561998 0.72233002 -1.98561998 0 P 0 ;0
L 0.63598002 -1.98461998 0.72328996 -1.98461998 0 P 0 ;0
L 0.63678996 -1.98361998 0.72425 -1.98361998 0 P 0 ;0
L 0.6376 -1.98261998 0.72521004 -1.98261998 0 P 0 ;0
L 0.63841004 -1.98161998 0.72628002 -1.98161998 0 P 0 ;0
L 0.63921998 -1.98061998 0.72738996 -1.98061998 0 P 0 ;0
L 0.64003002 -1.97961998 0.7285 -1.97961998 0 P 0 ;0
L 0.64083996 -1.97861998 0.72961004 -1.97861998 0 P 0 ;0
L 0.64165 -1.97761998 0.73071004 -1.97761998 0 P 0 ;0
L 0.64246004 -1.97661998 0.73181998 -1.97661998 0 P 0 ;0
L 0.64326998 -1.97561998 0.73293002 -1.97561998 0 P 0 ;0
L 0.64406998 -1.97461998 0.73403996 -1.97461998 0 P 0 ;0
L 0.64488002 -1.97361998 0.73515 -1.97361998 0 P 0 ;0
L 0.64568996 -1.97261998 0.73625 -1.97261998 0 P 0 ;0
L 0.6465 -1.97161998 0.73736004 -1.97161998 0 P 0 ;0
L 0.64731004 -1.97061998 0.73848002 -1.97061998 0 P 0 ;0
L 0.64811998 -1.96961998 0.73973002 -1.96961998 0 P 0 ;0
L 0.64893002 -1.96861998 0.74098996 -1.96861998 0 P 0 ;0
L 0.64981004 -1.96761998 0.74225 -1.96761998 0 P 0 ;0
L 0.65076004 -1.96661998 0.74351004 -1.96661998 0 P 0 ;0
L 0.65171004 -1.96561998 0.74476998 -1.96561998 0 P 0 ;0
L 0.65266998 -1.96461998 0.74603002 -1.96461998 0 P 0 ;0
L 0.65361998 -1.96361998 0.74728996 -1.96361998 0 P 0 ;0
L 0.65458002 -1.96261998 0.74855 -1.96261998 0 P 0 ;0
L 0.65553002 -1.96161998 0.74981004 -1.96161998 0 P 0 ;0
L 0.65648996 -1.96061998 0.75106004 -1.96061998 0 P 0 ;0
L 0.65743996 -1.95961998 0.75233996 -1.95961998 0 P 0 ;0
L 0.6584 -1.95861998 0.7537 -1.95861998 0 P 0 ;0
L 0.65935 -1.95761998 0.75506004 -1.95761998 0 P 0 ;0
L 0.66031004 -1.95661998 0.75641998 -1.95661998 0 P 0 ;0
L 0.66126004 -1.95561998 0.75778996 -1.95561998 0 P 0 ;0
L 0.66221004 -1.95461998 0.75916004 -1.95461998 0 P 0 ;0
L 0.66316998 -1.95361998 0.76053996 -1.95361998 0 P 0 ;0
L 0.66411998 -1.95261998 0.76193996 -1.95261998 0 P 0 ;0
L 0.66523002 -1.95161998 0.76333996 -1.95161998 0 P 0 ;0
L 0.66636004 -1.95061998 0.76406998 -1.95061998 0 P 0 ;0
L 0.66746998 -1.94961998 0.76355 -1.94961998 0 P 0 ;0
L 0.6686 -1.94861998 0.76291998 -1.94861998 0 P 0 ;0
L 0.66971004 -1.94761998 0.76226998 -1.94761998 0 P 0 ;0
L 0.67083996 -1.94661998 0.76161998 -1.94661998 0 P 0 ;0
L 0.67196004 -1.94561998 0.76096998 -1.94561998 0 P 0 ;0
L 0.67306998 -1.94461998 0.76033002 -1.94461998 0 P 0 ;0
L 0.6742 -1.94361998 0.75968996 -1.94361998 0 P 0 ;0
L 0.67531004 -1.94261998 0.75905 -1.94261998 0 P 0 ;0
L 0.67643996 -1.94161998 0.75846004 -1.94161998 0 P 0 ;0
L 0.67755 -1.94061998 0.75788996 -1.94061998 0 P 0 ;0
L 0.67868002 -1.93961998 0.75731998 -1.93961998 0 P 0 ;0
L 0.67978996 -1.93861998 0.75676998 -1.93861998 0 P 0 ;0
L 0.68091998 -1.93761998 0.75626998 -1.93761998 0 P 0 ;0
L 0.68221004 -1.93661998 0.75576998 -1.93661998 0 P 0 ;0
L 0.68353002 -1.93561998 0.75528002 -1.93561998 0 P 0 ;0
L 0.68483996 -1.93461998 0.75483996 -1.93461998 0 P 0 ;0
L 0.68616004 -1.93361998 0.75441004 -1.93361998 0 P 0 ;0
L 0.68746998 -1.93261998 0.75398002 -1.93261998 0 P 0 ;0
L 0.68878002 -1.93161998 0.7536 -1.93161998 0 P 0 ;0
L 0.6901 -1.93061998 0.75323996 -1.93061998 0 P 0 ;0
L 0.69141004 -1.92961998 0.75286998 -1.92961998 0 P 0 ;0
L 0.69271998 -1.92861998 0.75253996 -1.92861998 0 P 0 ;0
L 0.69403002 -1.92761998 0.75223002 -1.92761998 0 P 0 ;0
L 0.69535 -1.92661998 0.75193002 -1.92661998 0 P 0 ;0
L 0.69666004 -1.92561998 0.75163002 -1.92561998 0 P 0 ;0
L 0.69796998 -1.92461998 0.75138002 -1.92461998 0 P 0 ;0
L 0.69936998 -1.92361998 0.75113996 -1.92361998 0 P 0 ;0
L 0.70091004 -1.92261998 0.75088996 -1.92261998 0 P 0 ;0
L 0.70243996 -1.92161998 0.75066004 -1.92161998 0 P 0 ;0
L 0.70398002 -1.92061998 0.75046004 -1.92061998 0 P 0 ;0
L 0.70551998 -1.91961998 0.75026004 -1.91961998 0 P 0 ;0
L 0.70706004 -1.91861998 0.75006998 -1.91861998 0 P 0 ;0
L 0.7086 -1.91761998 0.7499 -1.91761998 0 P 0 ;0
L 0.71013996 -1.91661998 0.74976998 -1.91661998 0 P 0 ;0
L 0.71166998 -1.91561998 0.74961998 -1.91561998 0 P 0 ;0
L 0.71321004 -1.91461998 0.74951998 -1.91461998 0 P 0 ;0
L 0.71475 -1.91361998 0.74945 -1.91361998 0 P 0 ;0
L 0.61556998 -2.15661998 0.70655 -2.15661998 0 P 0 ;0
L 0.61503002 -2.15561998 0.7056 -2.15561998 0 P 0 ;0
L 0.61448996 -2.15461998 0.70465 -2.15461998 0 P 0 ;0
L 0.61395 -2.15361998 0.7037 -2.15361998 0 P 0 ;0
L 0.61341004 -2.15261998 0.70273996 -2.15261998 0 P 0 ;0
L 0.61286998 -2.15161998 0.70178996 -2.15161998 0 P 0 ;0
L 0.61233002 -2.15061998 0.70095 -2.15061998 0 P 0 ;0
L 0.61188002 -2.14961998 0.70015 -2.14961998 0 P 0 ;0
L 0.61143002 -2.14861998 0.69935 -2.14861998 0 P 0 ;0
L 0.61098002 -2.14761998 0.69855 -2.14761998 0 P 0 ;0
L 0.61053002 -2.14661998 0.69775 -2.14661998 0 P 0 ;0
L 0.61008002 -2.14561998 0.69695 -2.14561998 0 P 0 ;0
L 0.60963002 -2.14461998 0.69615 -2.14461998 0 P 0 ;0
L 0.60918002 -2.14361998 0.69535 -2.14361998 0 P 0 ;0
L 0.60873002 -2.14261998 0.69455 -2.14261998 0 P 0 ;0
L 0.60831004 -2.14161998 0.69381998 -2.14161998 0 P 0 ;0
L 0.60793996 -2.14061998 0.69315 -2.14061998 0 P 0 ;0
L 0.60756998 -2.13961998 0.69248002 -2.13961998 0 P 0 ;0
L 0.60721004 -2.13861998 0.69181004 -2.13861998 0 P 0 ;0
L 0.60683996 -2.13761998 0.69115 -2.13761998 0 P 0 ;0
L 0.60646998 -2.13661998 0.69048002 -2.13661998 0 P 0 ;0
L 0.60611004 -2.13561998 0.68981004 -2.13561998 0 P 0 ;0
L 0.60573996 -2.13461998 0.68918002 -2.13461998 0 P 0 ;0
L 0.60538002 -2.13361998 0.68863002 -2.13361998 0 P 0 ;0
L 0.60503996 -2.13261998 0.68808002 -2.13261998 0 P 0 ;0
L 0.60476004 -2.13161998 0.68753002 -2.13161998 0 P 0 ;0
L 0.60446998 -2.13061998 0.68698002 -2.13061998 0 P 0 ;0
L 0.60418002 -2.12961998 0.68643002 -2.12961998 0 P 0 ;0
L 0.6039 -2.12861998 0.68588002 -2.12861998 0 P 0 ;0
L 0.60361004 -2.12761998 0.68533002 -2.12761998 0 P 0 ;0
L 0.60331998 -2.12661998 0.68486004 -2.12661998 0 P 0 ;0
L 0.60303002 -2.12561998 0.68441998 -2.12561998 0 P 0 ;0
L 0.60275 -2.12461998 0.68396998 -2.12461998 0 P 0 ;0
L 0.60246004 -2.12361998 0.68353002 -2.12361998 0 P 0 ;0
L 0.60218002 -2.12261998 0.68308996 -2.12261998 0 P 0 ;0
L 0.60188996 -2.12161998 0.68263996 -2.12161998 0 P 0 ;0
L 0.60166998 -2.12061998 0.6822 -2.12061998 0 P 0 ;0
L 0.60145 -2.11961998 0.68176004 -2.11961998 0 P 0 ;0
L 0.60123002 -2.11861998 0.68138996 -2.11861998 0 P 0 ;0
L 0.60101004 -2.11761998 0.68105 -2.11761998 0 P 0 ;0
L 0.60078002 -2.11661998 0.68071004 -2.11661998 0 P 0 ;0
L 0.6006 -2.11561998 0.68036004 -2.11561998 0 P 0 ;0
L 0.60043002 -2.11461998 0.68001998 -2.11461998 0 P 0 ;0
L 0.60025 -2.11361998 0.67968002 -2.11361998 0 P 0 ;0
L 0.60008002 -2.11261998 0.67933002 -2.11261998 0 P 0 ;0
L 0.59991004 -2.11161998 0.67898996 -2.11161998 0 P 0 ;0
L 0.59976004 -2.11061998 0.6787 -2.11061998 0 P 0 ;0
L 0.59963996 -2.10961998 0.67845 -2.10961998 0 P 0 ;0
L 0.59951004 -2.10861998 0.6782 -2.10861998 0 P 0 ;0
L 0.59938002 -2.10761998 0.67795 -2.10761998 0 P 0 ;0
L 0.59925 -2.10661998 0.6777 -2.10661998 0 P 0 ;0
L 0.59913002 -2.10561998 0.67746004 -2.10561998 0 P 0 ;0
L 0.59905 -2.10461998 0.67721004 -2.10461998 0 P 0 ;0
L 0.59896998 -2.10361998 0.67696004 -2.10361998 0 P 0 ;0
L 0.59888002 -2.10261998 0.67671004 -2.10261998 0 P 0 ;0
L 0.5988 -2.10161998 0.67653996 -2.10161998 0 P 0 ;0
L 0.59871998 -2.10061998 0.67638002 -2.10061998 0 P 0 ;0
L 0.59866998 -2.09961998 0.67621004 -2.09961998 0 P 0 ;0
L 0.59863996 -2.09861998 0.67605 -2.09861998 0 P 0 ;0
L 0.59861004 -2.09761998 0.67588996 -2.09761998 0 P 0 ;0
L 0.59858996 -2.09661998 0.6758 -2.09661998 0 P 0 ;0
L 0.59856004 -2.09561998 0.67571004 -2.09561998 0 P 0 ;0
L 0.59853002 -2.09461998 0.67563002 -2.09461998 0 P 0 ;0
L 0.5985 -2.09361998 0.67553996 -2.09361998 0 P 0 ;0
L 0.59846998 -2.09261998 0.67546004 -2.09261998 0 P 0 ;0
L 0.59843996 -2.09161998 0.67546004 -2.09161998 0 P 0 ;0
L 0.59841998 -2.09061998 0.67545 -2.09061998 0 P 0 ;0
L 0.59838002 -2.08961998 0.67543996 -2.08961998 0 P 0 ;0
L 0.59836004 -2.08861998 0.67543002 -2.08861998 0 P 0 ;0
L 0.59833002 -2.08761998 0.67543002 -2.08761998 0 P 0 ;0
L 0.59835 -2.08661998 0.67541998 -2.08661998 0 P 0 ;0
L 0.59836998 -2.08561998 0.67541004 -2.08561998 0 P 0 ;0
L 0.5984 -2.08461998 0.67541004 -2.08461998 0 P 0 ;0
L 0.80005 -2.25161998 0.85543996 -2.25161998 0 P 0 ;0
L 0.78651998 -2.25061998 0.86596004 -2.25061998 0 P 0 ;0
L 0.77878996 -2.24961998 0.87636004 -2.24961998 0 P 0 ;0
L 0.77106004 -2.24861998 0.88285 -2.24861998 0 P 0 ;0
L 0.76398996 -2.24761998 0.88933996 -2.24761998 0 P 0 ;0
L 0.75891998 -2.24661998 0.89583996 -2.24661998 0 P 0 ;0
L 0.73781004 -1.8982 0.71738996 -1.90951998 0 P 0 ;0
L 0.71738996 -1.90951998 0.69766998 -1.92233996 0 P 0 ;0
L 0.69766998 -1.92233996 0.67971004 -1.93601998 0 P 0 ;0
L 0.67971004 -1.93601998 0.66278996 -1.95113002 0 P 0 ;0
L 0.66278996 -1.95113002 0.64786998 -1.96675 0 P 0 ;0
L 0.64786998 -1.96675 0.63423996 -1.98358996 0 P 0 ;0
L 0.63423996 -1.98358996 0.62643996 -1.99483002 0 P 0 ;0
L 0.62643996 -1.99483002 0.61933996 -2.00655 0 P 0 ;0
L 0.61933996 -2.00655 0.61298996 -2.01873996 0 P 0 ;0
L 0.61298996 -2.01873996 0.60503002 -2.03713002 0 P 0 ;0
L 0.60503002 -2.03713002 0.60225 -2.04506004 0 P 0 ;0
L 0.60225 -2.04506004 0.59998996 -2.05323002 0 P 0 ;0
L 0.59998996 -2.05323002 0.59833996 -2.0612 0 P 0 ;0
L 0.59833996 -2.0612 0.59725 -2.06928996 0 P 0 ;0
L 0.59725 -2.06928996 0.59656998 -2.07833996 0 P 0 ;0
L 0.59656998 -2.07833996 0.59633002 -2.0875 0 P 0 ;0
L 0.59633002 -2.0875 0.59668996 -2.10036998 0 P 0 ;0
L 0.59668996 -2.10036998 0.59715 -2.10596004 0 P 0 ;0
L 0.59715 -2.10596004 0.59786004 -2.11151004 0 P 0 ;0
L 0.59786004 -2.11151004 0.59878996 -2.11686998 0 P 0 ;0
L 0.59878996 -2.11686998 0.59996998 -2.1222 0 P 0 ;0
L 0.59996998 -2.1222 0.60326998 -2.13368996 0 P 0 ;0
L 0.60326998 -2.13368996 0.60656998 -2.1427 0 P 0 ;0
L 0.60656998 -2.1427 0.6105 -2.15143996 0 P 0 ;0
L 0.6105 -2.15143996 0.61505 -2.15988002 0 P 0 ;0
L 0.61505 -2.15988002 0.62023996 -2.16803996 0 P 0 ;0
L 0.62023996 -2.16803996 0.62828996 -2.17873002 0 P 0 ;0
L 0.62828996 -2.17873002 0.63718996 -2.18871004 0 P 0 ;0
L 0.63718996 -2.18871004 0.64693002 -2.19795 0 P 0 ;0
L 0.64693002 -2.19795 0.6582 -2.20701998 0 P 0 ;0
L 0.6582 -2.20701998 0.67011004 -2.21518996 0 P 0 ;0
L 0.67011004 -2.21518996 0.68261004 -2.22243002 0 P 0 ;0
L 0.68261004 -2.22243002 0.69673996 -2.22936004 0 P 0 ;0
L 0.69673996 -2.22936004 0.71123002 -2.23543996 0 P 0 ;0
L 0.71123002 -2.23543996 0.72611998 -2.24066998 0 P 0 ;0
L 0.72611998 -2.24066998 0.74536004 -2.24598996 0 P 0 ;0
L 0.74536004 -2.24598996 0.76493002 -2.24985 0 P 0 ;0
L 0.76493002 -2.24985 0.78671998 -2.25266998 0 P 0 ;0
L 0.78671998 -2.25266998 0.80863002 -2.25425 0 P 0 ;0
L 0.80863002 -2.25425 0.83146004 -2.25463002 0 P 0 ;0
L 0.83146004 -2.25463002 0.85418002 -2.25375 0 P 0 ;0
L 0.85418002 -2.25375 0.87641004 -2.25163996 0 P 0 ;0
L 0.87641004 -2.25163996 0.89853002 -2.24823002 0 P 0 ;0
L 0.89853002 -2.24823002 0.93045 -2.24101998 0 P 0 ;0
L 0.93045 -2.24101998 0.96466004 -2.23063002 0 P 0 ;0
L 0.96466004 -2.23063002 0.99911004 -2.2178 0 P 0 ;0
L 0.99911004 -2.2178 1.03183002 -2.20318002 0 P 0 ;0
L 1.03183002 -2.20318002 1.04391998 -2.19703002 0 P 0 ;0
L 1.04391998 -2.19703002 1.05581004 -2.19048996 0 P 0 ;0
L 1.05581004 -2.19048996 1.06676004 -2.18411998 0 P 0 ;0
L 1.06676004 -2.18411998 1.06681004 -2.18408996 0 P 0 ;0
L 1.06681004 -2.18408996 1.06685 -2.18405 0 P 0 ;0
L 1.06685 -2.18405 1.0669 -2.18401004 0 P 0 ;0
L 1.0669 -2.18401004 1.06693996 -2.18396998 0 P 0 ;0
L 1.06693996 -2.18396998 1.06696998 -2.18391998 0 P 0 ;0
L 1.06696998 -2.18391998 1.06701004 -2.18386998 0 P 0 ;0
L 1.06701004 -2.18386998 1.06703002 -2.18381998 0 P 0 ;0
L 1.06703002 -2.18381998 1.06706004 -2.18376004 0 P 0 ;0
L 1.06706004 -2.18376004 1.06706998 -2.18371004 0 P 0 ;0
L 1.06706998 -2.18371004 1.06708996 -2.18365 0 P 0 ;0
L 1.06708996 -2.18365 1.06708996 -2.18358996 0 P 0 ;0
L 1.06708996 -2.18358996 1.0671 -2.18353002 0 P 0 ;0
L 1.0671 -2.18353002 1.0671 -2.18346998 0 P 0 ;0
L 1.0671 -2.18346998 1.06708996 -2.18341004 0 P 0 ;0
L 1.06708996 -2.18341004 1.06706998 -2.18336004 0 P 0 ;0
L 1.06706998 -2.18336004 1.06706004 -2.1833 0 P 0 ;0
L 1.06706004 -2.1833 1.06703002 -2.18323996 0 P 0 ;0
L 1.06703002 -2.18323996 1.06701004 -2.18318996 0 P 0 ;0
L 1.06701004 -2.18318996 1.06696998 -2.18313996 0 P 0 ;0
L 1.06696998 -2.18313996 1.06693996 -2.18308996 0 P 0 ;0
L 1.06693996 -2.18308996 1.06688002 -2.18303002 0 P 0 ;0
L 1.06688002 -2.18303002 1.06678996 -2.18296998 0 P 0 ;0
L 1.06678996 -2.18296998 1.06673002 -2.18295 0 P 0 ;0
L 1.06673002 -2.18295 1.0667 -2.18295 0 P 0 ;0
L 1.0667 -2.18295 1.06666004 -2.18293996 0 P 0 ;0
L 1.06666004 -2.18293996 1.0666 -2.18293996 0 P 0 ;0
L 1.0666 -2.18293996 1.06656998 -2.18295 0 P 0 ;0
L 1.06656998 -2.18295 1.06653002 -2.18295 0 P 0 ;0
L 1.06653002 -2.18295 1.06153002 -2.1842 0 P 0 ;0
L 1.06153002 -2.1842 1.05583996 -2.18566998 0 P 0 ;0
L 1.05583996 -2.18566998 1.04916998 -2.1875 0 P 0 ;0
L 1.04916998 -2.1875 1.0153 -2.1962 0 P 0 ;0
L 1.0153 -2.1962 0.9814 -2.20333996 0 P 0 ;0
L 0.9814 -2.20333996 0.94881998 -2.2087 0 P 0 ;0
L 0.94881998 -2.2087 0.9189 -2.21198996 0 P 0 ;0
L 0.9189 -2.21198996 0.90113996 -2.21278996 0 P 0 ;0
L 0.90113996 -2.21278996 0.87738002 -2.21265 0 P 0 ;0
L 0.87738002 -2.21265 0.854 -2.21183002 0 P 0 ;0
L 0.854 -2.21183002 0.83788996 -2.21033996 0 P 0 ;0
L 0.83788996 -2.21033996 0.8174 -2.20693002 0 P 0 ;0
L 0.8174 -2.20693002 0.79708996 -2.2023 0 P 0 ;0
L 0.79708996 -2.2023 0.7769 -2.19641004 0 P 0 ;0
L 0.7769 -2.19641004 0.76433002 -2.19183996 0 P 0 ;0
L 0.76433002 -2.19183996 0.75208996 -2.18638002 0 P 0 ;0
L 0.75208996 -2.18638002 0.74026998 -2.18006998 0 P 0 ;0
L 0.74026998 -2.18006998 0.72886998 -2.17291004 0 P 0 ;0
L 0.72886998 -2.17291004 0.71961998 -2.16603002 0 P 0 ;0
L 0.71961998 -2.16603002 0.71098996 -2.15838996 0 P 0 ;0
L 0.71098996 -2.15838996 0.70303002 -2.15003002 0 P 0 ;0
L 0.70303002 -2.15003002 0.6958 -2.14098996 0 P 0 ;0
L 0.6958 -2.14098996 0.69106998 -2.1339 0 P 0 ;0
L 0.69106998 -2.1339 0.68696004 -2.12643002 0 P 0 ;0
L 0.68696004 -2.12643002 0.68351004 -2.11863002 0 P 0 ;0
L 0.68351004 -2.11863002 0.68073996 -2.11056004 0 P 0 ;0
L 0.68073996 -2.11056004 0.67866004 -2.10218996 0 P 0 ;0
L 0.67866004 -2.10218996 0.67788002 -2.09741998 0 P 0 ;0
L 0.67788002 -2.09741998 0.67746004 -2.0926 0 P 0 ;0
L 0.67746004 -2.0926 0.67738002 -2.08076004 0 P 0 ;0
L 0.67738002 -2.08076004 0.67828002 -2.06891004 0 P 0 ;0
L 0.67828002 -2.06891004 0.67903002 -2.06403996 0 P 0 ;0
L 0.67903002 -2.06403996 0.68013002 -2.05923996 0 P 0 ;0
L 0.68013002 -2.05923996 0.68288002 -2.05021998 0 P 0 ;0
L 0.68288002 -2.05021998 0.68623996 -2.04141004 0 P 0 ;0
L 0.68623996 -2.04141004 0.69018002 -2.03286004 0 P 0 ;0
L 0.69018002 -2.03286004 0.69486004 -2.02418002 0 P 0 ;0
L 0.69486004 -2.02418002 0.70003996 -2.0158 0 P 0 ;0
L 0.70003996 -2.0158 0.70573002 -2.00768996 0 P 0 ;0
L 0.70573002 -2.00768996 0.7158 -1.99531998 0 P 0 ;0
L 0.7158 -1.99531998 0.72681004 -1.98385 0 P 0 ;0
L 0.72681004 -1.98385 0.73971004 -1.9722 0 P 0 ;0
L 0.73971004 -1.9722 0.7533 -1.9614 0 P 0 ;0
L 0.7533 -1.9614 0.75753996 -1.95828002 0 P 0 ;0
L 0.75753996 -1.95828002 0.76138002 -1.95548002 0 P 0 ;0
L 0.76138002 -1.95548002 0.76463002 -1.95316004 0 P 0 ;0
L 0.76463002 -1.95316004 0.76516004 -1.95281004 0 P 0 ;0
L 0.76516004 -1.95281004 0.7657 -1.95248996 0 P 0 ;0
L 0.7657 -1.95248996 0.76578002 -1.95243996 0 P 0 ;0
L 0.76578002 -1.95243996 0.76586004 -1.95238002 0 P 0 ;0
L 0.76586004 -1.95238002 0.76593002 -1.95231998 0 P 0 ;0
L 0.76593002 -1.95231998 0.766 -1.95223996 0 P 0 ;0
L 0.766 -1.95223996 0.76606004 -1.95216998 0 P 0 ;0
L 0.76606004 -1.95216998 0.76616004 -1.95201004 0 P 0 ;0
L 0.76616004 -1.95201004 0.7662 -1.95191998 0 P 0 ;0
L 0.7662 -1.95191998 0.76626004 -1.95173996 0 P 0 ;0
L 0.76626004 -1.95173996 0.76628002 -1.95163996 0 P 0 ;0
L 0.76628002 -1.95163996 0.7663 -1.95143002 0 P 0 ;0
L 0.7663 -1.95143002 0.7663 -1.95121004 0 P 0 ;0
L 0.7663 -1.95121004 0.76628996 -1.951 0 P 0 ;0
L 0.76628996 -1.951 0.76625 -1.95078996 0 P 0 ;0
L 0.76625 -1.95078996 0.7662 -1.95058002 0 P 0 ;0
L 0.7662 -1.95058002 0.76613002 -1.95036998 0 P 0 ;0
L 0.76613002 -1.95036998 0.76583002 -1.94966998 0 P 0 ;0
L 0.76583002 -1.94966998 0.76548996 -1.94896998 0 P 0 ;0
L 0.76548996 -1.94896998 0.76508996 -1.9483 0 P 0 ;0
L 0.76508996 -1.9483 0.76253002 -1.94436004 0 P 0 ;0
L 0.76253002 -1.94436004 0.76056998 -1.94126998 0 P 0 ;0
L 0.76056998 -1.94126998 0.75871998 -1.93806004 0 P 0 ;0
L 0.75871998 -1.93806004 0.75716998 -1.93496998 0 P 0 ;0
L 0.75716998 -1.93496998 0.7558 -1.93178002 0 P 0 ;0
L 0.7558 -1.93178002 0.7546 -1.92853996 0 P 0 ;0
L 0.7546 -1.92853996 0.75358996 -1.92521004 0 P 0 ;0
L 0.75358996 -1.92521004 0.7527 -1.92161998 0 P 0 ;0
L 0.7527 -1.92161998 0.75196998 -1.91796004 0 P 0 ;0
L 0.75196998 -1.91796004 0.75155 -1.91496004 0 P 0 ;0
L 0.75155 -1.91496004 0.75133002 -1.91193002 0 P 0 ;0
L 0.75133002 -1.91193002 0.75126998 -1.9085 0 P 0 ;0
L 0.75126998 -1.9085 0.75136004 -1.90506004 0 P 0 ;0
L 0.75136004 -1.90506004 0.75161004 -1.90181998 0 P 0 ;0
L 0.75161004 -1.90181998 0.752 -1.8986 0 P 0 ;0
L 0.752 -1.8986 0.75228996 -1.89701998 0 P 0 ;0
L 0.75228996 -1.89701998 0.75268996 -1.89546998 0 P 0 ;0
L 0.75268996 -1.89546998 0.7532 -1.89395 0 P 0 ;0
L 0.7532 -1.89395 0.75358996 -1.89281998 0 P 0 ;0
L 0.75358996 -1.89281998 0.75373002 -1.89231998 0 P 0 ;0
L 0.75373002 -1.89231998 0.75383996 -1.8918 0 P 0 ;0
L 0.75383996 -1.8918 0.75391998 -1.89138996 0 P 0 ;0
L 0.75391998 -1.89138996 0.75396998 -1.89098996 0 P 0 ;0
L 0.75396998 -1.89098996 0.75396998 -1.89086004 0 P 0 ;0
L 0.75396998 -1.89086004 0.75393996 -1.89076998 0 P 0 ;0
L 0.75393996 -1.89076998 0.7539 -1.89071004 0 P 0 ;0
L 0.7539 -1.89071004 0.75386004 -1.89066998 0 P 0 ;0
L 0.75386004 -1.89066998 0.75381004 -1.89063002 0 P 0 ;0
L 0.75381004 -1.89063002 0.75378996 -1.89061004 0 P 0 ;0
L 0.75378996 -1.89061004 0.75373002 -1.89058996 0 P 0 ;0
L 0.75373002 -1.89058996 0.75368002 -1.89056998 0 P 0 ;0
L 0.75368002 -1.89056998 0.75356004 -1.89056998 0 P 0 ;0
L 0.75356004 -1.89056998 0.75346998 -1.8906 0 P 0 ;0
L 0.75346998 -1.8906 0.74898002 -1.8927 0 P 0 ;0
L 0.74898002 -1.8927 0.74383002 -1.89518002 0 P 0 ;0
L 0.74383002 -1.89518002 0.73781004 -1.8982 0 P 0 ;0
L 0.69776998 -2.22761998 0.96701004 -2.22761998 0 P 0 ;0
L 0.6957 -2.22661998 0.96968996 -2.22661998 0 P 0 ;0
L 0.69366998 -2.22561998 0.97238002 -2.22561998 0 P 0 ;0
L 0.69163002 -2.22461998 0.97506004 -2.22461998 0 P 0 ;0
L 0.68958996 -2.22361998 0.97775 -2.22361998 0 P 0 ;0
L 0.68756004 -2.22261998 0.98043002 -2.22261998 0 P 0 ;0
L 0.68551998 -2.22161998 0.98311004 -2.22161998 0 P 0 ;0
L 0.68348996 -2.22061998 0.9858 -2.22061998 0 P 0 ;0
L 0.68176998 -2.21961998 0.98848002 -2.21961998 0 P 0 ;0
L 0.68003996 -2.21861998 0.99116998 -2.21861998 0 P 0 ;0
L 0.67831004 -2.21761998 0.99385 -2.21761998 0 P 0 ;0
L 0.67658002 -2.21661998 0.99653996 -2.21661998 0 P 0 ;0
L 0.67485 -2.21561998 0.99908002 -2.21561998 0 P 0 ;0
L 0.67311998 -2.21461998 0.87665 -2.21461998 0 P 0 ;0
L 0.6714 -2.21361998 0.85166004 -2.21361998 0 P 0 ;0
L 0.6699 -2.21261998 0.84083002 -2.21261998 0 P 0 ;0
L 0.66845 -2.21161998 0.8334 -2.21161998 0 P 0 ;0
L 0.66698996 -2.21061998 0.8274 -2.21061998 0 P 0 ;0
L 0.66553002 -2.20961998 0.82138996 -2.20961998 0 P 0 ;0
L 0.66406998 -2.20861998 0.81583002 -2.20861998 0 P 0 ;0
L 0.66261998 -2.20761998 0.81143996 -2.20761998 0 P 0 ;0
L 0.66116004 -2.20661998 0.80706004 -2.20661998 0 P 0 ;0
L 0.6597 -2.20561998 0.80266998 -2.20561998 0 P 0 ;0
L 0.65841004 -2.20461998 0.79828996 -2.20461998 0 P 0 ;0
L 0.65716998 -2.20361998 0.79448996 -2.20361998 0 P 0 ;0
L 0.65593002 -2.20261998 0.79106004 -2.20261998 0 P 0 ;0
L 0.65468996 -2.20161998 0.78763996 -2.20161998 0 P 0 ;0
L 0.83143002 -2.25261998 0.80871998 -2.25225 0 P 0 ;0
L 0.80871998 -2.25225 0.78691998 -2.25066998 0 P 0 ;0
L 0.78691998 -2.25066998 0.76525 -2.24786998 0 P 0 ;0
L 0.76525 -2.24786998 0.74581998 -2.24403996 0 P 0 ;0
L 0.74581998 -2.24403996 0.72671004 -2.23876004 0 P 0 ;0
L 0.72671004 -2.23876004 0.71196004 -2.23356998 0 P 0 ;0
L 0.71196004 -2.23356998 0.69756998 -2.22753996 0 P 0 ;0
L 0.69756998 -2.22753996 0.68355 -2.22066004 0 P 0 ;0
L 0.68355 -2.22066004 0.67118002 -2.2135 0 P 0 ;0
L 0.67118002 -2.2135 0.65938996 -2.20541004 0 P 0 ;0
L 0.65938996 -2.20541004 0.64825 -2.19643996 0 P 0 ;0
L 0.64825 -2.19643996 0.63861998 -2.18731998 0 P 0 ;0
L 0.63861998 -2.18731998 0.62983002 -2.17746998 0 P 0 ;0
L 0.62983002 -2.17746998 0.62188996 -2.1669 0 P 0 ;0
L 0.62188996 -2.1669 0.61678002 -2.15886998 0 P 0 ;0
L 0.61678002 -2.15886998 0.6123 -2.15056004 0 P 0 ;0
L 0.6123 -2.15056004 0.60841998 -2.14193996 0 P 0 ;0
L 0.60841998 -2.14193996 0.60516998 -2.13306998 0 P 0 ;0
L 0.60516998 -2.13306998 0.60191004 -2.12171004 0 P 0 ;0
L 0.60191004 -2.12171004 0.60075 -2.11648002 0 P 0 ;0
L 0.60075 -2.11648002 0.59983996 -2.11121004 0 P 0 ;0
L 0.59983996 -2.11121004 0.59913996 -2.10576004 0 P 0 ;0
L 0.59913996 -2.10576004 0.59868996 -2.10026004 0 P 0 ;0
L 0.59868996 -2.10026004 0.59833002 -2.0875 0 P 0 ;0
L 0.59833002 -2.0875 0.59856998 -2.07843996 0 P 0 ;0
L 0.59856998 -2.07843996 0.59923996 -2.0695 0 P 0 ;0
L 0.59923996 -2.0695 0.60031998 -2.06153996 0 P 0 ;0
L 0.60031998 -2.06153996 0.60193002 -2.05368996 0 P 0 ;0
L 0.60193002 -2.05368996 0.60416004 -2.04566004 0 P 0 ;0
L 0.60416004 -2.04566004 0.60688996 -2.03786004 0 P 0 ;0
L 0.60688996 -2.03786004 0.6148 -2.01961004 0 P 0 ;0
L 0.6148 -2.01961004 0.62108996 -2.00753002 0 P 0 ;0
L 0.62108996 -2.00753002 0.62811998 -1.99591998 0 P 0 ;0
L 0.62811998 -1.99591998 0.63583996 -1.98478996 0 P 0 ;0
L 0.63583996 -1.98478996 0.64936998 -1.96808002 0 P 0 ;0
L 0.64936998 -1.96808002 0.66418002 -1.95256998 0 P 0 ;0
L 0.66418002 -1.95256998 0.68098002 -1.93756004 0 P 0 ;0
L 0.68098002 -1.93756004 0.69881998 -1.92398002 0 P 0 ;0
L 0.69881998 -1.92398002 0.71841998 -1.91123996 0 P 0 ;0
L 0.71841998 -1.91123996 0.73875 -1.89996998 0 P 0 ;0
L 0.73875 -1.89996998 0.74471004 -1.89696998 0 P 0 ;0
L 0.74471004 -1.89696998 0.74983002 -1.89451004 0 P 0 ;0
L 0.74983002 -1.89451004 0.7511 -1.89391004 0 P 0 ;0
L 0.7511 -1.89391004 0.75076998 -1.89488996 0 P 0 ;0
L 0.75076998 -1.89488996 0.75033996 -1.89658996 0 P 0 ;0
L 0.75033996 -1.89658996 0.75003002 -1.8983 0 P 0 ;0
L 0.75003002 -1.8983 0.74961998 -1.90161998 0 P 0 ;0
L 0.74961998 -1.90161998 0.74936004 -1.90496004 0 P 0 ;0
L 0.74936004 -1.90496004 0.74926998 -1.9085 0 P 0 ;0
L 0.74926998 -1.9085 0.74933002 -1.91201998 0 P 0 ;0
L 0.74933002 -1.91201998 0.74956004 -1.91516998 0 P 0 ;0
L 0.74956004 -1.91516998 0.75 -1.91828996 0 P 0 ;0
L 0.75 -1.91828996 0.75075 -1.92205 0 P 0 ;0
L 0.75075 -1.92205 0.75166004 -1.92573996 0 P 0 ;0
L 0.75166004 -1.92573996 0.7527 -1.92916998 0 P 0 ;0
L 0.7527 -1.92916998 0.75393996 -1.93253002 0 P 0 ;0
L 0.75393996 -1.93253002 0.75536004 -1.93581998 0 P 0 ;0
L 0.75536004 -1.93581998 0.75696004 -1.939 0 P 0 ;0
L 0.75696004 -1.939 0.75885 -1.94231004 0 P 0 ;0
L 0.75885 -1.94231004 0.76083996 -1.94543996 0 P 0 ;0
L 0.76083996 -1.94543996 0.76338996 -1.94933996 0 P 0 ;0
L 0.76338996 -1.94933996 0.76371998 -1.94991998 0 P 0 ;0
L 0.76371998 -1.94991998 0.76401004 -1.9505 0 P 0 ;0
L 0.76401004 -1.9505 0.76423996 -1.95103002 0 P 0 ;0
L 0.76423996 -1.95103002 0.76408996 -1.95111004 0 P 0 ;0
L 0.76408996 -1.95111004 0.76348996 -1.95151004 0 P 0 ;0
L 0.76348996 -1.95151004 0.76021004 -1.95386004 0 P 0 ;0
L 0.76021004 -1.95386004 0.7602 -1.95386998 0 P 0 ;0
L 0.7602 -1.95386998 0.75636998 -1.95666004 0 P 0 ;0
L 0.75636998 -1.95666004 0.75636004 -1.95666998 0 P 0 ;0
L 0.75636004 -1.95666998 0.75635 -1.95666998 0 P 0 ;0
L 0.75635 -1.95666998 0.75208996 -1.95981004 0 P 0 ;0
L 0.75208996 -1.95981004 0.73841004 -1.97066998 0 P 0 ;0
L 0.73841004 -1.97066998 0.72541004 -1.98241004 0 P 0 ;0
L 0.72541004 -1.98241004 0.7143 -1.994 0 P 0 ;0
L 0.7143 -1.994 0.71425 -1.99406004 0 P 0 ;0
L 0.71425 -1.99406004 0.70413996 -2.00648002 0 P 0 ;0
L 0.70413996 -2.00648002 0.69836998 -2.01468996 0 P 0 ;0
L 0.69836998 -2.01468996 0.69313002 -2.02318002 0 P 0 ;0
L 0.69313002 -2.02318002 0.68838996 -2.03196004 0 P 0 ;0
L 0.68838996 -2.03196004 0.68438996 -2.04063996 0 P 0 ;0
L 0.68438996 -2.04063996 0.68098996 -2.04958002 0 P 0 ;0
L 0.68098996 -2.04958002 0.6782 -2.05873002 0 P 0 ;0
L 0.6782 -2.05873002 0.67706004 -2.06366004 0 P 0 ;0
L 0.67706004 -2.06366004 0.67628996 -2.06866998 0 P 0 ;0
L 0.67628996 -2.06866998 0.67538002 -2.08068996 0 P 0 ;0
L 0.67538002 -2.08068996 0.67546004 -2.09268996 0 P 0 ;0
L 0.67546004 -2.09268996 0.67588996 -2.09766998 0 P 0 ;0
L 0.67588996 -2.09766998 0.6767 -2.10258996 0 P 0 ;0
L 0.6767 -2.10258996 0.67881998 -2.11111998 0 P 0 ;0
L 0.67881998 -2.11111998 0.68163996 -2.11936004 0 P 0 ;0
L 0.68163996 -2.11936004 0.68516004 -2.12731998 0 P 0 ;0
L 0.68516004 -2.12731998 0.68935 -2.13493996 0 P 0 ;0
L 0.68935 -2.13493996 0.69418002 -2.14216998 0 P 0 ;0
L 0.69418002 -2.14216998 0.70153002 -2.15135 0 P 0 ;0
L 0.70153002 -2.15135 0.7096 -2.15983002 0 P 0 ;0
L 0.7096 -2.15983002 0.71836004 -2.16758996 0 P 0 ;0
L 0.71836004 -2.16758996 0.71843002 -2.16763996 0 P 0 ;0
L 0.71843002 -2.16763996 0.72773996 -2.17456004 0 P 0 ;0
L 0.72773996 -2.17456004 0.73926998 -2.1818 0 P 0 ;0
L 0.73926998 -2.1818 0.75121004 -2.18818002 0 P 0 ;0
L 0.75121004 -2.18818002 0.75128002 -2.18821004 0 P 0 ;0
L 0.75128002 -2.18821004 0.76358002 -2.19368996 0 P 0 ;0
L 0.76358002 -2.19368996 0.77628002 -2.19831004 0 P 0 ;0
L 0.77628002 -2.19831004 0.79658996 -2.20423996 0 P 0 ;0
L 0.79658996 -2.20423996 0.81701004 -2.20888996 0 P 0 ;0
L 0.81701004 -2.20888996 0.83763996 -2.21233002 0 P 0 ;0
L 0.83763996 -2.21233002 0.85388002 -2.21383002 0 P 0 ;0
L 0.85388002 -2.21383002 0.87733996 -2.21465 0 P 0 ;0
L 0.87733996 -2.21465 0.90118002 -2.21478996 0 P 0 ;0
L 0.90118002 -2.21478996 0.91906004 -2.21398996 0 P 0 ;0
L 0.91906004 -2.21398996 0.94908996 -2.21068002 0 P 0 ;0
L 0.94908996 -2.21068002 0.98176998 -2.2053 0 P 0 ;0
L 0.98176998 -2.2053 1.01575 -2.19815 0 P 0 ;0
L 1.01575 -2.19815 1.04968002 -2.18943002 0 P 0 ;0
L 1.04968002 -2.18943002 1.05633996 -2.18761004 0 P 0 ;0
L 1.05633996 -2.18761004 1.05713996 -2.1874 0 P 0 ;0
L 1.05713996 -2.1874 1.05483002 -2.18875 0 P 0 ;0
L 1.05483002 -2.18875 1.04298996 -2.19526004 0 P 0 ;0
L 1.04298996 -2.19526004 1.03096998 -2.20136998 0 P 0 ;0
L 1.03096998 -2.20136998 0.99835 -2.21595 0 P 0 ;0
L 0.99835 -2.21595 0.96401998 -2.22873996 0 P 0 ;0
L 0.96401998 -2.22873996 0.92993996 -2.23908002 0 P 0 ;0
L 0.92993996 -2.23908002 0.89816004 -2.24626004 0 P 0 ;0
L 0.89816004 -2.24626004 0.87616004 -2.24965 0 P 0 ;0
L 0.87616004 -2.24965 0.85405 -2.25176004 0 P 0 ;0
L 0.85405 -2.25176004 0.83143002 -2.25261998 0 P 0 ;0
L 0.65345 -2.20061998 0.78421004 -2.20061998 0 P 0 ;0
L 0.65221004 -2.19961998 0.78078002 -2.19961998 0 P 0 ;0
L 0.65096004 -2.19861998 0.77735 -2.19861998 0 P 0 ;0
L 0.64971998 -2.19761998 0.77438996 -2.19761998 0 P 0 ;0
L 0.64848002 -2.19661998 0.77163996 -2.19661998 0 P 0 ;0
L 0.64738996 -2.19561998 0.76888996 -2.19561998 0 P 0 ;0
L 0.64633996 -2.19461998 0.76613996 -2.19461998 0 P 0 ;0
L 0.64528002 -2.19361998 0.76343002 -2.19361998 0 P 0 ;0
L 0.64421998 -2.19261998 0.76118996 -2.19261998 0 P 0 ;0
L 0.64316998 -2.19161998 0.75893996 -2.19161998 0 P 0 ;0
L 0.64211004 -2.19061998 0.7567 -2.19061998 0 P 0 ;0
L 0.64106004 -2.18961998 0.75446004 -2.18961998 0 P 0 ;0
L 0.64 -2.18861998 0.75221004 -2.18861998 0 P 0 ;0
L 0.63895 -2.18761998 0.75018002 -2.18761998 0 P 0 ;0
L 0.63801004 -2.18661998 0.74831004 -2.18661998 0 P 0 ;0
L 0.63711004 -2.18561998 0.74643002 -2.18561998 0 P 0 ;0
L 0.63621998 -2.18461998 0.74456004 -2.18461998 0 P 0 ;0
L 0.63533002 -2.18361998 0.74268002 -2.18361998 0 P 0 ;0
L 0.63443996 -2.18261998 0.74081004 -2.18261998 0 P 0 ;0
L 0.63353996 -2.18161998 0.73898996 -2.18161998 0 P 0 ;0
L 0.63265 -2.18061998 0.73738996 -2.18061998 0 P 0 ;0
L 0.63176004 -2.17961998 0.7358 -2.17961998 0 P 0 ;0
L 0.63086998 -2.17861998 0.73421004 -2.17861998 0 P 0 ;0
L 0.62996998 -2.17761998 0.73261998 -2.17761998 0 P 0 ;0
L 0.6292 -2.17661998 0.73103002 -2.17661998 0 P 0 ;0
L 0.62845 -2.17561998 0.72943996 -2.17561998 0 P 0 ;0
L 0.6277 -2.17461998 0.72783996 -2.17461998 0 P 0 ;0
L 0.62693996 -2.17361998 0.72648002 -2.17361998 0 P 0 ;0
L 0.62618996 -2.17261998 0.72513996 -2.17261998 0 P 0 ;0
L 0.62543996 -2.17161998 0.72378996 -2.17161998 0 P 0 ;0
L 0.62468996 -2.17061998 0.72245 -2.17061998 0 P 0 ;0
L 0.62393996 -2.16961998 0.7211 -2.16961998 0 P 0 ;0
L 0.62318002 -2.16861998 0.71976004 -2.16861998 0 P 0 ;0
L 0.62243996 -2.16761998 0.71841004 -2.16761998 0 P 0 ;0
L 0.62171004 -2.16661998 0.71726998 -2.16661998 0 P 0 ;0
L 0.62108002 -2.16561998 0.71613996 -2.16561998 0 P 0 ;0
L 0.62043996 -2.16461998 0.71501004 -2.16461998 0 P 0 ;0
L 0.61981004 -2.16361998 0.71388002 -2.16361998 0 P 0 ;0
L 0.61916998 -2.16261998 0.71276004 -2.16261998 0 P 0 ;0
L 0.61853002 -2.16161998 0.71163002 -2.16161998 0 P 0 ;0
L 0.6179 -2.16061998 0.7105 -2.16061998 0 P 0 ;0
L 0.61726004 -2.15961998 0.7094 -2.15961998 0 P 0 ;0
L 0.61665 -2.15861998 0.70845 -2.15861998 0 P 0 ;0
L 0.61611004 -2.15761998 0.7075 -2.15761998 0 P 0 ;0
L 0.75383996 -2.24561998 0.901 -2.24561998 0 P 0 ;0
L 0.74876998 -2.24461998 0.90541998 -2.24461998 0 P 0 ;0
L 0.74431004 -2.24361998 0.90985 -2.24361998 0 P 0 ;0
L 0.7407 -2.24261998 0.91426998 -2.24261998 0 P 0 ;0
L 0.73708002 -2.24161998 0.9187 -2.24161998 0 P 0 ;0
L 0.73346998 -2.24061998 0.92311998 -2.24061998 0 P 0 ;0
L 0.72986004 -2.23961998 0.92753996 -2.23961998 0 P 0 ;0
L 0.72633996 -2.23861998 0.93145 -2.23861998 0 P 0 ;0
L 0.72348996 -2.23761998 0.93473996 -2.23761998 0 P 0 ;0
L 0.72063996 -2.23661998 0.93803996 -2.23661998 0 P 0 ;0
L 0.7178 -2.23561998 0.94133002 -2.23561998 0 P 0 ;0
L 0.71495 -2.23461998 0.94461998 -2.23461998 0 P 0 ;0
L 0.7121 -2.23361998 0.94791998 -2.23361998 0 P 0 ;0
L 0.70968996 -2.23261998 0.95121004 -2.23261998 0 P 0 ;0
L 0.70731004 -2.23161998 0.95451004 -2.23161998 0 P 0 ;0
L 0.70491998 -2.23061998 0.9578 -2.23061998 0 P 0 ;0
L 0.70253996 -2.22961998 0.9611 -2.22961998 0 P 0 ;0
L 0.70015 -2.22861998 0.96431998 -2.22861998 0 P 0 ;0
L 8.45 3.66615 8.45 3.71615 6 P 0 
L 8.5 3.76615 8.5 3.81615 6 P 0 
L 8.45 3.81615 8.45 3.86615 6 P 0 
L 8.5 3.46615 8.5 3.51615 6 P 0 
L 8.45 3.41615 8.45 3.46615 6 P 0 
L 8.5 3.61615 8.5 3.66615 6 P 0 
L 8.45 3.26615 8.45 3.31615 6 P 0 
L 8.5 3.31615 8.5 3.36615 6 P 0 
L 8.2 3.66615 8.2 3.71615 6 P 0 
L 8.35 3.66615 8.35 3.71615 6 P 0 
L 8.4 3.76615 8.4 3.81615 6 P 0 
L 8.35 3.81615 8.35 3.86615 6 P 0 
L 8.2 3.81615 8.2 3.86615 6 P 0 
L 8.4 3.46615 8.4 3.51615 6 P 0 
L 8.35 3.41615 8.35 3.46615 6 P 0 
L 8.2 3.41615 8.2 3.46615 6 P 0 
L 8.4 3.61615 8.4 3.66615 6 P 0 
L 8.35 3.26615 8.35 3.31615 6 P 0 
L 8.4 3.31615 8.4 3.36615 6 P 0 
L 8.2 3.26615 8.2 3.31615 6 P 0 
L 8.25 2.86615 8.3 2.86615 6 P 0 
L 8.1 3.66615 8.1 3.71615 6 P 0 
L 8.15 3.76615 8.15 3.81615 6 P 0 
L 8.1 3.81615 8.1 3.86615 6 P 0 
L 8.05 3.76615 8.05 3.81615 6 P 0 
L 8.1 3.41615 8.1 3.46615 6 P 0 
L 8.15 3.46615 8.15 3.51615 6 P 0 
L 8 3.46615 8 3.51615 6 P 0 
L 8.05 3.61615 8.05 3.66615 6 P 0 
L 8.15 3.61615 8.15 3.66615 6 P 0 
L 8.1 3.26615 8.1 3.31615 6 P 0 
L 8.15 3.31615 8.15 3.36615 6 P 0 
L 8.05 3.31615 8.05 3.36615 6 P 0 
L 5.42048002 1.91835 5.42048002 1.87835 6 P 0 
L 5.57531004 1.8508 5.57531004 1.8108 6 P 0 
L 2.34606004 3.26615 2.34606004 3.31615 6 P 0 
L 2.39606004 3.31615 2.39606004 3.36615 6 P 0 
L 2.44606004 3.26615 2.44606004 3.31615 6 P 0 
L 2.49606004 3.31615 2.49606004 3.36615 6 P 0 
L 2.49606004 3.46615 2.49606004 3.51615 6 P 0 
L 2.44606004 3.41615 2.44606004 3.46615 6 P 0 
L 2.39606004 3.46615 2.39606004 3.51615 6 P 0 
L 2.34606004 3.41615 2.34606004 3.46615 6 P 0 
L 2.19606004 3.26615 2.19606004 3.31615 6 P 0 
L 2.09606004 3.26615 2.09606004 3.31615 6 P 0 
L 2.14606004 3.31615 2.14606004 3.36615 6 P 0 
L 2.19606004 3.41615 2.19606004 3.46615 6 P 0 
L 2.09606004 3.41615 2.09606004 3.46615 6 P 0 
L 2.04606004 3.31615 2.04606004 3.36615 6 P 0 
L 2.14606004 3.46615 2.14606004 3.51615 6 P 0 
L 1.99606004 3.46615 1.99606004 3.51615 6 P 0 
L 2.04606004 3.61615 2.04606004 3.66615 6 P 0 
L 2.09606004 3.66615 2.09606004 3.71615 6 P 0 
L 2.14606004 3.61615 2.14606004 3.66615 6 P 0 
L 2.19606004 3.66615 2.19606004 3.71615 6 P 0 
L 2.49606004 3.61615 2.49606004 3.66615 6 P 0 
L 2.34606004 3.66615 2.34606004 3.71615 6 P 0 
L 2.39606004 3.61615 2.39606004 3.66615 6 P 0 
L 2.44606004 3.66615 2.44606004 3.71615 6 P 0 
L 2.49606004 3.76615 2.49606004 3.81615 6 P 0 
L 2.44606004 3.81615 2.44606004 3.86615 6 P 0 
L 2.39606004 3.76615 2.39606004 3.81615 6 P 0 
L 2.34606004 3.81615 2.34606004 3.86615 6 P 0 
L 2.14606004 3.76615 2.14606004 3.81615 6 P 0 
L 2.19606004 3.81615 2.19606004 3.86615 6 P 0 
L 2.09606004 3.81615 2.09606004 3.86615 6 P 0 
L 2.04606004 3.76615 2.04606004 3.81615 6 P 0 
L 2.24606004 2.86615 2.29606004 2.86615 6 P 0 
L 5.42048002 1.6433 5.42048002 1.6033 6 P 0 
L 5.57531004 1.7118 5.57531004 1.6718 6 P 0 
L 5.42048002 1.7796 5.42048002 1.7396 6 P 0 
L 5.57531004 1.9869 5.57531004 1.9469 6 P 0 
L 5.42048002 2.0547 5.42048002 2.0147 6 P 0 
L 5.57531004 2.1278 5.57531004 2.0878 6 P 0 
L 5.42048002 2.1954 5.42048002 2.1554 6 P 0 
L 5.57531004 2.2632 5.57531004 2.2232 6 P 0 
L 5.42048002 2.3308 5.42048002 2.2908 6 P 0 
L 5.57531004 2.3986 5.57531004 2.3586 6 P 0 
L 5.42048002 2.4662 5.42048002 2.4262 6 P 0 
L 5.57531004 2.5378 5.57531004 2.4978 6 P 0 
L 5.57531004 2.673 5.57531004 2.633 6 P 0 
L 5.42048002 2.6054 5.42048002 2.5654 6 P 0 
L 10.09 2.73655 10.09 2.69655 6 P 0 
L 9.975 2.66445 9.975 2.62445 6 P 0 
L 9.975 2.5109 9.975 2.4709 6 P 0 
L 10.09 2.57845 10.09 2.53845 6 P 0 
L 10.09 2.44335 10.09 2.40335 6 P 0 
L 9.975 2.3758 9.975 2.3358 6 P 0 
L 10.09 2.30825 10.09 2.26825 6 P 0 
L 9.975 2.23955 9.975 2.19955 6 P 0 
L 10.09 2.17095 10.09 2.13095 6 P 0 
L 10.09 2.05655 10.09 2.01655 6 P 0 
L 10.225 1.96645 10.225 1.92645 6 P 0 
L 10.26025 1.86845 10.26025 1.82845 6 P 0 
L 10.26 1.70445 10.26 1.66445 6 P 0 
L 10.35543996 1.52156004 10.38371998 1.49328002 7 P 0 
L 10.46445 1.395 10.42445 1.395 6 P 0 
L 10.395 1.28555 10.395 1.32555 6 P 0 
L 11.53316004 1.412 11.53316004 1.452 6 P 0 
L 11.73316004 1.492 11.73316004 1.532 6 P 0 
L 11.53316004 1.572 11.53316004 1.612 6 P 0 
L 11.78316004 1.652 11.78316004 1.692 6 P 0 
L 11.53316004 1.732 11.53316004 1.772 6 P 0 
L 11.73316004 1.812 11.73316004 1.852 6 P 0 
L 11.53316004 1.892 11.53316004 1.932 6 P 0 
L 11.53316004 2.052 11.53316004 2.092 6 P 0 
L 11.73316004 1.972 11.73316004 2.012 6 P 0 
L 11.73316004 2.132 11.73316004 2.172 6 P 0 
L 11.83316004 2.212 11.83316004 2.252 6 P 0 
L 11.73316004 2.292 11.73316004 2.332 6 P 0 
L 11.53316004 2.372 11.53316004 2.412 6 P 0 
L 11.53316004 2.532 11.53316004 2.572 6 P 0 
L 11.73316004 2.452 11.73316004 2.492 6 P 0 
L 11.73316004 2.612 11.73316004 2.652 6 P 0 
L 8.98115 2.825 8.98115 2.865 6 P 0 
L 2.97721004 2.825 2.97721004 2.865 6 P 0 
L 11.03661004 2.46615 11.03661004 2.51615 6 P 0 
L 11.08661004 2.21615 11.08661004 2.26615 6 P 0 
L 10.98661004 2.21615 10.98661004 2.26615 6 P 0 
L 11.03661004 2.26615 11.03661004 2.31615 6 P 0 
L 10.93661004 2.26615 10.93661004 2.31615 6 P 0 
L 10.98661004 2.36615 10.98661004 2.41615 6 P 0 
L 10.93661004 2.41615 10.93661004 2.46615 6 P 0 
L 11.08661004 2.36615 11.08661004 2.41615 6 P 0 
L 10.93661004 2.01615 10.93661004 2.06615 6 P 0 
L 10.98661004 2.06615 10.98661004 2.11615 6 P 0 
L 11.03661004 2.01615 11.03661004 2.06615 6 P 0 
L 11.08661004 2.06615 11.08661004 2.11615 6 P 0 
L 10.93661004 1.86615 10.93661004 1.91615 6 P 0 
L 11.03661004 1.86615 11.03661004 1.91615 6 P 0 
L 10.98661004 1.91615 10.98661004 1.96615 6 P 0 
L 11.08661004 1.91615 11.08661004 1.96615 6 P 0 
L 10.73661004 2.46615 10.73661004 2.41615 6 P 0 
L 10.68661004 2.41615 10.68661004 2.36615 6 P 0 
L 10.68661004 2.26615 10.68661004 2.21615 6 P 0 
L 10.73661004 2.31615 10.73661004 2.26615 6 P 0 
L 10.68661004 2.11615 10.68661004 2.06615 6 P 0 
L 10.83661004 2.16615 10.88661004 2.16615 6 P 0 
L 10.73661004 2.01615 10.73661004 2.06615 6 P 0 
L 10.68661004 1.91615 10.68661004 1.96615 6 P 0 
L 10.73661004 1.86615 10.73661004 1.91615 6 P 0 
L 10.63661004 2.46615 10.63661004 2.41615 6 P 0 
L 10.58661004 2.41615 10.58661004 2.36615 6 P 0 
L 10.63661004 2.31615 10.63661004 2.26615 6 P 0 
L 10.58661004 2.26615 10.58661004 2.21615 6 P 0 
L 10.58661004 2.11615 10.58661004 2.06615 6 P 0 
L 10.63661004 2.01615 10.63661004 2.06615 6 P 0 
L 10.58661004 1.91615 10.58661004 1.96615 6 P 0 
L 10.63661004 1.86615 10.63661004 1.91615 6 P 0 
L 0.69348996 1.86611998 0.69348996 1.90611998 6 P 0 
L 5.03268002 2.46615 5.03268002 2.51615 6 P 0 
L 5.08268002 2.36615 5.08268002 2.41615 6 P 0 
L 4.93268002 2.41615 4.93268002 2.46615 6 P 0 
L 4.98268002 2.36615 4.98268002 2.41615 6 P 0 
L 4.93268002 2.26615 4.93268002 2.31615 6 P 0 
L 5.03268002 2.26615 5.03268002 2.31615 6 P 0 
L 4.98268002 2.21615 4.98268002 2.26615 6 P 0 
L 5.08268002 2.21615 5.08268002 2.26615 6 P 0 
L 5.08268002 2.06615 5.08268002 2.11615 6 P 0 
L 5.03268002 2.01615 5.03268002 2.06615 6 P 0 
L 4.98268002 2.06615 4.98268002 2.11615 6 P 0 
L 4.93268002 2.01615 4.93268002 2.06615 6 P 0 
L 5.08268002 1.91615 5.08268002 1.96615 6 P 0 
L 4.98268002 1.91615 4.98268002 1.96615 6 P 0 
L 5.03268002 1.86615 5.03268002 1.91615 6 P 0 
L 4.93268002 1.86615 4.93268002 1.91615 6 P 0 
L 4.73268002 1.86615 4.73268002 1.91615 6 P 0 
L 4.63268002 1.86615 4.63268002 1.91615 6 P 0 
L 4.68268002 1.91615 4.68268002 1.96615 6 P 0 
L 4.58268002 1.91615 4.58268002 1.96615 6 P 0 
L 4.63268002 2.01615 4.63268002 2.06615 6 P 0 
L 4.73268002 2.01615 4.73268002 2.06615 6 P 0 
L 4.83268002 2.16615 4.88268002 2.16615 6 P 0 
L 4.58268002 2.11615 4.58268002 2.06615 6 P 0 
L 4.68268002 2.11615 4.68268002 2.06615 6 P 0 
L 4.73268002 2.31615 4.73268002 2.26615 6 P 0 
L 4.68268002 2.26615 4.68268002 2.21615 6 P 0 
L 4.58268002 2.26615 4.58268002 2.21615 6 P 0 
L 4.63268002 2.31615 4.63268002 2.26615 6 P 0 
L 4.58268002 2.41615 4.58268002 2.36615 6 P 0 
L 4.68268002 2.41615 4.68268002 2.36615 6 P 0 
L 4.63268002 2.46615 4.63268002 2.41615 6 P 0 
L 4.73268002 2.46615 4.73268002 2.41615 6 P 0 
A 12.75476004 4.52361998 12.75476004 4.52361998 12.73621004 4.52361998 3 P 0 N
A 12.8335 4.48425 12.8335 4.48425 12.81495 4.48425 3 P 0 N
L 12.73621004 4.52361998 12.81495 4.48425 9 P 0 
L 12.73621004 4.36613996 12.81495 4.32676998 9 P 0 
A 12.8335 4.32676998 12.8335 4.32676998 12.81495 4.32676998 3 P 0 N
A 12.75476004 4.36613996 12.75476004 4.36613996 12.73621004 4.36613996 3 P 0 N
L 12.73621004 4.20866004 12.81495 4.16928996 9 P 0 
A 12.8335 4.16928996 12.8335 4.16928996 12.81495 4.16928996 3 P 0 N
A 12.75476004 4.20866004 12.75476004 4.20866004 12.73621004 4.20866004 3 P 0 N
L 12.73621004 4.05118002 12.81495 4.01181004 9 P 0 
A 12.8335 4.01181004 12.8335 4.01181004 12.81495 4.01181004 3 P 0 N
A 12.75476004 4.05118002 12.75476004 4.05118002 12.73621004 4.05118002 3 P 0 N
L 12.73621004 3.8937 12.81495 3.85433002 9 P 0 
A 12.8335 3.85433002 12.8335 3.85433002 12.81495 3.85433002 3 P 0 N
A 12.75476004 3.8937 12.75476004 3.8937 12.73621004 3.8937 3 P 0 N
A 12.75476004 3.73621998 12.75476004 3.73621998 12.73621004 3.73621998 3 P 0 N
L 12.73621004 3.73621998 12.81495 3.69685 9 P 0 
A 12.8335 3.69685 12.8335 3.69685 12.81495 3.69685 3 P 0 N
L 12.73621004 3.57873996 12.81495 3.53936998 9 P 0 
A 12.8335 3.53936998 12.8335 3.53936998 12.81495 3.53936998 3 P 0 N
A 12.75476004 3.57873996 12.75476004 3.57873996 12.73621004 3.57873996 3 P 0 N
L 12.73621004 3.42126004 12.81495 3.38188996 9 P 0 
A 12.8335 3.38188996 12.8335 3.38188996 12.81495 3.38188996 3 P 0 N
A 12.75476004 3.42126004 12.75476004 3.42126004 12.73621004 3.42126004 3 P 0 N
A 12.8335 3.22441004 12.8335 3.22441004 12.81495 3.22441004 3 P 0 N
L 12.73621004 3.02756004 12.81495 3.06693002 9 P 0 
A 12.8335 3.06693002 12.8335 3.06693002 12.81495 3.06693002 3 P 0 N
A 12.75476004 3.02756004 12.75476004 3.02756004 12.73621004 3.02756004 3 P 0 N
L 12.73621004 3.18503996 12.81495 3.22441004 9 P 0 
A 12.75476004 3.18503996 12.75476004 3.18503996 12.73621004 3.18503996 3 P 0 N
A 12.8335 2.75196998 12.8335 2.75196998 12.81495 2.75196998 3 P 0 N
L 12.73621004 2.87008002 12.81495 2.90945 9 P 0 
A 12.8335 2.90945 12.8335 2.90945 12.81495 2.90945 3 P 0 N
A 12.75476004 2.87008002 12.75476004 2.87008002 12.73621004 2.87008002 3 P 0 N
A 12.8335 2.51575 12.8335 2.51575 12.81495 2.51575 3 P 0 N
A 12.75476004 2.47638002 12.75476004 2.47638002 12.73621004 2.47638002 3 P 0 N
L 12.73621004 2.7126 12.81495 2.75196998 9 P 0 
A 12.75476004 2.7126 12.75476004 2.7126 12.73621004 2.7126 3 P 0 N
L 12.73621004 2.3189 12.81495 2.35826998 9 P 0 
A 12.8335 2.35826998 12.8335 2.35826998 12.81495 2.35826998 3 P 0 N
A 12.75476004 2.3189 12.75476004 2.3189 12.73621004 2.3189 3 P 0 N
L 12.73621004 2.47638002 12.81495 2.51575 9 P 0 
A 12.75476004 2.00393996 12.75476004 2.00393996 12.73621004 2.00393996 3 P 0 N
L 12.73621004 2.16141998 12.81495 2.20078996 9 P 0 
A 12.8335 2.20078996 12.8335 2.20078996 12.81495 2.20078996 3 P 0 N
A 12.75476004 2.16141998 12.75476004 2.16141998 12.73621004 2.16141998 3 P 0 N
L 12.73621004 2.00393996 12.81495 1.96456998 9 P 0 
A 12.8335 1.96456998 12.8335 1.96456998 12.81495 1.96456998 3 P 0 N
L 12.55905 4.563 12.63778996 4.60236998 9 P 0 
A 12.65633996 4.60236998 12.65633996 4.60236998 12.63778996 4.60236998 3 P 0 N
A 12.5776 4.563 12.5776 4.563 12.55905 4.563 3 P 0 N
L 12.55905 4.24803002 12.63778996 4.2874 9 P 0 
A 12.65633996 4.2874 12.65633996 4.2874 12.63778996 4.2874 3 P 0 N
A 12.5776 4.24803002 12.5776 4.24803002 12.55905 4.24803002 3 P 0 N
L 12.55905 4.40551004 12.63778996 4.44488002 9 P 0 
A 12.65633996 4.44488002 12.65633996 4.44488002 12.63778996 4.44488002 3 P 0 N
A 12.5776 4.40551004 12.5776 4.40551004 12.55905 4.40551004 3 P 0 N
A 12.65633996 3.97243996 12.65633996 3.97243996 12.63778996 3.97243996 3 P 0 N
L 12.55905 4.09055 12.63778996 4.12991998 9 P 0 
A 12.65633996 4.12991998 12.65633996 4.12991998 12.63778996 4.12991998 3 P 0 N
A 12.5776 4.09055 12.5776 4.09055 12.55905 4.09055 3 P 0 N
L 12.55905 3.77558996 12.63778996 3.81496004 9 P 0 
A 12.65633996 3.81496004 12.65633996 3.81496004 12.63778996 3.81496004 3 P 0 N
A 12.5776 3.77558996 12.5776 3.77558996 12.55905 3.77558996 3 P 0 N
L 12.55905 3.93306998 12.63778996 3.97243996 9 P 0 
A 12.5776 3.93306998 12.5776 3.93306998 12.55905 3.93306998 3 P 0 N
A 12.65633996 3.5 12.65633996 3.5 12.63778996 3.5 3 P 0 N
L 12.55905 3.61811004 12.63778996 3.65748002 9 P 0 
A 12.65633996 3.65748002 12.65633996 3.65748002 12.63778996 3.65748002 3 P 0 N
A 12.5776 3.61811004 12.5776 3.61811004 12.55905 3.61811004 3 P 0 N
L 12.55905 3.30315 12.63778996 3.26378002 9 P 0 
A 12.65633996 3.26378002 12.65633996 3.26378002 12.63778996 3.26378002 3 P 0 N
A 12.5776 3.30315 12.5776 3.30315 12.55905 3.30315 3 P 0 N
L 12.55905 3.46063002 12.63778996 3.5 9 P 0 
A 12.5776 3.46063002 12.5776 3.46063002 12.55905 3.46063002 3 P 0 N
L 12.55905 3.14566998 12.63778996 3.1063 9 P 0 
A 12.65633996 3.1063 12.65633996 3.1063 12.63778996 3.1063 3 P 0 N
A 12.5776 3.14566998 12.5776 3.14566998 12.55905 3.14566998 3 P 0 N
A 12.5776 2.98818996 12.5776 2.98818996 12.55905 2.98818996 3 P 0 N
L 12.55905 2.98818996 12.63778996 2.94881998 9 P 0 
A 12.65633996 2.94881998 12.65633996 2.94881998 12.63778996 2.94881998 3 P 0 N
L 12.55905 2.83071004 12.63778996 2.79133996 9 P 0 
A 12.65633996 2.79133996 12.65633996 2.79133996 12.63778996 2.79133996 3 P 0 N
A 12.5776 2.83071004 12.5776 2.83071004 12.55905 2.83071004 3 P 0 N
L 12.55905 2.59448996 12.63778996 2.55511998 9 P 0 
A 12.65633996 2.55511998 12.65633996 2.55511998 12.63778996 2.55511998 3 P 0 N
A 12.5776 2.59448996 12.5776 2.59448996 12.55905 2.59448996 3 P 0 N
L 12.55905 2.43701004 12.63778996 2.39763996 9 P 0 
A 12.65633996 2.39763996 12.65633996 2.39763996 12.63778996 2.39763996 3 P 0 N
A 12.5776 2.43701004 12.5776 2.43701004 12.55905 2.43701004 3 P 0 N
L 12.55905 2.27953002 12.63778996 2.24016004 9 P 0 
A 12.65633996 2.24016004 12.65633996 2.24016004 12.63778996 2.24016004 3 P 0 N
A 12.5776 2.27953002 12.5776 2.27953002 12.55905 2.27953002 3 P 0 N
A 12.5776 2.04331004 12.5776 2.04331004 12.55905 2.04331004 3 P 0 N
A 12.65633996 2.08268002 12.65633996 2.08268002 12.63778996 2.08268002 3 P 0 N
L 12.55905 2.04331004 12.63778996 2.08268002 9 P 0 
L 12.55905 1.96456998 12.63778996 1.9252 9 P 0 
A 12.65633996 1.9252 12.65633996 1.9252 12.63778996 1.9252 3 P 0 N
A 12.5776 1.96456998 12.5776 1.96456998 12.55905 1.96456998 3 P 0 N
A 0.11303996 4.52363002 0.11303996 4.52363002 0.09448996 4.52363002 3 P 0 N
A 0.19178002 4.563 0.19178002 4.563 0.17323002 4.563 3 P 0 N
L 0.09448996 4.52363002 0.17323002 4.563 9 P 0 
A 0.11303996 4.36613996 0.11303996 4.36613996 0.09448996 4.36613996 3 P 0 N
A 0.19178002 4.40551004 0.19178002 4.40551004 0.17323002 4.40551004 3 P 0 N
L 0.09448996 4.36613996 0.17323002 4.40551004 9 P 0 
A 0.11303996 4.20866004 0.11303996 4.20866004 0.09448996 4.20866004 3 P 0 N
A 0.19178002 4.24803002 0.19178002 4.24803002 0.17323002 4.24803002 3 P 0 N
L 0.09448996 4.20866004 0.17323002 4.24803002 9 P 0 
A 0.11303996 4.05118002 0.11303996 4.05118002 0.09448996 4.05118002 3 P 0 N
A 0.19178002 4.09055 0.19178002 4.09055 0.17323002 4.09055 3 P 0 N
L 0.09448996 4.05118002 0.17323002 4.09055 9 P 0 
A 0.11303996 3.8937 0.11303996 3.8937 0.09448996 3.8937 3 P 0 N
A 0.19178002 3.93306998 0.19178002 3.93306998 0.17323002 3.93306998 3 P 0 N
L 0.09448996 3.8937 0.17323002 3.93306998 9 P 0 
A 0.11303996 3.73621998 0.11303996 3.73621998 0.09448996 3.73621998 3 P 0 N
A 0.19178002 3.77558996 0.19178002 3.77558996 0.17323002 3.77558996 3 P 0 N
L 0.09448996 3.73621998 0.17323002 3.77558996 9 P 0 
A 0.11303996 3.57873996 0.11303996 3.57873996 0.09448996 3.57873996 3 P 0 N
A 0.19178002 3.61811004 0.19178002 3.61811004 0.17323002 3.61811004 3 P 0 N
L 0.09448996 3.57873996 0.17323002 3.61811004 9 P 0 
A 0.11303996 3.42126004 0.11303996 3.42126004 0.09448996 3.42126004 3 P 0 N
A 0.19178002 3.46063002 0.19178002 3.46063002 0.17323002 3.46063002 3 P 0 N
L 0.09448996 3.42126004 0.17323002 3.46063002 9 P 0 
A 0.2902 3.14566998 0.2902 3.14566998 0.27165 3.14566998 3 P 0 N
A 0.36893996 3.18503996 0.36893996 3.18503996 0.35038996 3.18503996 3 P 0 N
L 0.27165 3.14566998 0.35038996 3.18503996 9 P 0 
A 0.2902 2.98818996 0.2902 2.98818996 0.27165 2.98818996 3 P 0 N
A 0.36893996 3.02756004 0.36893996 3.02756004 0.35038996 3.02756004 3 P 0 N
L 0.27165 2.98818996 0.35038996 3.02756004 9 P 0 
A 0.2902 2.83071004 0.2902 2.83071004 0.27165 2.83071004 3 P 0 N
A 0.36893996 2.87008002 0.36893996 2.87008002 0.35038996 2.87008002 3 P 0 N
L 0.27165 2.83071004 0.35038996 2.87008002 9 P 0 
A 0.2902 2.67323002 0.2902 2.67323002 0.27165 2.67323002 3 P 0 N
A 0.36893996 2.7126 0.36893996 2.7126 0.35038996 2.7126 3 P 0 N
L 0.27165 2.67323002 0.35038996 2.7126 9 P 0 
A 0.2902 2.43701004 0.2902 2.43701004 0.27165 2.43701004 3 P 0 N
A 0.36893996 2.47638002 0.36893996 2.47638002 0.35038996 2.47638002 3 P 0 N
L 0.27165 2.43701004 0.35038996 2.47638002 9 P 0 
A 0.2902 2.27953002 0.2902 2.27953002 0.27165 2.27953002 3 P 0 N
A 0.36893996 2.3189 0.36893996 2.3189 0.35038996 2.3189 3 P 0 N
L 0.27165 2.27953002 0.35038996 2.3189 9 P 0 
A 0.2902 2.12205 0.2902 2.12205 0.27165 2.12205 3 P 0 N
A 0.36893996 2.16141998 0.36893996 2.16141998 0.35038996 2.16141998 3 P 0 N
L 0.27165 2.12205 0.35038996 2.16141998 9 P 0 
L 0.09448996 2.00393996 0.17323002 2.04331004 9 P 0 
A 0.19178002 2.04331004 0.19178002 2.04331004 0.17323002 2.04331004 3 P 0 N
A 0.11303996 2.00393996 0.11303996 2.00393996 0.09448996 2.00393996 3 P 0 N
A 0.2902 1.96456998 0.2902 1.96456998 0.27165 1.96456998 3 P 0 N
A 0.36893996 1.9252 0.36893996 1.9252 0.35038996 1.9252 3 P 0 N
L 0.27165 1.96456998 0.35038996 1.9252 8 P 0 
A 0.11303996 1.9252 0.11303996 1.9252 0.09448996 1.9252 3 P 0 N
A 0.19178002 1.88583002 0.19178002 1.88583002 0.17323002 1.88583002 3 P 0 N
L 0.09448996 1.9252 0.17323002 1.88583002 9 P 0 
A 0.11303996 2.24016004 0.11303996 2.24016004 0.09448996 2.24016004 3 P 0 N
A 0.19178002 2.20078996 0.19178002 2.20078996 0.17323002 2.20078996 3 P 0 N
L 0.09448996 2.24016004 0.17323002 2.20078996 9 P 0 
A 0.11303996 2.39763996 0.11303996 2.39763996 0.09448996 2.39763996 3 P 0 N
A 0.19178002 2.35826998 0.19178002 2.35826998 0.17323002 2.35826998 3 P 0 N
L 0.09448996 2.39763996 0.17323002 2.35826998 9 P 0 
A 0.11303996 2.55511998 0.11303996 2.55511998 0.09448996 2.55511998 3 P 0 N
A 0.19178002 2.51575 0.19178002 2.51575 0.17323002 2.51575 3 P 0 N
L 0.09448996 2.55511998 0.17323002 2.51575 9 P 0 
A 0.11303996 2.79133996 0.11303996 2.79133996 0.09448996 2.79133996 3 P 0 N
A 0.19178002 2.75196998 0.19178002 2.75196998 0.17323002 2.75196998 3 P 0 N
L 0.09448996 2.79133996 0.17323002 2.75196998 9 P 0 
A 0.11303996 2.94881998 0.11303996 2.94881998 0.09448996 2.94881998 3 P 0 N
A 0.19178002 2.90945 0.19178002 2.90945 0.17323002 2.90945 3 P 0 N
L 0.09448996 2.94881998 0.17323002 2.90945 9 P 0 
A 0.11303996 3.1063 0.11303996 3.1063 0.09448996 3.1063 3 P 0 N
A 0.19178002 3.06693002 0.19178002 3.06693002 0.17323002 3.06693002 3 P 0 N
L 0.09448996 3.1063 0.17323002 3.06693002 9 P 0 
A 0.11303996 3.26378002 0.11303996 3.26378002 0.09448996 3.26378002 3 P 0 N
A 0.19178002 3.22441004 0.19178002 3.22441004 0.17323002 3.22441004 3 P 0 N
L 0.09448996 3.26378002 0.17323002 3.22441004 9 P 0 
A 0.2902 3.38188996 0.2902 3.38188996 0.27165 3.38188996 3 P 0 N
A 0.36893996 3.34251998 0.36893996 3.34251998 0.35038996 3.34251998 3 P 0 N
L 0.27165 3.38188996 0.35038996 3.34251998 9 P 0 
A 0.2902 3.53936998 0.2902 3.53936998 0.27165 3.53936998 3 P 0 N
A 0.36893996 3.5 0.36893996 3.5 0.35038996 3.5 3 P 0 N
L 0.27165 3.53936998 0.35038996 3.5 9 P 0 
A 0.2902 3.69685 0.2902 3.69685 0.27165 3.69685 3 P 0 N
A 0.36893996 3.65748002 0.36893996 3.65748002 0.35038996 3.65748002 3 P 0 N
L 0.27165 3.69685 0.35038996 3.65748002 9 P 0 
A 0.2902 3.85433002 0.2902 3.85433002 0.27165 3.85433002 3 P 0 N
A 0.36893996 3.81496004 0.36893996 3.81496004 0.35038996 3.81496004 3 P 0 N
L 0.27165 3.85433002 0.35038996 3.81496004 9 P 0 
A 0.2902 4.01181004 0.2902 4.01181004 0.27165 4.01181004 3 P 0 N
A 0.36893996 3.97243996 0.36893996 3.97243996 0.35038996 3.97243996 3 P 0 N
L 0.27165 4.01181004 0.35038996 3.97243996 9 P 0 
A 0.2902 4.16928996 0.2902 4.16928996 0.27165 4.16928996 3 P 0 N
A 0.36893996 4.12991998 0.36893996 4.12991998 0.35038996 4.12991998 3 P 0 N
L 0.27165 4.16928996 0.35038996 4.12991998 9 P 0 
A 0.2902 4.32676998 0.2902 4.32676998 0.27165 4.32676998 3 P 0 N
A 0.36893996 4.2874 0.36893996 4.2874 0.35038996 4.2874 3 P 0 N
L 0.27165 4.32676998 0.35038996 4.2874 9 P 0 
L 0.27165 4.48425 0.35038996 4.44488002 9 P 0 
A 0.36893996 4.44488002 0.36893996 4.44488002 0.35038996 4.44488002 3 P 0 N
A 0.2902 4.48425 0.2902 4.48425 0.27165 4.48425 3 P 0 N
L 4.87 0.025 6.565 0.025 14 P 0 
L 4.885 0.085 6.53 0.085 14 P 0 
L 4.895 0.15 6.54 0.15 14 P 0 
L 4.89 0.215 6.555 0.215 14 P 0 
L 4.89 0.3 6.535 0.3 14 P 0 
L 4.895 0.37 6.54 0.37 14 P 0 
A 12.84646004 6.02361998 12.9252 5.94488002 12.84646004 5.94488002 9 P 0 Y
A 12.9252 0.07873996 12.84646004 0 12.84646004 0.07873996 9 P 0 Y
L 12.9252 5.94488002 12.9252 0.07873996 9 P 0 
L 12.84646004 0 6.66536004 0 9 P 0 
A 6.58661998 0.35433002 6.50788002 0.43306998 6.50788002 0.35433002 9 P 0 N
A 6.66536004 0 6.58661998 0.07873996 6.66535994 0.07873996 9 P 0 Y
L 6.58661998 0.07873996 6.58661998 0.35433002 9 P 0 
A 4.93308002 0.43306998 4.85433996 0.35433002 4.93307992 0.35433002 9 P 0 N
L 6.50788002 0.43306998 4.93308002 0.43306998 9 P 0 
L 4.85433996 0.35433002 4.85433996 0.07873996 9 P 0 
A 4.85433996 0.07873996 4.77558996 0 4.7755999 0.07873996 9 P 0 Y
A 0.07873996 0 0 0.07873996 0.07873996 0.07873996 9 P 0 Y
L 4.77558996 0 0.07873996 0 9 P 0 
L 0.07873996 6.02361998 12.84646004 6.02361998 9 P 0 
A 0 5.94488002 0.07873996 6.02361998 0.07873996 5.94488002 9 P 0 Y
L 0 0.07873996 0 5.94488002 9 P 0 
L 0 6.07011998 12.89 6.07011998 14 P 0 
L 0 -0.0465 12.89 -0.0465 14 P 0 
L 0.005 6.16 0.035 6.13 3 P 0 
L 12.91 6.15 12.88 6.12 3 P 0 
L 12.91 -0.13 12.88 -0.1 3 P 0 
L 0.005 -0.135 0.035 -0.105 3 P 0 
L 0 -0.41426004 0 -0.093 9 P 0 
A 0.07873996 -0.493 0 -0.41426004 0.07873996 -0.41426004 9 P 0 Y
L 12.84646004 -0.493 0.07873996 -0.493 9 P 0 
A 12.9252 -0.41426004 12.84646004 -0.493 12.84646004 -0.41426004 9 P 0 Y
L 12.9252 -0.093 12.9252 -0.41426004 9 P 0 
L 0 -0.093 12.9252 -0.093 9 P 0 
L 0 6.11661998 12.9252 6.11661998 9 P 0 
L 0 6.43788002 0 6.11661998 9 P 0 
A 0.07873996 6.51661998 0 6.43788002 0.07873996 6.43788002 9 P 0 N
L 12.84646004 6.51661998 0.07873996 6.51661998 9 P 0 
A 12.9252 6.43788002 12.84646004 6.51661998 12.84646004 6.43788002 9 P 0 N
L 12.9252 6.11661998 12.9252 6.43788002 9 P 0 
L 0.0349 -2.3038 0.0349 -1.0038 2 P 0 ;0
L 0.0349 -1.0038 4.5349 -1.0038 2 P 0 ;0
L 4.5349 -1.0038 4.5349 -2.3038 2 P 0 ;0
L 4.5349 -2.3038 0.0349 -2.3038 2 P 0 ;0
L 0.0349 -1.6038 4.5349 -1.6038 2 P 0 ;0
L 0.0349 -1.8038 4.5349 -1.8038 2 P 0 ;0
L 2.4349 -2.1038 4.0349 -2.1038 2 P 0 ;0
L 2.4349 -2.3038 2.4349 -1.8038 2 P 0 ;0
L 3.2349 -2.1038 3.2349 -1.8038 2 P 0 ;0
L 4.0349 -2.3038 4.0349 -1.8038 2 P 0 ;0
L 0.0723999 -1.6844687 0.07906663 -1.69030079 1 P 0 ;0
L 0.07906663 -1.69030079 0.08656654 -1.6938 1 P 0 ;0
L 0.08656654 -1.6938 0.09323337 -1.6938 1 P 0 ;0
L 0.09323337 -1.6938 0.0999001 -1.69030079 1 P 0 ;0
L 0.0999001 -1.69030079 0.10490059 -1.6844687 1 P 0 ;0
L 0.10490059 -1.6844687 0.1074 -1.67629951 1 P 0 ;0
L 0.1074 -1.67629951 0.10573376 -1.66813455 1 P 0 ;0
L 0.10573376 -1.66813455 0.10156644 -1.66113396 1 P 0 ;0
L 0.10156644 -1.66113396 0.09406654 -1.65646614 1 P 0 ;0
L 0.09406654 -1.65646614 0.08406713 -1.65413327 1 P 0 ;0
L 0.08406713 -1.65413327 0.07823346 -1.64946762 1 P 0 ;0
L 0.07823346 -1.64946762 0.07573248 -1.64130059 1 P 0 ;0
L 0.07573248 -1.64130059 0.0774003 -1.63313356 1 P 0 ;0
L 0.0774003 -1.63313356 0.08156614 -1.62730148 1 P 0 ;0
L 0.08156614 -1.62730148 0.0873997 -1.6238 1 P 0 ;0
L 0.0873997 -1.6238 0.09323337 -1.6238 1 P 8191 ;0
L 0.09323337 -1.6238 0.09906693 -1.62613287 1 P 0 ;0
L 0.09906693 -1.62613287 0.10406742 -1.63196713 1 P 0 ;0
L 0.1383999 -1.6938 0.1383999 -1.6238 1 P 0 ;0
L 0.1734 -1.6238 0.1734 -1.6938 1 P 0 ;0
L 0.1734 -1.65880108 0.1383999 -1.65880108 1 P 0 ;0
L 0.23856683 -1.6938 0.20523307 -1.6938 1 P 0 ;0
L 0.20523307 -1.6938 0.20523307 -1.6238 1 P 0 ;0
L 0.20523307 -1.6238 0.23856683 -1.6238 1 P 0 ;0
L 0.22523337 -1.65763258 0.20523307 -1.65763258 1 P 0 ;0
L 0.30456683 -1.6938 0.27123307 -1.6938 1 P 0 ;0
L 0.27123307 -1.6938 0.27123307 -1.6238 1 P 0 ;0
L 0.27123307 -1.6238 0.30456683 -1.6238 1 P 0 ;0
L 0.29123337 -1.65763258 0.27123307 -1.65763258 1 P 0 ;0
L 0.35389921 -1.6238 0.35389921 -1.6938 1 P 0 ;0
L 0.33473356 -1.6238 0.37306634 -1.6238 1 P 0 ;0
L 0.09489921 -1.7188 0.09489921 -1.7888 1 P 0 ;0
L 0.07573356 -1.7188 0.11406634 -1.7188 1 P 0 ;0
L 0.1508998 -1.7188 0.17089862 -1.7188 1 P 0 ;0
L 0.16089921 -1.7188 0.16089921 -1.7888 1 P 0 ;0
L 0.1508998 -1.7888 0.17089862 -1.7888 1 P 0 ;0
L 0.22689921 -1.7188 0.22689921 -1.7888 1 P 0 ;0
L 0.20773356 -1.7188 0.24606634 -1.7188 1 P 0 ;0
L 0.27623307 -1.7188 0.27623307 -1.7888 1 P 0 ;0
L 0.27623307 -1.7888 0.30956683 -1.7888 1 P 0 ;0
L 0.37556683 -1.7888 0.34223307 -1.7888 1 P 0 ;0
L 0.34223307 -1.7888 0.34223307 -1.7188 1 P 0 ;0
L 0.34223307 -1.7188 0.37556683 -1.7188 1 P 0 ;0
L 0.36223337 -1.75263258 0.34223307 -1.75263258 1 P 0 ;0
L 2.5438999 -1.96813563 2.5519 -1.97480089 1 P 0 ;0
L 2.5519 -1.97480089 2.5608999 -1.9788 1 P 0 ;0
L 2.5608999 -1.9788 2.5689 -1.9788 1 P 0 ;0
L 2.5689 -1.9788 2.5769001 -1.97480089 1 P 0 ;0
L 2.5769001 -1.97480089 2.58290069 -1.96813563 1 P 0 ;0
L 2.58290069 -1.96813563 2.5859 -1.95879941 1 P 0 ;0
L 2.5859 -1.95879941 2.58390049 -1.94946811 1 P 0 ;0
L 2.58390049 -1.94946811 2.5788997 -1.94146732 1 P 0 ;0
L 2.5788997 -1.94146732 2.5698998 -1.93613278 1 P 0 ;0
L 2.5698998 -1.93613278 2.55790049 -1.93346663 1 P 0 ;0
L 2.55790049 -1.93346663 2.5509002 -1.92813445 1 P 0 ;0
L 2.5509002 -1.92813445 2.54789902 -1.91880069 1 P 0 ;0
L 2.54789902 -1.91880069 2.54990039 -1.90946683 1 P 0 ;0
L 2.54990039 -1.90946683 2.55489931 -1.90280167 1 P 0 ;0
L 2.55489931 -1.90280167 2.5618997 -1.8988 1 P 0 ;0
L 2.5618997 -1.8988 2.5689 -1.8988 1 P 0 ;0
L 2.5689 -1.8988 2.57590039 -1.90146614 1 P 0 ;0
L 2.57590039 -1.90146614 2.58190089 -1.90813386 1 P 0 ;0
L 2.6648998 -1.90546772 2.65889931 -1.90146614 1 P 0 ;0
L 2.65889931 -1.90146614 2.65190079 -1.8988 1 P 0 ;0
L 2.65190079 -1.8988 2.64390069 -1.8988 1 P 0 ;0
L 2.64390069 -1.8988 2.63489892 -1.90280167 1 P 0 ;0
L 2.63489892 -1.90280167 2.62790039 -1.90946683 1 P 0 ;0
L 2.62790039 -1.90946683 2.62289961 -1.91746762 1 P 0 ;0
L 2.62289961 -1.91746762 2.61889862 -1.93080049 1 P 0 ;0
L 2.61889862 -1.93080049 2.61789892 -1.94280039 1 P 0 ;0
L 2.61789892 -1.94280039 2.6199003 -1.9548003 1 P 0 ;0
L 2.6199003 -1.9548003 2.62289961 -1.96280098 1 P 0 ;0
L 2.62289961 -1.96280098 2.6289002 -1.97080177 1 P 0 ;0
L 2.6289002 -1.97080177 2.63590049 -1.97613396 1 P 0 ;0
L 2.63590049 -1.97613396 2.64289902 -1.9788 1 P 0 ;0
L 2.64289902 -1.9788 2.64989941 -1.9788 1 P 0 ;0
L 2.64989941 -1.9788 2.6568997 -1.97613396 1 P 0 ;0
L 2.6568997 -1.97613396 2.6629003 -1.97213484 1 P 0 ;0
L 2.6629003 -1.97213484 2.66790098 -1.96680266 1 P 0 ;0
L 2.69589892 -1.9788 2.72089902 -1.8988 1 P 0 ;0
L 2.72089902 -1.8988 2.74590098 -1.9788 1 P 0 ;0
L 2.73689931 -1.95080118 2.70489882 -1.95080118 1 P 0 ;0
L 2.77889961 -1.8988 2.77889961 -1.9788 1 P 0 ;0
L 2.77889961 -1.9788 2.8189003 -1.9788 1 P 0 ;0
L 2.8969003 -1.9788 2.85689961 -1.9788 1 P 0 ;0
L 2.85689961 -1.9788 2.85689961 -1.8988 1 P 0 ;0
L 2.85689961 -1.8988 2.8969003 -1.8988 1 P 0 ;0
L 2.8809 -1.93746575 2.85689961 -1.93746575 1 P 0 ;0
L 3.03289902 -1.9788 3.03289902 -1.8988 1 P 0 ;0
L 3.03289902 -1.8988 3.0208998 -1.91479911 1 P 0 ;0
L 3.0208998 -1.9788 3.04489833 -1.9788 1 P 0 ;0
L 3.11089902 -1.98146604 3.10889951 -1.98013297 1 P 8191 ;0
L 3.10889951 -1.98013297 3.10889951 -1.97746703 1 P 8191 ;0
L 3.10889951 -1.97746703 3.11089902 -1.97613396 1 P 8191 ;0
L 3.11089902 -1.97613396 3.11290039 -1.97746703 1 P 8191 ;0
L 3.11290039 -1.97746703 3.11290039 -1.98013297 1 P 8191 ;0
L 3.11290039 -1.98013297 3.11089902 -1.98146604 1 P 8191 ;0
L 3.11089902 -1.945469 3.10889951 -1.94413346 1 P 8191 ;0
L 3.10889951 -1.94413346 3.10889951 -1.94146732 1 P 8191 ;0
L 3.10889951 -1.94146732 3.11089902 -1.94013435 1 P 8191 ;0
L 3.11089902 -1.94013435 3.11290039 -1.94146732 1 P 8191 ;0
L 3.11290039 -1.94146732 3.11290039 -1.94413346 1 P 8191 ;0
L 3.11290039 -1.94413346 3.11089902 -1.945469 1 P 8191 ;0
L 3.18889902 -1.9788 3.18889902 -1.8988 1 P 0 ;0
L 3.18889902 -1.8988 3.1768998 -1.91479911 1 P 0 ;0
L 3.1768998 -1.9788 3.20089833 -1.9788 1 P 0 ;0
L 2.5138999 -2.23313563 2.5219 -2.23980089 1 P 0 ;0
L 2.5219 -2.23980089 2.5308999 -2.2438 1 P 0 ;0
L 2.5308999 -2.2438 2.5389 -2.2438 1 P 0 ;0
L 2.5389 -2.2438 2.5469001 -2.23980089 1 P 0 ;0
L 2.5469001 -2.23980089 2.55290069 -2.23313563 1 P 0 ;0
L 2.55290069 -2.23313563 2.5559 -2.22379941 1 P 0 ;0
L 2.5559 -2.22379941 2.55390049 -2.21446811 1 P 0 ;0
L 2.55390049 -2.21446811 2.5488997 -2.20646732 1 P 0 ;0
L 2.5488997 -2.20646732 2.5398998 -2.20113278 1 P 0 ;0
L 2.5398998 -2.20113278 2.52790049 -2.19846663 1 P 0 ;0
L 2.52790049 -2.19846663 2.5209002 -2.19313445 1 P 0 ;0
L 2.5209002 -2.19313445 2.51789902 -2.18380069 1 P 0 ;0
L 2.51789902 -2.18380069 2.51990039 -2.17446683 1 P 0 ;0
L 2.51990039 -2.17446683 2.52489931 -2.16780167 1 P 0 ;0
L 2.52489931 -2.16780167 2.5318997 -2.1638 1 P 0 ;0
L 2.5318997 -2.1638 2.5389 -2.1638 1 P 0 ;0
L 2.5389 -2.1638 2.54590039 -2.16646614 1 P 0 ;0
L 2.54590039 -2.16646614 2.55190089 -2.17313386 1 P 0 ;0
L 2.5918999 -2.2438 2.5918999 -2.1638 1 P 0 ;0
L 2.6339 -2.1638 2.6339 -2.2438 1 P 0 ;0
L 2.6339 -2.20380128 2.5918999 -2.20380128 1 P 0 ;0
L 2.7109003 -2.2438 2.67089961 -2.2438 1 P 0 ;0
L 2.67089961 -2.2438 2.67089961 -2.1638 1 P 0 ;0
L 2.67089961 -2.1638 2.7109003 -2.1638 1 P 0 ;0
L 2.6949 -2.20246575 2.67089961 -2.20246575 1 P 0 ;0
L 2.7889003 -2.2438 2.74889961 -2.2438 1 P 0 ;0
L 2.74889961 -2.2438 2.74889961 -2.1638 1 P 0 ;0
L 2.74889961 -2.1638 2.7889003 -2.1638 1 P 0 ;0
L 2.7729 -2.20246575 2.74889961 -2.20246575 1 P 0 ;0
L 2.84689902 -2.1638 2.84689902 -2.2438 1 P 0 ;0
L 2.8239003 -2.1638 2.86989961 -2.1638 1 P 0 ;0
L 3.29489961 -1.9238 3.29489961 -2.0038 1 P 0 ;0
L 3.29489961 -2.0038 3.3349003 -2.0038 1 P 0 ;0
L 3.36789892 -2.0038 3.39289902 -1.9238 1 P 0 ;0
L 3.39289902 -1.9238 3.41790098 -2.0038 1 P 0 ;0
L 3.40889931 -1.97580118 3.37689882 -1.97580118 1 P 0 ;0
L 3.47089902 -2.0038 3.47089902 -1.96780039 1 P 0 ;0
L 3.47089902 -1.96780039 3.45089961 -1.9238 1 P 0 ;0
L 3.4909003 -1.9238 3.47089902 -1.96780039 1 P 0 ;0
L 3.5689003 -2.0038 3.52889961 -2.0038 1 P 0 ;0
L 3.52889961 -2.0038 3.52889961 -1.9238 1 P 0 ;0
L 3.52889961 -1.9238 3.5689003 -1.9238 1 P 0 ;0
L 3.5529 -1.96246575 3.52889961 -1.96246575 1 P 0 ;0
L 3.60689961 -2.0038 3.60689961 -1.9238 1 P 0 ;0
L 3.60689961 -1.9238 3.6318998 -1.9238 1 P 0 ;0
L 3.6318998 -1.9238 3.6398999 -1.92780167 1 P 0 ;0
L 3.6398999 -1.92780167 3.64490069 -1.93313386 1 P 0 ;0
L 3.64490069 -1.93313386 3.6469003 -1.94380069 1 P 0 ;0
L 3.6469003 -1.94380069 3.64490069 -1.95446752 1 P 0 ;0
L 3.64490069 -1.95446752 3.6389001 -1.96113278 1 P 0 ;0
L 3.6389001 -1.96113278 3.6318998 -1.96513435 1 P 0 ;0
L 3.6318998 -1.96513435 3.60689961 -1.96513435 1 P 0 ;0
L 3.6318998 -1.96513435 3.6469003 -2.0038 1 P 0 ;0
L 3.33989902 -2.2538 3.33189892 -2.25246703 1 P 0 ;0
L 3.33189892 -2.25246703 3.32490039 -2.24713484 1 P 0 ;0
L 3.32490039 -2.24713484 3.3188999 -2.23913406 1 P 0 ;0
L 3.3188999 -2.23913406 3.31489892 -2.2298003 1 P 0 ;0
L 3.31489892 -2.2298003 3.31289931 -2.21913346 1 P 0 ;0
L 3.31289931 -2.21913346 3.31289931 -2.20846663 1 P 0 ;0
L 3.31289931 -2.20846663 3.31489892 -2.1977998 1 P 0 ;0
L 3.31489892 -2.1977998 3.3188999 -2.18846604 1 P 0 ;0
L 3.3188999 -2.18846604 3.32490039 -2.18046772 1 P 0 ;0
L 3.32490039 -2.18046772 3.33189892 -2.17513307 1 P 0 ;0
L 3.33189892 -2.17513307 3.33989902 -2.1738 1 P 0 ;0
L 3.33989902 -2.1738 3.34789911 -2.17513307 1 P 0 ;0
L 3.34789911 -2.17513307 3.35489951 -2.18046772 1 P 0 ;0
L 3.35489951 -2.18046772 3.3609 -2.18846604 1 P 0 ;0
L 3.3609 -2.18846604 3.36490098 -2.1977998 1 P 0 ;0
L 3.36490098 -2.1977998 3.36690059 -2.20846663 1 P 0 ;0
L 3.36690059 -2.20846663 3.36690059 -2.21913346 1 P 0 ;0
L 3.36690059 -2.21913346 3.36490098 -2.2298003 1 P 0 ;0
L 3.36490098 -2.2298003 3.3609 -2.23913406 1 P 0 ;0
L 3.3609 -2.23913406 3.35489951 -2.24713484 1 P 0 ;0
L 3.35489951 -2.24713484 3.34789911 -2.25246703 1 P 0 ;0
L 3.34789911 -2.25246703 3.33989902 -2.2538 1 P 0 ;0
L 3.39889941 -2.2538 3.39889941 -2.1738 1 P 0 ;0
L 3.39889941 -2.1738 3.43690049 -2.1738 1 P 0 ;0
L 3.4228998 -2.21246575 3.39889941 -2.21246575 1 P 0 ;0
L 0.16489872 -1.0538 0.16489872 -1.1538 1 P 0 ;0
L 0.13423376 -1.0538 0.19556614 -1.0538 1 P 0 ;0
L 0.2588997 -1.0538 0.29089774 -1.0538 1 P 0 ;0
L 0.27489872 -1.0538 0.27489872 -1.1538 1 P 0 ;0
L 0.2588997 -1.1538 0.29089774 -1.1538 1 P 0 ;0
L 0.38489872 -1.0538 0.38489872 -1.1538 1 P 0 ;0
L 0.35423376 -1.0538 0.41556614 -1.0538 1 P 0 ;0
L 0.46823287 -1.0538 0.46823287 -1.1538 1 P 0 ;0
L 0.46823287 -1.1538 0.52156703 -1.1538 1 P 0 ;0
L 0.63156703 -1.1538 0.57823287 -1.1538 1 P 0 ;0
L 0.57823287 -1.1538 0.57823287 -1.0538 1 P 0 ;0
L 0.57823287 -1.0538 0.63156703 -1.0538 1 P 0 ;0
L 0.61023337 -1.10213219 0.57823287 -1.10213219 1 P 0 ;0
L 4.18989892 -1.9538 4.21489902 -1.8738 1 P 0 ;0
L 4.21489902 -1.8738 4.23990098 -1.9538 1 P 0 ;0
L 4.23089931 -1.92580118 4.19889882 -1.92580118 1 P 0 ;0
L 4.27289961 -1.9538 4.27289961 -1.8738 1 P 0 ;0
L 4.27289961 -1.8738 4.2978998 -1.8738 1 P 0 ;0
L 4.2978998 -1.8738 4.3058999 -1.87780167 1 P 0 ;0
L 4.3058999 -1.87780167 4.31090069 -1.88313386 1 P 0 ;0
L 4.31090069 -1.88313386 4.3129003 -1.89380069 1 P 0 ;0
L 4.3129003 -1.89380069 4.31090069 -1.90446752 1 P 0 ;0
L 4.31090069 -1.90446752 4.3049001 -1.91113278 1 P 0 ;0
L 4.3049001 -1.91113278 4.2978998 -1.91513435 1 P 0 ;0
L 4.2978998 -1.91513435 4.27289961 -1.91513435 1 P 0 ;0
L 4.2978998 -1.91513435 4.3129003 -1.9538 1 P 0 ;0
L 4.37089902 -1.8738 4.37089902 -1.9538 1 P 0 ;0
L 4.3479003 -1.8738 4.39389961 -1.8738 1 P 0 ;0
L 3.61989892 -2.2538 3.61989892 -2.1638 1 P 0 ;0
L 3.61989892 -2.1638 3.6058997 -2.18179892 1 P 0 ;0
L 3.6058997 -2.2538 3.63389803 -2.2538 1 P 0 ;0
L 3.68773268 -2.17879961 3.69473337 -2.16980148 1 P 0 ;0
L 3.69473337 -2.16980148 3.70290039 -2.1652997 1 P 0 ;0
L 3.70290039 -2.1652997 3.71223386 -2.1638 1 P 0 ;0
L 3.71223386 -2.1638 3.7239002 -2.16679941 1 P 0 ;0
L 3.7239002 -2.16679941 3.73206722 -2.17430059 1 P 0 ;0
L 3.73206722 -2.17430059 3.7344001 -2.18329862 1 P 0 ;0
L 3.7344001 -2.18329862 3.73323366 -2.19230217 1 P 0 ;0
L 3.73323366 -2.19230217 3.72856585 -2.19980059 1 P 0 ;0
L 3.72856585 -2.19980059 3.70523317 -2.2148001 1 P 0 ;0
L 3.70523317 -2.2148001 3.69473337 -2.22530069 1 P 0 ;0
L 3.69473337 -2.22530069 3.68773268 -2.24030295 1 P 0 ;0
L 3.68773268 -2.24030295 3.6853998 -2.2538 1 P 0 ;0
L 3.6853998 -2.2538 3.7344001 -2.2538 1 P 0 ;0
L 0.59099833 -1.36499882 0.5990003 -1.35750039 1 P 0 ;0
L 0.5990003 -1.35750039 0.60499902 -1.34500315 1 P 0 ;0
L 0.60499902 -1.34500315 0.60900187 -1.32749764 1 P 0 ;0
L 0.60900187 -1.32749764 0.60499902 -1.31250089 1 P 0 ;0
L 0.60499902 -1.31250089 0.59700079 -1.30250305 1 P 0 ;0
L 0.59700079 -1.30250305 0.5830001 -1.295 1 P 0 ;0
L 0.5830001 -1.295 0.52900059 -1.295 1 P 0 ;0
L 0.52900059 -1.295 0.52900059 -1.445 1 P 0 ;0
L 0.52900059 -1.445 0.59500118 -1.445 1 P 0 ;0
L 0.59500118 -1.445 0.60900187 -1.43500217 1 P 0 ;0
L 0.60900187 -1.43500217 0.6170001 -1.42000079 1 P 0 ;0
L 0.6170001 -1.42000079 0.62099931 -1.4025 1 P 0 ;0
L 0.62099931 -1.4025 0.6170001 -1.38500374 1 P 0 ;0
L 0.6170001 -1.38500374 0.60499902 -1.37000236 1 P 0 ;0
L 0.60499902 -1.37000236 0.59099833 -1.36499882 1 P 0 ;0
L 0.59099833 -1.36499882 0.52900059 -1.36499882 1 P 0 ;0
L 0.77100138 -1.445 0.77100138 -1.34500315 1 P 0 ;0
L 0.77100138 -1.36249941 0.76299951 -1.35250148 1 P 0 ;0
L 0.76299951 -1.35250148 0.75099833 -1.34750256 1 P 0 ;0
L 0.75099833 -1.34750256 0.73700138 -1.34500315 1 P 0 ;0
L 0.73700138 -1.34500315 0.72300069 -1.35000207 1 P 0 ;0
L 0.72300069 -1.35000207 0.71099961 -1.3599999 1 P 0 ;0
L 0.71099961 -1.3599999 0.70299764 -1.37500128 1 P 0 ;0
L 0.70299764 -1.37500128 0.69899852 -1.39500157 1 P 0 ;0
L 0.69899852 -1.39500157 0.70299764 -1.41500187 1 P 0 ;0
L 0.70299764 -1.41500187 0.71099961 -1.43000325 1 P 0 ;0
L 0.71099961 -1.43000325 0.72300069 -1.44000108 1 P 0 ;0
L 0.72300069 -1.44000108 0.73700138 -1.445 1 P 0 ;0
L 0.73700138 -1.445 0.75099833 -1.44250059 1 P 0 ;0
L 0.75099833 -1.44250059 0.76299951 -1.43500217 1 P 0 ;0
L 0.76299951 -1.43500217 0.77100138 -1.42500433 1 P 0 ;0
L 0.86700039 -1.445 0.86700039 -1.34500315 1 P 0 ;0
L 0.86700039 -1.36499882 0.87699833 -1.35500098 1 P 0 ;0
L 0.87699833 -1.35500098 0.8869998 -1.34750256 1 P 0 ;0
L 0.8869998 -1.34750256 0.90100049 -1.34500315 1 P 0 ;0
L 0.90100049 -1.34500315 0.91099833 -1.34750256 1 P 0 ;0
L 0.91099833 -1.34750256 0.92299951 -1.35500098 1 P 0 ;0
L 1.02700039 -1.445 1.02700039 -1.34500315 1 P 0 ;0
L 1.02700039 -1.36499882 1.03699833 -1.35500098 1 P 0 ;0
L 1.03699833 -1.35500098 1.0469998 -1.34750256 1 P 0 ;0
L 1.0469998 -1.34750256 1.06100049 -1.34500315 1 P 0 ;0
L 1.06100049 -1.34500315 1.07099833 -1.34750256 1 P 0 ;0
L 1.07099833 -1.34750256 1.08299951 -1.35500098 1 P 0 ;0
L 1.18500089 -1.37750069 1.24900187 -1.37750069 1 P 0 ;0
L 1.24900187 -1.37750069 1.24299951 -1.3599999 1 P 0 ;0
L 1.24299951 -1.3599999 1.23300157 -1.35000207 1 P 0 ;0
L 1.23300157 -1.35000207 1.21900089 -1.34500315 1 P 0 ;0
L 1.21900089 -1.34500315 1.2050003 -1.34750256 1 P 0 ;0
L 1.2050003 -1.34750256 1.19299911 -1.35500098 1 P 0 ;0
L 1.19299911 -1.35500098 1.18500089 -1.37250177 1 P 0 ;0
L 1.18500089 -1.37250177 1.18099803 -1.38750315 1 P 0 ;0
L 1.18099803 -1.38750315 1.18099803 -1.4025 1 P 0 ;0
L 1.18099803 -1.4025 1.18500089 -1.41750138 1 P 0 ;0
L 1.18500089 -1.41750138 1.19499872 -1.43250276 1 P 0 ;0
L 1.19499872 -1.43250276 1.2069998 -1.44250059 1 P 0 ;0
L 1.2069998 -1.44250059 1.22100049 -1.445 1 P 0 ;0
L 1.22100049 -1.445 1.23500118 -1.44000108 1 P 0 ;0
L 1.23500118 -1.44000108 1.24900187 -1.42500433 1 P 0 ;0
L 1.37499813 -1.445 1.37499813 -1.295 1 P 0 ;0
L 1.50500089 -1.37750069 1.56900187 -1.37750069 1 P 0 ;0
L 1.56900187 -1.37750069 1.56299951 -1.3599999 1 P 0 ;0
L 1.56299951 -1.3599999 1.55300157 -1.35000207 1 P 0 ;0
L 1.55300157 -1.35000207 1.53900089 -1.34500315 1 P 0 ;0
L 1.53900089 -1.34500315 1.5250003 -1.34750256 1 P 0 ;0
L 1.5250003 -1.34750256 1.51299911 -1.35500098 1 P 0 ;0
L 1.51299911 -1.35500098 1.50500089 -1.37250177 1 P 0 ;0
L 1.50500089 -1.37250177 1.50099803 -1.38750315 1 P 0 ;0
L 1.50099803 -1.38750315 1.50099803 -1.4025 1 P 0 ;0
L 1.50099803 -1.4025 1.50500089 -1.41750138 1 P 0 ;0
L 1.50500089 -1.41750138 1.51499872 -1.43250276 1 P 0 ;0
L 1.51499872 -1.43250276 1.5269998 -1.44250059 1 P 0 ;0
L 1.5269998 -1.44250059 1.54100049 -1.445 1 P 0 ;0
L 1.54100049 -1.445 1.55500118 -1.44000108 1 P 0 ;0
L 1.55500118 -1.44000108 1.56900187 -1.42500433 1 P 0 ;0
L 1.6529998 -1.48999951 1.66500089 -1.49499843 1 P 0 ;0
L 1.66500089 -1.49499843 1.68100108 -1.48999951 1 P 0 ;0
L 1.68100108 -1.48999951 1.69099902 -1.48000167 1 P 0 ;0
L 1.69099902 -1.48000167 1.69900089 -1.4674997 1 P 0 ;0
L 1.69900089 -1.4674997 1.71099833 -1.42750374 1 P 0 ;0
L 1.71099833 -1.42750374 1.7370001 -1.34500315 1 P 0 ;0
L 1.67299911 -1.34500315 1.71099833 -1.42750374 1 P 0 ;0
L 1.82500089 -1.37750069 1.88900187 -1.37750069 1 P 0 ;0
L 1.88900187 -1.37750069 1.88299951 -1.3599999 1 P 0 ;0
L 1.88299951 -1.3599999 1.87300157 -1.35000207 1 P 0 ;0
L 1.87300157 -1.35000207 1.85900089 -1.34500315 1 P 0 ;0
L 1.85900089 -1.34500315 1.8450003 -1.34750256 1 P 0 ;0
L 1.8450003 -1.34750256 1.83299911 -1.35500098 1 P 0 ;0
L 1.83299911 -1.35500098 1.82500089 -1.37250177 1 P 0 ;0
L 1.82500089 -1.37250177 1.82099803 -1.38750315 1 P 0 ;0
L 1.82099803 -1.38750315 1.82099803 -1.4025 1 P 0 ;0
L 1.82099803 -1.4025 1.82500089 -1.41750138 1 P 0 ;0
L 1.82500089 -1.41750138 1.83499872 -1.43250276 1 P 0 ;0
L 1.83499872 -1.43250276 1.8469998 -1.44250059 1 P 0 ;0
L 1.8469998 -1.44250059 1.86100049 -1.445 1 P 0 ;0
L 1.86100049 -1.445 1.87500118 -1.44000108 1 P 0 ;0
L 1.87500118 -1.44000108 1.88900187 -1.42500433 1 P 0 ;0
L 2.18699921 -1.37000236 2.22700167 -1.37000236 1 P 0 ;0
L 2.22700167 -1.37000236 2.22700167 -1.41500187 1 P 0 ;0
L 2.22700167 -1.41500187 2.21500059 -1.43000325 1 P 0 ;0
L 2.21500059 -1.43000325 2.2009999 -1.44000108 1 P 0 ;0
L 2.2009999 -1.44000108 2.18100049 -1.445 1 P 0 ;0
L 2.18100049 -1.445 2.16100108 -1.44000108 1 P 0 ;0
L 2.16100108 -1.44000108 2.14700039 -1.43000325 1 P 0 ;0
L 2.14700039 -1.43000325 2.13499931 -1.41500187 1 P 0 ;0
L 2.13499931 -1.41500187 2.12699734 -1.39750108 1 P 0 ;0
L 2.12699734 -1.39750108 2.12299823 -1.37750069 1 P 0 ;0
L 2.12299823 -1.37750069 2.12299823 -1.3599999 1 P 0 ;0
L 2.12299823 -1.3599999 2.12699734 -1.34500315 1 P 0 ;0
L 2.12699734 -1.34500315 2.13499931 -1.32749764 1 P 0 ;0
L 2.13499931 -1.32749764 2.14700039 -1.31250089 1 P 0 ;0
L 2.14700039 -1.31250089 2.15899783 -1.30250305 1 P 0 ;0
L 2.15899783 -1.30250305 2.17499813 -1.295 1 P 0 ;0
L 2.17499813 -1.295 2.18899882 -1.295 1 P 0 ;0
L 2.18899882 -1.295 2.20499902 -1.29999902 1 P 0 ;0
L 2.20499902 -1.29999902 2.2170001 -1.31000138 1 P 0 ;0
L 2.29699892 -1.31999931 2.309 -1.30500246 1 P 0 ;0
L 2.309 -1.30500246 2.32300069 -1.29749951 1 P 0 ;0
L 2.32300069 -1.29749951 2.33900089 -1.295 1 P 0 ;0
L 2.33900089 -1.295 2.3590003 -1.29999902 1 P 0 ;0
L 2.3590003 -1.29999902 2.37300098 -1.31250089 1 P 0 ;0
L 2.37300098 -1.31250089 2.3770001 -1.32749764 1 P 0 ;0
L 2.3770001 -1.32749764 2.37500059 -1.34250364 1 P 0 ;0
L 2.37500059 -1.34250364 2.36699862 -1.35500098 1 P 0 ;0
L 2.36699862 -1.35500098 2.3269998 -1.3800002 1 P 0 ;0
L 2.3269998 -1.3800002 2.309 -1.39750108 1 P 0 ;0
L 2.309 -1.39750108 2.29699892 -1.42250482 1 P 0 ;0
L 2.29699892 -1.42250482 2.2929998 -1.445 1 P 0 ;0
L 2.2929998 -1.445 2.3770001 -1.445 1 P 0 ;0
L 2.6129998 -1.42500433 2.629 -1.43750167 1 P 0 ;0
L 2.629 -1.43750167 2.6469998 -1.445 1 P 0 ;0
L 2.6469998 -1.445 2.6630001 -1.445 1 P 0 ;0
L 2.6630001 -1.445 2.6790003 -1.43750167 1 P 0 ;0
L 2.6790003 -1.43750167 2.69100138 -1.42500433 1 P 0 ;0
L 2.69100138 -1.42500433 2.6970001 -1.40749892 1 P 0 ;0
L 2.6970001 -1.40749892 2.69300098 -1.39000266 1 P 0 ;0
L 2.69300098 -1.39000266 2.68299951 -1.37500128 1 P 0 ;0
L 2.68299951 -1.37500128 2.66499961 -1.36499882 1 P 0 ;0
L 2.66499961 -1.36499882 2.64100108 -1.3599999 1 P 0 ;0
L 2.64100108 -1.3599999 2.62700039 -1.35000207 1 P 0 ;0
L 2.62700039 -1.35000207 2.62099803 -1.33250118 1 P 0 ;0
L 2.62099803 -1.33250118 2.62500089 -1.31500039 1 P 0 ;0
L 2.62500089 -1.31500039 2.63499872 -1.30250305 1 P 0 ;0
L 2.63499872 -1.30250305 2.64899941 -1.295 1 P 0 ;0
L 2.64899941 -1.295 2.6630001 -1.295 1 P 0 ;0
L 2.6630001 -1.295 2.67700079 -1.29999902 1 P 0 ;0
L 2.67700079 -1.29999902 2.68900187 -1.31250089 1 P 0 ;0
L 2.7729998 -1.445 2.8570001 -1.295 1 P 0 ;0
L 2.7729998 -1.295 2.8570001 -1.445 1 P 0 ;0
L 2.92299823 -1.445 2.92299823 -1.295 1 P 0 ;0
L 2.92299823 -1.295 2.97499813 -1.42000079 1 P 0 ;0
L 2.97499813 -1.42000079 3.02700167 -1.295 1 P 0 ;0
L 3.02700167 -1.295 3.02700167 -1.445 1 P 0 ;0
L 3.09699892 -1.31999931 3.109 -1.30500246 1 P 0 ;0
L 3.109 -1.30500246 3.12300069 -1.29749951 1 P 0 ;0
L 3.12300069 -1.29749951 3.13900089 -1.295 1 P 0 ;0
L 3.13900089 -1.295 3.1590003 -1.29999902 1 P 0 ;0
L 3.1590003 -1.29999902 3.17300098 -1.31250089 1 P 0 ;0
L 3.17300098 -1.31250089 3.1770001 -1.32749764 1 P 0 ;0
L 3.1770001 -1.32749764 3.17500059 -1.34250364 1 P 0 ;0
L 3.17500059 -1.34250364 3.16699862 -1.35500098 1 P 0 ;0
L 3.16699862 -1.35500098 3.1269998 -1.3800002 1 P 0 ;0
L 3.1269998 -1.3800002 3.109 -1.39750108 1 P 0 ;0
L 3.109 -1.39750108 3.09699892 -1.42250482 1 P 0 ;0
L 3.09699892 -1.42250482 3.0929998 -1.445 1 P 0 ;0
L 3.0929998 -1.445 3.1770001 -1.445 1 P 0 ;0
L 3.269 -1.39500157 3.3209999 -1.39500157 1 P 0 ;0
L 3.41499931 -1.445 3.41499931 -1.295 1 P 0 ;0
L 3.41499931 -1.295 3.46499961 -1.295 1 P 0 ;0
L 3.46499961 -1.295 3.4809999 -1.30250305 1 P 0 ;0
L 3.4809999 -1.30250305 3.49100138 -1.31250089 1 P 0 ;0
L 3.49100138 -1.31250089 3.49500059 -1.33250118 1 P 0 ;0
L 3.49500059 -1.33250118 3.49100138 -1.35250148 1 P 0 ;0
L 3.49100138 -1.35250148 3.4790003 -1.36499882 1 P 0 ;0
L 3.4790003 -1.36499882 3.46499961 -1.37250177 1 P 0 ;0
L 3.46499961 -1.37250177 3.41499931 -1.37250177 1 P 0 ;0
L 3.46499961 -1.37250177 3.49500059 -1.445 1 P 0 ;0
L 3.61499813 -1.34500315 3.61499813 -1.445 1 P 0 ;0
L 3.61499813 -1.30500246 3.61099902 -1.30250305 1 P 8191 ;0
L 3.61099902 -1.30250305 3.61099902 -1.29749951 1 P 8191 ;0
L 3.61099902 -1.29749951 3.61499813 -1.295 1 P 8191 ;0
L 3.61499813 -1.295 3.61900089 -1.29749951 1 P 8191 ;0
L 3.61900089 -1.29749951 3.61900089 -1.30250305 1 P 8191 ;0
L 3.61900089 -1.30250305 3.61499813 -1.30500246 1 P 8191 ;0
L 3.74500089 -1.42750374 3.75499872 -1.43750167 1 P 0 ;0
L 3.75499872 -1.43750167 3.76899941 -1.445 1 P 0 ;0
L 3.76899941 -1.445 3.78100049 -1.445 1 P 0 ;0
L 3.78100049 -1.445 3.79300157 -1.44000108 1 P 0 ;0
L 3.79300157 -1.44000108 3.8009999 -1.43250276 1 P 0 ;0
L 3.8009999 -1.43250276 3.80499902 -1.42250482 1 P 0 ;0
L 3.80499902 -1.42250482 3.80299951 -1.40749892 1 P 0 ;0
L 3.80299951 -1.40749892 3.79500118 -1.40000049 1 P 0 ;0
L 3.79500118 -1.40000049 3.75899783 -1.38500374 1 P 0 ;0
L 3.75899783 -1.38500374 3.75099961 -1.36749833 1 P 0 ;0
L 3.75099961 -1.36749833 3.75499872 -1.35500098 1 P 0 ;0
L 3.75499872 -1.35500098 3.76300069 -1.34750256 1 P 0 ;0
L 3.76300069 -1.34750256 3.77499813 -1.34500315 1 P 0 ;0
L 3.77499813 -1.34500315 3.78699921 -1.34750256 1 P 0 ;0
L 3.78699921 -1.34750256 3.7990003 -1.35500098 1 P 0 ;0
L 3.90500089 -1.37750069 3.96900187 -1.37750069 1 P 0 ;0
L 3.96900187 -1.37750069 3.96299951 -1.3599999 1 P 0 ;0
L 3.96299951 -1.3599999 3.95300157 -1.35000207 1 P 0 ;0
L 3.95300157 -1.35000207 3.93900089 -1.34500315 1 P 0 ;0
L 3.93900089 -1.34500315 3.9250003 -1.34750256 1 P 0 ;0
L 3.9250003 -1.34750256 3.91299911 -1.35500098 1 P 0 ;0
L 3.91299911 -1.35500098 3.90500089 -1.37250177 1 P 0 ;0
L 3.90500089 -1.37250177 3.90099803 -1.38750315 1 P 0 ;0
L 3.90099803 -1.38750315 3.90099803 -1.4025 1 P 0 ;0
L 3.90099803 -1.4025 3.90500089 -1.41750138 1 P 0 ;0
L 3.90500089 -1.41750138 3.91499872 -1.43250276 1 P 0 ;0
L 3.91499872 -1.43250276 3.9269998 -1.44250059 1 P 0 ;0
L 3.9269998 -1.44250059 3.94100049 -1.445 1 P 0 ;0
L 3.94100049 -1.445 3.95500118 -1.44000108 1 P 0 ;0
L 3.95500118 -1.44000108 3.96900187 -1.42500433 1 P 0 ;0
L 4.06700039 -1.445 4.06700039 -1.34500315 1 P 0 ;0
L 4.06700039 -1.36499882 4.07699833 -1.35500098 1 P 0 ;0
L 4.07699833 -1.35500098 4.0869998 -1.34750256 1 P 0 ;0
L 4.0869998 -1.34750256 4.10100049 -1.34500315 1 P 0 ;0
L 4.10100049 -1.34500315 4.11099833 -1.34750256 1 P 0 ;0
L 4.11099833 -1.34750256 4.12299951 -1.35500098 1 P 0 ;0
L 4.16964783 -2.2038 4.21839813 -2.0478 1 P 0 ;0
L 4.21839813 -2.0478 4.26715207 -2.2038 1 P 0 ;0
L 4.24959862 -2.14920217 4.18719774 -2.14920217 1 P 0 ;0
L 4.37939813 -2.2038 4.37939813 -2.0478 1 P 0 ;0
L 4.37939813 -2.0478 4.35599961 -2.07899813 1 P 0 ;0
L 4.35599961 -2.2038 4.40279675 -2.2038 1 P 0 ;0
L 2.0009002 -0.9538 2.0009002 -0.8038 1 P 0 ;0
L 2.0009002 -0.8038 2.04089902 -0.8038 1 P 0 ;0
L 2.04089902 -0.8038 2.05689921 -0.81130305 1 P 0 ;0
L 2.05689921 -0.81130305 2.0689003 -0.82130089 1 P 0 ;0
L 2.0689003 -0.82130089 2.07890187 -0.83629764 1 P 0 ;0
L 2.07890187 -0.83629764 2.0869001 -0.85380315 1 P 0 ;0
L 2.0869001 -0.85380315 2.0888997 -0.87880236 1 P 0 ;0
L 2.0888997 -0.87880236 2.0869001 -0.90380157 1 P 0 ;0
L 2.0869001 -0.90380157 2.07890187 -0.92130246 1 P 0 ;0
L 2.07890187 -0.92130246 2.0689003 -0.93630374 1 P 0 ;0
L 2.0689003 -0.93630374 2.05689921 -0.94630167 1 P 0 ;0
L 2.05689921 -0.94630167 2.04089902 -0.9538 1 P 0 ;0
L 2.04089902 -0.9538 2.0009002 -0.9538 1 P 0 ;0
L 2.15489783 -0.9538 2.20489813 -0.8038 1 P 0 ;0
L 2.20489813 -0.8038 2.25490207 -0.9538 1 P 0 ;0
L 2.23689862 -0.90130207 2.17289764 -0.90130207 1 P 0 ;0
L 2.36489813 -0.8038 2.36489813 -0.9538 1 P 0 ;0
L 2.31890059 -0.8038 2.41089931 -0.8038 1 P 0 ;0
L 2.56490059 -0.9538 2.48489931 -0.9538 1 P 0 ;0
L 2.48489931 -0.9538 2.48489931 -0.8038 1 P 0 ;0
L 2.48489931 -0.8038 2.56490059 -0.8038 1 P 0 ;0
L 2.5329001 -0.87629833 2.48489931 -0.87629833 1 P 0 ;0
L 2.84489813 -0.9538 2.82889783 -0.95130059 1 P 0 ;0
L 2.82889783 -0.95130059 2.81490089 -0.94130276 1 P 0 ;0
L 2.81490089 -0.94130276 2.8028998 -0.92630138 1 P 0 ;0
L 2.8028998 -0.92630138 2.79489783 -0.90880049 1 P 0 ;0
L 2.79489783 -0.90880049 2.79089862 -0.8888002 1 P 0 ;0
L 2.79089862 -0.8888002 2.79089862 -0.8687999 1 P 0 ;0
L 2.79089862 -0.8687999 2.79489783 -0.84879961 1 P 0 ;0
L 2.79489783 -0.84879961 2.8028998 -0.83129872 1 P 0 ;0
L 2.8028998 -0.83129872 2.81490089 -0.81630197 1 P 0 ;0
L 2.81490089 -0.81630197 2.82889783 -0.80629951 1 P 0 ;0
L 2.82889783 -0.80629951 2.84489813 -0.8038 1 P 0 ;0
L 2.84489813 -0.8038 2.86089833 -0.80629951 1 P 0 ;0
L 2.86089833 -0.80629951 2.87489902 -0.81630197 1 P 0 ;0
L 2.87489902 -0.81630197 2.8869001 -0.83129872 1 P 0 ;0
L 2.8869001 -0.83129872 2.89490207 -0.84879961 1 P 0 ;0
L 2.89490207 -0.84879961 2.89890128 -0.8687999 1 P 0 ;0
L 2.89890128 -0.8687999 2.89890128 -0.8888002 1 P 0 ;0
L 2.89890128 -0.8888002 2.89490207 -0.90880049 1 P 0 ;0
L 2.89490207 -0.90880049 2.8869001 -0.92630138 1 P 0 ;0
L 2.8869001 -0.92630138 2.87489902 -0.94130276 1 P 0 ;0
L 2.87489902 -0.94130276 2.86089833 -0.95130059 1 P 0 ;0
L 2.86089833 -0.95130059 2.84489813 -0.9538 1 P 0 ;0
L 3.0488997 -0.81630197 3.03689862 -0.80879902 1 P 0 ;0
L 3.03689862 -0.80879902 3.02290157 -0.8038 1 P 0 ;0
L 3.02290157 -0.8038 3.00690138 -0.8038 1 P 0 ;0
L 3.00690138 -0.8038 2.98889783 -0.81130305 1 P 0 ;0
L 2.98889783 -0.81130305 2.97490089 -0.82380039 1 P 0 ;0
L 2.97490089 -0.82380039 2.96489931 -0.83880177 1 P 0 ;0
L 2.96489931 -0.83880177 2.95689734 -0.86380098 1 P 0 ;0
L 2.95689734 -0.86380098 2.95489783 -0.88630069 1 P 0 ;0
L 2.95489783 -0.88630069 2.95890059 -0.90880049 1 P 0 ;0
L 2.95890059 -0.90880049 2.96489931 -0.92380187 1 P 0 ;0
L 2.96489931 -0.92380187 2.97690039 -0.93880325 1 P 0 ;0
L 2.97690039 -0.93880325 2.99090108 -0.94880108 1 P 0 ;0
L 2.99090108 -0.94880108 3.00489813 -0.9538 1 P 0 ;0
L 3.00489813 -0.9538 3.01889882 -0.9538 1 P 0 ;0
L 3.01889882 -0.9538 3.03289951 -0.94880108 1 P 0 ;0
L 3.03289951 -0.94880108 3.04490059 -0.94130276 1 P 0 ;0
L 3.04490059 -0.94130276 3.05490207 -0.93130482 1 P 0 ;0
L 3.16489813 -0.8038 3.16489813 -0.9538 1 P 0 ;0
L 3.11890059 -0.8038 3.21089931 -0.8038 1 P 0 ;0
L 3.28889852 -0.95879892 3.36090138 -0.8038 1 P 0 ;0
L 3.44689892 -0.82879931 3.4589 -0.81380246 1 P 0 ;0
L 3.4589 -0.81380246 3.47290069 -0.80629951 1 P 0 ;0
L 3.47290069 -0.80629951 3.48890089 -0.8038 1 P 0 ;0
L 3.48890089 -0.8038 3.5089003 -0.80879902 1 P 0 ;0
L 3.5089003 -0.80879902 3.52290098 -0.82130089 1 P 0 ;0
L 3.52290098 -0.82130089 3.5269001 -0.83629764 1 P 0 ;0
L 3.5269001 -0.83629764 3.52490059 -0.85130364 1 P 0 ;0
L 3.52490059 -0.85130364 3.51689862 -0.86380098 1 P 0 ;0
L 3.51689862 -0.86380098 3.4768998 -0.8888002 1 P 0 ;0
L 3.4768998 -0.8888002 3.4589 -0.90630108 1 P 0 ;0
L 3.4589 -0.90630108 3.44689892 -0.93130482 1 P 0 ;0
L 3.44689892 -0.93130482 3.4428998 -0.9538 1 P 0 ;0
L 3.4428998 -0.9538 3.5269001 -0.9538 1 P 0 ;0
L 3.64089902 -0.9538 3.64489813 -0.92130246 1 P 0 ;0
L 3.64489813 -0.92130246 3.65090049 -0.89380374 1 P 0 ;0
L 3.65090049 -0.89380374 3.65889882 -0.8687999 1 P 0 ;0
L 3.65889882 -0.8687999 3.6689003 -0.84130118 1 P 0 ;0
L 3.6689003 -0.84130118 3.68490059 -0.8038 1 P 0 ;0
L 3.68490059 -0.8038 3.60489931 -0.8038 1 P 0 ;0
L 3.76889852 -0.95879892 3.84090138 -0.8038 1 P 0 ;0
L 3.92689892 -0.82879931 3.9389 -0.81380246 1 P 0 ;0
L 3.9389 -0.81380246 3.95290069 -0.80629951 1 P 0 ;0
L 3.95290069 -0.80629951 3.96890089 -0.8038 1 P 0 ;0
L 3.96890089 -0.8038 3.9889003 -0.80879902 1 P 0 ;0
L 3.9889003 -0.80879902 4.00290098 -0.82130089 1 P 0 ;0
L 4.00290098 -0.82130089 4.0069001 -0.83629764 1 P 0 ;0
L 4.0069001 -0.83629764 4.00490059 -0.85130364 1 P 0 ;0
L 4.00490059 -0.85130364 3.99689862 -0.86380098 1 P 0 ;0
L 3.99689862 -0.86380098 3.9568998 -0.8888002 1 P 0 ;0
L 3.9568998 -0.8888002 3.9389 -0.90630108 1 P 0 ;0
L 3.9389 -0.90630108 3.92689892 -0.93130482 1 P 0 ;0
L 3.92689892 -0.93130482 3.9228998 -0.9538 1 P 0 ;0
L 3.9228998 -0.9538 4.0069001 -0.9538 1 P 0 ;0
L 4.12489813 -0.8038 4.10889783 -0.80879902 1 P 0 ;0
L 4.10889783 -0.80879902 4.09690039 -0.82130089 1 P 0 ;0
L 4.09690039 -0.82130089 4.08889852 -0.83629764 1 P 0 ;0
L 4.08889852 -0.83629764 4.0828998 -0.85630256 1 P 0 ;0
L 4.0828998 -0.85630256 4.0809002 -0.87880236 1 P 0 ;0
L 4.0809002 -0.87880236 4.0828998 -0.90130207 1 P 0 ;0
L 4.0828998 -0.90130207 4.08889852 -0.92130246 1 P 0 ;0
L 4.08889852 -0.92130246 4.09690039 -0.93630374 1 P 0 ;0
L 4.09690039 -0.93630374 4.10889783 -0.94880108 1 P 0 ;0
L 4.10889783 -0.94880108 4.12489813 -0.9538 1 P 0 ;0
L 4.12489813 -0.9538 4.14089833 -0.94880108 1 P 0 ;0
L 4.14089833 -0.94880108 4.15289951 -0.93630374 1 P 0 ;0
L 4.15289951 -0.93630374 4.16090138 -0.92130246 1 P 0 ;0
L 4.16090138 -0.92130246 4.1669001 -0.90130207 1 P 0 ;0
L 4.1669001 -0.90130207 4.1688997 -0.87880236 1 P 0 ;0
L 4.1688997 -0.87880236 4.1669001 -0.85630256 1 P 0 ;0
L 4.1669001 -0.85630256 4.16090138 -0.83629764 1 P 0 ;0
L 4.16090138 -0.83629764 4.15289951 -0.82130089 1 P 0 ;0
L 4.15289951 -0.82130089 4.14089833 -0.80879902 1 P 0 ;0
L 4.14089833 -0.80879902 4.12489813 -0.8038 1 P 0 ;0
L 4.28489813 -0.9538 4.28489813 -0.8038 1 P 0 ;0
L 4.28489813 -0.8038 4.26089961 -0.83379823 1 P 0 ;0
L 4.26089961 -0.9538 4.30889665 -0.9538 1 P 0 ;0
L 4.44089902 -0.9538 4.44489813 -0.92130246 1 P 0 ;0
L 4.44489813 -0.92130246 4.45090049 -0.89380374 1 P 0 ;0
L 4.45090049 -0.89380374 4.45889882 -0.8687999 1 P 0 ;0
L 4.45889882 -0.8687999 4.4689003 -0.84130118 1 P 0 ;0
L 4.4689003 -0.84130118 4.48490059 -0.8038 1 P 0 ;0
L 4.48490059 -0.8038 4.40489931 -0.8038 1 P 0 ;0
L 1.9639003 -1.6638 1.93590197 -1.6638 1 P 0 ;0
L 1.94990108 -1.6638 1.94990108 -1.7538 1 P 0 ;0
L 1.9639003 -1.7538 1.93590197 -1.7538 1 P 0 ;0
L 1.88673297 -1.7538 1.88673297 -1.6638 1 P 0 ;0
L 1.88673297 -1.6638 1.83306713 -1.7538 1 P 0 ;0
L 1.83306713 -1.7538 1.83306713 -1.6638 1 P 0 ;0
L 1.76990108 -1.6638 1.76990108 -1.7538 1 P 0 ;0
L 1.79673297 -1.6638 1.74306713 -1.6638 1 P 0 ;0
L 1.65656634 -1.7538 1.70323376 -1.7538 1 P 0 ;0
L 1.70323376 -1.7538 1.70323376 -1.6638 1 P 0 ;0
L 1.70323376 -1.6638 1.65656634 -1.6638 1 P 0 ;0
L 1.67523327 -1.70729902 1.70323376 -1.70729902 1 P 0 ;0
L 1.61323376 -1.7538 1.61323376 -1.6638 1 P 0 ;0
L 1.61323376 -1.6638 1.58406693 -1.6638 1 P 0 ;0
L 1.58406693 -1.6638 1.57473346 -1.66830187 1 P 0 ;0
L 1.57473346 -1.66830187 1.56889921 -1.67430059 1 P 0 ;0
L 1.56889921 -1.67430059 1.56656634 -1.68630069 1 P 0 ;0
L 1.56656634 -1.68630069 1.56889921 -1.69830089 1 P 0 ;0
L 1.56889921 -1.69830089 1.5758998 -1.70579931 1 P 0 ;0
L 1.5758998 -1.70579931 1.58406693 -1.71030108 1 P 0 ;0
L 1.58406693 -1.71030108 1.61323376 -1.71030108 1 P 0 ;0
L 1.58406693 -1.71030108 1.56656634 -1.7538 1 P 0 ;0
L 1.52673297 -1.7538 1.52673297 -1.6638 1 P 0 ;0
L 1.52673297 -1.6638 1.47306713 -1.7538 1 P 0 ;0
L 1.47306713 -1.7538 1.47306713 -1.6638 1 P 0 ;0
L 1.43906791 -1.7538 1.40990108 -1.6638 1 P 0 ;0
L 1.40990108 -1.6638 1.38073219 -1.7538 1 P 0 ;0
L 1.39123415 -1.72230128 1.42856811 -1.72230128 1 P 0 ;0
L 1.34323376 -1.6638 1.34323376 -1.7538 1 P 0 ;0
L 1.34323376 -1.7538 1.29656634 -1.7538 1 P 0 ;0
L 1.16323376 -1.6638 1.16323376 -1.7538 1 P 0 ;0
L 1.16323376 -1.7538 1.11656634 -1.7538 1 P 0 ;0
L 1.07906791 -1.7538 1.04990108 -1.6638 1 P 0 ;0
L 1.04990108 -1.6638 1.02073219 -1.7538 1 P 0 ;0
L 1.03123415 -1.72230128 1.06856811 -1.72230128 1 P 0 ;0
L 0.95990108 -1.7538 0.95990108 -1.71330049 1 P 0 ;0
L 0.95990108 -1.71330049 0.98323376 -1.6638 1 P 0 ;0
L 0.93656634 -1.6638 0.95990108 -1.71330049 1 P 0 ;0
L 0.84656634 -1.7538 0.89323376 -1.7538 1 P 0 ;0
L 0.89323376 -1.7538 0.89323376 -1.6638 1 P 0 ;0
L 0.89323376 -1.6638 0.84656634 -1.6638 1 P 0 ;0
L 0.86523327 -1.70729902 0.89323376 -1.70729902 1 P 0 ;0
L 0.80323376 -1.7538 0.80323376 -1.6638 1 P 0 ;0
L 0.80323376 -1.6638 0.77406693 -1.6638 1 P 0 ;0
L 0.77406693 -1.6638 0.76473346 -1.66830187 1 P 0 ;0
L 0.76473346 -1.66830187 0.75889921 -1.67430059 1 P 0 ;0
L 0.75889921 -1.67430059 0.75656634 -1.68630069 1 P 0 ;0
L 0.75656634 -1.68630069 0.75889921 -1.69830089 1 P 0 ;0
L 0.75889921 -1.69830089 0.7658998 -1.70579931 1 P 0 ;0
L 0.7658998 -1.70579931 0.77406693 -1.71030108 1 P 0 ;0
L 0.77406693 -1.71030108 0.80323376 -1.71030108 1 P 0 ;0
L 0.77406693 -1.71030108 0.75656634 -1.7538 1 P 0 ;0
L 0.61973445 -1.74330226 0.61156742 -1.75080069 1 P 0 ;0
L 0.61156742 -1.75080069 0.60223396 -1.7538 1 P 0 ;0
L 0.60223396 -1.7538 0.59290049 -1.75080069 1 P 0 ;0
L 0.59290049 -1.75080069 0.58473346 -1.74180266 1 P 0 ;0
L 0.58473346 -1.74180266 0.57889921 -1.7283 1 P 0 ;0
L 0.57889921 -1.7283 0.57656634 -1.7148001 1 P 0 ;0
L 0.57656634 -1.7148001 0.57656634 -1.69830089 1 P 0 ;0
L 0.57656634 -1.69830089 0.57889921 -1.68480108 1 P 0 ;0
L 0.57889921 -1.68480108 0.58473346 -1.67280089 1 P 0 ;0
L 0.58473346 -1.67280089 0.59173406 -1.66679941 1 P 0 ;0
L 0.59173406 -1.66679941 0.59990108 -1.6638 1 P 0 ;0
L 0.59990108 -1.6638 0.60923455 -1.66679941 1 P 0 ;0
L 0.60923455 -1.66679941 0.61623307 -1.67280089 1 P 0 ;0
L 0.61623307 -1.67280089 0.62090089 -1.68179892 1 P 0 ;0
L 0.62090089 -1.68179892 0.62323376 -1.69380187 1 P 0 ;0
L 0.62323376 -1.69380187 0.62090089 -1.70429961 1 P 0 ;0
L 0.62090089 -1.70429961 0.61506663 -1.7148001 1 P 0 ;0
L 0.61506663 -1.7148001 0.60806604 -1.72080157 1 P 0 ;0
L 0.60806604 -1.72080157 0.59990108 -1.72230128 1 P 0 ;0
L 0.59990108 -1.72230128 0.59056762 -1.71930197 1 P 0 ;0
L 0.59056762 -1.71930197 0.58356703 -1.71180079 1 P 0 ;0
L 0.58356703 -1.71180079 0.57656634 -1.69830089 1 P 0 ;0
L 3.80006555 -1.99330226 3.80823258 -2.00080069 1 P 0 ;0
L 3.80823258 -2.00080069 3.81756604 -2.0038 1 P 0 ;0
L 3.81756604 -2.0038 3.82689951 -2.00080069 1 P 0 ;0
L 3.82689951 -2.00080069 3.83506654 -1.99180266 1 P 0 ;0
L 3.83506654 -1.99180266 3.84090079 -1.9783 1 P 0 ;0
L 3.84090079 -1.9783 3.84323366 -1.9648001 1 P 0 ;0
L 3.84323366 -1.9648001 3.84323366 -1.94830089 1 P 0 ;0
L 3.84323366 -1.94830089 3.84090079 -1.93480108 1 P 0 ;0
L 3.84090079 -1.93480108 3.83506654 -1.92280089 1 P 0 ;0
L 3.83506654 -1.92280089 3.82806594 -1.91679941 1 P 0 ;0
L 3.82806594 -1.91679941 3.81989892 -1.9138 1 P 0 ;0
L 3.81989892 -1.9138 3.81056545 -1.91679941 1 P 0 ;0
L 3.81056545 -1.91679941 3.80356693 -1.92280089 1 P 0 ;0
L 3.80356693 -1.92280089 3.79889911 -1.93179892 1 P 0 ;0
L 3.79889911 -1.93179892 3.79656624 -1.94380187 1 P 0 ;0
L 3.79656624 -1.94380187 3.79889911 -1.95429961 1 P 0 ;0
L 3.79889911 -1.95429961 3.80473337 -1.9648001 1 P 0 ;0
L 3.80473337 -1.9648001 3.81173396 -1.97080157 1 P 0 ;0
L 3.81173396 -1.97080157 3.81989892 -1.97230128 1 P 0 ;0
L 3.81989892 -1.97230128 3.82923238 -1.96930197 1 P 0 ;0
L 3.82923238 -1.96930197 3.83623297 -1.96180079 1 P 0 ;0
L 3.83623297 -1.96180079 3.84323366 -1.94830089 1 P 0 ;0
L 3.05006555 -2.24330226 3.05823258 -2.25080069 1 P 0 ;0
L 3.05823258 -2.25080069 3.06756604 -2.2538 1 P 0 ;0
L 3.06756604 -2.2538 3.07689951 -2.25080069 1 P 0 ;0
L 3.07689951 -2.25080069 3.08506654 -2.24180266 1 P 0 ;0
L 3.08506654 -2.24180266 3.09090079 -2.2283 1 P 0 ;0
L 3.09090079 -2.2283 3.09323366 -2.2148001 1 P 0 ;0
L 3.09323366 -2.2148001 3.09323366 -2.19830089 1 P 0 ;0
L 3.09323366 -2.19830089 3.09090079 -2.18480108 1 P 0 ;0
L 3.09090079 -2.18480108 3.08506654 -2.17280089 1 P 0 ;0
L 3.08506654 -2.17280089 3.07806594 -2.16679941 1 P 0 ;0
L 3.07806594 -2.16679941 3.06989892 -2.1638 1 P 0 ;0
L 3.06989892 -2.1638 3.06056545 -2.16679941 1 P 0 ;0
L 3.06056545 -2.16679941 3.05356693 -2.17280089 1 P 0 ;0
L 3.05356693 -2.17280089 3.04889911 -2.18179892 1 P 0 ;0
L 3.04889911 -2.18179892 3.04656624 -2.19380187 1 P 0 ;0
L 3.04656624 -2.19380187 3.04889911 -2.20429961 1 P 0 ;0
L 3.04889911 -2.20429961 3.05473337 -2.2148001 1 P 0 ;0
L 3.05473337 -2.2148001 3.06173396 -2.22080157 1 P 0 ;0
L 3.06173396 -2.22080157 3.06989892 -2.22230128 1 P 0 ;0
L 3.06989892 -2.22230128 3.07923238 -2.21930197 1 P 0 ;0
L 3.07923238 -2.21930197 3.08623297 -2.21180079 1 P 0 ;0
L 3.08623297 -2.21180079 3.09323366 -2.19830089 1 P 0 ;0

### steps/drc/layers/lc/features
#
#Feature symbol names
#
$0 r2
$1 r5
$2 r6
$3 r6.5
$4 r7
$5 r7.7
$6 r10
$7 r15
$8 r17
$9 r20
$10 r25.2
$11 r30
$12 r39.37
$13 r40
$14 r43.7
$15 r46.06
$16 r51.18
$17 r74.8
$18 r92.52
$19 r98.43
$20 r118.11
$21 r125
$22 r129.92
$23 r137.8
$24 r157.48
$25 r177.17
$26 r393.7
$27 s15
$28 s20
$29 s30
$30 s43.7
$31 s50
$32 s74.8
$33 oval196.85x137.8
$34 rect100x125.98
$35 rect11.02x43.31
$36 rect13.78x51.18
$37 rect15.75x35.43
$38 rect15.75x66.93
$39 rect161.42x78.74
$40 rect23.62x37.4
$41 rect23.62x41.34
$42 rect236.22x1614.17
$43 rect25.2x72.44
$44 rect29.92x50
$45 rect31.5x7.88xr3.94x14
$46 rect31.5x7.88xr3.94x23
$47 rect35.43x15.75
$48 rect39.37x108.27
$49 rect7.88x31.5xr3.94x12
$50 rect7.88x31.5xr3.94x34
$51 rect72.83x137.8
$52 rect74.8x66.93
$53 rect78.74x157.48
$54 rect78.74x35.43
$55 rect78.74x43.31
$56 rect82.68x122.05
$57 sp-8c5_2p0_254
$58 sp-8c5_2p0_254+2
$59 sp-9c5_7p0_254
$60 sp-9c5_7p0_254+2

#
#Feature attribute names
#
@0 .nomenclature
@1 .pattern_fill
@2 .smd
@3 .test_point
@4 .geometry
@5 .string
@6 .pad_usage
@7 .string_angle

#
#Feature attribute text strings
#
&0 TPB30V20D10AT28BPM
&1 R0_35X1_3
&2 C1_11P0_7
&3 C1_11P0_7TP
&4 S0_508
&5 R1_05X0_6
&6 ICT-TPT30TPM
&7 R1_27X0_76
&8 R0_9X0_4
&9 R0_9X2
&10 R1_1X0_28
&11 C0_64
&12 V17D8AT30SM11
&13 V20D10AT28SM14
&14 C2_5N
&15 R2X1_1
&16 R1X2_75
&17 S1_11P0_7TP
&18 S1_11P0_7
&19 SP-SC0_2X0_8TI-B
&20 R1_7X0_4
&21 S1_27
&22 R1_7X1_9
&23 S0_762
&24 R1_85X3_5
&25 R4X2
&26 R3_2X2_54
&27 R0_95X0_6
&28 R0_64X1_84
&29 R4_1X2
&30 V20D10AT28PG
&31 R2_1X3_1TM0
&32 C1_17P0_76TPM
&33 C1_9P1_4
&34 S1_9P1_4
&35 SP-8C5_2P0_254
&36 R6X41
&37 SP-9C5_7P0_254
&38 C3_175N-A
&39 E-C40SM100PM5-G
&40 C10N
&41 C3_3N
&42 C4_5N-B
&43 C4N-B
&44 C3_5N
&45 O5X3_5N
&46 C3N
&47 C1_3N
&48 C2_35N
&49 C1N
&50 45
&51 L12
&52 L10
&53 L5
&54 L3
&55 L1
&56 85
&57 SHEET
&58 TITLE
&59 SCALE 1:1
&60 LAYER
&61 OF
&62 ART
&63 12
&64 1
&65 TOP SIDE
&66 Barreleye G2 SXM2-Riser
&67 A1
&68 DATE OCT/27/2017

#
#Layer features
#
L 7.96733002 4.85788002 7.96733002 4.82231998 5 P 0 
L 7.96733002 4.82231998 7.96573996 4.82073002 5 P 0 
L 7.96573996 4.82073002 7.96573996 4.7218 5 P 0 
L 7.96573996 4.7218 7.97653996 4.711 5 P 0 
L 7.97653996 4.711 7.97653996 4.49653996 5 P 0 
L 7.97653996 4.49653996 7.895 4.415 5 P 0 
L 7.895 4.415 7.7927 4.415 5 P 0 
L 7.7927 4.415 7.785 4.4227 5 P 0 
L 7.785 4.4227 7.785 4.45 5 P 0 
P 7.785 4.45 9 P 0 0;4=0,6=1
P 7.96733002 4.85788002 36 P 0 0;2,4=1,6=0
L 7.94371004 4.85788002 7.94371004 4.82783002 5 P 0 
L 7.94371004 4.82783002 7.95003996 4.8215 5 P 0 
L 7.95003996 4.8215 7.95003996 4.51005 5 P 0 
L 7.95003996 4.51005 7.88998996 4.45 5 P 0 
L 7.88998996 4.45 7.835 4.45 5 P 0 
P 7.835 4.45 9 P 0 0;4=0,6=1
P 7.94371004 4.85788002 36 P 0 0;2,4=1,6=0
P 1.96378996 4.85788002 36 P 0 0;2,4=1,6=0
P 1.8 4.485 9 P 0 0;4=0,6=1
L 1.8 4.485 1.84 4.445 5 P 0 
L 1.84 4.445 1.88 4.445 5 P 0 
L 1.88 4.445 1.973 4.538 5 P 0 
L 1.973 4.538 1.973 4.711 5 P 0 
L 1.973 4.711 1.9622 4.7218 5 P 0 
L 1.9622 4.7218 1.9622 4.82073002 5 P 0 
L 1.9622 4.82073002 1.96378996 4.82231998 5 P 0 
L 1.96378996 4.82231998 1.96378996 4.85788002 5 P 0 
P 1.86 4.485 9 P 0 0;4=0,6=1
P 1.94016998 4.85788002 36 P 0 0;2,4=1,6=0
L 1.86 4.485 1.9465 4.5715 5 P 0 
L 1.9465 4.5715 1.9465 4.8215 5 P 0 
L 1.9465 4.8215 1.94016998 4.82783002 5 P 0 
L 1.94016998 4.82783002 1.94016998 4.85788002 5 P 0 
P 0.27165 1.72835 14 P 0 0;4=2,6=0
P 0.17323002 2.12205 14 P 0 0;4=2,6=0
P 12.73621004 1.76771998 14 P 0 0;4=2,6=0
P 12.81495 2.59448996 14 P 0 0;4=2,6=0
P 12.63778996 2.16141998 14 P 0 0;4=2,6=0
P 0.725 -0.25 14 P 0 0;4=3,6=0
P 0.875 -0.25 14 P 0 0;4=3,6=0
P 1.065 6.26 14 P 0 0;4=3,6=0
P 1.065 6.36 14 P 0 0;4=3,6=0
P 1.29 6.26 14 P 0 0;4=3,6=0
P 1.29 6.36 14 P 0 0;4=3,6=0
P 1.515 6.26 14 P 0 0;4=3,6=0
P 1.515 6.36 14 P 0 0;4=3,6=0
P 0.84 6.26 14 P 0 0;4=3,6=0
P 0.84 6.36 14 P 0 0;4=3,6=0
P 1.74 6.26 14 P 0 0;4=3,6=0
L 9.7 6.30445 1.746 6.30445 2 P 0 
L 1.746 6.30445 1.74 6.29845 2 P 0 
L 1.74 6.29845 1.74 6.26 2 P 0 
P 1.74 6.36 14 P 0 0;4=3,6=0
L 9.7 6.31555 1.746 6.31555 2 P 0 
L 1.746 6.31555 1.74 6.32155 2 P 0 
L 1.74 6.32155 1.74 6.36 2 P 0 
L 4.97 5.733 4.94 5.733 5 P 0 
L 4.94 5.733 4.929 5.744 5 P 0 
L 4.9574 5.65315 4.9574 5.6624 5 P 0 
L 4.9574 5.6624 4.97 5.675 5 P 0 
L 4.97 5.675 4.97 5.733 5 P 0 
P 4.97 5.733 28 P 0 0;2,4=4,6=0
P 4.9574 5.65315 41 P 0 0;2,4=5,6=0
P 4.929 5.744 11 P 0 0;3,4=6,6=1
L 4.665 5.48 4.665 5.69 5 P 0 
L 4.665 5.69 4.585 5.77 5 P 0 
L 4.585 5.77 4.585 5.78 5 P 0 
L 4.585 5.78 4.585 5.8165 5 P 0 
L 4.585 5.8165 4.5765 5.825 5 P 0 
L 4.5765 5.825 4.5435 5.825 5 P 0 
L 4.5435 5.825 4.535 5.8165 5 P 0 
L 4.535 5.8165 4.535 5.78 5 P 0 
P 4.535 5.78 44 P 0 0;2,4=7,6=0
P 4.585 5.78 44 P 0 0;2,4=7,6=0
P 5.04441004 5.55965 37 P 0 0;2,4=8,6=0
L 5.04441004 5.55965 5.04441004 5.52058996 5 P 0 
L 5.04441004 5.52058996 5.055 5.51 5 P 0 
L 5.055 5.51 5.115 5.51 5 P 0 
L 5.115 5.51 5.125 5.5 5 P 0 
L 5.125 5.5 5.125 5.467 5 P 0 
P 5.125 5.467 28 P 0 0;2,4=4,6=0
L 5.125 5.467 5.075 5.467 5 P 0 
L 5.075 5.467 5.025 5.467 5 P 0 
P 5.025 5.467 28 P 0 0;2,4=4,6=0
P 5.075 5.467 28 P 0 0;2,4=4,6=0
P 4.665 5.48 11 P 0 0;3,4=6,6=1
L 4.665 5.48 4.665 5.395 5 P 0 
L 4.665 5.395 4.73 5.33 5 P 0 
L 4.73 5.33 4.965 5.33 5 P 0 
L 4.965 5.33 4.995 5.36 5 P 0 
L 4.995 5.36 4.995 5.455 5 P 0 
L 4.995 5.455 5.007 5.467 5 P 0 
L 5.007 5.467 5.025 5.467 5 P 0 
L 5.015 5.755 5.003 5.767 5 P 0 
L 5.003 5.767 4.97 5.767 5 P 0 
L 5.07 5.64035 5.07 5.69 5 P 0 
L 5.07 5.69 5.06 5.7 5 P 0 
L 5.06 5.7 5.06 5.733 5 P 0 
P 4.97 5.767 28 P 0 0;2,4=4,6=0
L 5.06 5.733 5.037 5.733 5 P 0 
L 5.037 5.733 5.015 5.755 5 P 0 
P 5.06 5.733 28 P 0 0;2,4=4,6=0
P 5.07 5.64035 37 P 0 0;2,4=8,6=0
P 5.015 5.755 11 P 0 0;3,4=6,6=1
L 4.91 5.485 4.91 5.505 5 P 0 
L 4.91 5.505 4.92 5.515 5 P 0 
L 4.92 5.515 4.92 5.54685 5 P 0 
L 4.91 5.485 4.91 5.442 5 P 0 
P 4.92 5.54685 41 P 0 0;2,4=5,6=0
P 4.91 5.442 28 P 0 0;2,4=4,6=0
L 4.91 5.442 4.86 5.442 5 P 0 
P 4.86 5.442 28 P 0 0;2,4=4,6=0
P 4.91 5.485 11 P 0 0;3,4=6,6=1
L 4.81 5.485 4.81 5.5023 5 P 0 
L 4.81 5.5023 4.8177 5.51 5 P 0 
L 4.8177 5.51 4.8749 5.51 5 P 0 
L 4.8749 5.51 4.8826 5.5177 5 P 0 
L 4.8826 5.5177 4.8826 5.54685 5 P 0 
L 4.81 5.485 4.81 5.442 5 P 0 
P 4.8826 5.54685 41 P 0 0;2,4=5,6=0
P 4.81 5.442 28 P 0 0;2,4=4,6=0
L 4.81 5.442 4.76 5.442 5 P 0 
P 4.76 5.442 28 P 0 0;2,4=4,6=0
P 4.81 5.485 11 P 0 0;3,4=6,6=1
L 4.8826 5.65315 4.8826 5.7104 5 P 0 
L 4.8826 5.7104 4.86 5.733 5 P 0 
L 4.76 5.71071004 4.81571004 5.71071004 5 P 0 
L 4.81571004 5.71071004 4.838 5.733 5 P 0 
L 4.838 5.733 4.86 5.733 5 P 0 
P 4.86 5.733 28 P 0 0;2,4=4,6=0
P 4.76 5.71071004 54 P 0 0;2,4=9,6=0
P 4.8826 5.65315 41 P 0 0;2,4=5,6=0
P 4.725 5.775 11 P 0 0;3,4=6,6=1
L 4.725 5.775 4.725 5.725 5 P 0 
L 4.725 5.725 4.73928996 5.71071004 5 P 0 
L 4.73928996 5.71071004 4.76 5.71071004 5 P 0 
L 0.73 5.07 0.73 5.113 5 P 0 
L 0.73 5.027 0.805 5.027 5 P 0 
L 0.805 5.027 0.839 4.993 5 P 0 
L 0.839 4.993 0.97 4.993 5 P 0 
P 0.97 4.993 28 P 0 0;2,4=4,6=0
P 0.73 5.027 28 P 0 0;2,4=4,6=0
L 0.79046998 5.1239 0.79046998 5.10546998 5 P 0 
L 0.79046998 5.10546998 0.78466004 5.09966004 5 P 0 
L 0.78466004 5.09966004 0.76433996 5.09966004 5 P 0 
L 0.76433996 5.09966004 0.751 5.113 5 P 0 
L 0.751 5.113 0.73 5.113 5 P 0 
L 0.73 5.027 0.73 5.07 5 P 0 
P 0.73 5.113 28 P 0 0;2,4=4,6=0
P 0.79046998 5.1239 35 P 0 0;2,4=10,6=0
L 0.73 5.113 0.68 5.113 5 P 0 
P 0.68 5.113 28 P 0 0;2,4=4,6=0
P 0.73 5.07 11 P 0 0;3,4=6,6=1
L 4.14 4.605 4.125 4.59 5 P 0 
L 4.125 4.59 4.097 4.59 5 P 0 
P 4.08035 4.66441004 47 P 0 0;2,4=8,6=0
P 4.097 4.59 28 P 0 0;2,4=4,6=0
L 4.097 4.59 4.097 4.607 5 P 0 
L 4.097 4.607 4.106 4.616 5 P 0 
L 4.106 4.616 4.106 4.647 5 P 0 
L 4.106 4.647 4.08858996 4.66441004 5 P 0 
L 4.08858996 4.66441004 4.08035 4.66441004 5 P 0 
P 4.14 4.605 11 P 0 0;3,4=6,6=1
L 2.07106004 3.54115 2.09606004 3.56615 5 P 0 
P 2.07106004 3.54115 10 P 0 0;2,4=11,6=0
P 2.09606004 3.56615 8 P 0 0;4=12,6=1
L 8.075 3.54115 8.1 3.56615 5 P 0 
P 8.1 3.56615 8 P 0 0;4=12,6=1
P 8.075 3.54115 10 P 0 0;2,4=11,6=0
P 12.55905 3.38188996 14 P 0 0;4=2,6=0
P 12.81495 4.64173996 14 P 0 0;4=2,6=0
P 12.81495 1.88583002 14 P 0 0;4=2,6=0
P 0.35038996 4.60236998 14 P 0 0;4=2,6=0
P 0.35038996 2.55511998 14 P 0 0;4=2,6=0
P 0.35038996 1.84646004 14 P 0 0;4=2,6=0
P 0.09448996 3.34251998 14 P 0 0;4=2,6=0
P 6.385 5.03 9 P 0 0;4=13,6=1
P 6.38348996 4.99705 28 P 0 0;2,4=4,6=0
L 6.385 5.03 6.385 5.025 5 P 0 
L 6.385 5.025 6.38348996 5.02348996 5 P 0 
L 6.38348996 5.02348996 6.38348996 4.99705 5 P 0 
P 12.68701998 0.97243996 19 P 0 0;4=14
P 0.22245 0.93306998 19 P 0 0;4=14
P 12.68701004 4.91338002 19 P 0 0;4=14
L 3.94 4.593 3.94 4.545 5 P 0 
P 3.82558996 4.72035 37 P 0 0;2,4=8,6=0
L 3.94 4.593 3.902 4.593 5 P 0 
L 3.902 4.593 3.855 4.64 5 P 0 
L 3.855 4.64 3.855 4.68 5 P 0 
L 3.855 4.68 3.82558996 4.70941004 5 P 0 
L 3.82558996 4.70941004 3.82558996 4.72035 5 P 0 
P 3.94 4.593 28 P 0 0;2,4=4,6=0
P 3.99965 4.69 47 P 0 0;2,4=8,6=0
L 3.94 4.593 4.013 4.593 5 P 0 
L 4.013 4.593 4.035 4.615 5 P 0 
L 4.035 4.615 4.035 4.68 5 P 0 
L 4.035 4.68 4.025 4.69 5 P 0 
L 4.025 4.69 3.99965 4.69 5 P 0 
P 3.94 4.545 9 P 0 0;4=0,6=1
P 4.91 5.375 9 P 0 0;4=13,6=1
P 4.91 5.408 28 P 0 0;2,4=4,6=0
L 4.91 5.408 4.91 5.375 5 P 0 
L 9.865 4.635 9.865 5.325 5 P 0 
L 9.865 5.325 9.6662 5.5238 5 P 0 
L 9.6662 5.5238 6.9512 5.5238 5 P 0 
L 6.9512 5.5238 6.5876 5.8874 5 P 0 
L 6.5876 5.8874 4.28913996 5.8874 5 P 0 
L 4.28913996 5.8874 4.245 5.84326004 5 P 0 
L 4.245 5.84326004 4.245 5.705 5 P 0 
L 4.245 5.705 4.22 5.68 5 P 0 
L 4.22 5.68 4.01676998 5.68 5 P 0 
L 9.91 4.633 9.867 4.633 5 P 0 
L 9.867 4.633 9.865 4.635 5 P 0 
P 4.01676998 5.68 55 P 0 0;2,4=15,6=0
L 9.97441004 4.64965 9.97441004 4.61558996 5 P 0 
L 9.97441004 4.61558996 9.98 4.61 5 P 0 
L 9.98 4.61 9.98 4.577 5 P 0 
P 9.98 4.577 28 P 0 0;2,4=4,6=0
P 9.97441004 4.64965 37 P 0 0;2,4=8,6=0
L 9.91 4.577 9.98 4.577 5 P 0 
P 9.91 4.577 28 P 0 0;2,4=4,6=0
L 9.91 4.577 9.91 4.633 5 P 0 
P 9.91 4.633 28 P 0 0;2,4=4,6=0
P 9.865 4.635 11 P 0 0;3,4=6,6=1
L 3.925 5.78 3.67 5.78 5 P 0 
L 3.67 5.78 3.645 5.755 5 P 0 
L 3.645 5.755 3.645 4.72 5 P 0 
L 3.645 4.72 3.62 4.695 5 P 0 
L 3.62 4.695 3.62 4.62 5 P 0 
L 3.62 4.62 3.64441004 4.59558996 5 P 0 
L 3.64441004 4.59558996 3.64441004 4.58965 5 P 0 
L 3.57 4.517 3.57 4.5418 5 P 0 
L 3.57 4.5418 3.5782 4.55 5 P 0 
L 3.5782 4.55 3.63621004 4.55 5 P 0 
L 3.63621004 4.55 3.64441004 4.5582 5 P 0 
L 3.64441004 4.5582 3.64441004 4.58965 5 P 0 
L 3.57 4.517 3.62 4.517 5 P 0 
P 4.01676998 5.78 55 P 0 0;2,4=15,6=0
L 3.67 4.517 3.62 4.517 5 P 0 
P 3.62 4.517 28 P 0 0;2,4=4,6=0
P 3.67 4.517 28 P 0 0;2,4=4,6=0
P 3.64441004 4.58965 37 P 0 0;2,4=8,6=0
P 3.57 4.517 28 P 0 0;2,4=4,6=0
L 4.01676998 5.78 3.925 5.78 5 P 0 
P 3.925 5.78 11 P 0 0;3,4=6,6=1
L 3.6817 5.74 3.6817 4.7117 5 P 0 
L 3.6817 4.7117 3.67 4.7 5 P 0 
L 3.67 4.7 3.67 4.67035 5 P 0 
L 1.08 5.85 1.08 5.84 5 P 0 
L 1.08 5.84 1.063 5.823 5 P 0 
L 1.063 5.823 1.04 5.823 5 P 0 
L 1.04428996 5.70373996 1.04428996 5.77571004 5 P 0 
L 1.04428996 5.77571004 1.04 5.78 5 P 0 
L 1.04 5.78 1.04 5.823 5 P 0 
P 1.04 5.823 28 P 0 0;2,4=4,6=0
P 1.04428996 5.70373996 48 P 0 0;2,4=16,6=0
P 1.08 5.85 9 P 0 0;4=0,6=1
P 3.67 4.67035 37 P 0 0;2,4=8,6=0
P 3.6817 5.74 9 P 0 0;4=13,6=1
P 10.07 2.928 9 P 0 0;4=13,6=1
L 4.105 4.985 4.105 5.463 5 P 0 
L 4.105 5.463 4.088 5.48 5 P 0 
L 4.088 5.48 4.01676998 5.48 5 P 0 
P 4.105 4.985 9 P 0 0;4=0,6=1
P 4.01676998 5.48 55 P 0 0;2,4=15,6=0
L 4.02 4.355 4.218 4.553 5 P 0 
L 4.218 4.553 4.218 5.472 5 P 0 
L 4.218 5.472 4.11 5.58 5 P 0 
L 4.11 5.58 4.01676998 5.58 5 P 0 
P 4.125 2.725 9 P 0 0;4=13,6=1
P 4.01676998 5.58 55 P 0 0;2,4=15,6=0
P 4.02 4.355 9 P 0 0;4=0,6=1
L 1.16 5.85 1.16 5.83 5 P 0 
L 1.16 5.83 1.153 5.823 5 P 0 
L 1.153 5.823 1.12 5.823 5 P 0 
L 1.12303002 5.70373996 1.12303002 5.81996998 5 P 0 
L 1.12303002 5.81996998 1.12 5.823 5 P 0 
P 1.12 5.823 28 P 0 0;2,4=4,6=0
P 1.12303002 5.70373996 48 P 0 0;2,4=16,6=0
P 1.16 5.85 9 P 0 0;4=0,6=1
P 10 4.73035 37 P 0 0;2,4=8,6=0
P 3.815 5.815 9 P 0 0;4=13,6=1
L 10 4.73035 10 5.24 5 P 0 
L 10 5.24 9.685 5.555 5 P 0 
L 9.685 5.555 6.99 5.555 5 P 0 
L 6.99 5.555 6.62 5.925 5 P 0 
L 6.62 5.925 3.925 5.925 5 P 0 
L 3.925 5.925 3.815 5.815 5 P 0 
P 1.19 6.36 30 P 0 0;4=17,6=0
P 1.19 6.26 30 P 0 0;4=17,6=0
P 1.415 6.36 30 P 0 0;4=17,6=0
P 1.415 6.26 30 P 0 0;4=17,6=0
P 1.64 6.36 30 P 0 0;4=17,6=0
P 1.64 6.26 30 P 0 0;4=17,6=0
P 0.965 6.26 30 P 0 0;4=17,6=0
P 0.965 6.36 30 P 0 0;4=17,6=0
P 0.74 6.26 30 P 0 0;4=17,6=0
P 0.74 6.36 30 P 0 0;4=17,6=0
L 0.97441004 5.20965 0.97441004 5.16241004 5 P 0 
L 0.97441004 5.16241004 0.97 5.158 5 P 0 
L 0.97 5.158 0.97 5.127 5 P 0 
P 0.97 5.127 28 P 0 0;2,4=4,6=0
P 0.97441004 5.20965 37 P 0 0;2,4=8,6=0
P 0.929 5.037 11 P 0 0;3,4=6,6=1
L 0.929 5.037 0.943 5.051 5 P 0 
L 0.943 5.051 0.943 5.1193 5 P 0 
L 0.943 5.1193 0.9507 5.127 5 P 0 
L 0.9507 5.127 0.97 5.127 5 P 0 
L 1 5.29035 1 5.312 5 P 0 
L 1 5.312 1.01 5.322 5 P 0 
L 1.01 5.322 1.022 5.322 5 P 0 
L 1.022 5.322 1.043 5.343 5 P 0 
L 1.044 5.383 1.044 5.344 5 P 0 
L 1.044 5.344 1.043 5.343 5 P 0 
P 1 5.29035 37 P 0 0;2,4=8,6=0
P 1.044 5.383 28 P 0 0;2,4=4,6=0
L 1.044 5.383 0.996 5.383 5 P 0 
P 0.996 5.383 28 P 0 0;2,4=4,6=0
P 1.043 5.343 11 P 0 0;3,4=6,6=1
P 12.63778996 1.37401998 30 P 0 0;4=18,6=0
P 0.17323002 1.33465 30 P 0 0;4=18,6=0
L 6.501 5.017 6.47813996 5.017 5 P 0 
L 6.47813996 5.017 6.45818996 4.99705 5 P 0 
P 6.55228996 4.94855 45 P 0 0;2,4=19,6=0
P 6.501 5.017 9 P 0 0;4=0,6=1
P 6.45818996 4.99705 28 P 0 0;2,4=4,6=0
L 6.501 5.017 6.501 4.964 3 P 0 
L 6.501 4.964 6.51645 4.94855 3 P 0 
L 6.51645 4.94855 6.55228996 4.94855 3 P 0 
P 7.425 3.43 9 P 0 0;4=0,6=1
P 7.445 1.705 9 P 0 0;4=13,6=1
P 11.06161004 3.79115 10 P 0 0;2,4=11,6=0
L 11.06161004 3.79115 11.03661004 3.81615 5 P 0 
P 11.03661004 3.81615 8 P 0 0;4=12,6=1
P 11.135 2.845 9 P 0 0;4=13,6=1
P 11.03661004 2.16615 8 P 0 0;4=12,6=1
L 11.01161004 2.19115 11.03661004 2.16615 5 P 0 
P 11.01161004 2.19115 10 P 0 0;2,4=11,6=0
L 3.8899 4.765 3.8899 4.7171 5 P 0 
L 3.8899 4.7171 3.89 4.717 5 P 0 
L 3.8899 4.79498996 3.8899 4.765 5 P 0 
P 3.89 4.717 28 P 0 0;2,4=4,6=0
P 3.8899 4.79498996 28 P 0 0;2,4=4,6=0
P 3.8899 4.765 9 P 0 0;4=0,6=1
L 4.93268002 2.41615 4.90768002 2.44115 5 P 0 
P 4.90768002 2.44115 10 P 0 0;2,4=11,6=0
P 4.93268002 2.41615 8 P 0 0;4=12,6=1
L 4.93268002 2.46615 4.90768002 2.49115 5 P 0 
P 4.90768002 2.49115 10 P 0 0;2,4=11,6=0
P 4.93268002 2.46615 8 P 0 0;4=12,6=1
L 7.3054 4.9602 7.3054 5.03071004 5 P 0 
L 7.3054 5.03071004 7.2926 5.04351004 5 P 0 
L 7.2926 5.04351004 7.2926 5.09151004 5 P 0 
P 7.2926 5.09151004 28 P 0 0;2,4=4,6=0
P 7.3054 4.9602 38 P 0 0;2,4=20,6=0
L 7.2926 5.09151004 7.3426 5.09151004 5 P 0 
P 7.3426 5.09151004 28 P 0 0;2,4=4,6=0
P 7.2926 5.04351004 9 P 0 0;4=0,6=1
L 7.2426 5.04351004 7.2426 5.09151004 5 P 0 
L 7.2798 4.9602 7.2798 5.00631004 5 P 0 
L 7.2798 5.00631004 7.2426 5.04351004 5 P 0 
P 7.2426 5.09151004 28 P 0 0;2,4=4,6=0
P 7.2798 4.9602 38 P 0 0;2,4=20,6=0
L 7.2426 5.09151004 7.1926 5.09151004 5 P 0 
P 7.1926 5.09151004 28 P 0 0;2,4=4,6=0
P 7.2426 5.04351004 9 P 0 0;4=0,6=1
L 3.4591 4.97913996 3.4591 5.0041 5 P 0 
L 3.4591 5.0041 3.46731998 5.01231998 5 P 0 
L 3.46731998 5.01231998 3.46731998 5.28913996 5 P 0 
L 3.46731998 5.28913996 3.45646004 5.3 5 P 0 
P 3.45646004 5.3 9 P 0 0;4=0,6=1
P 3.4591 4.97913996 36 P 0 0;2,4=1,6=0
L 1.28906004 5.04351004 1.30186004 5.03071004 5 P 0 
L 1.30186004 5.03071004 1.30186004 4.9602 5 P 0 
L 1.28906004 5.09151004 1.28906004 5.04351004 5 P 0 
P 1.28906004 5.04351004 9 P 0 0;4=0,6=1
P 1.30186004 4.9602 38 P 0 0;2,4=20,6=0
P 1.28906004 5.09151004 28 P 0 0;2,4=4,6=0
L 1.28906004 5.09151004 1.33906004 5.09151004 5 P 0 
P 1.33906004 5.09151004 28 P 0 0;2,4=4,6=0
L 1.23906004 5.04351004 1.27626004 5.00631004 5 P 0 
L 1.27626004 5.00631004 1.27626004 4.9602 5 P 0 
L 1.23906004 5.09151004 1.23906004 5.04351004 5 P 0 
P 1.23906004 5.04351004 9 P 0 0;4=0,6=1
P 1.27626004 4.9602 38 P 0 0;2,4=20,6=0
P 1.23906004 5.09151004 28 P 0 0;2,4=4,6=0
L 1.23906004 5.09151004 1.18906004 5.09151004 5 P 0 
P 1.18906004 5.09151004 28 P 0 0;2,4=4,6=0
L 9.46263996 4.97913996 9.46263996 5.0041 5 P 0 
L 9.46263996 5.0041 9.47086004 5.01231998 5 P 0 
L 9.47086004 5.01231998 9.47086004 5.28913996 5 P 0 
L 9.47086004 5.28913996 9.46 5.3 5 P 0 
P 9.46 5.3 9 P 0 0;4=0,6=1
P 9.46263996 4.97913996 36 P 0 0;2,4=1,6=0
P 4.70768002 2.39115 10 P 0 0;2,4=11,6=0
L 4.68268002 2.36615 4.70768002 2.39115 5 P 0 
P 4.68268002 2.36615 8 P 0 0;4=12,6=1
P 0.27165 4.01181004 14 P 0 0;4=2,6=0
P 4.60768002 2.39115 10 P 0 0;2,4=11,6=0
L 4.58268002 2.36615 4.60768002 2.39115 5 P 0 
P 4.58268002 2.36615 8 P 0 0;4=12,6=1
P 0.27165 4.16928996 14 P 0 0;4=2,6=0
P 4.65768002 2.44115 10 P 0 0;2,4=11,6=0
L 4.63268002 2.41615 4.65768002 2.44115 5 P 0 
P 4.63268002 2.41615 8 P 0 0;4=12,6=1
P 0.27165 4.32676998 14 P 0 0;4=2,6=0
P 4.75768002 2.29115 10 P 0 0;2,4=11,6=0
L 4.75768002 2.29115 4.73268002 2.26615 5 P 0 
P 4.73268002 2.26615 8 P 0 0;4=12,6=1
P 0.27165 3.38188996 14 P 0 0;4=2,6=0
P 4.75768002 2.44115 10 P 0 0;2,4=11,6=0
L 4.75768002 2.44115 4.73268002 2.41615 5 P 0 
P 4.73268002 2.41615 8 P 0 0;4=12,6=1
P 0.27165 4.48425 14 P 0 0;4=2,6=0
P 4.70768002 2.24115 10 P 0 0;2,4=11,6=0
L 4.70768002 2.24115 4.68268002 2.21615 5 P 0 
P 4.68268002 2.21615 8 P 0 0;4=12,6=1
P 0.27165 3.53936998 14 P 0 0;4=2,6=0
P 4.65768002 2.29115 10 P 0 0;2,4=11,6=0
L 4.65768002 2.29115 4.63268002 2.26615 5 P 0 
P 4.63268002 2.26615 8 P 0 0;4=12,6=1
P 0.27165 3.85433002 14 P 0 0;4=2,6=0
P 4.60768002 2.09115 10 P 0 0;2,4=11,6=0
L 4.60768002 2.09115 4.58268002 2.06615 5 P 0 
P 4.58268002 2.06615 8 P 0 0;4=12,6=1
P 0.35038996 3.02756004 14 P 0 0;4=2,6=0
P 4.60768002 2.14115 10 P 0 0;2,4=11,6=0
L 4.60768002 2.14115 4.58268002 2.11615 5 P 0 
P 4.58268002 2.11615 8 P 0 0;4=12,6=1
P 0.27165 2.98818996 14 P 0 0;4=2,6=0
P 4.65768002 1.89115 10 P 0 0;2,4=11,6=0
L 4.65768002 1.89115 4.63268002 1.86615 5 P 0 
P 4.63268002 1.86615 8 P 0 0;4=12,6=1
P 0.35038996 2.3189 14 P 0 0;4=2,6=0
L 4.60768002 1.99115 4.58268002 1.96615 5 P 0 
P 4.60768002 1.99115 10 P 0 0;2,4=11,6=0
P 4.58268002 1.96615 8 P 0 0;4=12,6=1
P 0.27165 2.43701004 14 P 0 0;4=2,6=0
P 4.70768002 2.09115 10 P 0 0;2,4=11,6=0
L 4.70768002 2.09115 4.68268002 2.06615 5 P 0 
P 4.68268002 2.06615 8 P 0 0;4=12,6=1
P 0.35038996 3.18503996 14 P 0 0;4=2,6=0
L 4.60768002 1.94115 4.58268002 1.91615 5 P 0 
P 4.60768002 1.94115 10 P 0 0;2,4=11,6=0
P 4.58268002 1.91615 8 P 0 0;4=12,6=1
P 0.35038996 2.47638002 14 P 0 0;4=2,6=0
P 4.65768002 1.94115 10 P 0 0;2,4=11,6=0
L 4.65768002 1.94115 4.63268002 1.91615 5 P 0 
P 0.27165 2.27953002 14 P 0 0;4=2,6=0
P 4.63268002 1.91615 8 P 0 0;4=12,6=1
P 5.42048002 1.7396 8 P 0 0;4=12,6=1
P 0.09448996 2.55511998 14 P 0 0;4=2,6=0
P 4.70768002 2.14115 10 P 0 0;2,4=11,6=0
L 4.70768002 2.14115 4.68268002 2.11615 5 P 0 
P 4.68268002 2.11615 8 P 0 0;4=12,6=1
P 0.27165 3.14566998 14 P 0 0;4=2,6=0
P 5.42048002 1.7796 8 P 0 0;4=12,6=1
P 0.17323002 2.51575 14 P 0 0;4=2,6=0
P 4.70768002 1.94115 10 P 0 0;2,4=11,6=0
L 4.70768002 1.94115 4.68268002 1.91615 5 P 0 
P 4.68268002 1.91615 8 P 0 0;4=12,6=1
P 0.35038996 2.16141998 14 P 0 0;4=2,6=0
P 4.70768002 1.99115 10 P 0 0;2,4=11,6=0
L 4.70768002 1.99115 4.68268002 1.96615 5 P 0 
P 4.68268002 1.96615 8 P 0 0;4=12,6=1
P 0.27165 2.12205 14 P 0 0;4=2,6=0
P 5.57531004 2.0878 8 P 0 0;4=12,6=1
P 0.09448996 3.1063 14 P 0 0;4=2,6=0
P 5.57531004 2.1278 8 P 0 0;4=12,6=1
P 0.17323002 3.06693002 14 P 0 0;4=2,6=0
P 5.57531004 2.2232 8 P 0 0;4=12,6=1
P 0.17323002 3.46063002 14 P 0 0;4=2,6=0
P 5.57531004 2.2632 8 P 0 0;4=12,6=1
P 0.09448996 3.42126004 14 P 0 0;4=2,6=0
P 5.42048002 2.4662 8 P 0 0;4=12,6=1
P 0.09448996 4.05118002 14 P 0 0;4=2,6=0
P 5.57531004 2.3986 8 P 0 0;4=12,6=1
P 0.09448996 3.8937 14 P 0 0;4=2,6=0
P 5.57531004 2.673 8 P 0 0;4=12,6=1
P 0.09448996 4.36613996 14 P 0 0;4=2,6=0
P 5.57531004 1.9869 8 P 0 0;4=12,6=1
P 0.17323002 2.75196998 14 P 0 0;4=2,6=0
P 5.57531004 2.4978 8 P 0 0;4=12,6=1
P 0.17323002 4.24803002 14 P 0 0;4=2,6=0
P 5.57531004 1.6718 8 P 0 0;4=12,6=1
P 0.17323002 2.20078996 14 P 0 0;4=2,6=0
P 5.57531004 2.633 8 P 0 0;4=12,6=1
P 0.17323002 4.40551004 14 P 0 0;4=2,6=0
P 5.57531004 1.7118 8 P 0 0;4=12,6=1
P 0.09448996 2.24016004 14 P 0 0;4=2,6=0
P 5.57531004 2.5378 8 P 0 0;4=12,6=1
P 0.09448996 4.20866004 14 P 0 0;4=2,6=0
P 5.42048002 1.6433 8 P 0 0;4=12,6=1
P 0.09448996 2.39763996 14 P 0 0;4=2,6=0
P 5.42048002 2.6054 8 P 0 0;4=12,6=1
P 0.09448996 4.52361998 14 P 0 0;4=2,6=0
P 5.42048002 1.87835 8 P 0 0;4=12,6=1
P 0.09448996 2.94881998 14 P 0 0;4=2,6=0
P 5.57531004 2.3586 8 P 0 0;4=12,6=1
P 0.17323002 3.93306998 14 P 0 0;4=2,6=0
P 5.42048002 1.6033 8 P 0 0;4=12,6=1
P 0.17323002 2.35826998 14 P 0 0;4=2,6=0
P 5.42048002 2.4262 8 P 0 0;4=12,6=1
P 0.17323002 4.09055 14 P 0 0;4=2,6=0
P 5.42048002 1.91835 8 P 0 0;4=12,6=1
P 0.17323002 2.90945 14 P 0 0;4=2,6=0
P 5.42048002 2.0547 8 P 0 0;4=12,6=1
P 0.17323002 3.22441004 14 P 0 0;4=2,6=0
P 5.57531004 1.9469 8 P 0 0;4=12,6=1
P 0.09448996 2.79133996 14 P 0 0;4=2,6=0
P 5.42048002 2.0147 8 P 0 0;4=12,6=1
P 0.09448996 3.26378002 14 P 0 0;4=2,6=0
P 5.57531004 1.8508 8 P 0 0;4=12,6=1
P 0.09448996 2.00393996 14 P 0 0;4=2,6=0
P 5.57531004 1.8108 8 P 0 0;4=12,6=1
P 0.17323002 2.04331004 14 P 0 0;4=2,6=0
P 0.35038996 3.97243996 14 P 0 0;4=2,6=0
P 4.68268002 2.41615 8 P 0 0;4=12,6=1
L 4.68268002 2.41615 4.70768002 2.44115 5 P 0 
P 4.70768002 2.44115 10 P 0 0;2,4=11,6=0
P 4.75768002 2.49115 10 P 0 0;2,4=11,6=0
L 4.75768002 2.49115 4.73268002 2.46615 5 P 0 
P 4.73268002 2.46615 8 P 0 0;4=12,6=1
P 0.35038996 4.44488002 14 P 0 0;4=2,6=0
P 4.65768002 2.49115 10 P 0 0;2,4=11,6=0
L 4.63268002 2.46615 4.65768002 2.49115 5 P 0 
P 4.63268002 2.46615 8 P 0 0;4=12,6=1
P 0.35038996 4.2874 14 P 0 0;4=2,6=0
P 0.35038996 4.12991998 14 P 0 0;4=2,6=0
P 4.58268002 2.41615 8 P 0 0;4=12,6=1
L 4.58268002 2.41615 4.60768002 2.44115 5 P 0 
P 4.60768002 2.44115 10 P 0 0;2,4=11,6=0
P 4.70768002 2.29115 10 P 0 0;2,4=11,6=0
L 4.70768002 2.29115 4.68268002 2.26615 5 P 0 
P 4.68268002 2.26615 8 P 0 0;4=12,6=1
P 0.35038996 3.5 14 P 0 0;4=2,6=0
P 5.42048002 2.1554 8 P 0 0;4=12,6=1
P 0.17323002 3.77558996 14 P 0 0;4=2,6=0
P 4.75768002 2.34115 10 P 0 0;2,4=11,6=0
L 4.75768002 2.34115 4.73268002 2.31615 5 P 0 
P 4.73268002 2.31615 8 P 0 0;4=12,6=1
P 0.35038996 3.34251998 14 P 0 0;4=2,6=0
P 4.65768002 2.34115 10 P 0 0;2,4=11,6=0
L 4.65768002 2.34115 4.63268002 2.31615 5 P 0 
P 4.63268002 2.31615 8 P 0 0;4=12,6=1
P 0.35038996 3.81496004 14 P 0 0;4=2,6=0
P 4.60768002 2.29115 10 P 0 0;2,4=11,6=0
L 4.60768002 2.29115 4.58268002 2.26615 5 P 0 
P 4.58268002 2.26615 8 P 0 0;4=12,6=1
P 0.35038996 3.65748002 14 P 0 0;4=2,6=0
P 5.42048002 2.5654 8 P 0 0;4=12,6=1
P 0.17323002 4.563 14 P 0 0;4=2,6=0
P 5.42048002 2.1954 8 P 0 0;4=12,6=1
P 0.09448996 3.73621998 14 P 0 0;4=2,6=0
P 0.09448996 3.57873996 14 P 0 0;4=2,6=0
P 5.42048002 2.3308 8 P 0 0;4=12,6=1
P 0.17323002 3.61811004 14 P 0 0;4=2,6=0
P 5.42048002 2.2908 8 P 0 0;4=12,6=1
P 4.75768002 1.94115 10 P 0 0;2,4=11,6=0
L 4.75768002 1.94115 4.73268002 1.91615 5 P 0 
P 0.35038996 1.9252 14 P 0 0;4=2,6=0
P 4.73268002 1.91615 8 P 0 0;4=12,6=1
P 4.75768002 1.89115 10 P 0 0;2,4=11,6=0
L 4.75768002 1.89115 4.73268002 1.86615 5 P 0 
P 4.73268002 1.86615 8 P 0 0;4=12,6=1
P 0.27165 1.96456998 14 P 0 0;4=2,6=0
L 4.60768002 2.24115 4.58268002 2.21615 5 P 0 
P 4.60768002 2.24115 10 P 0 0;2,4=11,6=0
P 4.58268002 2.21615 8 P 0 0;4=12,6=1
P 0.27165 3.69685 14 P 0 0;4=2,6=0
P 4.75768002 2.09115 10 P 0 0;2,4=11,6=0
L 4.75768002 2.09115 4.73268002 2.06615 5 P 0 
P 4.73268002 2.06615 8 P 0 0;4=12,6=1
P 0.27165 2.67323002 14 P 0 0;4=2,6=0
P 4.75768002 2.04115 10 P 0 0;2,4=11,6=0
L 4.75768002 2.04115 4.73268002 2.01615 5 P 0 
P 4.73268002 2.01615 8 P 0 0;4=12,6=1
P 0.35038996 2.7126 14 P 0 0;4=2,6=0
P 4.65768002 2.04115 10 P 0 0;2,4=11,6=0
L 4.65768002 2.04115 4.63268002 2.01615 5 P 0 
P 4.63268002 2.01615 8 P 0 0;4=12,6=1
P 0.35038996 2.87008002 14 P 0 0;4=2,6=0
P 4.65768002 2.09115 10 P 0 0;2,4=11,6=0
L 4.65768002 2.09115 4.63268002 2.06615 5 P 0 
P 4.63268002 2.06615 8 P 0 0;4=12,6=1
P 0.27165 2.83071004 14 P 0 0;4=2,6=0
P 6.785 4.725 9 P 0 0;4=13,6=1
P 6.785 4.685 9 P 0 0;4=13,6=1
P 6.74018996 4.765 9 P 0 0;4=13,6=1
P 6.74208996 4.7052 31 P 0 0;2,4=21,6=0
P 6.87618996 4.71823002 52 P 0 0;2,4=22,6=0
P 6.83118996 4.81705 31 P 0 0;2,4=21,6=0
P 6.71318996 4.77205 28 P 0 0;2,4=4,6=0
P 6.69008996 4.88555 46 P 0 0;2,4=19,6=0
P 6.69008996 4.86980994 46 P 0 0;2,4=19,6=0
P 6.69008996 4.85405994 46 P 0 0;2,4=19,6=0
P 6.74 4.805 9 P 0 0;4=0,6=1
P 6.785 4.845 9 P 0 0;4=13,6=1
P 6.785 4.805 9 P 0 0;4=13,6=1
P 6.785 4.765 9 P 0 0;4=13,6=1
P 6.74 4.845 9 P 0 0;4=13,6=1
S P 0
OB 6.71918996063 4.67705 I
OS 6.71618996063 4.68005
OS 6.71618996063 4.73605
OS 6.70318996063 4.74905
OS 6.70318996063 4.79205
OS 6.6732 4.82203996063
OS 6.6732 4.88326003937
OS 6.676269980315 4.886319980315
OS 6.677130019685 4.887180019685
OS 6.72605 4.887180019685
OS 6.72676003937 4.886480019685
OS 6.75118996063 4.86205
OS 6.84818996063 4.86205
OS 6.85618996063 4.85405
OS 6.85618996063 4.76705
OS 6.86118996063 4.76205
OS 6.91118996063 4.76205
OS 6.92118996063 4.75205
OS 6.92118996063 4.68205
OS 6.91618996063 4.67705
OS 6.71918996063 4.67705
OE
SE
L 6.65818996 5.09705 6.65818996 5.0932 6 P 0 
L 6.65818996 5.0932 6.65 5.08501004 6 P 0 
L 6.65 5.08501004 6.65 5.055 6 P 0 
L 6.65 5.055 6.63693996 5.04193996 6 P 0 
L 6.63693996 5.04193996 6.63693996 5.00563002 3 P 0 
P 6.63693996 5.00563002 50 P 0 0;2,4=19,6=0
P 6.65818996 5.09705 28 P 0 0;2,4=4,6=0
P 6.65 5.055 9 P 0 0;4=0,6=1
L 6.45818996 5.09705 6.49205 5.09705 5 P 0 
L 6.45818996 5.09705 6.45818996 5.04705 5 P 0 
P 6.45818996 5.04705 28 P 0 0;2,4=4,6=0
P 6.45818996 5.09705 28 P 0 0;2,4=4,6=0
P 6.49205 5.09705 9 P 0 0;4=0,6=1
P 6.55228996 4.96428996 45 P 0 0;2,4=19,6=0
L 6.45818996 5.04705 6.5123 5.04705 5 P 0 
L 6.5123 5.04705 6.529 5.03035 5 P 0 
L 6.529 5.03035 6.529 4.996 5 P 0 
L 6.529 4.996 6.51995 4.98695 5 P 0 
L 6.51995 4.98695 6.51995 4.97605 5 P 0 
L 6.51995 4.97605 6.53171004 4.96428996 5 P 0 
L 6.53171004 4.96428996 6.55228996 4.96428996 5 P 0 
L 6.495 4.9328 6.47243996 4.9328 6 P 0 
L 6.47243996 4.9328 6.45818996 4.94705 6 P 0 
L 6.55228996 4.9328 6.495 4.9328 4 P 0 
P 6.495 4.9328 9 P 0 0;4=0,6=1
P 6.55228996 4.9328 45 P 0 0;2,4=19,6=0
P 6.45818996 4.94705 28 P 0 0;2,4=4,6=0
P 6.55228996 4.98003996 45 P 0 0;2,4=19,6=0
L 6.55118996 5.04705 6.56798996 5.03025 4 P 0 
L 6.56798996 5.03025 6.56798996 4.98498996 4 P 0 
L 6.56798996 4.98498996 6.56303996 4.98003996 4 P 0 
L 6.56303996 4.98003996 6.55228996 4.98003996 4 P 0 
P 6.55118996 5.04705 9 P 0 0;4=0,6=1
L 6.55118996 5.04705 6.53918996 5.05905 6 P 0 
L 6.53918996 5.05905 6.53918996 5.09705 6 P 0 
P 6.53918996 5.09705 28 P 0 0;2,4=4,6=0
L 6.78 4.94705 6.75118996 4.94705 3 P 0 
L 6.75118996 4.94705 6.73693996 4.9328 3 P 0 
L 6.73693996 4.9328 6.69008996 4.9328 3 P 0 
L 6.81218996 4.94705 6.78 4.94705 9 P 0 
P 6.78 4.94705 9 P 0 0;4=0,6=1
P 6.81218996 4.94705 29 P 0 0;2,4=23,6=0
P 6.69008996 4.9328 46 P 0 0;2,4=19,6=0
L 6.51618996 4.72305 6.51618996 4.69441004 9 P 0 
L 6.51618996 4.69441004 6.51718996 4.69341004 9 P 0 
L 6.51718996 4.69341004 6.51718996 4.66705 9 P 0 
P 6.51718996 4.66705 29 P 0 0;2,4=23,6=0
P 6.51618996 4.72305 29 P 0 0;2,4=23,6=0
P 6.52 4.605 11 P 0 0;3,4=6,6=1
L 6.52 4.605 6.51718996 4.60781004 6 P 0 
L 6.51718996 4.60781004 6.51718996 4.66705 6 P 0 
L 6.42418996 4.94705 6.38318996 4.94705 6 P 0 
P 6.38318996 4.94705 28 P 0 0;2,4=4,6=0
P 6.42418996 4.94705 28 P 0 0;2,4=4,6=0
L 6.69008996 4.91705 6.735 4.91705 3 P 0 
L 6.735 4.91705 6.755 4.89705 3 P 0 
L 6.755 4.89705 6.765 4.88705 9 P 0 
L 6.765 4.88705 6.81218996 4.88705 9 P 0 
P 6.755 4.89705 9 P 0 0;4=0,6=1
P 6.81218996 4.88705 29 P 0 0;2,4=23,6=0
P 6.69008996 4.91705 46 P 0 0;2,4=19,6=0
P 6.755 5.13 11 P 0 0;3,4=6,6=1
P 5.49093996 4.5861 28 P 0 0;2,4=4,6=0
P 6.65268996 5.00563002 50 P 0 0;2,4=19,6=0
L 6.755 5.087 6.71 5.087 6 P 0 
P 6.71 5.087 28 P 0 0;2,4=4,6=0
P 6.755 5.087 28 P 0 0;2,4=4,6=0
L 6.755 5.087 6.755 5.13 6 P 0 
L 6.65268996 5.00563002 6.65268996 5.01268996 3 P 0 
L 6.65268996 5.01268996 6.685 5.045 3 P 0 
L 6.685 5.045 6.685 5.075 3 P 0 
L 6.685 5.075 6.697 5.087 6 P 0 
L 6.697 5.087 6.71 5.087 6 P 0 
L 6.755 5.13 6.755 5.135 6 P 0 
L 6.755 5.135 6.745 5.145 6 P 0 
L 6.745 5.145 5.49501004 5.145 6 P 0 
L 5.49501004 5.145 5.44198996 5.09198002 6 P 0 
L 5.44198996 5.09198002 5.44198996 4.5938 6 P 0 
L 5.44198996 4.5938 5.44968996 4.5861 6 P 0 
L 5.44968996 4.5861 5.49093996 4.5861 6 P 0 
L 6.74 4.987 6.74 4.967 3 P 0 
L 6.74 4.967 6.72155 4.94855 3 P 0 
L 6.72155 4.94855 6.69008996 4.94855 3 P 0 
P 6.74 4.987 9 P 0 0;4=0,6=1
P 6.69008996 4.94855 46 P 0 0;2,4=19,6=0
L 6.57518996 4.66705 6.57518996 4.605 6 P 0 
L 6.57618996 4.73505 6.57618996 4.69948996 9 P 0 
L 6.57618996 4.69948996 6.57518996 4.69848996 9 P 0 
L 6.57518996 4.69848996 6.57518996 4.66705 9 P 0 
P 6.57518996 4.66705 29 P 0 0;2,4=23,6=0
P 6.57618996 4.73505 28 P 0 0;2,4=4,6=0
P 6.57518996 4.605 11 P 0 0;3,4=6,6=1
P 6.69008996 4.98003996 46 P 0 0;2,4=19,6=0
P 6.71 5.053 28 P 0 0;2,4=4,6=0
P 6.755 5.053 28 P 0 0;2,4=4,6=0
P 6.803 5 28 P 0 0;2,4=4,6=0
P 6.8 5.045 11 P 0 0;3,4=6,6=1
S P 0
OB 6.73311003937 5.00311003937 I
OS 6.732780019685 5.00296003937
OC 6.72403996063 4.994219980315 6.74 4.987 N
OS 6.72388996063 4.99388996063
OS 6.70623996063 4.97623996063
OS 6.678280019685 4.97623996063
OC 6.67691003937 4.976169980315 6.678203641732 4.96428996063 N
OS 6.67595 4.97605
OS 6.67368996063 4.97831003937
OS 6.67368996063 5.01368996063
OS 6.698069980315 5.038069980315
OS 6.698069980315 5.061069980315
OS 6.7 5.063
OS 6.805 5.063
OS 6.815 5.053
OS 6.815 4.99
OS 6.81 4.985
OS 6.77 4.985
OS 6.75 5.005
OS 6.735 5.005
OS 6.73311003937 5.00311003937
OE
SE
P 6.43043996 4.77205 51 P 0 0;2,4=24,6=0
P 6.34918996 4.94705 28 P 0 0;2,4=4,6=0
P 6.51618996 4.78105 29 P 0 0;2,4=23,6=0
P 6.55228996 4.9013 45 P 0 0;2,4=19,6=0
P 6.55228996 4.88555 45 P 0 0;2,4=19,6=0
P 6.55228996 4.86980994 45 P 0 0;2,4=19,6=0
P 6.55228996 4.85405994 45 P 0 0;2,4=19,6=0
S P 0
OB 6.37818996063 4.69005 I
OS 6.33618996063 4.73205
OS 6.33618996063 4.95705
OS 6.33818996063 4.95905
OS 6.35718996063 4.95905
OS 6.35918996063 4.95705
OS 6.35918996063 4.91405
OS 6.36618996063 4.90705
OS 6.528519980315 4.90705
OS 6.528519980315 4.9051
OS 6.5641 4.9051
OC 6.56453996063 4.9051 6.564319980315 4.91705 N
OC 6.567462204724 4.903985433071 6.564687992126 4.9011 Y
OC 6.56868996063 4.90111003937 6.56468996063 4.901101870079 Y
OS 6.56868996063 4.83455
OS 6.53818996063 4.80405
OS 6.53818996063 4.77105
OS 6.53318996063 4.76605
OS 6.49418996063 4.76605
OS 6.49018996063 4.76205
OS 6.49018996063 4.69605
OS 6.48418996063 4.69005
OS 6.37818996063 4.69005
OE
SE
P 12.73621004 2.08268002 14 P 0 0;4=2,6=0
P 12.73621004 2.63386004 14 P 0 0;4=2,6=0
P 12.81495 3.30315 14 P 0 0;4=2,6=0
P 12.73621004 4.60236998 14 P 0 0;4=2,6=0
P 12.55905 1.96456998 14 P 0 0;4=2,6=0
P 12.63778996 1.9252 14 P 0 0;4=2,6=0
P 0.09448996 1.9252 14 P 0 0;4=2,6=0
P 0.17323002 1.88583002 14 P 0 0;4=2,6=0
P 0.27165 2.04331004 14 P 0 0;4=2,6=0
P 0.27165 4.563 14 P 0 0;4=2,6=0
P 0.35038996 3.26378002 14 P 0 0;4=2,6=0
P 0.27165 2.59448996 14 P 0 0;4=2,6=0
P 0.17323002 1.72835 14 P 0 0;4=2,6=0
P 5.00768002 1.94115 10 P 0 0;2,4=11,6=0
L 5.03268002 1.91615 5.00768002 1.94115 5 P 0 
P 5.03268002 1.91615 8 P 0 0;4=12,6=1
P 1.025 -0.25 14 P 0 0;4=3,6=0
P 1.175 -0.25 14 P 0 0;4=3,6=0
P 1.325 -0.25 14 P 0 0;4=3,6=0
L 3.275 -0.24 3.275 -0.19873002 5 P 0 
L 3.275 -0.19873002 3.26626998 -0.19 5 P 0 
L 3.26626998 -0.19 3.21896998 -0.19 5 P 0 
L 3.21896998 -0.19 3.21126998 -0.1977 5 P 0 
L 3.21126998 -0.1977 3.21126998 -0.4123 5 P 0 
L 3.21126998 -0.4123 3.20356998 -0.42 5 P 0 
L 3.20356998 -0.42 3.15626998 -0.42 5 P 0 
L 3.15626998 -0.42 3.14856998 -0.4123 5 P 0 
L 3.14856998 -0.4123 3.14856998 -0.1977 5 P 0 
L 3.14856998 -0.1977 3.14086998 -0.19 5 P 0 
L 3.14086998 -0.19 3.09356998 -0.19 5 P 0 
L 3.09356998 -0.19 3.08586998 -0.1977 5 P 0 
L 3.08586998 -0.1977 3.08586998 -0.4123 5 P 0 
L 3.08586998 -0.4123 3.07816998 -0.42 5 P 0 
L 3.07816998 -0.42 3.03086998 -0.42 5 P 0 
L 3.03086998 -0.42 3.02316998 -0.4123 5 P 0 
L 3.02316998 -0.4123 3.02316998 -0.1977 5 P 0 
L 3.02316998 -0.1977 3.01546998 -0.19 5 P 0 
L 3.01546998 -0.19 2.96816998 -0.19 5 P 0 
L 2.96816998 -0.19 2.96046998 -0.1977 5 P 0 
L 2.96046998 -0.1977 2.96046998 -0.4123 5 P 0 
L 2.96046998 -0.4123 2.95276998 -0.42 5 P 0 
L 2.95276998 -0.42 2.90546998 -0.42 5 P 0 
L 2.90546998 -0.42 2.89776998 -0.4123 5 P 0 
L 2.89776998 -0.4123 2.89776998 -0.1977 5 P 0 
L 2.89776998 -0.1977 2.89006998 -0.19 5 P 0 
L 2.89006998 -0.19 2.84276998 -0.19 5 P 0 
L 2.84276998 -0.19 2.83506998 -0.1977 5 P 0 
L 2.83506998 -0.1977 2.83506998 -0.4123 5 P 0 
L 2.83506998 -0.4123 2.82736998 -0.42 5 P 0 
L 2.82736998 -0.42 2.78006998 -0.42 5 P 0 
L 2.78006998 -0.42 2.77236998 -0.4123 5 P 0 
L 2.77236998 -0.4123 2.77236998 -0.1977 5 P 0 
L 2.77236998 -0.1977 2.76466998 -0.19 5 P 0 
L 2.76466998 -0.19 2.71736998 -0.19 5 P 0 
L 2.71736998 -0.19 2.70966998 -0.1977 5 P 0 
L 2.70966998 -0.1977 2.70966998 -0.4123 5 P 0 
L 2.70966998 -0.4123 2.70196998 -0.42 5 P 0 
L 2.70196998 -0.42 2.65466998 -0.42 5 P 0 
L 2.65466998 -0.42 2.64696998 -0.4123 5 P 0 
L 2.64696998 -0.4123 2.64696998 -0.1977 5 P 0 
L 2.64696998 -0.1977 2.63926998 -0.19 5 P 0 
L 2.63926998 -0.19 2.59196998 -0.19 5 P 0 
L 2.59196998 -0.19 2.58426998 -0.1977 5 P 0 
L 2.58426998 -0.1977 2.58426998 -0.4123 5 P 0 
L 2.58426998 -0.4123 2.57656998 -0.42 5 P 0 
L 2.57656998 -0.42 2.52926998 -0.42 5 P 0 
L 2.52926998 -0.42 2.52156998 -0.4123 5 P 0 
L 2.52156998 -0.4123 2.52156998 -0.1977 5 P 0 
L 2.52156998 -0.1977 2.51386998 -0.19 5 P 0 
L 2.51386998 -0.19 2.46656998 -0.19 5 P 0 
L 2.46656998 -0.19 2.45886998 -0.1977 5 P 0 
L 2.45886998 -0.1977 2.45886998 -0.4123 5 P 0 
L 2.45886998 -0.4123 2.45116998 -0.42 5 P 0 
L 2.45116998 -0.42 2.40386998 -0.42 5 P 0 
L 2.40386998 -0.42 2.39616998 -0.4123 5 P 0 
L 2.39616998 -0.4123 2.39616998 -0.1977 5 P 0 
L 2.39616998 -0.1977 2.38846998 -0.19 5 P 0 
L 2.38846998 -0.19 2.34116998 -0.19 5 P 0 
L 2.34116998 -0.19 2.33346998 -0.1977 5 P 0 
L 2.33346998 -0.1977 2.33346998 -0.4123 5 P 0 
L 2.33346998 -0.4123 2.32576998 -0.42 5 P 0 
L 2.32576998 -0.42 2.27846998 -0.42 5 P 0 
L 2.27846998 -0.42 2.27076998 -0.4123 5 P 0 
L 2.27076998 -0.4123 2.27076998 -0.1977 5 P 0 
L 2.27076998 -0.1977 2.26306998 -0.19 5 P 0 
L 2.26306998 -0.19 2.21576998 -0.19 5 P 0 
L 2.21576998 -0.19 2.20806998 -0.1977 5 P 0 
L 2.20806998 -0.1977 2.20806998 -0.4123 5 P 0 
L 2.20806998 -0.4123 2.20036998 -0.42 5 P 0 
L 2.20036998 -0.42 2.15306998 -0.42 5 P 0 
L 2.15306998 -0.42 2.14536998 -0.4123 5 P 0 
L 2.14536998 -0.4123 2.14536998 -0.1977 5 P 0 
L 2.14536998 -0.1977 2.13766998 -0.19 5 P 0 
L 2.13766998 -0.19 2.09036998 -0.19 5 P 0 
L 2.09036998 -0.19 2.08266998 -0.1977 5 P 0 
L 2.08266998 -0.1977 2.08266998 -0.4123 5 P 0 
L 2.08266998 -0.4123 2.07496998 -0.42 5 P 0 
L 2.07496998 -0.42 2.02766998 -0.42 5 P 0 
L 2.02766998 -0.42 2.01996998 -0.4123 5 P 0 
L 2.01996998 -0.4123 2.01996998 -0.1977 5 P 0 
L 2.01996998 -0.1977 2.01226998 -0.19 5 P 0 
L 2.01226998 -0.19 1.96496998 -0.19 5 P 0 
L 1.96496998 -0.19 1.95726998 -0.1977 5 P 0 
L 1.95726998 -0.1977 1.95726998 -0.4123 5 P 0 
L 1.95726998 -0.4123 1.94956998 -0.42 5 P 0 
L 1.94956998 -0.42 1.90226998 -0.42 5 P 0 
L 1.90226998 -0.42 1.89456998 -0.4123 5 P 0 
L 1.89456998 -0.4123 1.89456998 -0.1977 5 P 0 
L 1.89456998 -0.1977 1.88686998 -0.19 5 P 0 
L 1.88686998 -0.19 1.83956998 -0.19 5 P 0 
L 1.83956998 -0.19 1.83186998 -0.1977 5 P 0 
L 1.83186998 -0.1977 1.83186998 -0.4123 5 P 0 
L 1.83186998 -0.4123 1.82416998 -0.42 5 P 0 
L 1.82416998 -0.42 1.77686998 -0.42 5 P 0 
L 1.77686998 -0.42 1.76916998 -0.4123 5 P 0 
L 1.76916998 -0.4123 1.76916998 -0.1977 5 P 0 
L 1.76916998 -0.1977 1.76146998 -0.19 5 P 0 
L 1.76146998 -0.19 1.71416998 -0.19 5 P 0 
L 1.71416998 -0.19 1.70646998 -0.1977 5 P 0 
L 1.70646998 -0.1977 1.70646998 -0.4123 5 P 0 
L 1.70646998 -0.4123 1.69876998 -0.42 5 P 0 
L 1.69876998 -0.42 1.65146998 -0.42 5 P 0 
L 1.65146998 -0.42 1.64376998 -0.4123 5 P 0 
L 1.64376998 -0.4123 1.64376998 -0.1977 5 P 0 
L 1.64376998 -0.1977 1.63606998 -0.19 5 P 0 
L 1.63606998 -0.19 1.58876998 -0.19 5 P 0 
L 1.58876998 -0.19 1.58106998 -0.1977 5 P 0 
L 1.58106998 -0.1977 1.58106998 -0.4123 5 P 0 
L 1.58106998 -0.4123 1.57336998 -0.42 5 P 0 
L 1.57336998 -0.42 1.495 -0.42 5 P 0 
L 1.495 -0.42 1.325 -0.25 5 P 0 
P 5.00768002 2.09115 10 P 0 0;2,4=11,6=0
L 5.00768002 2.09115 5.03268002 2.06615 5 P 0 
P 5.03268002 2.06615 8 P 0 0;4=12,6=1
P 12.63778996 4.12991998 14 P 0 0;4=2,6=0
P 11.53316004 2.372 8 P 0 0;4=12,6=1
P 5.05768002 2.29115 10 P 0 0;2,4=11,6=0
L 5.08268002 2.26615 5.05768002 2.29115 5 P 0 
P 5.08268002 2.26615 8 P 0 0;4=12,6=1
P 11.53316004 1.892 8 P 0 0;4=12,6=1
P 12.55905 3.30315 14 P 0 0;4=2,6=0
P 12.81495 2.51575 14 P 0 0;4=2,6=0
P 10.61161004 1.94115 10 P 0 0;2,4=11,6=0
L 10.58661004 1.91615 10.61161004 1.94115 5 P 0 
P 10.58661004 1.91615 8 P 0 0;4=12,6=1
P 10.26 1.66445 8 P 0 0;4=12,6=1
P 10.66161004 3.09115 10 P 0 0;2,4=11,6=0
P 10.61161004 3.09115 10 P 0 0;2,4=11,6=0
P 10.61161004 2.99115 10 P 0 0;2,4=11,6=0
P 10.66161004 2.99115 10 P 0 0;2,4=11,6=0
P 10.61161004 2.94115 10 P 0 0;2,4=11,6=0
P 10.66161004 2.94115 10 P 0 0;2,4=11,6=0
P 10.81161004 3.09115 10 P 0 0;2,4=11,6=0
P 10.81161004 2.99115 10 P 0 0;2,4=11,6=0
P 10.86161004 3.09115 10 P 0 0;2,4=11,6=0
P 10.86161004 2.99115 10 P 0 0;2,4=11,6=0
P 10.71161004 3.09115 10 P 0 0;2,4=11,6=0
P 10.76161004 3.09115 10 P 0 0;2,4=11,6=0
P 10.71161004 2.99115 10 P 0 0;2,4=11,6=0
P 10.76161004 2.99115 10 P 0 0;2,4=11,6=0
P 10.81161004 2.94115 10 P 0 0;2,4=11,6=0
P 10.86161004 2.94115 10 P 0 0;2,4=11,6=0
P 10.71161004 2.94115 10 P 0 0;2,4=11,6=0
P 10.76161004 2.94115 10 P 0 0;2,4=11,6=0
P 11.01161004 3.09115 10 P 0 0;2,4=11,6=0
P 11.01161004 2.99115 10 P 0 0;2,4=11,6=0
P 11.06161004 3.09115 10 P 0 0;2,4=11,6=0
P 11.06161004 2.99115 10 P 0 0;2,4=11,6=0
P 10.96161004 3.09115 10 P 0 0;2,4=11,6=0
P 10.91161004 3.09115 10 P 0 0;2,4=11,6=0
P 10.96161004 2.99115 10 P 0 0;2,4=11,6=0
P 10.91161004 2.99115 10 P 0 0;2,4=11,6=0
P 11.01161004 2.94115 10 P 0 0;2,4=11,6=0
P 11.06161004 2.94115 10 P 0 0;2,4=11,6=0
P 10.96161004 2.94115 10 P 0 0;2,4=11,6=0
P 10.91161004 2.94115 10 P 0 0;2,4=11,6=0
P 10.66161004 3.29115 10 P 0 0;2,4=11,6=0
P 10.61161004 3.24115 10 P 0 0;2,4=11,6=0
P 10.61161004 3.29115 10 P 0 0;2,4=11,6=0
P 10.66161004 3.24115 10 P 0 0;2,4=11,6=0
P 10.66161004 3.14115 10 P 0 0;2,4=11,6=0
P 10.61161004 3.14115 10 P 0 0;2,4=11,6=0
P 10.81161004 3.24115 10 P 0 0;2,4=11,6=0
P 10.81161004 3.29115 10 P 0 0;2,4=11,6=0
P 10.86161004 3.29115 10 P 0 0;2,4=11,6=0
P 10.86161004 3.24115 10 P 0 0;2,4=11,6=0
P 10.76161004 3.29115 10 P 0 0;2,4=11,6=0
P 10.76161004 3.24115 10 P 0 0;2,4=11,6=0
P 10.71161004 3.24115 10 P 0 0;2,4=11,6=0
P 10.71161004 3.29115 10 P 0 0;2,4=11,6=0
P 10.81161004 3.14115 10 P 0 0;2,4=11,6=0
P 10.86161004 3.14115 10 P 0 0;2,4=11,6=0
P 10.76161004 3.14115 10 P 0 0;2,4=11,6=0
P 10.71161004 3.14115 10 P 0 0;2,4=11,6=0
P 11.01161004 3.24115 10 P 0 0;2,4=11,6=0
P 11.01161004 3.29115 10 P 0 0;2,4=11,6=0
P 11.06161004 3.24115 10 P 0 0;2,4=11,6=0
P 11.06161004 3.29115 10 P 0 0;2,4=11,6=0
P 10.96161004 3.29115 10 P 0 0;2,4=11,6=0
P 10.96161004 3.24115 10 P 0 0;2,4=11,6=0
P 10.91161004 3.24115 10 P 0 0;2,4=11,6=0
P 10.91161004 3.29115 10 P 0 0;2,4=11,6=0
P 11.01161004 3.14115 10 P 0 0;2,4=11,6=0
P 11.06161004 3.14115 10 P 0 0;2,4=11,6=0
P 10.96161004 3.14115 10 P 0 0;2,4=11,6=0
P 10.91161004 3.14115 10 P 0 0;2,4=11,6=0
P 10.61161004 3.59115 10 P 0 0;2,4=11,6=0
P 10.66161004 3.59115 10 P 0 0;2,4=11,6=0
P 10.61161004 3.54115 10 P 0 0;2,4=11,6=0
P 10.66161004 3.54115 10 P 0 0;2,4=11,6=0
P 10.61161004 3.44115 10 P 0 0;2,4=11,6=0
P 10.66161004 3.39115 10 P 0 0;2,4=11,6=0
P 10.66161004 3.44115 10 P 0 0;2,4=11,6=0
P 10.61161004 3.39115 10 P 0 0;2,4=11,6=0
P 10.81161004 3.59115 10 P 0 0;2,4=11,6=0
P 10.81161004 3.54115 10 P 0 0;2,4=11,6=0
P 10.86161004 3.59115 10 P 0 0;2,4=11,6=0
P 10.86161004 3.54115 10 P 0 0;2,4=11,6=0
P 10.76161004 3.59115 10 P 0 0;2,4=11,6=0
P 10.71161004 3.59115 10 P 0 0;2,4=11,6=0
P 10.76161004 3.54115 10 P 0 0;2,4=11,6=0
P 10.71161004 3.54115 10 P 0 0;2,4=11,6=0
P 10.81161004 3.44115 10 P 0 0;2,4=11,6=0
P 10.81161004 3.39115 10 P 0 0;2,4=11,6=0
P 10.86161004 3.39115 10 P 0 0;2,4=11,6=0
P 10.86161004 3.44115 10 P 0 0;2,4=11,6=0
P 10.76161004 3.39115 10 P 0 0;2,4=11,6=0
P 10.71161004 3.39115 10 P 0 0;2,4=11,6=0
P 10.71161004 3.44115 10 P 0 0;2,4=11,6=0
P 10.76161004 3.44115 10 P 0 0;2,4=11,6=0
P 11.01161004 3.59115 10 P 0 0;2,4=11,6=0
P 11.01161004 3.54115 10 P 0 0;2,4=11,6=0
P 11.06161004 3.59115 10 P 0 0;2,4=11,6=0
P 11.06161004 3.54115 10 P 0 0;2,4=11,6=0
P 10.96161004 3.59115 10 P 0 0;2,4=11,6=0
P 10.91161004 3.59115 10 P 0 0;2,4=11,6=0
P 10.96161004 3.54115 10 P 0 0;2,4=11,6=0
P 10.91161004 3.54115 10 P 0 0;2,4=11,6=0
P 11.01161004 3.44115 10 P 0 0;2,4=11,6=0
P 11.01161004 3.39115 10 P 0 0;2,4=11,6=0
P 11.06161004 3.44115 10 P 0 0;2,4=11,6=0
P 11.06161004 3.39115 10 P 0 0;2,4=11,6=0
P 10.96161004 3.44115 10 P 0 0;2,4=11,6=0
P 10.96161004 3.39115 10 P 0 0;2,4=11,6=0
P 10.91161004 3.44115 10 P 0 0;2,4=11,6=0
P 10.91161004 3.39115 10 P 0 0;2,4=11,6=0
P 10.61161004 3.84115 10 P 0 0;2,4=11,6=0
P 10.66161004 3.84115 10 P 0 0;2,4=11,6=0
P 10.61161004 3.74115 10 P 0 0;2,4=11,6=0
P 10.66161004 3.74115 10 P 0 0;2,4=11,6=0
P 10.61161004 3.69115 10 P 0 0;2,4=11,6=0
P 10.66161004 3.69115 10 P 0 0;2,4=11,6=0
P 10.81161004 3.84115 10 P 0 0;2,4=11,6=0
P 10.81161004 3.74115 10 P 0 0;2,4=11,6=0
P 10.86161004 3.84115 10 P 0 0;2,4=11,6=0
P 10.86161004 3.74115 10 P 0 0;2,4=11,6=0
P 10.76161004 3.84115 10 P 0 0;2,4=11,6=0
P 10.71161004 3.84115 10 P 0 0;2,4=11,6=0
P 10.76161004 3.74115 10 P 0 0;2,4=11,6=0
P 10.71161004 3.74115 10 P 0 0;2,4=11,6=0
P 10.81161004 3.69115 10 P 0 0;2,4=11,6=0
P 10.86161004 3.69115 10 P 0 0;2,4=11,6=0
P 10.76161004 3.69115 10 P 0 0;2,4=11,6=0
P 10.71161004 3.69115 10 P 0 0;2,4=11,6=0
P 11.01161004 3.84115 10 P 0 0;2,4=11,6=0
P 11.01161004 3.74115 10 P 0 0;2,4=11,6=0
P 11.06161004 3.84115 10 P 0 0;2,4=11,6=0
P 11.06161004 3.74115 10 P 0 0;2,4=11,6=0
P 10.96161004 3.84115 10 P 0 0;2,4=11,6=0
P 10.91161004 3.84115 10 P 0 0;2,4=11,6=0
P 10.96161004 3.74115 10 P 0 0;2,4=11,6=0
P 10.91161004 3.74115 10 P 0 0;2,4=11,6=0
P 11.01161004 3.69115 10 P 0 0;2,4=11,6=0
P 11.06161004 3.69115 10 P 0 0;2,4=11,6=0
P 10.96161004 3.69115 10 P 0 0;2,4=11,6=0
P 10.91161004 3.69115 10 P 0 0;2,4=11,6=0
P 11.03998996 4.8431 9 P 0 0;4=13,6=1
P 11.08498996 4.8431 9 P 0 0;4=13,6=1
P 11.13498996 4.8431 9 P 0 0;4=13,6=1
P 11.17998996 4.8431 9 P 0 0;4=13,6=1
P 11.17998996 4.8031 9 P 0 0;4=13,6=1
P 11.17998996 4.7581 9 P 0 0;4=13,6=1
P 11.17998996 4.7131 9 P 0 0;4=13,6=1
P 11.17998996 4.6731 9 P 0 0;4=13,6=1
P 11.03998996 4.6731 9 P 0 0;4=13,6=1
P 11.08498996 4.6731 9 P 0 0;4=13,6=1
P 11.13498996 4.6731 9 P 0 0;4=13,6=1
P 11.03998996 4.7131 9 P 0 0;4=13,6=1
P 11.03998996 4.8031 9 P 0 0;4=13,6=1
P 11.03998996 4.7581 9 P 0 0;4=13,6=1
P 10.81998996 4.6631 9 P 0 0;4=13,6=1
P 10.85998996 4.6631 9 P 0 0;4=13,6=1
P 10.65998996 4.6631 9 P 0 0;4=13,6=1
P 10.69998996 4.6631 9 P 0 0;4=13,6=1
P 10.81998996 4.7031 9 P 0 0;4=13,6=1
P 10.81998996 4.8381 9 P 0 0;4=13,6=1
P 10.81998996 4.7931 9 P 0 0;4=13,6=1
P 10.81998996 4.7481 9 P 0 0;4=13,6=1
P 10.85998996 4.7031 9 P 0 0;4=13,6=1
P 10.85998996 4.8381 9 P 0 0;4=13,6=1
P 10.85998996 4.7931 9 P 0 0;4=13,6=1
P 10.85998996 4.7481 9 P 0 0;4=13,6=1
P 10.65998996 4.7031 9 P 0 0;4=13,6=1
P 10.65998996 4.8381 9 P 0 0;4=13,6=1
P 10.65998996 4.7931 9 P 0 0;4=13,6=1
P 10.65998996 4.7481 9 P 0 0;4=13,6=1
P 10.69998996 4.7031 9 P 0 0;4=13,6=1
P 10.69998996 4.8381 9 P 0 0;4=13,6=1
P 10.69998996 4.7931 9 P 0 0;4=13,6=1
P 10.69998996 4.7481 9 P 0 0;4=13,6=1
P 10.77998996 4.6431 9 P 0 0;4=13,6=1
P 10.73498996 4.6431 9 P 0 0;4=13,6=1
P 10.73998996 4.8381 9 P 0 0;4=13,6=1
P 10.77998996 4.8381 9 P 0 0;4=13,6=1
P 10.30998996 4.6631 9 P 0 0;4=13,6=1
P 10.26998996 4.6631 9 P 0 0;4=13,6=1
P 10.34498996 4.6431 9 P 0 0;4=13,6=1
P 10.38998996 4.6431 9 P 0 0;4=13,6=1
P 10.42998996 4.6631 9 P 0 0;4=13,6=1
P 10.46998996 4.6631 9 P 0 0;4=13,6=1
P 10.30998996 4.7481 9 P 0 0;4=13,6=1
P 10.30998996 4.7931 9 P 0 0;4=13,6=1
P 10.30998996 4.7031 9 P 0 0;4=13,6=1
P 10.26998996 4.7481 9 P 0 0;4=13,6=1
P 10.26998996 4.7931 9 P 0 0;4=13,6=1
P 10.26998996 4.7031 9 P 0 0;4=13,6=1
P 10.26998996 4.8381 9 P 0 0;4=13,6=1
P 10.30998996 4.8381 9 P 0 0;4=13,6=1
P 10.38998996 4.8381 9 P 0 0;4=13,6=1
P 10.34998996 4.8381 9 P 0 0;4=13,6=1
P 10.46998996 4.8381 9 P 0 0;4=13,6=1
P 10.42998996 4.8381 9 P 0 0;4=13,6=1
P 10.42998996 4.7031 9 P 0 0;4=13,6=1
P 10.42998996 4.7931 9 P 0 0;4=13,6=1
P 10.42998996 4.7481 9 P 0 0;4=13,6=1
P 10.46998996 4.7031 9 P 0 0;4=13,6=1
P 10.46998996 4.7931 9 P 0 0;4=13,6=1
P 10.46998996 4.7481 9 P 0 0;4=13,6=1
P 10.36698996 4.74133996 53 P 0 0;2,4=25,6=0
P 10.75698996 4.74133996 53 P 0 0;2,4=25,6=0
P 11.10998996 4.75636998 34 P 0 0;2,4=26,6=0
L 10.61161004 3.14115 10.58661004 3.16615 9 P 0 
P 10.58661004 3.16615 8 P 0 0;4=12,6=1
L 10.66161004 2.99115 10.63661004 3.01615 9 P 0 
P 10.63661004 3.01615 8 P 0 0;4=12,6=1
L 10.61161004 3.09115 10.58661004 3.11615 9 P 0 
P 10.58661004 3.11615 8 P 0 0;4=12,6=1
L 10.61161004 2.99115 10.58661004 3.01615 9 P 0 
P 10.58661004 3.01615 8 P 0 0;4=12,6=1
L 10.66161004 3.09115 10.63661004 3.11615 9 P 0 
P 10.63661004 3.11615 8 P 0 0;4=12,6=1
L 10.66161004 2.94115 10.63661004 2.96615 9 P 0 
P 10.63661004 2.96615 8 P 0 0;4=12,6=1
L 10.61161004 2.94115 10.58661004 2.96615 9 P 0 
P 10.58661004 2.96615 8 P 0 0;4=12,6=1
L 10.61161004 3.39115 10.58661004 3.41615 9 P 0 
P 10.58661004 3.41615 8 P 0 0;4=12,6=1
L 10.66161004 3.14115 10.63661004 3.16615 9 P 0 
P 10.63661004 3.16615 8 P 0 0;4=12,6=1
L 10.66161004 3.24115 10.63661004 3.26615 9 P 0 
P 10.63661004 3.26615 8 P 0 0;4=12,6=1
L 10.61161004 3.29115 10.58661004 3.31615 9 P 0 
P 10.58661004 3.31615 8 P 0 0;4=12,6=1
L 10.61161004 3.24115 10.58661004 3.26615 9 P 0 
P 10.58661004 3.26615 8 P 0 0;4=12,6=1
L 10.66161004 3.29115 10.63661004 3.31615 9 P 0 
P 10.63661004 3.31615 8 P 0 0;4=12,6=1
L 10.66161004 3.54115 10.63661004 3.56615 9 P 0 
P 10.63661004 3.56615 8 P 0 0;4=12,6=1
L 10.66161004 3.59115 10.63661004 3.61615 9 P 0 
P 10.63661004 3.61615 8 P 0 0;4=12,6=1
L 10.61161004 3.54115 10.58661004 3.56615 9 P 0 
P 10.58661004 3.56615 8 P 0 0;4=12,6=1
L 10.61161004 3.59115 10.58661004 3.61615 9 P 0 
P 10.58661004 3.61615 8 P 0 0;4=12,6=1
L 10.66161004 3.44115 10.63661004 3.46615 9 P 0 
P 10.63661004 3.46615 8 P 0 0;4=12,6=1
L 10.66161004 3.39115 10.63661004 3.41615 9 P 0 
P 10.63661004 3.41615 8 P 0 0;4=12,6=1
L 10.61161004 3.44115 10.58661004 3.46615 9 P 0 
P 10.58661004 3.46615 8 P 0 0;4=12,6=1
L 10.66161004 3.84115 10.63661004 3.86615 9 P 0 
P 10.63661004 3.86615 8 P 0 0;4=12,6=1
L 10.66161004 3.74115 10.63661004 3.76615 9 P 0 
P 10.63661004 3.76615 8 P 0 0;4=12,6=1
L 10.61161004 3.84115 10.58661004 3.86615 9 P 0 
P 10.58661004 3.86615 8 P 0 0;4=12,6=1
L 10.61161004 3.74115 10.58661004 3.76615 9 P 0 
P 10.58661004 3.76615 8 P 0 0;4=12,6=1
L 10.66161004 3.69115 10.63661004 3.71615 9 P 0 
P 10.63661004 3.71615 8 P 0 0;4=12,6=1
L 10.61161004 3.69115 10.58661004 3.71615 9 P 0 
P 10.58661004 3.71615 8 P 0 0;4=12,6=1
L 10.91161004 2.94115 10.88661004 2.96615 9 P 0 
P 10.88661004 2.96615 8 P 0 0;4=12,6=1
L 10.86161004 2.94115 10.83661004 2.96615 9 P 0 
P 10.83661004 2.96615 8 P 0 0;4=12,6=1
L 10.91161004 2.99115 10.88661004 3.01615 9 P 0 
P 10.88661004 3.01615 8 P 0 0;4=12,6=1
L 10.86161004 2.99115 10.83661004 3.01615 9 P 0 
P 10.83661004 3.01615 8 P 0 0;4=12,6=1
L 10.91161004 3.09115 10.88661004 3.11615 9 P 0 
P 10.88661004 3.11615 8 P 0 0;4=12,6=1
L 10.86161004 3.09115 10.83661004 3.11615 9 P 0 
P 10.83661004 3.11615 8 P 0 0;4=12,6=1
L 10.86161004 3.14115 10.83661004 3.16615 9 P 0 
P 10.83661004 3.16615 8 P 0 0;4=12,6=1
L 10.81161004 3.14115 10.78661004 3.16615 9 P 0 
P 10.78661004 3.16615 8 P 0 0;4=12,6=1
L 10.71161004 3.14115 10.68661004 3.16615 9 P 0 
P 10.68661004 3.16615 8 P 0 0;4=12,6=1
L 10.76161004 3.14115 10.73661004 3.16615 9 P 0 
P 10.73661004 3.16615 8 P 0 0;4=12,6=1
L 10.81161004 2.99115 10.78661004 3.01615 9 P 0 
P 10.78661004 3.01615 8 P 0 0;4=12,6=1
L 10.81161004 3.09115 10.78661004 3.11615 9 P 0 
P 10.78661004 3.11615 8 P 0 0;4=12,6=1
L 10.76161004 2.99115 10.73661004 3.01615 9 P 0 
P 10.73661004 3.01615 8 P 0 0;4=12,6=1
L 10.76161004 3.09115 10.73661004 3.11615 9 P 0 
P 10.73661004 3.11615 8 P 0 0;4=12,6=1
L 10.71161004 2.99115 10.68661004 3.01615 9 P 0 
P 10.68661004 3.01615 8 P 0 0;4=12,6=1
L 10.71161004 3.09115 10.68661004 3.11615 9 P 0 
P 10.68661004 3.11615 8 P 0 0;4=12,6=1
L 10.81161004 2.94115 10.78661004 2.96615 9 P 0 
P 10.78661004 2.96615 8 P 0 0;4=12,6=1
L 10.76161004 2.94115 10.73661004 2.96615 9 P 0 
P 10.73661004 2.96615 8 P 0 0;4=12,6=1
L 10.71161004 2.94115 10.68661004 2.96615 9 P 0 
P 10.68661004 2.96615 8 P 0 0;4=12,6=1
L 10.91161004 3.14115 10.88661004 3.16615 9 P 0 
P 10.88661004 3.16615 8 P 0 0;4=12,6=1
L 10.91161004 3.24115 10.88661004 3.26615 9 P 0 
P 10.88661004 3.26615 8 P 0 0;4=12,6=1
L 10.86161004 3.24115 10.83661004 3.26615 9 P 0 
P 10.83661004 3.26615 8 P 0 0;4=12,6=1
L 10.86161004 3.29115 10.83661004 3.31615 9 P 0 
P 10.83661004 3.31615 8 P 0 0;4=12,6=1
L 10.91161004 3.29115 10.88661004 3.31615 9 P 0 
P 10.88661004 3.31615 8 P 0 0;4=12,6=1
L 10.86161004 3.39115 10.83661004 3.41615 9 P 0 
P 10.83661004 3.41615 8 P 0 0;4=12,6=1
L 10.81161004 3.39115 10.78661004 3.41615 9 P 0 
P 10.78661004 3.41615 8 P 0 0;4=12,6=1
L 10.71161004 3.39115 10.68661004 3.41615 9 P 0 
P 10.68661004 3.41615 8 P 0 0;4=12,6=1
L 10.76161004 3.39115 10.73661004 3.41615 9 P 0 
P 10.73661004 3.41615 8 P 0 0;4=12,6=1
L 10.81161004 3.29115 10.78661004 3.31615 9 P 0 
P 10.78661004 3.31615 8 P 0 0;4=12,6=1
L 10.81161004 3.24115 10.78661004 3.26615 9 P 0 
P 10.78661004 3.26615 8 P 0 0;4=12,6=1
L 10.71161004 3.29115 10.68661004 3.31615 9 P 0 
P 10.68661004 3.31615 8 P 0 0;4=12,6=1
L 10.71161004 3.24115 10.68661004 3.26615 9 P 0 
P 10.68661004 3.26615 8 P 0 0;4=12,6=1
L 10.76161004 3.24115 10.73661004 3.26615 9 P 0 
P 10.73661004 3.26615 8 P 0 0;4=12,6=1
L 10.76161004 3.29115 10.73661004 3.31615 9 P 0 
P 10.73661004 3.31615 8 P 0 0;4=12,6=1
L 10.91161004 3.39115 10.88661004 3.41615 9 P 0 
P 10.88661004 3.41615 8 P 0 0;4=12,6=1
L 10.86161004 3.44115 10.83661004 3.46615 9 P 0 
P 10.83661004 3.46615 8 P 0 0;4=12,6=1
L 10.91161004 3.44115 10.88661004 3.46615 9 P 0 
P 10.88661004 3.46615 8 P 0 0;4=12,6=1
L 10.86161004 3.54115 10.83661004 3.56615 9 P 0 
P 10.83661004 3.56615 8 P 0 0;4=12,6=1
L 10.91161004 3.54115 10.88661004 3.56615 9 P 0 
P 10.88661004 3.56615 8 P 0 0;4=12,6=1
L 10.86161004 3.59115 10.83661004 3.61615 9 P 0 
P 10.83661004 3.61615 8 P 0 0;4=12,6=1
L 10.91161004 3.59115 10.88661004 3.61615 9 P 0 
P 10.88661004 3.61615 8 P 0 0;4=12,6=1
L 10.81161004 3.54115 10.78661004 3.56615 9 P 0 
P 10.78661004 3.56615 8 P 0 0;4=12,6=1
L 10.81161004 3.59115 10.78661004 3.61615 9 P 0 
P 10.78661004 3.61615 8 P 0 0;4=12,6=1
L 10.71161004 3.59115 10.68661004 3.61615 9 P 0 
P 10.68661004 3.61615 8 P 0 0;4=12,6=1
L 10.71161004 3.54115 10.68661004 3.56615 9 P 0 
P 10.68661004 3.56615 8 P 0 0;4=12,6=1
L 10.76161004 3.59115 10.73661004 3.61615 9 P 0 
P 10.73661004 3.61615 8 P 0 0;4=12,6=1
L 10.76161004 3.54115 10.73661004 3.56615 9 P 0 
P 10.73661004 3.56615 8 P 0 0;4=12,6=1
L 10.81161004 3.44115 10.78661004 3.46615 9 P 0 
P 10.78661004 3.46615 8 P 0 0;4=12,6=1
L 10.76161004 3.44115 10.73661004 3.46615 9 P 0 
P 10.73661004 3.46615 8 P 0 0;4=12,6=1
L 10.71161004 3.44115 10.68661004 3.46615 9 P 0 
P 10.68661004 3.46615 8 P 0 0;4=12,6=1
L 10.86161004 3.69115 10.83661004 3.71615 9 P 0 
P 10.83661004 3.71615 8 P 0 0;4=12,6=1
L 10.91161004 3.69115 10.88661004 3.71615 9 P 0 
P 10.88661004 3.71615 8 P 0 0;4=12,6=1
L 10.86161004 3.74115 10.83661004 3.76615 9 P 0 
P 10.83661004 3.76615 8 P 0 0;4=12,6=1
L 10.91161004 3.74115 10.88661004 3.76615 9 P 0 
P 10.88661004 3.76615 8 P 0 0;4=12,6=1
L 10.86161004 3.84115 10.83661004 3.86615 9 P 0 
P 10.83661004 3.86615 8 P 0 0;4=12,6=1
L 10.91161004 3.84115 10.88661004 3.86615 9 P 0 
P 10.88661004 3.86615 8 P 0 0;4=12,6=1
L 10.81161004 3.84115 10.78661004 3.86615 9 P 0 
P 10.78661004 3.86615 8 P 0 0;4=12,6=1
L 10.81161004 3.74115 10.78661004 3.76615 9 P 0 
P 10.78661004 3.76615 8 P 0 0;4=12,6=1
L 10.71161004 3.84115 10.68661004 3.86615 9 P 0 
P 10.68661004 3.86615 8 P 0 0;4=12,6=1
L 10.71161004 3.74115 10.68661004 3.76615 9 P 0 
P 10.68661004 3.76615 8 P 0 0;4=12,6=1
L 10.76161004 3.84115 10.73661004 3.86615 9 P 0 
P 10.73661004 3.86615 8 P 0 0;4=12,6=1
L 10.76161004 3.74115 10.73661004 3.76615 9 P 0 
P 10.73661004 3.76615 8 P 0 0;4=12,6=1
L 10.81161004 3.69115 10.78661004 3.71615 9 P 0 
P 10.78661004 3.71615 8 P 0 0;4=12,6=1
L 10.71161004 3.69115 10.68661004 3.71615 9 P 0 
P 10.68661004 3.71615 8 P 0 0;4=12,6=1
L 10.76161004 3.69115 10.73661004 3.71615 9 P 0 
P 10.73661004 3.71615 8 P 0 0;4=12,6=1
L 11.06161004 2.94115 11.03661004 2.96615 9 P 0 
P 11.03661004 2.96615 8 P 0 0;4=12,6=1
L 10.96161004 2.94115 10.93661004 2.96615 9 P 0 
P 10.93661004 2.96615 8 P 0 0;4=12,6=1
L 11.01161004 2.94115 10.98661004 2.96615 9 P 0 
P 10.98661004 2.96615 8 P 0 0;4=12,6=1
L 11.06161004 2.99115 11.03661004 3.01615 9 P 0 
P 11.03661004 3.01615 8 P 0 0;4=12,6=1
L 10.96161004 2.99115 10.93661004 3.01615 9 P 0 
P 10.93661004 3.01615 8 P 0 0;4=12,6=1
L 11.01161004 2.99115 10.98661004 3.01615 9 P 0 
P 10.98661004 3.01615 8 P 0 0;4=12,6=1
L 11.06161004 3.09115 11.03661004 3.11615 9 P 0 
P 11.03661004 3.11615 8 P 0 0;4=12,6=1
L 10.96161004 3.09115 10.93661004 3.11615 9 P 0 
P 10.93661004 3.11615 8 P 0 0;4=12,6=1
L 11.01161004 3.09115 10.98661004 3.11615 9 P 0 
P 10.98661004 3.11615 8 P 0 0;4=12,6=1
L 11.06161004 3.14115 11.03661004 3.16615 9 P 0 
P 11.03661004 3.16615 8 P 0 0;4=12,6=1
L 10.96161004 3.14115 10.93661004 3.16615 9 P 0 
P 10.93661004 3.16615 8 P 0 0;4=12,6=1
L 11.01161004 3.14115 10.98661004 3.16615 9 P 0 
P 10.98661004 3.16615 8 P 0 0;4=12,6=1
L 11.06161004 3.24115 11.03661004 3.26615 9 P 0 
P 11.03661004 3.26615 8 P 0 0;4=12,6=1
L 10.96161004 3.24115 10.93661004 3.26615 9 P 0 
P 10.93661004 3.26615 8 P 0 0;4=12,6=1
L 11.01161004 3.24115 10.98661004 3.26615 9 P 0 
P 10.98661004 3.26615 8 P 0 0;4=12,6=1
L 11.01161004 3.29115 10.98661004 3.31615 9 P 0 
P 10.98661004 3.31615 8 P 0 0;4=12,6=1
L 10.96161004 3.29115 10.93661004 3.31615 9 P 0 
P 10.93661004 3.31615 8 P 0 0;4=12,6=1
L 11.06161004 3.29115 11.03661004 3.31615 9 P 0 
P 11.03661004 3.31615 8 P 0 0;4=12,6=1
L 11.01161004 3.39115 10.98661004 3.41615 9 P 0 
P 10.98661004 3.41615 8 P 0 0;4=12,6=1
L 10.96161004 3.39115 10.93661004 3.41615 9 P 0 
P 10.93661004 3.41615 8 P 0 0;4=12,6=1
L 11.06161004 3.39115 11.03661004 3.41615 9 P 0 
P 11.03661004 3.41615 8 P 0 0;4=12,6=1
L 11.01161004 3.44115 10.98661004 3.46615 9 P 0 
P 10.98661004 3.46615 8 P 0 0;4=12,6=1
L 10.96161004 3.44115 10.93661004 3.46615 9 P 0 
P 10.93661004 3.46615 8 P 0 0;4=12,6=1
L 11.06161004 3.44115 11.03661004 3.46615 9 P 0 
P 11.03661004 3.46615 8 P 0 0;4=12,6=1
L 11.01161004 3.54115 10.98661004 3.56615 9 P 0 
P 10.98661004 3.56615 8 P 0 0;4=12,6=1
L 10.96161004 3.54115 10.93661004 3.56615 9 P 0 
P 10.93661004 3.56615 8 P 0 0;4=12,6=1
L 11.06161004 3.54115 11.03661004 3.56615 9 P 0 
P 11.03661004 3.56615 8 P 0 0;4=12,6=1
L 11.01161004 3.59115 10.98661004 3.61615 9 P 0 
P 10.98661004 3.61615 8 P 0 0;4=12,6=1
L 10.96161004 3.59115 10.93661004 3.61615 9 P 0 
P 10.93661004 3.61615 8 P 0 0;4=12,6=1
L 11.06161004 3.59115 11.03661004 3.61615 9 P 0 
P 11.03661004 3.61615 8 P 0 0;4=12,6=1
L 11.01161004 3.69115 10.98661004 3.71615 9 P 0 
P 10.98661004 3.71615 8 P 0 0;4=12,6=1
L 10.96161004 3.69115 10.93661004 3.71615 9 P 0 
P 10.93661004 3.71615 8 P 0 0;4=12,6=1
L 11.06161004 3.69115 11.03661004 3.71615 9 P 0 
P 11.03661004 3.71615 8 P 0 0;4=12,6=1
L 11.01161004 3.74115 10.98661004 3.76615 9 P 0 
P 10.98661004 3.76615 8 P 0 0;4=12,6=1
L 10.96161004 3.74115 10.93661004 3.76615 9 P 0 
P 10.93661004 3.76615 8 P 0 0;4=12,6=1
L 11.06161004 3.74115 11.03661004 3.76615 9 P 0 
P 11.03661004 3.76615 8 P 0 0;4=12,6=1
L 11.01161004 3.84115 10.98661004 3.86615 9 P 0 
P 10.98661004 3.86615 8 P 0 0;4=12,6=1
L 10.96161004 3.84115 10.93661004 3.86615 9 P 0 
P 10.93661004 3.86615 8 P 0 0;4=12,6=1
L 11.06161004 3.84115 11.03661004 3.86615 9 P 0 
P 11.03661004 3.86615 8 P 0 0;4=12,6=1
S P 0
OB 10.483 2.866 I
OS 10.464 2.885
OS 10.464 3.726
OS 10.25998996063 3.93001003937
OS 10.25998996063 4.8381
OS 10.26998996063 4.8481
OS 11.18498996063 4.8481
OS 11.225 4.80808996063
OS 11.225 3.31438996063
OC 11.225 3.28561003937 11.235 3.3 N
OS 11.225 2.905
OS 11.186 2.866
OS 10.483 2.866
OE
OB 10.9885 3.788780019685 H
OS 10.991769980315 3.78551003937
OS 10.991919980315 3.78503996063
OC 11.018015748031 3.771552755906 11.011611122047 3.79115 N
OC 11.03111003937 3.79785 11.01161003937 3.791151082677 N
OC 11.031501673228 3.799811515748 11.033 3.798492519685 Y
OC 11.0334 3.80045 11.03300265748 3.79848996063 Y
OC 11.035130019685 3.8002 11.036553248031 3.81616003937 N
OS 11.03585 3.800130019685
OS 11.041280019685 3.79471003937
OS 11.04115 3.793730019685
OC 11.059030019685 3.81161003937 11.06161003937 3.79115 N
OS 11.05805 3.811480019685
OS 11.052630019685 3.81691003937
OS 11.05256003937 3.817630019685
OC 11.034261712598 3.831987992126 11.036608661417 3.81613996063 N
OC 11.02091003937 3.81293996063 11.03661003937 3.816138484252 N
OC 11.020271555118 3.811041633858 11.01895 3.81254261811 Y
OC 11.01831003937 3.81065 11.018952559055 3.81253996063 Y
OC 11.017719980315 3.81083996063 11.011697047244 3.791119980315 N
OS 11.01725 3.81098996063
OS 10.99935 3.82888996063
OC 10.98084773622 3.833218011811 10.9866125 3.81615 N
OC 10.96876003937 3.81856003937 10.98661003937 3.816153051181 N
OC 10.966076771654 3.81530984252 10.9648 3.819096653543 Y
OC 10.961969980315 3.816269980315 10.964797244094 3.8191 Y
OS 10.94935 3.82888996063
OC 10.93084773622 3.833218011811 10.9366125 3.81615 N
OC 10.91876003937 3.81856003937 10.93661003937 3.816153051181 N
OC 10.916076771654 3.81530984252 10.9148 3.819096653543 Y
OC 10.911969980315 3.816269980315 10.914797244094 3.8191 Y
OS 10.89935 3.82888996063
OC 10.88084773622 3.833218011811 10.8866125 3.81615 N
OC 10.86876003937 3.81856003937 10.88661003937 3.816153051181 N
OC 10.866076771654 3.81530984252 10.8648 3.819096653543 Y
OC 10.861969980315 3.816269980315 10.864797244094 3.8191 Y
OS 10.84935 3.82888996063
OC 10.83084773622 3.833218011811 10.8366125 3.81615 N
OC 10.81876003937 3.81856003937 10.83661003937 3.816153051181 N
OC 10.816076771654 3.81530984252 10.8148 3.819096653543 Y
OC 10.811969980315 3.816269980315 10.814797244094 3.8191 Y
OS 10.79935 3.82888996063
OC 10.78084773622 3.833218011811 10.7866125 3.81615 N
OC 10.76876003937 3.81856003937 10.78661003937 3.816153051181 N
OC 10.766076771654 3.81530984252 10.7648 3.819096653543 Y
OC 10.761969980315 3.816269980315 10.764797244094 3.8191 Y
OS 10.74935 3.82888996063
OC 10.73084773622 3.833218011811 10.7366125 3.81615 N
OC 10.71876003937 3.81856003937 10.73661003937 3.816153051181 N
OC 10.716076771654 3.81530984252 10.7148 3.819096653543 Y
OC 10.711969980315 3.816269980315 10.714797244094 3.8191 Y
OS 10.69935 3.82888996063
OC 10.68084773622 3.833218011811 10.6866125 3.81615 N
OC 10.66876003937 3.81856003937 10.68661003937 3.816153051181 N
OC 10.666076771654 3.81530984252 10.6648 3.819096653543 Y
OC 10.661969980315 3.816269980315 10.664797244094 3.8191 Y
OS 10.64935 3.82888996063
OC 10.63084773622 3.833218011811 10.6366125 3.81615 N
OC 10.61876003937 3.81856003937 10.63661003937 3.816153051181 N
OC 10.616076771654 3.81530984252 10.6148 3.819096653543 Y
OC 10.611969980315 3.816269980315 10.614797244094 3.8191 Y
OS 10.59935 3.82888996063
OC 10.573869980315 3.80341003937 10.58661003937 3.81615 N
OS 10.591769980315 3.78551003937
OS 10.591919980315 3.78503996063
OC 10.612520866142 3.770550098425 10.611613779528 3.79115 N
OC 10.631769980315 3.7868 10.611614173228 3.79115 N
OC 10.634549901575 3.789785137795 10.635680019685 3.785945767717 Y
OC 10.6385 3.788780019685 10.635676968504 3.78595 Y
OS 10.641769980315 3.78551003937
OS 10.641919980315 3.78503996063
OC 10.662520866142 3.770550098425 10.661613779528 3.79115 N
OC 10.681769980315 3.7868 10.661614173228 3.79115 N
OC 10.684549901575 3.789785137795 10.685680019685 3.785945767717 Y
OC 10.6885 3.788780019685 10.685676968504 3.78595 Y
OS 10.691769980315 3.78551003937
OS 10.691919980315 3.78503996063
OC 10.712520866142 3.770550098425 10.711613779528 3.79115 N
OC 10.731769980315 3.7868 10.711614173228 3.79115 N
OC 10.734549901575 3.789785137795 10.735680019685 3.785945767717 Y
OC 10.7385 3.788780019685 10.735676968504 3.78595 Y
OS 10.741769980315 3.78551003937
OS 10.741919980315 3.78503996063
OC 10.762520866142 3.770550098425 10.761613779528 3.79115 N
OC 10.781769980315 3.7868 10.761614173228 3.79115 N
OC 10.784549901575 3.789785137795 10.785680019685 3.785945767717 Y
OC 10.7885 3.788780019685 10.785676968504 3.78595 Y
OS 10.791769980315 3.78551003937
OS 10.791919980315 3.78503996063
OC 10.812520866142 3.770550098425 10.811613779528 3.79115 N
OC 10.831769980315 3.7868 10.811614173228 3.79115 N
OC 10.834549901575 3.789785137795 10.835680019685 3.785945767717 Y
OC 10.8385 3.788780019685 10.835676968504 3.78595 Y
OS 10.841769980315 3.78551003937
OS 10.841919980315 3.78503996063
OC 10.862520866142 3.770550098425 10.861613779528 3.79115 N
OC 10.881769980315 3.7868 10.861614173228 3.79115 N
OC 10.884549901575 3.789785137795 10.885680019685 3.785945767717 Y
OC 10.8885 3.788780019685 10.885676968504 3.78595 Y
OS 10.891769980315 3.78551003937
OS 10.891919980315 3.78503996063
OC 10.912520866142 3.770550098425 10.911613779528 3.79115 N
OC 10.931769980315 3.7868 10.911614173228 3.79115 N
OC 10.934549901575 3.789785137795 10.935680019685 3.785945767717 Y
OC 10.9385 3.788780019685 10.935676968504 3.78595 Y
OS 10.941769980315 3.78551003937
OS 10.941919980315 3.78503996063
OC 10.962520866142 3.770550098425 10.961613779528 3.79115 N
OC 10.981769980315 3.7868 10.961614173228 3.79115 N
OC 10.984549901575 3.789785137795 10.985680019685 3.785945767717 Y
OC 10.9885 3.788780019685 10.985676968504 3.78595 Y
OE
OB 10.611969980315 3.666269980315 H
OS 10.59935 3.67888996063
OC 10.573869980315 3.65341003937 10.58661003937 3.66615 N
OS 10.591769980315 3.63551003937
OS 10.591919980315 3.63503996063
OC 10.612520866142 3.620550098425 10.611613779528 3.64115 N
OC 10.631769980315 3.6368 10.611614173228 3.64115 N
OC 10.634549901575 3.639785137795 10.635680019685 3.635945767717 Y
OC 10.6385 3.638780019685 10.635676968504 3.63595 Y
OS 10.641769980315 3.63551003937
OS 10.641919980315 3.63503996063
OC 10.662520866142 3.620550098425 10.661613779528 3.64115 N
OC 10.681769980315 3.6368 10.661614173228 3.64115 N
OC 10.684549901575 3.639785137795 10.685680019685 3.635945767717 Y
OC 10.6885 3.638780019685 10.685676968504 3.63595 Y
OS 10.691769980315 3.63551003937
OS 10.691919980315 3.63503996063
OC 10.712520866142 3.620550098425 10.711613779528 3.64115 N
OC 10.731769980315 3.6368 10.711614173228 3.64115 N
OC 10.734549901575 3.639785137795 10.735680019685 3.635945767717 Y
OC 10.7385 3.638780019685 10.735676968504 3.63595 Y
OS 10.741769980315 3.63551003937
OS 10.741919980315 3.63503996063
OC 10.762520866142 3.620550098425 10.761613779528 3.64115 N
OC 10.781769980315 3.6368 10.761614173228 3.64115 N
OC 10.784549901575 3.639785137795 10.785680019685 3.635945767717 Y
OC 10.7885 3.638780019685 10.785676968504 3.63595 Y
OS 10.791769980315 3.63551003937
OS 10.791919980315 3.63503996063
OC 10.812520866142 3.620550098425 10.811613779528 3.64115 N
OC 10.831769980315 3.6368 10.811614173228 3.64115 N
OC 10.834549901575 3.639785137795 10.835680019685 3.635945767717 Y
OC 10.8385 3.638780019685 10.835676968504 3.63595 Y
OS 10.841769980315 3.63551003937
OS 10.841919980315 3.63503996063
OC 10.862520866142 3.620550098425 10.861613779528 3.64115 N
OC 10.881769980315 3.6368 10.861614173228 3.64115 N
OC 10.884549901575 3.639785137795 10.885680019685 3.635945767717 Y
OC 10.8885 3.638780019685 10.885676968504 3.63595 Y
OS 10.891769980315 3.63551003937
OS 10.891919980315 3.63503996063
OC 10.912520866142 3.620550098425 10.911613779528 3.64115 N
OC 10.931769980315 3.6368 10.911614173228 3.64115 N
OC 10.934549901575 3.639785137795 10.935680019685 3.635945767717 Y
OC 10.9385 3.638780019685 10.935676968504 3.63595 Y
OS 10.941769980315 3.63551003937
OS 10.941919980315 3.63503996063
OC 10.962520866142 3.620550098425 10.961613779528 3.64115 N
OC 10.981769980315 3.6368 10.961614173228 3.64115 N
OC 10.984549901575 3.639785137795 10.985680019685 3.635945767717 Y
OC 10.9885 3.638780019685 10.985676968504 3.63595 Y
OS 10.991769980315 3.63551003937
OS 10.991919980315 3.63503996063
OC 11.012520866142 3.620550098425 11.011613779528 3.64115 N
OC 11.031769980315 3.6368 11.011614173228 3.64115 N
OC 11.034549901575 3.639785137795 11.035680019685 3.635945767717 Y
OC 11.0385 3.638780019685 11.035676968504 3.63595 Y
OS 11.041769980315 3.63551003937
OS 11.041919980315 3.63503996063
OC 11.067719980315 3.66083996063 11.061609940945 3.64115 N
OS 11.06725 3.66098996063
OS 11.04935 3.67888996063
OC 11.03084773622 3.683218011811 11.0366125 3.66615 N
OC 11.01876003937 3.66856003937 11.03661003937 3.666153051181 N
OC 11.016076771654 3.66530984252 11.0148 3.669096653543 Y
OC 11.011969980315 3.666269980315 11.014797244094 3.6691 Y
OS 10.99935 3.67888996063
OC 10.98084773622 3.683218011811 10.9866125 3.66615 N
OC 10.96876003937 3.66856003937 10.98661003937 3.666153051181 N
OC 10.966076771654 3.66530984252 10.9648 3.669096653543 Y
OC 10.961969980315 3.666269980315 10.964797244094 3.6691 Y
OS 10.94935 3.67888996063
OC 10.93084773622 3.683218011811 10.9366125 3.66615 N
OC 10.91876003937 3.66856003937 10.93661003937 3.666153051181 N
OC 10.916076771654 3.66530984252 10.9148 3.669096653543 Y
OC 10.911969980315 3.666269980315 10.914797244094 3.6691 Y
OS 10.89935 3.67888996063
OC 10.88084773622 3.683218011811 10.8866125 3.66615 N
OC 10.86876003937 3.66856003937 10.88661003937 3.666153051181 N
OC 10.866076771654 3.66530984252 10.8648 3.669096653543 Y
OC 10.861969980315 3.666269980315 10.864797244094 3.6691 Y
OS 10.84935 3.67888996063
OC 10.83084773622 3.683218011811 10.8366125 3.66615 N
OC 10.81876003937 3.66856003937 10.83661003937 3.666153051181 N
OC 10.816076771654 3.66530984252 10.8148 3.669096653543 Y
OC 10.811969980315 3.666269980315 10.814797244094 3.6691 Y
OS 10.79935 3.67888996063
OC 10.78084773622 3.683218011811 10.7866125 3.66615 N
OC 10.76876003937 3.66856003937 10.78661003937 3.666153051181 N
OC 10.766076771654 3.66530984252 10.7648 3.669096653543 Y
OC 10.761969980315 3.666269980315 10.764797244094 3.6691 Y
OS 10.74935 3.67888996063
OC 10.73084773622 3.683218011811 10.7366125 3.66615 N
OC 10.71876003937 3.66856003937 10.73661003937 3.666153051181 N
OC 10.716076771654 3.66530984252 10.7148 3.669096653543 Y
OC 10.711969980315 3.666269980315 10.714797244094 3.6691 Y
OS 10.69935 3.67888996063
OC 10.68084773622 3.683218011811 10.6866125 3.66615 N
OC 10.66876003937 3.66856003937 10.68661003937 3.666153051181 N
OC 10.666076771654 3.66530984252 10.6648 3.669096653543 Y
OC 10.661969980315 3.666269980315 10.664797244094 3.6691 Y
OS 10.64935 3.67888996063
OC 10.63084773622 3.683218011811 10.6366125 3.66615 N
OC 10.61876003937 3.66856003937 10.63661003937 3.666153051181 N
OC 10.616076771654 3.66530984252 10.6148 3.669096653543 Y
OC 10.611969980315 3.666269980315 10.614797244094 3.6691 Y
OE
OB 10.611969980315 3.516269980315 H
OS 10.59935 3.52888996063
OC 10.573869980315 3.50341003937 10.58661003937 3.51615 N
OS 10.591769980315 3.48551003937
OS 10.591919980315 3.48503996063
OC 10.612520866142 3.470550098425 10.611613779528 3.49115 N
OC 10.631769980315 3.4868 10.611614173228 3.49115 N
OC 10.634549901575 3.489785137795 10.635680019685 3.485945767717 Y
OC 10.6385 3.488780019685 10.635676968504 3.48595 Y
OS 10.641769980315 3.48551003937
OS 10.641919980315 3.48503996063
OC 10.662520866142 3.470550098425 10.661613779528 3.49115 N
OC 10.681769980315 3.4868 10.661614173228 3.49115 N
OC 10.684549901575 3.489785137795 10.685680019685 3.485945767717 Y
OC 10.6885 3.488780019685 10.685676968504 3.48595 Y
OS 10.691769980315 3.48551003937
OS 10.691919980315 3.48503996063
OC 10.712520866142 3.470550098425 10.711613779528 3.49115 N
OC 10.731769980315 3.4868 10.711614173228 3.49115 N
OC 10.734549901575 3.489785137795 10.735680019685 3.485945767717 Y
OC 10.7385 3.488780019685 10.735676968504 3.48595 Y
OS 10.741769980315 3.48551003937
OS 10.741919980315 3.48503996063
OC 10.762520866142 3.470550098425 10.761613779528 3.49115 N
OC 10.781769980315 3.4868 10.761614173228 3.49115 N
OC 10.784549901575 3.489785137795 10.785680019685 3.485945767717 Y
OC 10.7885 3.488780019685 10.785676968504 3.48595 Y
OS 10.791769980315 3.48551003937
OS 10.791919980315 3.48503996063
OC 10.812520866142 3.470550098425 10.811613779528 3.49115 N
OC 10.831769980315 3.4868 10.811614173228 3.49115 N
OC 10.834549901575 3.489785137795 10.835680019685 3.485945767717 Y
OC 10.8385 3.488780019685 10.835676968504 3.48595 Y
OS 10.841769980315 3.48551003937
OS 10.841919980315 3.48503996063
OC 10.862520866142 3.470550098425 10.861613779528 3.49115 N
OC 10.881769980315 3.4868 10.861614173228 3.49115 N
OC 10.884549901575 3.489785137795 10.885680019685 3.485945767717 Y
OC 10.8885 3.488780019685 10.885676968504 3.48595 Y
OS 10.891769980315 3.48551003937
OS 10.891919980315 3.48503996063
OC 10.912520866142 3.470550098425 10.911613779528 3.49115 N
OC 10.931769980315 3.4868 10.911614173228 3.49115 N
OC 10.934549901575 3.489785137795 10.935680019685 3.485945767717 Y
OC 10.9385 3.488780019685 10.935676968504 3.48595 Y
OS 10.941769980315 3.48551003937
OS 10.941919980315 3.48503996063
OC 10.962520866142 3.470550098425 10.961613779528 3.49115 N
OC 10.981769980315 3.4868 10.961614173228 3.49115 N
OC 10.984549901575 3.489785137795 10.985680019685 3.485945767717 Y
OC 10.9885 3.488780019685 10.985676968504 3.48595 Y
OS 10.991769980315 3.48551003937
OS 10.991919980315 3.48503996063
OC 11.012520866142 3.470550098425 11.011613779528 3.49115 N
OC 11.031769980315 3.4868 11.011614173228 3.49115 N
OC 11.034549901575 3.489785137795 11.035680019685 3.485945767717 Y
OC 11.0385 3.488780019685 11.035676968504 3.48595 Y
OS 11.041769980315 3.48551003937
OS 11.041919980315 3.48503996063
OC 11.067719980315 3.51083996063 11.061609940945 3.49115 N
OS 11.06725 3.51098996063
OS 11.04935 3.52888996063
OC 11.03084773622 3.533218011811 11.0366125 3.51615 N
OC 11.01876003937 3.51856003937 11.03661003937 3.516153051181 N
OC 11.016076771654 3.51530984252 11.0148 3.519096653543 Y
OC 11.011969980315 3.516269980315 11.014797244094 3.5191 Y
OS 10.99935 3.52888996063
OC 10.98084773622 3.533218011811 10.9866125 3.51615 N
OC 10.96876003937 3.51856003937 10.98661003937 3.516153051181 N
OC 10.966076771654 3.51530984252 10.9648 3.519096653543 Y
OC 10.961969980315 3.516269980315 10.964797244094 3.5191 Y
OS 10.94935 3.52888996063
OC 10.93084773622 3.533218011811 10.9366125 3.51615 N
OC 10.91876003937 3.51856003937 10.93661003937 3.516153051181 N
OC 10.916076771654 3.51530984252 10.9148 3.519096653543 Y
OC 10.911969980315 3.516269980315 10.914797244094 3.5191 Y
OS 10.89935 3.52888996063
OC 10.88084773622 3.533218011811 10.8866125 3.51615 N
OC 10.86876003937 3.51856003937 10.88661003937 3.516153051181 N
OC 10.866076771654 3.51530984252 10.8648 3.519096653543 Y
OC 10.861969980315 3.516269980315 10.864797244094 3.5191 Y
OS 10.84935 3.52888996063
OC 10.83084773622 3.533218011811 10.8366125 3.51615 N
OC 10.81876003937 3.51856003937 10.83661003937 3.516153051181 N
OC 10.816076771654 3.51530984252 10.8148 3.519096653543 Y
OC 10.811969980315 3.516269980315 10.814797244094 3.5191 Y
OS 10.79935 3.52888996063
OC 10.78084773622 3.533218011811 10.7866125 3.51615 N
OC 10.76876003937 3.51856003937 10.78661003937 3.516153051181 N
OC 10.766076771654 3.51530984252 10.7648 3.519096653543 Y
OC 10.761969980315 3.516269980315 10.764797244094 3.5191 Y
OS 10.74935 3.52888996063
OC 10.73084773622 3.533218011811 10.7366125 3.51615 N
OC 10.71876003937 3.51856003937 10.73661003937 3.516153051181 N
OC 10.716076771654 3.51530984252 10.7148 3.519096653543 Y
OC 10.711969980315 3.516269980315 10.714797244094 3.5191 Y
OS 10.69935 3.52888996063
OC 10.68084773622 3.533218011811 10.6866125 3.51615 N
OC 10.66876003937 3.51856003937 10.68661003937 3.516153051181 N
OC 10.666076771654 3.51530984252 10.6648 3.519096653543 Y
OC 10.661969980315 3.516269980315 10.664797244094 3.5191 Y
OS 10.64935 3.52888996063
OC 10.63084773622 3.533218011811 10.6366125 3.51615 N
OC 10.61876003937 3.51856003937 10.63661003937 3.516153051181 N
OC 10.616076771654 3.51530984252 10.6148 3.519096653543 Y
OC 10.611969980315 3.516269980315 10.614797244094 3.5191 Y
OE
OB 10.611969980315 3.366269980315 H
OS 10.59935 3.37888996063
OC 10.573869980315 3.35341003937 10.58661003937 3.36615 N
OS 10.591769980315 3.33551003937
OS 10.591919980315 3.33503996063
OC 10.612520866142 3.320550098425 10.611613779528 3.34115 N
OC 10.631769980315 3.3368 10.611614173228 3.34115 N
OC 10.634549901575 3.339785137795 10.635680019685 3.335945767717 Y
OC 10.6385 3.338780019685 10.635676968504 3.33595 Y
OS 10.641769980315 3.33551003937
OS 10.641919980315 3.33503996063
OC 10.662520866142 3.320550098425 10.661613779528 3.34115 N
OC 10.681769980315 3.3368 10.661614173228 3.34115 N
OC 10.684549901575 3.339785137795 10.685680019685 3.335945767717 Y
OC 10.6885 3.338780019685 10.685676968504 3.33595 Y
OS 10.691769980315 3.33551003937
OS 10.691919980315 3.33503996063
OC 10.712520866142 3.320550098425 10.711613779528 3.34115 N
OC 10.731769980315 3.3368 10.711614173228 3.34115 N
OC 10.734549901575 3.339785137795 10.735680019685 3.335945767717 Y
OC 10.7385 3.338780019685 10.735676968504 3.33595 Y
OS 10.741769980315 3.33551003937
OS 10.741919980315 3.33503996063
OC 10.762520866142 3.320550098425 10.761613779528 3.34115 N
OC 10.781769980315 3.3368 10.761614173228 3.34115 N
OC 10.784549901575 3.339785137795 10.785680019685 3.335945767717 Y
OC 10.7885 3.338780019685 10.785676968504 3.33595 Y
OS 10.791769980315 3.33551003937
OS 10.791919980315 3.33503996063
OC 10.812520866142 3.320550098425 10.811613779528 3.34115 N
OC 10.831769980315 3.3368 10.811614173228 3.34115 N
OC 10.834549901575 3.339785137795 10.835680019685 3.335945767717 Y
OC 10.8385 3.338780019685 10.835676968504 3.33595 Y
OS 10.841769980315 3.33551003937
OS 10.841919980315 3.33503996063
OC 10.862520866142 3.320550098425 10.861613779528 3.34115 N
OC 10.881769980315 3.3368 10.861614173228 3.34115 N
OC 10.884549901575 3.339785137795 10.885680019685 3.335945767717 Y
OC 10.8885 3.338780019685 10.885676968504 3.33595 Y
OS 10.891769980315 3.33551003937
OS 10.891919980315 3.33503996063
OC 10.912520866142 3.320550098425 10.911613779528 3.34115 N
OC 10.931769980315 3.3368 10.911614173228 3.34115 N
OC 10.934549901575 3.339785137795 10.935680019685 3.335945767717 Y
OC 10.9385 3.338780019685 10.935676968504 3.33595 Y
OS 10.941769980315 3.33551003937
OS 10.941919980315 3.33503996063
OC 10.962520866142 3.320550098425 10.961613779528 3.34115 N
OC 10.981769980315 3.3368 10.961614173228 3.34115 N
OC 10.984549901575 3.339785137795 10.985680019685 3.335945767717 Y
OC 10.9885 3.338780019685 10.985676968504 3.33595 Y
OS 10.991769980315 3.33551003937
OS 10.991919980315 3.33503996063
OC 11.012520866142 3.320550098425 11.011613779528 3.34115 N
OC 11.031769980315 3.3368 11.011614173228 3.34115 N
OC 11.034549901575 3.339785137795 11.035680019685 3.335945767717 Y
OC 11.0385 3.338780019685 11.035676968504 3.33595 Y
OS 11.041769980315 3.33551003937
OS 11.041919980315 3.33503996063
OC 11.067719980315 3.36083996063 11.061609940945 3.34115 N
OS 11.06725 3.36098996063
OS 11.04935 3.37888996063
OC 11.03084773622 3.383218011811 11.0366125 3.36615 N
OC 11.01876003937 3.36856003937 11.03661003937 3.366153051181 N
OC 11.016076771654 3.36530984252 11.0148 3.369096653543 Y
OC 11.011969980315 3.366269980315 11.014797244094 3.3691 Y
OS 10.99935 3.37888996063
OC 10.98084773622 3.383218011811 10.9866125 3.36615 N
OC 10.96876003937 3.36856003937 10.98661003937 3.366153051181 N
OC 10.966076771654 3.36530984252 10.9648 3.369096653543 Y
OC 10.961969980315 3.366269980315 10.964797244094 3.3691 Y
OS 10.94935 3.37888996063
OC 10.93084773622 3.383218011811 10.9366125 3.36615 N
OC 10.91876003937 3.36856003937 10.93661003937 3.366153051181 N
OC 10.916076771654 3.36530984252 10.9148 3.369096653543 Y
OC 10.911969980315 3.366269980315 10.914797244094 3.3691 Y
OS 10.89935 3.37888996063
OC 10.88084773622 3.383218011811 10.8866125 3.36615 N
OC 10.86876003937 3.36856003937 10.88661003937 3.366153051181 N
OC 10.866076771654 3.36530984252 10.8648 3.369096653543 Y
OC 10.861969980315 3.366269980315 10.864797244094 3.3691 Y
OS 10.84935 3.37888996063
OC 10.83084773622 3.383218011811 10.8366125 3.36615 N
OC 10.81876003937 3.36856003937 10.83661003937 3.366153051181 N
OC 10.816076771654 3.36530984252 10.8148 3.369096653543 Y
OC 10.811969980315 3.366269980315 10.814797244094 3.3691 Y
OS 10.79935 3.37888996063
OC 10.78084773622 3.383218011811 10.7866125 3.36615 N
OC 10.76876003937 3.36856003937 10.78661003937 3.366153051181 N
OC 10.766076771654 3.36530984252 10.7648 3.369096653543 Y
OC 10.761969980315 3.366269980315 10.764797244094 3.3691 Y
OS 10.74935 3.37888996063
OC 10.73084773622 3.383218011811 10.7366125 3.36615 N
OC 10.71876003937 3.36856003937 10.73661003937 3.366153051181 N
OC 10.716076771654 3.36530984252 10.7148 3.369096653543 Y
OC 10.711969980315 3.366269980315 10.714797244094 3.3691 Y
OS 10.69935 3.37888996063
OC 10.68084773622 3.383218011811 10.6866125 3.36615 N
OC 10.66876003937 3.36856003937 10.68661003937 3.366153051181 N
OC 10.666076771654 3.36530984252 10.6648 3.369096653543 Y
OC 10.661969980315 3.366269980315 10.664797244094 3.3691 Y
OS 10.64935 3.37888996063
OC 10.63084773622 3.383218011811 10.6366125 3.36615 N
OC 10.61876003937 3.36856003937 10.63661003937 3.366153051181 N
OC 10.616076771654 3.36530984252 10.6148 3.369096653543 Y
OC 10.611969980315 3.366269980315 10.614797244094 3.3691 Y
OE
OB 10.611969980315 3.216269980315 H
OS 10.59935 3.22888996063
OC 10.573869980315 3.20341003937 10.58661003937 3.21615 N
OS 10.591769980315 3.18551003937
OS 10.591919980315 3.18503996063
OC 10.612520866142 3.170550098425 10.611613779528 3.19115 N
OC 10.631769980315 3.1868 10.611614173228 3.19115 N
OC 10.634549901575 3.189785137795 10.635680019685 3.185945767717 Y
OC 10.6385 3.188780019685 10.635676968504 3.18595 Y
OS 10.641769980315 3.18551003937
OS 10.641919980315 3.18503996063
OC 10.662520866142 3.170550098425 10.661613779528 3.19115 N
OC 10.681769980315 3.1868 10.661614173228 3.19115 N
OC 10.684549901575 3.189785137795 10.685680019685 3.185945767717 Y
OC 10.6885 3.188780019685 10.685676968504 3.18595 Y
OS 10.691769980315 3.18551003937
OS 10.691919980315 3.18503996063
OC 10.712520866142 3.170550098425 10.711613779528 3.19115 N
OC 10.731769980315 3.1868 10.711614173228 3.19115 N
OC 10.734549901575 3.189785137795 10.735680019685 3.185945767717 Y
OC 10.7385 3.188780019685 10.735676968504 3.18595 Y
OS 10.741769980315 3.18551003937
OS 10.741919980315 3.18503996063
OC 10.762520866142 3.170550098425 10.761613779528 3.19115 N
OC 10.781769980315 3.1868 10.761614173228 3.19115 N
OC 10.784549901575 3.189785137795 10.785680019685 3.185945767717 Y
OC 10.7885 3.188780019685 10.785676968504 3.18595 Y
OS 10.791769980315 3.18551003937
OS 10.791919980315 3.18503996063
OC 10.812520866142 3.170550098425 10.811613779528 3.19115 N
OC 10.831769980315 3.1868 10.811614173228 3.19115 N
OC 10.834549901575 3.189785137795 10.835680019685 3.185945767717 Y
OC 10.8385 3.188780019685 10.835676968504 3.18595 Y
OS 10.841769980315 3.18551003937
OS 10.841919980315 3.18503996063
OC 10.862520866142 3.170550098425 10.861613779528 3.19115 N
OC 10.881769980315 3.1868 10.861614173228 3.19115 N
OC 10.884549901575 3.189785137795 10.885680019685 3.185945767717 Y
OC 10.8885 3.188780019685 10.885676968504 3.18595 Y
OS 10.891769980315 3.18551003937
OS 10.891919980315 3.18503996063
OC 10.912520866142 3.170550098425 10.911613779528 3.19115 N
OC 10.931769980315 3.1868 10.911614173228 3.19115 N
OC 10.934549901575 3.189785137795 10.935680019685 3.185945767717 Y
OC 10.9385 3.188780019685 10.935676968504 3.18595 Y
OS 10.941769980315 3.18551003937
OS 10.941919980315 3.18503996063
OC 10.962520866142 3.170550098425 10.961613779528 3.19115 N
OC 10.981769980315 3.1868 10.961614173228 3.19115 N
OC 10.984549901575 3.189785137795 10.985680019685 3.185945767717 Y
OC 10.9885 3.188780019685 10.985676968504 3.18595 Y
OS 10.991769980315 3.18551003937
OS 10.991919980315 3.18503996063
OC 11.012520866142 3.170550098425 11.011613779528 3.19115 N
OC 11.031769980315 3.1868 11.011614173228 3.19115 N
OC 11.034549901575 3.189785137795 11.035680019685 3.185945767717 Y
OC 11.0385 3.188780019685 11.035676968504 3.18595 Y
OS 11.041769980315 3.18551003937
OS 11.041919980315 3.18503996063
OC 11.067719980315 3.21083996063 11.061609940945 3.19115 N
OS 11.06725 3.21098996063
OS 11.04935 3.22888996063
OC 11.03084773622 3.233218011811 11.0366125 3.21615 N
OC 11.01876003937 3.21856003937 11.03661003937 3.216153051181 N
OC 11.016076771654 3.21530984252 11.0148 3.219096653543 Y
OC 11.011969980315 3.216269980315 11.014797244094 3.2191 Y
OS 10.99935 3.22888996063
OC 10.98084773622 3.233218011811 10.9866125 3.21615 N
OC 10.96876003937 3.21856003937 10.98661003937 3.216153051181 N
OC 10.966076771654 3.21530984252 10.9648 3.219096653543 Y
OC 10.961969980315 3.216269980315 10.964797244094 3.2191 Y
OS 10.94935 3.22888996063
OC 10.93084773622 3.233218011811 10.9366125 3.21615 N
OC 10.91876003937 3.21856003937 10.93661003937 3.216153051181 N
OC 10.916076771654 3.21530984252 10.9148 3.219096653543 Y
OC 10.911969980315 3.216269980315 10.914797244094 3.2191 Y
OS 10.89935 3.22888996063
OC 10.88084773622 3.233218011811 10.8866125 3.21615 N
OC 10.86876003937 3.21856003937 10.88661003937 3.216153051181 N
OC 10.866076771654 3.21530984252 10.8648 3.219096653543 Y
OC 10.861969980315 3.216269980315 10.864797244094 3.2191 Y
OS 10.84935 3.22888996063
OC 10.83084773622 3.233218011811 10.8366125 3.21615 N
OC 10.81876003937 3.21856003937 10.83661003937 3.216153051181 N
OC 10.816076771654 3.21530984252 10.8148 3.219096653543 Y
OC 10.811969980315 3.216269980315 10.814797244094 3.2191 Y
OS 10.79935 3.22888996063
OC 10.78084773622 3.233218011811 10.7866125 3.21615 N
OC 10.76876003937 3.21856003937 10.78661003937 3.216153051181 N
OC 10.766076771654 3.21530984252 10.7648 3.219096653543 Y
OC 10.761969980315 3.216269980315 10.764797244094 3.2191 Y
OS 10.74935 3.22888996063
OC 10.73084773622 3.233218011811 10.7366125 3.21615 N
OC 10.71876003937 3.21856003937 10.73661003937 3.216153051181 N
OC 10.716076771654 3.21530984252 10.7148 3.219096653543 Y
OC 10.711969980315 3.216269980315 10.714797244094 3.2191 Y
OS 10.69935 3.22888996063
OC 10.68084773622 3.233218011811 10.6866125 3.21615 N
OC 10.66876003937 3.21856003937 10.68661003937 3.216153051181 N
OC 10.666076771654 3.21530984252 10.6648 3.219096653543 Y
OC 10.661969980315 3.216269980315 10.664797244094 3.2191 Y
OS 10.64935 3.22888996063
OC 10.63084773622 3.233218011811 10.6366125 3.21615 N
OC 10.61876003937 3.21856003937 10.63661003937 3.216153051181 N
OC 10.616076771654 3.21530984252 10.6148 3.219096653543 Y
OC 10.611969980315 3.216269980315 10.614797244094 3.2191 Y
OE
OB 10.611969980315 3.066269980315 H
OS 10.59935 3.07888996063
OC 10.573869980315 3.05341003937 10.58661003937 3.06615 N
OS 10.591769980315 3.03551003937
OS 10.591919980315 3.03503996063
OC 10.612520866142 3.020550098425 10.611613779528 3.04115 N
OC 10.631769980315 3.0368 10.611614173228 3.04115 N
OC 10.634549901575 3.039785137795 10.635680019685 3.035945767717 Y
OC 10.6385 3.038780019685 10.635676968504 3.03595 Y
OS 10.641769980315 3.03551003937
OS 10.641919980315 3.03503996063
OC 10.662520866142 3.020550098425 10.661613779528 3.04115 N
OC 10.681769980315 3.0368 10.661614173228 3.04115 N
OC 10.684549901575 3.039785137795 10.685680019685 3.035945767717 Y
OC 10.6885 3.038780019685 10.685676968504 3.03595 Y
OS 10.691769980315 3.03551003937
OS 10.691919980315 3.03503996063
OC 10.712520866142 3.020550098425 10.711613779528 3.04115 N
OC 10.731769980315 3.0368 10.711614173228 3.04115 N
OC 10.734549901575 3.039785137795 10.735680019685 3.035945767717 Y
OC 10.7385 3.038780019685 10.735676968504 3.03595 Y
OS 10.741769980315 3.03551003937
OS 10.741919980315 3.03503996063
OC 10.762520866142 3.020550098425 10.761613779528 3.04115 N
OC 10.781769980315 3.0368 10.761614173228 3.04115 N
OC 10.784549901575 3.039785137795 10.785680019685 3.035945767717 Y
OC 10.7885 3.038780019685 10.785676968504 3.03595 Y
OS 10.791769980315 3.03551003937
OS 10.791919980315 3.03503996063
OC 10.812520866142 3.020550098425 10.811613779528 3.04115 N
OC 10.831769980315 3.0368 10.811614173228 3.04115 N
OC 10.834549901575 3.039785137795 10.835680019685 3.035945767717 Y
OC 10.8385 3.038780019685 10.835676968504 3.03595 Y
OS 10.841769980315 3.03551003937
OS 10.841919980315 3.03503996063
OC 10.862520866142 3.020550098425 10.861613779528 3.04115 N
OC 10.881769980315 3.0368 10.861614173228 3.04115 N
OC 10.884549901575 3.039785137795 10.885680019685 3.035945767717 Y
OC 10.8885 3.038780019685 10.885676968504 3.03595 Y
OS 10.891769980315 3.03551003937
OS 10.891919980315 3.03503996063
OC 10.912520866142 3.020550098425 10.911613779528 3.04115 N
OC 10.931769980315 3.0368 10.911614173228 3.04115 N
OC 10.934549901575 3.039785137795 10.935680019685 3.035945767717 Y
OC 10.9385 3.038780019685 10.935676968504 3.03595 Y
OS 10.941769980315 3.03551003937
OS 10.941919980315 3.03503996063
OC 10.962520866142 3.020550098425 10.961613779528 3.04115 N
OC 10.981769980315 3.0368 10.961614173228 3.04115 N
OC 10.984549901575 3.039785137795 10.985680019685 3.035945767717 Y
OC 10.9885 3.038780019685 10.985676968504 3.03595 Y
OS 10.991769980315 3.03551003937
OS 10.991919980315 3.03503996063
OC 11.012520866142 3.020550098425 11.011613779528 3.04115 N
OC 11.031769980315 3.0368 11.011614173228 3.04115 N
OC 11.034549901575 3.039785137795 11.035680019685 3.035945767717 Y
OC 11.0385 3.038780019685 11.035676968504 3.03595 Y
OS 11.041769980315 3.03551003937
OS 11.041919980315 3.03503996063
OC 11.067719980315 3.06083996063 11.061609940945 3.04115 N
OS 11.06725 3.06098996063
OS 11.04935 3.07888996063
OC 11.03084773622 3.083218011811 11.0366125 3.06615 N
OC 11.01876003937 3.06856003937 11.03661003937 3.066153051181 N
OC 11.016076771654 3.06530984252 11.0148 3.069096653543 Y
OC 11.011969980315 3.066269980315 11.014797244094 3.0691 Y
OS 10.99935 3.07888996063
OC 10.98084773622 3.083218011811 10.9866125 3.06615 N
OC 10.96876003937 3.06856003937 10.98661003937 3.066153051181 N
OC 10.966076771654 3.06530984252 10.9648 3.069096653543 Y
OC 10.961969980315 3.066269980315 10.964797244094 3.0691 Y
OS 10.94935 3.07888996063
OC 10.93084773622 3.083218011811 10.9366125 3.06615 N
OC 10.91876003937 3.06856003937 10.93661003937 3.066153051181 N
OC 10.916076771654 3.06530984252 10.9148 3.069096653543 Y
OC 10.911969980315 3.066269980315 10.914797244094 3.0691 Y
OS 10.89935 3.07888996063
OC 10.88084773622 3.083218011811 10.8866125 3.06615 N
OC 10.86876003937 3.06856003937 10.88661003937 3.066153051181 N
OC 10.866076771654 3.06530984252 10.8648 3.069096653543 Y
OC 10.861969980315 3.066269980315 10.864797244094 3.0691 Y
OS 10.84935 3.07888996063
OC 10.83084773622 3.083218011811 10.8366125 3.06615 N
OC 10.81876003937 3.06856003937 10.83661003937 3.066153051181 N
OC 10.816076771654 3.06530984252 10.8148 3.069096653543 Y
OC 10.811969980315 3.066269980315 10.814797244094 3.0691 Y
OS 10.79935 3.07888996063
OC 10.78084773622 3.083218011811 10.7866125 3.06615 N
OC 10.76876003937 3.06856003937 10.78661003937 3.066153051181 N
OC 10.766076771654 3.06530984252 10.7648 3.069096653543 Y
OC 10.761969980315 3.066269980315 10.764797244094 3.0691 Y
OS 10.74935 3.07888996063
OC 10.73084773622 3.083218011811 10.7366125 3.06615 N
OC 10.71876003937 3.06856003937 10.73661003937 3.066153051181 N
OC 10.716076771654 3.06530984252 10.7148 3.069096653543 Y
OC 10.711969980315 3.066269980315 10.714797244094 3.0691 Y
OS 10.69935 3.07888996063
OC 10.68084773622 3.083218011811 10.6866125 3.06615 N
OC 10.66876003937 3.06856003937 10.68661003937 3.066153051181 N
OC 10.666076771654 3.06530984252 10.6648 3.069096653543 Y
OC 10.661969980315 3.066269980315 10.664797244094 3.0691 Y
OS 10.64935 3.07888996063
OC 10.63084773622 3.083218011811 10.6366125 3.06615 N
OC 10.61876003937 3.06856003937 10.63661003937 3.066153051181 N
OC 10.616076771654 3.06530984252 10.6148 3.069096653543 Y
OC 10.611969980315 3.066269980315 10.614797244094 3.0691 Y
OE
OB 10.611969980315 2.916269980315 H
OS 10.59935 2.92888996063
OC 10.573869980315 2.90341003937 10.58661003937 2.91615 N
OS 10.591769980315 2.88551003937
OS 10.591919980315 2.88503996063
OC 10.612520866142 2.870550098425 10.611613779528 2.89115 N
OC 10.631769980315 2.8868 10.611614173228 2.89115 N
OC 10.634549901575 2.889785137795 10.635680019685 2.885945767717 Y
OC 10.6385 2.888780019685 10.635676968504 2.88595 Y
OS 10.641769980315 2.88551003937
OS 10.641919980315 2.88503996063
OC 10.662520866142 2.870550098425 10.661613779528 2.89115 N
OC 10.681769980315 2.8868 10.661614173228 2.89115 N
OC 10.684549901575 2.889785137795 10.685680019685 2.885945767717 Y
OC 10.6885 2.888780019685 10.685676968504 2.88595 Y
OS 10.691769980315 2.88551003937
OS 10.691919980315 2.88503996063
OC 10.712520866142 2.870550098425 10.711613779528 2.89115 N
OC 10.731769980315 2.8868 10.711614173228 2.89115 N
OC 10.734549901575 2.889785137795 10.735680019685 2.885945767717 Y
OC 10.7385 2.888780019685 10.735676968504 2.88595 Y
OS 10.741769980315 2.88551003937
OS 10.741919980315 2.88503996063
OC 10.762520866142 2.870550098425 10.761613779528 2.89115 N
OC 10.781769980315 2.8868 10.761614173228 2.89115 N
OC 10.784549901575 2.889785137795 10.785680019685 2.885945767717 Y
OC 10.7885 2.888780019685 10.785676968504 2.88595 Y
OS 10.791769980315 2.88551003937
OS 10.791919980315 2.88503996063
OC 10.812520866142 2.870550098425 10.811613779528 2.89115 N
OC 10.831769980315 2.8868 10.811614173228 2.89115 N
OC 10.834549901575 2.889785137795 10.835680019685 2.885945767717 Y
OC 10.8385 2.888780019685 10.835676968504 2.88595 Y
OS 10.841769980315 2.88551003937
OS 10.841919980315 2.88503996063
OC 10.862520866142 2.870550098425 10.861613779528 2.89115 N
OC 10.881769980315 2.8868 10.861614173228 2.89115 N
OC 10.884549901575 2.889785137795 10.885680019685 2.885945767717 Y
OC 10.8885 2.888780019685 10.885676968504 2.88595 Y
OS 10.891769980315 2.88551003937
OS 10.891919980315 2.88503996063
OC 10.912520866142 2.870550098425 10.911613779528 2.89115 N
OC 10.931769980315 2.8868 10.911614173228 2.89115 N
OC 10.934549901575 2.889785137795 10.935680019685 2.885945767717 Y
OC 10.9385 2.888780019685 10.935676968504 2.88595 Y
OS 10.941769980315 2.88551003937
OS 10.941919980315 2.88503996063
OC 10.962520866142 2.870550098425 10.961613779528 2.89115 N
OC 10.981769980315 2.8868 10.961614173228 2.89115 N
OC 10.984549901575 2.889785137795 10.985680019685 2.885945767717 Y
OC 10.9885 2.888780019685 10.985676968504 2.88595 Y
OS 10.991769980315 2.88551003937
OS 10.991919980315 2.88503996063
OC 11.012520866142 2.870550098425 11.011613779528 2.89115 N
OC 11.031769980315 2.8868 11.011614173228 2.89115 N
OC 11.034549901575 2.889785137795 11.035680019685 2.885945767717 Y
OC 11.0385 2.888780019685 11.035676968504 2.88595 Y
OS 11.041769980315 2.88551003937
OS 11.041919980315 2.88503996063
OC 11.067719980315 2.91083996063 11.061609940945 2.89115 N
OS 11.06725 2.91098996063
OS 11.04935 2.92888996063
OC 11.03084773622 2.933218011811 11.0366125 2.91615 N
OC 11.01876003937 2.91856003937 11.03661003937 2.916153051181 N
OC 11.016076771654 2.91530984252 11.0148 2.919096653543 Y
OC 11.011969980315 2.916269980315 11.014797244094 2.9191 Y
OS 10.99935 2.92888996063
OC 10.98084773622 2.933218011811 10.9866125 2.91615 N
OC 10.96876003937 2.91856003937 10.98661003937 2.916153051181 N
OC 10.966076771654 2.91530984252 10.9648 2.919096653543 Y
OC 10.961969980315 2.916269980315 10.964797244094 2.9191 Y
OS 10.94935 2.92888996063
OC 10.93084773622 2.933218011811 10.9366125 2.91615 N
OC 10.91876003937 2.91856003937 10.93661003937 2.916153051181 N
OC 10.916076771654 2.91530984252 10.9148 2.919096653543 Y
OC 10.911969980315 2.916269980315 10.914797244094 2.9191 Y
OS 10.89935 2.92888996063
OC 10.88084773622 2.933218011811 10.8866125 2.91615 N
OC 10.86876003937 2.91856003937 10.88661003937 2.916153051181 N
OC 10.866076771654 2.91530984252 10.8648 2.919096653543 Y
OC 10.861969980315 2.916269980315 10.864797244094 2.9191 Y
OS 10.84935 2.92888996063
OC 10.83084773622 2.933218011811 10.8366125 2.91615 N
OC 10.81876003937 2.91856003937 10.83661003937 2.916153051181 N
OC 10.816076771654 2.91530984252 10.8148 2.919096653543 Y
OC 10.811969980315 2.916269980315 10.814797244094 2.9191 Y
OS 10.79935 2.92888996063
OC 10.78084773622 2.933218011811 10.7866125 2.91615 N
OC 10.76876003937 2.91856003937 10.78661003937 2.916153051181 N
OC 10.766076771654 2.91530984252 10.7648 2.919096653543 Y
OC 10.761969980315 2.916269980315 10.764797244094 2.9191 Y
OS 10.74935 2.92888996063
OC 10.73084773622 2.933218011811 10.7366125 2.91615 N
OC 10.71876003937 2.91856003937 10.73661003937 2.916153051181 N
OC 10.716076771654 2.91530984252 10.7148 2.919096653543 Y
OC 10.711969980315 2.916269980315 10.714797244094 2.9191 Y
OS 10.69935 2.92888996063
OC 10.68084773622 2.933218011811 10.6866125 2.91615 N
OC 10.66876003937 2.91856003937 10.68661003937 2.916153051181 N
OC 10.666076771654 2.91530984252 10.6648 2.919096653543 Y
OC 10.661969980315 2.916269980315 10.664797244094 2.9191 Y
OS 10.64935 2.92888996063
OC 10.63084773622 2.933218011811 10.6366125 2.91615 N
OC 10.61876003937 2.91856003937 10.63661003937 2.916153051181 N
OC 10.616076771654 2.91530984252 10.6148 2.919096653543 Y
OC 10.611969980315 2.916269980315 10.614797244094 2.9191 Y
OE
OB 11.044130019685 4.22441003937 H
OC 11.044130019685 4.22441003937 10.836619980315 4.22441003937 N
OE
SE
P 5.05768002 2.09115 10 P 0 0;2,4=11,6=0
L 5.08268002 2.06615 5.05768002 2.09115 5 P 0 
P 5.08268002 2.06615 8 P 0 0;4=12,6=1
P 10.58661004 2.36615 8 P 0 0;4=12,6=1
L 10.61161004 2.39115 10.58661004 2.36615 5 P 0 
P 10.61161004 2.39115 10 P 0 0;2,4=11,6=0
P 9.975 2.4709 8 P 0 0;4=12,6=1
P 12.73621004 4.20866004 14 P 0 0;4=2,6=0
L 11.06161004 2.39115 11.08661004 2.36615 5 P 0 
P 11.08661004 2.36615 8 P 0 0;4=12,6=1
P 11.06161004 2.39115 10 P 0 0;2,4=11,6=0
L 5.08268002 2.11615 5.05768002 2.14115 5 P 0 
P 5.05768002 2.14115 10 P 0 0;2,4=11,6=0
P 5.08268002 2.11615 8 P 0 0;4=12,6=1
L 11.06161004 2.44115 11.08661004 2.41615 5 P 0 
P 11.08661004 2.41615 8 P 0 0;4=12,6=1
P 11.06161004 2.44115 10 P 0 0;2,4=11,6=0
P 12.73621004 2.47638002 14 P 0 0;4=2,6=0
P 10.61161004 1.99115 10 P 0 0;2,4=11,6=0
L 10.58661004 1.96615 10.61161004 1.99115 5 P 0 
P 10.58661004 1.96615 8 P 0 0;4=12,6=1
P 10.26 1.70445 8 P 0 0;4=12,6=1
L 10.96161004 2.44115 10.98661004 2.41615 5 P 0 
P 10.98661004 2.41615 8 P 0 0;4=12,6=1
P 10.96161004 2.44115 10 P 0 0;2,4=11,6=0
P 8.5 3.76615 8 P 0 0;4=12,6=1
P 8.475 3.74115 10 P 0 0;2,4=11,6=0
L 8.5 3.76615 8.475 3.74115 5 P 0 
L 9.34453002 4.97913996 9.34453002 5.00201998 2 P 0 
L 9.34453002 5.00201998 9.33826004 5.00828996 2 P 0 
L 9.33826004 5.00828996 9.33826004 5.08905 2 P 0 
L 9.33826004 5.08905 9.35271004 5.1035 2 P 0 
P 9.35271004 5.1035 8 P 0 0;4=12,6=1
P 9.34453002 4.97913996 36 P 0 0;2,4=1,6=0
P 4.95768002 2.09115 10 P 0 0;2,4=11,6=0
L 4.95768002 2.09115 4.98268002 2.06615 5 P 0 
P 4.98268002 2.06615 8 P 0 0;4=12,6=1
P 8.5 3.81615 8 P 0 0;4=12,6=1
P 8.475 3.79115 10 P 0 0;2,4=11,6=0
L 8.5 3.81615 8.475 3.79115 5 P 0 
L 9.3209 4.97913996 9.32091004 4.97915 2 P 0 
L 9.32091004 4.97915 9.32091004 5.00138002 2 P 0 
L 9.32091004 5.00138002 9.32716004 5.00763002 2 P 0 
L 9.32716004 5.00763002 9.32716004 5.08905 2 P 0 
L 9.32716004 5.08905 9.31271004 5.1035 2 P 0 
P 9.31271004 5.1035 8 P 0 0;4=12,6=1
P 9.3209 4.97913996 36 P 0 0;2,4=1,6=0
P 12.55905 2.59448996 14 P 0 0;4=2,6=0
P 11.53316004 1.572 8 P 0 0;4=12,6=1
P 4.95768002 2.14115 10 P 0 0;2,4=11,6=0
L 4.95768002 2.14115 4.98268002 2.11615 5 P 0 
P 4.98268002 2.11615 8 P 0 0;4=12,6=1
L 10.96161004 2.39115 10.98661004 2.36615 5 P 0 
P 10.98661004 2.36615 8 P 0 0;4=12,6=1
P 10.96161004 2.39115 10 P 0 0;2,4=11,6=0
P 8.5 3.61615 8 P 0 0;4=12,6=1
P 8.475 3.59115 10 P 0 0;2,4=11,6=0
L 8.5 3.61615 8.475 3.59115 5 P 0 
L 9.55711998 4.97913996 9.55711998 5.00141998 2 P 0 
L 9.55711998 5.00141998 9.55086004 5.00768002 2 P 0 
L 9.55086004 5.00768002 9.55086004 5.12555 2 P 0 
L 9.55086004 5.12555 9.56531004 5.14 2 P 0 
P 9.56531004 5.14 8 P 0 0;4=12,6=1
P 9.55711998 4.97913996 36 P 0 0;2,4=1,6=0
L 4.93268002 2.01615 4.90768002 2.04115 5 P 0 
P 4.90768002 2.04115 10 P 0 0;2,4=11,6=0
P 4.93268002 2.01615 8 P 0 0;4=12,6=1
P 11.53316004 1.412 8 P 0 0;4=12,6=1
P 12.63778996 2.39763996 14 P 0 0;4=2,6=0
P 8.5 3.66615 8 P 0 0;4=12,6=1
P 8.475 3.64115 10 P 0 0;2,4=11,6=0
L 8.5 3.66615 8.475 3.64115 5 P 0 
L 9.5335 4.97913996 9.5335 5.00196004 2 P 0 
L 9.5335 5.00196004 9.53976004 5.00821998 2 P 0 
L 9.53976004 5.00821998 9.53976004 5.12555 2 P 0 
L 9.53976004 5.12555 9.52531004 5.14 2 P 0 
P 9.52531004 5.14 8 P 0 0;4=12,6=1
P 9.5335 4.97913996 36 P 0 0;2,4=1,6=0
P 12.73621004 2.87008002 14 P 0 0;4=2,6=0
P 10.66161004 2.09115 10 P 0 0;2,4=11,6=0
L 10.66161004 2.09115 10.63661004 2.06615 5 P 0 
P 10.63661004 2.06615 8 P 0 0;4=12,6=1
P 10.225 1.96645 8 P 0 0;4=12,6=1
P 11.53316004 1.452 8 P 0 0;4=12,6=1
P 12.55905 2.43701004 14 P 0 0;4=2,6=0
P 8.35 3.66615 8 P 0 0;4=12,6=1
P 8.325 3.64115 10 P 0 0;2,4=11,6=0
L 8.35 3.66615 8.325 3.64115 5 P 0 
L 9.55711998 4.85788002 9.55711998 4.83558002 2 P 0 
L 9.55711998 4.83558002 9.55086004 4.82931998 2 P 0 
L 9.55086004 4.82931998 9.55086004 4.73418002 2 P 0 
L 9.55086004 4.73418002 9.56531004 4.71973002 2 P 0 
P 9.56531004 4.71973002 8 P 0 0;4=12,6=1
P 9.55711998 4.85788002 36 P 0 0;2,4=1,6=0
L 4.93268002 2.06615 4.90768002 2.09115 5 P 0 
P 4.90768002 2.09115 10 P 0 0;2,4=11,6=0
P 4.93268002 2.06615 8 P 0 0;4=12,6=1
P 8.35 3.71615 8 P 0 0;4=12,6=1
P 8.325 3.69115 10 P 0 0;2,4=11,6=0
L 8.35 3.71615 8.325 3.69115 5 P 0 
L 9.5335 4.85788002 9.5335 4.83503996 2 P 0 
L 9.5335 4.83503996 9.53976004 4.82878002 2 P 0 
L 9.53976004 4.82878002 9.53976004 4.73418002 2 P 0 
L 9.53976004 4.73418002 9.52531004 4.71973002 2 P 0 
P 9.52531004 4.71973002 8 P 0 0;4=12,6=1
P 9.5335 4.85788002 36 P 0 0;2,4=1,6=0
P 11.83316004 2.212 8 P 0 0;4=12,6=1
P 12.63778996 3.65748002 14 P 0 0;4=2,6=0
P 12.73621004 3.02756004 14 P 0 0;4=2,6=0
P 10.61161004 2.14115 10 P 0 0;2,4=11,6=0
L 10.61161004 2.14115 10.58661004 2.11615 5 P 0 
P 10.58661004 2.11615 8 P 0 0;4=12,6=1
P 10.09 2.05655 8 P 0 0;4=12,6=1
P 11.53316004 1.932 8 P 0 0;4=12,6=1
P 12.63778996 3.26378002 14 P 0 0;4=2,6=0
L 8.75398002 4.97913996 8.75398002 5.00243996 2 P 0 
L 8.75398002 5.00243996 8.76023996 5.0087 2 P 0 
L 8.76023996 5.0087 8.76023996 5.12555 2 P 0 
L 8.76023996 5.12555 8.74578996 5.14 2 P 0 
P 8.74578996 5.14 8 P 0 0;4=12,6=1
P 8.75398002 4.97913996 36 P 0 0;2,4=1,6=0
L 8.05 3.61615 8.025 3.59115 5 P 0 
P 8.025 3.59115 10 P 0 0;2,4=11,6=0
P 8.05 3.61615 8 P 0 0;4=12,6=1
P 12.81495 4.01181004 14 P 0 0;4=2,6=0
P 10.71161004 2.44115 10 P 0 0;2,4=11,6=0
L 10.71161004 2.44115 10.68661004 2.41615 5 P 0 
P 10.09 2.57845 8 P 0 0;4=12,6=1
P 10.68661004 2.41615 8 P 0 0;4=12,6=1
P 11.73316004 1.492 8 P 0 0;4=12,6=1
P 12.63778996 2.24016004 14 P 0 0;4=2,6=0
L 8.7776 4.97913996 8.7776 5.00193996 2 P 0 
L 8.7776 5.00193996 8.77133996 5.0082 2 P 0 
L 8.77133996 5.0082 8.77133996 5.12555 2 P 0 
L 8.77133996 5.12555 8.78578996 5.14 2 P 0 
P 8.78578996 5.14 8 P 0 0;4=12,6=1
P 8.7776 4.97913996 36 P 0 0;2,4=1,6=0
L 8.05 3.66615 8.025 3.64115 5 P 0 
P 8.025 3.64115 10 P 0 0;2,4=11,6=0
P 8.05 3.66615 8 P 0 0;4=12,6=1
P 12.73621004 2.7126 14 P 0 0;4=2,6=0
P 10.76161004 2.09115 10 P 0 0;2,4=11,6=0
L 10.76161004 2.09115 10.73661004 2.06615 5 P 0 
P 10.73661004 2.06615 8 P 0 0;4=12,6=1
P 10.26025 1.86845 8 P 0 0;4=12,6=1
L 11.01161004 2.44115 11.03661004 2.46615 5 P 0 
P 11.03661004 2.46615 8 P 0 0;4=12,6=1
P 11.01161004 2.44115 10 P 0 0;2,4=11,6=0
P 8.15 3.61615 8 P 0 0;4=12,6=1
P 8.125 3.59115 10 P 0 0;2,4=11,6=0
L 8.15 3.61615 8.125 3.59115 5 P 0 
L 8.82483996 4.97913996 8.82483996 5.0023 2 P 0 
L 8.82483996 5.0023 8.8311 5.00856004 2 P 0 
L 8.8311 5.00856004 8.8311 5.04326004 2 P 0 
L 8.8311 5.04326004 8.89886004 5.11101998 2 P 0 
L 8.89886004 5.11101998 8.89886004 5.15556998 2 P 0 
L 8.89886004 5.15556998 8.88441004 5.17001998 2 P 0 
P 8.88441004 5.17001998 8 P 0 0;4=12,6=1
P 8.82483996 4.97913996 36 P 0 0;2,4=1,6=0
P 12.55905 4.09055 14 P 0 0;4=2,6=0
P 11.53316004 2.412 8 P 0 0;4=12,6=1
L 11.01161004 2.49115 11.03661004 2.51615 5 P 0 
P 11.03661004 2.51615 8 P 0 0;4=12,6=1
P 11.01161004 2.49115 10 P 0 0;2,4=11,6=0
P 8.15 3.66615 8 P 0 0;4=12,6=1
P 8.125 3.64115 10 P 0 0;2,4=11,6=0
L 8.15 3.66615 8.125 3.64115 5 P 0 
L 8.84846004 4.97913996 8.84846004 5.00108002 2 P 0 
L 8.84846004 5.00108002 8.8422 5.00733996 2 P 0 
L 8.8422 5.00733996 8.8422 5.03866004 2 P 0 
L 8.8422 5.03866004 8.90996004 5.10641998 2 P 0 
L 8.90996004 5.10641998 8.90996004 5.15556998 2 P 0 
L 8.90996004 5.15556998 8.92441004 5.17001998 2 P 0 
P 8.92441004 5.17001998 8 P 0 0;4=12,6=1
P 8.84846004 4.97913996 36 P 0 0;2,4=1,6=0
L 0.97 5.027 0.97 5.093 5 P 0 
P 0.97 5.093 28 P 0 0;2,4=4,6=0
L 1.03 5.027 1.057 5.027 5 P 0 
P 0.97 5.027 28 P 0 0;2,4=4,6=0
L 0.97 5.027 1.03 5.027 5 P 0 
P 1.03 5.027 28 P 0 0;2,4=4,6=0
P 1.057 5.027 9 P 0 0;4=0,6=1
P 12.73621004 3.18503996 14 P 0 0;4=2,6=0
P 10.71161004 2.14115 10 P 0 0;2,4=11,6=0
L 10.71161004 2.14115 10.68661004 2.11615 5 P 0 
P 10.68661004 2.11615 8 P 0 0;4=12,6=1
P 10.09 2.17095 8 P 0 0;4=12,6=1
P 11.78316004 1.692 8 P 0 0;4=12,6=1
P 12.55905 2.04331004 14 P 0 0;4=2,6=0
P 12.81495 2.90945 14 P 0 0;4=2,6=0
P 10.66161004 2.04115 10 P 0 0;2,4=11,6=0
L 10.66161004 2.04115 10.63661004 2.01615 5 P 0 
P 10.63661004 2.01615 8 P 0 0;4=12,6=1
P 10.225 1.92645 8 P 0 0;4=12,6=1
P 11.78316004 1.652 8 P 0 0;4=12,6=1
P 12.63778996 2.08268002 14 P 0 0;4=2,6=0
L 1.122 5.417 1.094 5.417 5 P 0 
P 1.094 5.417 28 P 0 0;2,4=4,6=0
P 1.04428996 5.53641998 48 P 0 0;2,4=16,6=0
P 1.122 5.417 9 P 0 0;4=13,6=1
L 1.094 5.417 1.086 5.425 5 P 0 
L 1.086 5.425 1.086 5.45998996 5 P 0 
L 1.086 5.45998996 1.04428996 5.5017 5 P 0 
L 1.04428996 5.5017 1.04428996 5.53641998 5 P 0 
P 5.855 0.925 9 P 0 0;4=13,6=1
P 3.88 4.545 9 P 0 0;4=0,6=1
L 0.96555 5.78055 0.97 5.785 5 P 0 
L 0.97 5.785 0.97 5.823 5 P 0 
L 4.07 4.625 4.07 4.615 5 P 0 
L 4.07 4.615 4.063 4.608 5 P 0 
L 4.063 4.608 4.063 4.59 5 P 0 
L 0.96555 5.70373996 0.96555 5.78055 5 P 0 
P 0.97 5.823 28 P 0 0;2,4=4,6=0
P 0.96555 5.70373996 48 P 0 0;2,4=16,6=0
L 0.5574 5.85528002 0.5574 5.9174 5 P 0 
L 0.5574 5.9174 0.575 5.935 5 P 0 
L 0.575 5.935 0.92 5.935 5 P 0 
L 0.92 5.935 0.93 5.925 5 P 0 
L 0.93 5.925 0.93 5.835 5 P 0 
L 0.93 5.835 0.942 5.823 5 P 0 
L 0.942 5.823 0.97 5.823 5 P 0 
P 0.5574 5.85528002 40 P 0 0;2,4=27,6=0
P 0.96555 5.78055 9 P 0 0;4=0,6=1
P 4.07 4.625 9 P 0 0;4=13,6=1
P 4.063 4.59 28 P 0 0;2,4=4,6=0
L 9.91 4.433 9.91 4.543 5 P 0 
L 5.075 5.433 5.075 5.345 5 P 0 
L 5.075 5.345 5 5.27 5 P 0 
L 5 5.27 4.625 5.27 5 P 0 
L 4.625 5.27 4.535 5.36 5 P 0 
L 4.535 5.36 4.535 5.48 5 P 0 
P 10.61161004 2.74115 10 P 0 0;2,4=11,6=0
L 10.61161004 2.74115 10.58661004 2.71615 5 P 0 
P 10.58661004 2.71615 8 P 0 0;4=12,6=1
L 4.29 5.68 4.28 5.69 5 P 0 
L 4.28 5.69 4.28 5.82 5 P 0 
L 4.28 5.82 4.315 5.855 5 P 0 
L 4.315 5.855 6.555 5.855 5 P 0 
L 6.555 5.855 6.92 5.49 5 P 0 
L 6.92 5.49 9.625 5.49 5 P 0 
L 9.625 5.49 9.81 5.305 5 P 0 
L 9.81 5.305 9.81 4.605 5 P 0 
L 9.81 4.605 9.872 4.543 5 P 0 
L 9.872 4.543 9.91 4.543 5 P 0 
L 4.29 5.68 4.36323002 5.68 5 P 0 
L 4.36323002 5.48 4.305 5.48 5 P 0 
L 4.305 5.48 4.28 5.505 5 P 0 
L 4.28 5.505 4.28 5.67 5 P 0 
L 4.28 5.67 4.29 5.68 5 P 0 
P 9.91 4.543 28 P 0 0;2,4=4,6=0
P 9.91 4.433 9 P 0 0;4=0,6=1
L 4.535 5.48 4.36323002 5.48 5 P 0 
P 4.36323002 5.48 55 P 0 0;2,4=15,6=0
P 4.535 5.48 44 P 0 0;2,4=7,6=0
P 4.36323002 5.68 55 P 0 0;2,4=15,6=0
P 5.075 5.433 28 P 0 0;2,4=4,6=0
P 9.995 2.936 9 P 0 0;4=13,6=1
L 0.503 5.7 0.4727 5.7 5 P 0 
L 0.4727 5.7 0.46 5.6873 5 P 0 
L 0.46 5.6873 0.46 5.649 5 P 0 
P 0.46 5.649 11 P 0 0;3,4=6,6=1
P 0.52 5.649 29 P 0 0;2,4=23,6=0
P 0.503 5.7 28 P 0 0;2,4=4,6=0
L 0.52 5.649 0.46 5.649 5 P 0 
P 11.83316004 2.252 8 P 0 0;4=12,6=1
P 12.55905 3.61811004 14 P 0 0;4=2,6=0
L 0.52 5.76471998 0.52 5.735 5 P 0 
L 0.52 5.735 0.537 5.718 5 P 0 
L 0.537 5.718 0.537 5.7 5 P 0 
P 0.537 5.7 28 P 0 0;2,4=4,6=0
P 0.52 5.76471998 40 P 0 0;2,4=27,6=0
P 0.46 5.735 11 P 0 0;3,4=6,6=1
L 0.46 5.735 0.46 5.77433996 5 P 0 
L 0.46 5.77433996 0.46771004 5.78205 5 P 0 
L 0.46771004 5.78205 0.50795 5.78205 5 P 0 
L 0.50795 5.78205 0.52 5.77 5 P 0 
L 0.52 5.77 0.52 5.76471998 5 P 0 
L 1.32745 4.9602 1.32745 4.9869 5 P 0 
L 1.32745 4.9869 1.38906004 5.04851004 5 P 0 
L 1.38906004 5.04851004 1.38906004 5.09151004 5 P 0 
P 1.38906004 5.09151004 28 P 0 0;2,4=4,6=0
P 1.32745 4.9602 38 P 0 0;2,4=20,6=0
P 1.38906004 5.04851004 11 P 0 0;3,4=6,6=1
P 12.81495 3.06693002 14 P 0 0;4=2,6=0
P 10.61161004 2.09115 10 P 0 0;2,4=11,6=0
L 10.61161004 2.09115 10.58661004 2.06615 5 P 0 
P 10.58661004 2.06615 8 P 0 0;4=12,6=1
P 10.09 2.01655 8 P 0 0;4=12,6=1
P 8.1 3.81615 8 P 0 0;4=12,6=1
P 8.075 3.79115 10 P 0 0;2,4=11,6=0
L 8.1 3.81615 8.075 3.79115 5 P 0 
L 9.10831004 4.97913996 9.10831004 5.00178002 2 P 0 
L 9.10831004 5.00178002 9.11456004 5.00803002 2 P 0 
L 9.11456004 5.00803002 9.11456004 5.03905 2 P 0 
L 9.11456004 5.03905 9.10011004 5.0535 2 P 0 
P 9.10011004 5.0535 8 P 0 0;4=12,6=1
P 9.10831004 4.97913996 36 P 0 0;2,4=1,6=0
P 8.1 3.86615 8 P 0 0;4=12,6=1
P 8.075 3.84115 10 P 0 0;2,4=11,6=0
L 8.1 3.86615 8.075 3.84115 5 P 0 
L 9.13193002 4.97913996 9.13193002 5.00261998 2 P 0 
L 9.13193002 5.00261998 9.12566004 5.00888996 2 P 0 
L 9.12566004 5.00888996 9.12566004 5.03905 2 P 0 
L 9.12566004 5.03905 9.14011004 5.0535 2 P 0 
P 9.14011004 5.0535 8 P 0 0;4=12,6=1
P 9.13193002 4.97913996 36 P 0 0;2,4=1,6=0
L 3.9599 5.35898996 3.9599 5.395 5 P 0 
P 3.9599 5.35898996 28 P 0 0;2,4=4,6=0
P 3.9599 5.395 9 P 0 0;4=0,6=1
L 0.88681004 5.78181004 0.89 5.785 5 P 0 
L 0.89 5.785 0.89 5.823 5 P 0 
L 0.88681004 5.70373996 0.88681004 5.78181004 5 P 0 
P 0.89 5.823 28 P 0 0;2,4=4,6=0
P 0.88681004 5.70373996 48 P 0 0;2,4=16,6=0
P 0.88681004 5.78181004 9 P 0 0;4=13,6=1
P 12.73621004 2.3189 14 P 0 0;4=2,6=0
P 10.66161004 1.94115 10 P 0 0;2,4=11,6=0
L 10.66161004 1.94115 10.63661004 1.91615 5 P 0 
P 10.63661004 1.91615 8 P 0 0;4=12,6=1
P 10.38371998 1.49328002 8 P 0 0;4=12,6=1
L 8.35 3.81615 8.325 3.79115 5 P 0 
P 8.325 3.79115 10 P 0 0;2,4=11,6=0
P 8.35 3.81615 8 P 0 0;4=12,6=1
L 9.27366004 4.97913996 9.27366004 5.00216004 2 P 0 
L 9.27366004 5.00216004 9.2674 5.00841998 2 P 0 
L 9.2674 5.00841998 9.2674 5.20556998 2 P 0 
L 9.2674 5.20556998 9.28185 5.22001998 2 P 0 
P 9.28185 5.22001998 8 P 0 0;4=12,6=1
P 9.27366004 4.97913996 36 P 0 0;2,4=1,6=0
L 0.72933002 5.463 0.72933002 5.46066998 5 P 0 
L 0.72933002 5.46066998 0.755 5.435 5 P 0 
L 0.755 5.435 0.755 5.417 5 P 0 
L 0.72933002 5.53641998 0.72933002 5.463 5 P 0 
P 0.755 5.417 28 P 0 0;2,4=4,6=0
P 0.72933002 5.53641998 48 P 0 0;2,4=16,6=0
L 0.755 5.417 0.705 5.417 5 P 0 
P 0.705 5.417 28 P 0 0;2,4=4,6=0
P 0.72933002 5.463 9 P 0 0;4=0,6=1
P 11.53316004 2.572 8 P 0 0;4=12,6=1
P 12.55905 4.56298996 14 P 0 0;4=2,6=0
L 8.35 3.86615 8.325 3.84115 5 P 0 
P 8.325 3.84115 10 P 0 0;2,4=11,6=0
P 8.35 3.86615 8 P 0 0;4=12,6=1
L 9.25003996 4.97913996 9.25003996 5.00221998 2 P 0 
L 9.25003996 5.00221998 9.2563 5.00848002 2 P 0 
L 9.2563 5.00848002 9.2563 5.20556998 2 P 0 
L 9.2563 5.20556998 9.24185 5.22001998 2 P 0 
P 9.24185 5.22001998 8 P 0 0;4=12,6=1
P 9.25003996 4.97913996 36 P 0 0;2,4=1,6=0
L 4.435 5.595 4.435 5.765 5 P 0 
L 4.435 5.765 4.42 5.78 5 P 0 
L 4.42 5.78 4.36323002 5.78 5 P 0 
L 5.03 5.4 5.03 5.35 5 P 0 
L 5.03 5.35 4.98 5.3 5 P 0 
L 4.98 5.3 4.655 5.3 5 P 0 
L 4.655 5.3 4.585 5.37 5 P 0 
L 4.585 5.37 4.585 5.48 5 P 0 
P 4.125 2.682 9 P 0 0;4=13,6=1
P 3.62 4.483 28 P 0 0;2,4=4,6=0
P 3.94 4.42 9 P 0 0;4=0,6=1
L 5.03 5.4 5.025 5.405 5 P 0 
L 5.025 5.405 5.025 5.433 5 P 0 
P 4.36323002 5.58 55 P 0 0;2,4=15,6=0
P 4.36323002 5.78 55 P 0 0;2,4=15,6=0
P 4.585 5.48 44 P 0 0;2,4=7,6=0
P 5.025 5.433 28 P 0 0;2,4=4,6=0
P 5.03 5.4 9 P 0 0;4=13,6=1
P 4.60768002 2.74115 10 P 0 0;2,4=11,6=0
L 4.60768002 2.74115 4.58268002 2.71615 5 P 0 
P 4.58268002 2.71615 8 P 0 0;4=12,6=1
L 4.36323002 5.58 4.42 5.58 5 P 0 
L 4.42 5.58 4.435 5.595 5 P 0 
L 4.435 5.595 4.57 5.595 5 P 0 
L 4.57 5.595 4.585 5.58 5 P 0 
L 4.585 5.58 4.585 5.48 5 P 0 
L 3.94 4.42 3.935 4.415 5 P 0 
L 3.935 4.415 3.64 4.415 5 P 0 
L 3.64 4.415 3.62 4.435 5 P 0 
L 3.62 4.435 3.62 4.483 5 P 0 
P 8.45 3.81615 8 P 0 0;4=12,6=1
P 8.425 3.79115 10 P 0 0;2,4=11,6=0
L 8.45 3.81615 8.425 3.79115 5 P 0 
L 9.20278996 4.85788002 9.20278996 4.83523996 2 P 0 
L 9.20278996 4.83523996 9.19653002 4.82898002 2 P 0 
L 9.19653002 4.82898002 9.19653002 4.79736998 2 P 0 
L 9.19653002 4.79736998 9.21098002 4.78291998 2 P 0 
P 9.21098002 4.78291998 8 P 0 0;4=12,6=1
P 9.20278996 4.85788002 36 P 0 0;2,4=1,6=0
P 8.45 3.86615 8 P 0 0;4=12,6=1
P 8.425 3.84115 10 P 0 0;2,4=11,6=0
L 8.45 3.86615 8.425 3.84115 5 P 0 
L 9.17916998 4.85788002 9.17916998 4.83536004 2 P 0 
L 9.17916998 4.83536004 9.18543002 4.8291 2 P 0 
L 9.18543002 4.8291 9.18543002 4.79736998 2 P 0 
L 9.18543002 4.79736998 9.17098002 4.78291998 2 P 0 
P 9.17098002 4.78291998 8 P 0 0;4=12,6=1
P 9.17916998 4.85788002 36 P 0 0;2,4=1,6=0
P 3.75998996 0.2711 28 P 0 0;2,4=4,6=0
P 3.75998996 0.24001004 9 P 0 0;4=0,6=1
L 3.75998996 0.2711 3.75998996 0.24001004 7 P 0 
P 9.55795 0.29243002 28 P 0 0;2,4=4,6=0
P 9.55795 0.26133996 9 P 0 0;4=0,6=1
L 9.55795 0.29243002 9.55795 0.26133996 7 P 0 
L 3.71203002 0.77535 3.69591998 0.77535 7 P 0 
L 3.69591998 0.77535 3.69566998 0.7751 7 P 0 
L 3.69566998 0.7751 3.66998996 0.7751 7 P 0 
P 3.60998996 0.7751 28 P 0 0;2,4=4,6=0
L 3.66998996 0.7751 3.60998996 0.7751 7 P 0 
P 3.66998996 0.7751 28 P 0 0;2,4=4,6=0
P 3.71203002 0.77535 9 P 0 0;4=13,6=1
L 3.70998996 0.62931998 3.70998996 0.7 9 P 0 
P 3.70998996 0.62931998 43 P 0 0;2,4=28,6=0
P 3.70998996 0.7 9 P 0 0;4=13,6=1
P 9.50795 0.65065 43 P 0 0;2,4=28,6=0
L 9.50795 0.65065 9.50795 0.72133002 9 P 0 
P 9.50795 0.72133002 9 P 0 0;4=13,6=1
P 9.46795 0.82631998 9 P 0 0;4=13,6=1
L 9.46795 0.79643002 9.46795 0.82631998 7 P 0 
P 9.40795 0.79643002 28 P 0 0;2,4=4,6=0
P 9.46795 0.79643002 28 P 0 0;2,4=4,6=0
L 9.40795 0.79643002 9.46795 0.79643002 7 P 0 
P 4.02893002 2.59336998 9 P 0 0;4=13,6=1
P 11.395 2.725 9 P 0 0;4=0,6=1
P 11.395 2.8 9 P 0 0;4=13,6=1
P 11.58613002 2.905 9 P 0 0;4=13,6=1
P 11.58613002 2.785 9 P 0 0;4=13,6=1
P 1.33906004 4.60351004 9 P 0 0;4=0,6=1
L 1.33906004 4.63151004 1.33906004 4.60351004 7 P 0 
P 1.28906004 4.63151004 28 P 0 0;2,4=4,6=0
P 1.33906004 4.63151004 28 P 0 0;2,4=4,6=0
L 1.28906004 4.63151004 1.33906004 4.63151004 7 P 0 
L 3.67 4.483 3.67 4.45 7 P 0 
P 3.67 4.483 28 P 0 0;2,4=4,6=0
P 3.67 4.45 9 P 0 0;4=13,6=1
L 3.72 4.545 3.72 4.555 7 P 0 
L 3.72 4.555 3.69558996 4.57941004 7 P 0 
L 3.69558996 4.57941004 3.69558996 4.58965 7 P 0 
L 3.72 4.517 3.72 4.545 7 P 0 
P 3.72 4.517 28 P 0 0;2,4=4,6=0
P 3.69558996 4.58965 37 P 0 0;2,4=8,6=0
P 3.72 4.545 9 P 0 0;4=13,6=1
L 7.2926 4.63151004 7.3426 4.63151004 7 P 0 
P 7.3426 4.63151004 28 P 0 0;2,4=4,6=0
P 7.2926 4.63151004 28 P 0 0;2,4=4,6=0
P 5.37968996 2.8 9 P 0 0;4=13,6=1
P 5.387 2.725 9 P 0 0;4=0,6=1
P 5.5822 2.785 9 P 0 0;4=13,6=1
P 5.5822 2.905 9 P 0 0;4=13,6=1
P 7.2426 4.69351004 9 P 0 0;4=13,6=1
P 7.25421004 4.79681998 38 P 0 0;2,4=20,6=0
P 7.2426 4.66551004 28 P 0 0;2,4=4,6=0
L 7.2426 4.66551004 7.2426 4.69351004 7 P 0 
L 7.2426 4.69351004 7.2426 4.75851004 7 P 0 
L 7.2426 4.75851004 7.25421004 4.77011998 7 P 0 
L 7.25421004 4.77011998 7.25421004 4.79681998 7 P 0 
L 7.2926 4.63151004 7.2926 4.60351004 7 P 0 
P 7.2926 4.60351004 9 P 0 0;4=13,6=1
L 9.98 4.543 9.98 4.51 7 P 0 
P 9.98 4.543 28 P 0 0;2,4=4,6=0
P 9.98 4.51 9 P 0 0;4=13,6=1
P 10.07286004 2.82336998 9 P 0 0;4=13,6=1
L 10.03 4.61 10.02558996 4.61441004 7 P 0 
L 10.02558996 4.61441004 10.02558996 4.64965 7 P 0 
L 10.03 4.577 10.03 4.61 7 P 0 
P 10.03 4.577 28 P 0 0;2,4=4,6=0
P 10.02558996 4.64965 37 P 0 0;2,4=8,6=0
P 10.03 4.61 9 P 0 0;4=13,6=1
P 1.23906004 4.66551004 28 P 0 0;2,4=4,6=0
P 1.23906004 4.69351004 9 P 0 0;4=13,6=1
P 1.25066998 4.79681998 38 P 0 0;2,4=20,6=0
L 1.23906004 4.69351004 1.23906004 4.75851004 7 P 0 
L 1.23906004 4.75851004 1.25066998 4.77011998 7 P 0 
L 1.25066998 4.77011998 1.25066998 4.79681998 7 P 0 
L 1.23906004 4.66551004 1.23906004 4.69351004 7 P 0 
L 3.89 4.683 3.89 4.655 7 P 0 
P 3.89 4.683 28 P 0 0;2,4=4,6=0
P 3.89 4.655 9 P 0 0;4=13,6=1
L 3.9899 4.79498996 3.9899 4.765 7 P 0 
L 3.9899 4.79498996 4.0399 4.79498996 7 P 0 
P 4.0399 4.79498996 28 P 0 0;2,4=4,6=0
P 3.9899 4.79498996 28 P 0 0;2,4=4,6=0
P 3.9899 4.765 9 P 0 0;4=13,6=1
L 4.1049 4.86 4.1049 4.82898996 7 P 0 
P 4.03666998 4.96076998 38 P 0 0;2,4=20,6=0
P 4.1049 4.82898996 28 P 0 0;2,4=4,6=0
P 4.1049 4.86 9 P 0 0;4=13,6=1
L 4.03666998 4.96076998 4.03666998 4.94333002 7 P 0 
L 4.03666998 4.94333002 4.1049 4.8751 7 P 0 
L 4.1049 4.8751 4.1049 4.86 7 P 0 
L 4.0599 5.35898996 4.0599 5.395 7 P 0 
L 4.0099 5.35898996 4.0599 5.35898996 7 P 0 
P 4.0599 5.35898996 28 P 0 0;2,4=4,6=0
P 4.0099 5.35898996 28 P 0 0;2,4=4,6=0
P 4.0599 5.395 9 P 0 0;4=13,6=1
L 3.91 5.477 3.91 5.51 7 P 0 
P 3.91 5.477 28 P 0 0;2,4=4,6=0
P 3.91 5.51 9 P 0 0;4=13,6=1
L 5.125 5.433 5.125 5.4 7 P 0 
P 5.125 5.433 28 P 0 0;2,4=4,6=0
P 5.125 5.4 9 P 0 0;4=13,6=1
S P 0
OB 1.334 5.645 I
OS 1.329 5.65
OS 1.329 5.766
OS 1.293 5.802
OS 1.293 5.831
OS 1.295 5.833
OS 1.466 5.833
OS 1.474 5.825
OS 1.474 5.669
OS 1.460819980315 5.655819980315
OC 1.453225590551 5.65120246063 1.477355610236 5.620069980315 N
OC 1.44686003937 5.645 1.477355905512 5.620069980315 N
OS 1.334 5.645
OE
SE
P 1.43798996 5.70373996 48 P 0 0;2,4=16,6=0
P 1.35925 5.70373996 48 P 0 0;2,4=16,6=0
P 1.37925 5.78 9 P 0 0;4=13,6=1
P 1.45798996 5.78 9 P 0 0;4=13,6=1
P 1.355 5.823 28 P 0 0;2,4=4,6=0
P 1.455 5.823 28 P 0 0;2,4=4,6=0
P 1.305 5.823 28 P 0 0;2,4=4,6=0
P 1.405 5.823 28 P 0 0;2,4=4,6=0
P 1.42 5.78 9 P 0 0;4=13,6=1
P 1.335 5.78 9 P 0 0;4=13,6=1
P 12.63778996 2.55511998 14 P 0 0;4=2,6=0
P 11.53316004 1.612 8 P 0 0;4=12,6=1
P 8.4 3.76615 8 P 0 0;4=12,6=1
P 8.375 3.74115 10 P 0 0;2,4=11,6=0
L 8.4 3.76615 8.375 3.74115 5 P 0 
L 9.27366004 4.85788002 9.27366004 4.83551998 2 P 0 
L 9.27366004 4.83551998 9.2674 4.82926004 2 P 0 
L 9.2674 4.82926004 9.2674 4.65645 2 P 0 
L 9.2674 4.65645 9.28185 4.642 2 P 0 
P 9.28185 4.642 8 P 0 0;4=12,6=1
P 9.27366004 4.85788002 36 P 0 0;2,4=1,6=0
P 12.73621004 4.36613996 14 P 0 0;4=2,6=0
P 10.66161004 2.44115 10 P 0 0;2,4=11,6=0
L 10.66161004 2.44115 10.63661004 2.41615 5 P 0 
P 10.63661004 2.41615 8 P 0 0;4=12,6=1
P 9.975 2.66445 8 P 0 0;4=12,6=1
P 8.4 3.81615 8 P 0 0;4=12,6=1
P 8.375 3.79115 10 P 0 0;2,4=11,6=0
L 8.4 3.81615 8.375 3.79115 5 P 0 
L 9.25003996 4.85788002 9.25003996 4.8361 2 P 0 
L 9.25003996 4.8361 9.2563 4.82983996 2 P 0 
L 9.2563 4.82983996 9.2563 4.65645 2 P 0 
L 9.2563 4.65645 9.24185 4.642 2 P 0 
P 9.24185 4.642 8 P 0 0;4=12,6=1
P 9.25003996 4.85788002 36 P 0 0;2,4=1,6=0
P 11.53316004 2.532 8 P 0 0;4=12,6=1
P 12.63778996 4.60236998 14 P 0 0;4=2,6=0
P 8.45 3.66615 8 P 0 0;4=12,6=1
P 8.425 3.64115 10 P 0 0;2,4=11,6=0
L 8.45 3.66615 8.425 3.64115 5 P 0 
L 9.41538996 4.85788002 9.41538996 4.83583996 2 P 0 
L 9.41538996 4.83583996 9.40913002 4.82958002 2 P 0 
L 9.40913002 4.82958002 9.40913002 4.79736998 2 P 0 
L 9.40913002 4.79736998 9.42358002 4.78291998 2 P 0 
P 9.42358002 4.78291998 8 P 0 0;4=12,6=1
P 9.41538996 4.85788002 36 P 0 0;2,4=1,6=0
L 0.95951004 5.4595 0.96555 5.46553996 5 P 0 
L 0.96555 5.46553996 0.96555 5.53641998 5 P 0 
L 0.948 5.417 0.948 5.44798996 5 P 0 
L 0.948 5.44798996 0.95951004 5.4595 5 P 0 
P 0.96555 5.53641998 48 P 0 0;2,4=16,6=0
P 0.948 5.417 28 P 0 0;2,4=4,6=0
L 0.948 5.417 0.996 5.417 5 P 0 
P 0.996 5.417 28 P 0 0;2,4=4,6=0
P 0.95951004 5.4595 9 P 0 0;4=0,6=1
P 8.45 3.71615 8 P 0 0;4=12,6=1
P 8.425 3.69115 10 P 0 0;2,4=11,6=0
L 8.45 3.71615 8.425 3.69115 5 P 0 
L 9.39176998 4.85788002 9.39176998 4.83576004 2 P 0 
L 9.39176998 4.83576004 9.39803002 4.8295 2 P 0 
L 9.39803002 4.8295 9.39803002 4.79736998 2 P 0 
L 9.39803002 4.79736998 9.38358002 4.78291998 2 P 0 
P 9.38358002 4.78291998 8 P 0 0;4=12,6=1
P 9.39176998 4.85788002 36 P 0 0;2,4=1,6=0
P 8.4 3.61615 8 P 0 0;4=12,6=1
P 8.375 3.59115 10 P 0 0;2,4=11,6=0
L 8.4 3.61615 8.375 3.59115 5 P 0 
L 9.48626004 4.85788002 9.48626004 4.83571998 2 P 0 
L 9.48626004 4.83571998 9.48 4.82946004 2 P 0 
L 9.48 4.82946004 9.48 4.60145 2 P 0 
L 9.48 4.60145 9.49445 4.587 2 P 0 
P 9.49445 4.587 8 P 0 0;4=12,6=1
P 9.48626004 4.85788002 36 P 0 0;2,4=1,6=0
P 8.4 3.66615 8 P 0 0;4=12,6=1
P 8.375 3.64115 10 P 0 0;2,4=11,6=0
L 8.4 3.66615 8.375 3.64115 5 P 0 
L 9.46263996 4.85788002 9.46263996 4.8359 2 P 0 
L 9.46263996 4.8359 9.4689 4.82963996 2 P 0 
L 9.4689 4.82963996 9.4689 4.60145 2 P 0 
L 9.4689 4.60145 9.45445 4.587 2 P 0 
P 9.45445 4.587 8 P 0 0;4=12,6=1
P 9.46263996 4.85788002 36 P 0 0;2,4=1,6=0
L 9.07353996 4.42 9.07353996 4.50588996 5 P 0 
L 9.07353996 4.50588996 9.12283996 4.55518996 5 P 0 
L 9.12283996 4.55518996 9.12283996 4.70681004 5 P 0 
L 9.12283996 4.70681004 9.107 4.72265 5 P 0 
L 9.107 4.72265 9.107 4.826 5 P 0 
L 9.107 4.826 9.10831004 4.82731004 5 P 0 
L 9.10831004 4.82731004 9.10831004 4.85788002 5 P 0 
P 9.07353996 4.42 9 P 0 0;4=13,6=1
P 7.1926 5.15351004 9 P 0 0;4=0,6=1
P 7.1926 5.12551004 28 P 0 0;2,4=4,6=0
L 7.1926 5.12551004 7.1926 5.15351004 5 P 0 
P 9.10831004 4.85788002 36 P 0 0;2,4=1,6=0
P 8.1 3.66615 8 P 0 0;4=12,6=1
P 8.075 3.64115 10 P 0 0;2,4=11,6=0
L 8.1 3.66615 8.075 3.64115 5 P 0 
L 8.75398002 4.85788002 8.75398002 4.8361 2 P 0 
L 8.75398002 4.8361 8.76023996 4.82983996 2 P 0 
L 8.76023996 4.82983996 8.76023996 4.68145 2 P 0 
L 8.76023996 4.68145 8.74578996 4.667 2 P 0 
P 8.74578996 4.667 8 P 0 0;4=12,6=1
P 8.75398002 4.85788002 36 P 0 0;2,4=1,6=0
P 8.1 3.71615 8 P 0 0;4=12,6=1
P 8.075 3.69115 10 P 0 0;2,4=11,6=0
L 8.1 3.71615 8.075 3.69115 5 P 0 
L 8.7776 4.85788002 8.7776 4.83551998 2 P 0 
L 8.7776 4.83551998 8.77133996 4.82926004 2 P 0 
L 8.77133996 4.82926004 8.77133996 4.68145 2 P 0 
L 8.77133996 4.68145 8.78578996 4.667 2 P 0 
P 8.78578996 4.667 8 P 0 0;4=12,6=1
P 8.7776 4.85788002 36 P 0 0;2,4=1,6=0
P 8.2 3.66615 8 P 0 0;4=12,6=1
P 8.175 3.64115 10 P 0 0;2,4=11,6=0
L 8.2 3.66615 8.175 3.64115 5 P 0 
L 8.82483996 4.85788002 8.82483996 4.8347 2 P 0 
L 8.82483996 4.8347 8.8311 4.82843996 2 P 0 
L 8.8311 4.82843996 8.8311 4.79736998 2 P 0 
L 8.8311 4.79736998 8.81665 4.78291998 2 P 0 
P 8.81665 4.78291998 8 P 0 0;4=12,6=1
P 8.82483996 4.85788002 36 P 0 0;2,4=1,6=0
P 8.2 3.71615 8 P 0 0;4=12,6=1
P 8.175 3.69115 10 P 0 0;2,4=11,6=0
L 8.2 3.71615 8.175 3.69115 5 P 0 
L 8.84846004 4.85788002 8.84846004 4.83591998 2 P 0 
L 8.84846004 4.83591998 8.8422 4.82966004 2 P 0 
L 8.8422 4.82966004 8.8422 4.79736998 2 P 0 
L 8.8422 4.79736998 8.85665 4.78291998 2 P 0 
P 8.85665 4.78291998 8 P 0 0;4=12,6=1
P 8.84846004 4.85788002 36 P 0 0;2,4=1,6=0
P 8.05 3.76615 8 P 0 0;4=12,6=1
P 8.025 3.74115 10 P 0 0;2,4=11,6=0
L 8.05 3.76615 8.025 3.74115 5 P 0 
L 8.96656998 4.85788002 8.96656998 4.83498002 2 P 0 
L 8.96656998 4.83498002 8.97283002 4.82871998 2 P 0 
L 8.97283002 4.82871998 8.97283002 4.78998002 2 P 0 
L 8.97283002 4.78998002 8.90506998 4.72221998 2 P 0 
L 8.90506998 4.72221998 8.90506998 4.68145 2 P 0 
L 8.90506998 4.68145 8.89061998 4.667 2 P 0 
P 8.89061998 4.667 8 P 0 0;4=12,6=1
P 8.96656998 4.85788002 36 P 0 0;2,4=1,6=0
P 8.05 3.81615 8 P 0 0;4=12,6=1
P 8.025 3.79115 10 P 0 0;2,4=11,6=0
L 8.05 3.81615 8.025 3.79115 5 P 0 
L 8.9902 4.85788002 8.9902 4.83566004 2 P 0 
L 8.9902 4.83566004 8.98393002 4.82938996 2 P 0 
L 8.98393002 4.82938996 8.98393002 4.78538002 2 P 0 
L 8.98393002 4.78538002 8.91616998 4.71761998 2 P 0 
L 8.91616998 4.71761998 8.91616998 4.68145 2 P 0 
L 8.91616998 4.68145 8.93061998 4.667 2 P 0 
P 8.93061998 4.667 8 P 0 0;4=12,6=1
P 8.9902 4.85788002 36 P 0 0;2,4=1,6=0
L 9.03743996 4.85788002 9.03743996 4.8361 2 P 0 
L 9.03743996 4.8361 9.0437 4.82983996 2 P 0 
L 9.0437 4.82983996 9.0437 4.68145 2 P 0 
L 9.0437 4.68145 9.02925 4.667 2 P 0 
P 9.02925 4.667 8 P 0 0;4=12,6=1
P 9.03743996 4.85788002 36 P 0 0;2,4=1,6=0
L 8.2 3.81615 8.175 3.79115 5 P 0 
P 8.175 3.79115 10 P 0 0;2,4=11,6=0
P 8.2 3.81615 8 P 0 0;4=12,6=1
L 9.06106004 4.85788002 9.06106004 4.83551998 2 P 0 
L 9.06106004 4.83551998 9.0548 4.82926004 2 P 0 
L 9.0548 4.82926004 9.0548 4.68145 2 P 0 
L 9.0548 4.68145 9.06925 4.667 2 P 0 
P 9.06925 4.667 8 P 0 0;4=12,6=1
P 9.06106004 4.85788002 36 P 0 0;2,4=1,6=0
L 8.2 3.86615 8.175 3.84115 5 P 0 
P 8.175 3.84115 10 P 0 0;2,4=11,6=0
P 8.2 3.86615 8 P 0 0;4=12,6=1
P 4.70768002 2.74115 10 P 0 0;2,4=11,6=0
L 4.70768002 2.74115 4.68268002 2.71615 5 P 0 
P 4.68268002 2.71615 8 P 0 0;4=12,6=1
L 0.91 5.19 0.91 5.233 5 P 0 
L 0.91 5.147 0.91 5.19 5 P 0 
P 0.91 5.233 28 P 0 0;2,4=4,6=0
L 1.02558996 5.29035 1.02558996 5.25558996 5 P 0 
L 1.02558996 5.25558996 1.015 5.245 5 P 0 
L 1.015 5.245 0.95 5.245 5 P 0 
L 0.95 5.245 0.938 5.233 5 P 0 
L 0.938 5.233 0.91 5.233 5 P 0 
P 1.02558996 5.29035 37 P 0 0;2,4=8,6=0
P 0.91 5.147 28 P 0 0;2,4=4,6=0
P 0.91 5.19 11 P 0 0;3,4=6,6=1
P 4.95768002 2.74115 10 P 0 0;2,4=11,6=0
L 4.95768002 2.74115 4.98268002 2.71615 5 P 0 
P 4.98268002 2.71615 8 P 0 0;4=12,6=1
P 2.12106004 2.49115 10 P 0 0;2,4=11,6=0
L 2.12106004 2.49115 2.14606004 2.51615 5 P 0 
P 2.14606004 2.51615 8 P 0 0;4=12,6=1
L 8.45 3.41615 8.425 3.39115 5 P 0 
P 8.425 3.39115 10 P 0 0;2,4=11,6=0
P 8.45 3.41615 8 P 0 0;4=12,6=1
P 8.17993002 4.97913996 36 P 0 0;2,4=1,6=0
P 8.18811004 5.0535 8 P 0 0;4=12,6=1
L 8.17993002 4.97913996 8.17993002 5.00161998 2 P 0 
L 8.17993002 5.00161998 8.17366004 5.00788996 2 P 0 
L 8.17366004 5.00788996 8.17366004 5.03905 2 P 0 
L 8.17366004 5.03905 8.18811004 5.0535 2 P 0 
P 5.05768002 3.79115 10 P 0 0;2,4=11,6=0
L 5.05768002 3.79115 5.03268002 3.81615 5 P 0 
P 5.03268002 3.81615 8 P 0 0;4=12,6=1
P 4.07408002 4.01978996 9 P 0 0;4=0,6=1
L 8.45 3.46615 8.425 3.44115 5 P 0 
P 8.425 3.44115 10 P 0 0;2,4=11,6=0
P 8.45 3.46615 8 P 0 0;4=12,6=1
P 8.1563 4.97913996 36 P 0 0;2,4=1,6=0
P 8.14811004 5.0535 8 P 0 0;4=12,6=1
L 8.1563 4.97913996 8.15631004 4.97915 2 P 0 
L 8.15631004 4.97915 8.15631004 5.00078002 2 P 0 
L 8.15631004 5.00078002 8.16256004 5.00703002 2 P 0 
L 8.16256004 5.00703002 8.16256004 5.03905 2 P 0 
L 8.16256004 5.03905 8.14811004 5.0535 2 P 0 
P 5.00768002 2.19115 10 P 0 0;2,4=11,6=0
L 5.00768002 2.19115 5.03268002 2.16615 5 P 0 
P 5.03268002 2.16615 8 P 0 0;4=12,6=1
L 3.9099 5.395 3.9099 5.4429 5 P 0 
L 3.9099 5.4429 3.91 5.443 5 P 0 
L 3.9099 5.35898996 3.9099 5.395 5 P 0 
P 3.91 5.443 28 P 0 0;2,4=4,6=0
P 3.9099 5.35898996 28 P 0 0;2,4=4,6=0
P 3.9099 5.395 9 P 0 0;4=0,6=1
P 8.45 3.26615 8 P 0 0;4=12,6=1
P 8.425 3.24115 10 P 0 0;2,4=11,6=0
L 8.45 3.26615 8.425 3.24115 5 P 0 
P 8.39251998 4.97913996 36 P 0 0;2,4=1,6=0
P 8.40071004 5.115 8 P 0 0;4=12,6=1
L 8.39251998 4.97913996 8.39251998 5.00201998 2 P 0 
L 8.39251998 5.00201998 8.38626004 5.00828002 2 P 0 
L 8.38626004 5.00828002 8.38626004 5.10055 2 P 0 
L 8.38626004 5.10055 8.40071004 5.115 2 P 0 
L 0.91 5.267 0.867 5.267 5 P 0 
L 0.867 5.267 0.84953002 5.24953002 5 P 0 
L 0.84953002 5.24953002 0.84953002 5.2361 5 P 0 
P 0.84953002 5.2361 35 P 0 0;2,4=10,6=0
P 0.91 5.267 28 P 0 0;2,4=4,6=0
L 0.91 5.267 0.91 5.31 5 P 0 
P 0.91 5.31 11 P 0 0;3,4=6,6=1
P 8.45 3.31615 8 P 0 0;4=12,6=1
P 8.425 3.29115 10 P 0 0;2,4=11,6=0
L 8.45 3.31615 8.425 3.29115 5 P 0 
P 8.3689 4.97913996 36 P 0 0;2,4=1,6=0
P 8.36071004 5.115 8 P 0 0;4=12,6=1
L 8.3689 4.97913996 8.3689 5.00236004 2 P 0 
L 8.3689 5.00236004 8.37516004 5.00861998 2 P 0 
L 8.37516004 5.00861998 8.37516004 5.10055 2 P 0 
L 8.37516004 5.10055 8.36071004 5.115 2 P 0 
L 8.35 3.26615 8.325 3.24115 5 P 0 
P 8.325 3.24115 10 P 0 0;2,4=11,6=0
P 8.35 3.26615 8 P 0 0;4=12,6=1
P 8.39251998 4.85788002 36 P 0 0;2,4=1,6=0
P 8.40071004 4.742 8 P 0 0;4=12,6=1
L 8.39251998 4.85788002 8.39251998 4.83598002 2 P 0 
L 8.39251998 4.83598002 8.38626004 4.82971998 2 P 0 
L 8.38626004 4.82971998 8.38626004 4.75645 2 P 0 
L 8.38626004 4.75645 8.40071004 4.742 2 P 0 
L 8.35 3.31615 8.325 3.29115 5 P 0 
P 8.325 3.29115 10 P 0 0;2,4=11,6=0
P 8.35 3.31615 8 P 0 0;4=12,6=1
P 8.3689 4.85788002 36 P 0 0;2,4=1,6=0
P 8.36071004 4.742 8 P 0 0;4=12,6=1
L 8.3689 4.85788002 8.3689 4.83563996 2 P 0 
L 8.3689 4.83563996 8.37516004 4.82938002 2 P 0 
L 8.37516004 4.82938002 8.37516004 4.75645 2 P 0 
L 8.37516004 4.75645 8.36071004 4.742 2 P 0 
P 8.275 3.54115 10 P 0 0;2,4=11,6=0
P 8.3 3.56615 8 P 0 0;4=12,6=1
L 8.275 3.54115 8.3 3.56615 5 P 0 
P 8.05 3.31615 8 P 0 0;4=12,6=1
P 8.025 3.29115 10 P 0 0;2,4=11,6=0
L 8.05 3.31615 8.025 3.29115 5 P 0 
L 7.58938002 4.97913996 7.58938002 5.00183996 2 P 0 
L 7.58938002 5.00183996 7.59563996 5.0081 2 P 0 
L 7.59563996 5.0081 7.59563996 5.15455 2 P 0 
L 7.59563996 5.15455 7.58118996 5.169 2 P 0 
P 7.58118996 5.169 8 P 0 0;4=12,6=1
P 7.58938002 4.97913996 36 P 0 0;2,4=1,6=0
L 8.225 3.54115 8.25 3.56615 5 P 0 
P 8.25 3.56615 8 P 0 0;4=12,6=1
P 8.225 3.54115 10 P 0 0;2,4=11,6=0
P 8.05 3.36615 8 P 0 0;4=12,6=1
P 8.025 3.34115 10 P 0 0;2,4=11,6=0
L 8.05 3.36615 8.025 3.34115 5 P 0 
L 7.613 4.97913996 7.613 5.00153996 2 P 0 
L 7.613 5.00153996 7.60673996 5.0078 2 P 0 
L 7.60673996 5.0078 7.60673996 5.15455 2 P 0 
L 7.60673996 5.15455 7.62118996 5.169 2 P 0 
P 7.62118996 5.169 8 P 0 0;4=12,6=1
P 7.613 4.97913996 36 P 0 0;2,4=1,6=0
L 2.24606004 2.86615 2.22106004 2.84115 2 P 0 
P 2.22106004 2.84115 10 P 0 0;2,4=11,6=0
P 2.24606004 2.86615 8 P 0 0;4=12,6=1
L 3.9865 4.635 3.9865 4.65126004 7 P 0 
L 3.9865 4.65126004 3.99965 4.66441004 7 P 0 
L 3.81998996 0.7751 3.86 0.7751 7 P 0 
L 10.51 5.26 10.495 5.245 9 P 0 
L 10.495 5.245 10.465 5.245 9 P 0 
L 10.465 5.275 10.495 5.275 9 P 0 
L 10.495 5.275 10.51 5.26 9 P 0 
L 10.51 5.18 10.495 5.195 9 P 0 
L 10.495 5.195 10.465 5.195 9 P 0 
L 10.465 5.165 10.495 5.165 9 P 0 
L 10.495 5.165 10.51 5.18 9 P 0 
L 12.2 4.96 12.215 4.945 9 P 0 
L 12.215 4.945 12.215 4.915 9 P 0 
L 12.185 4.915 12.185 4.945 9 P 0 
L 12.185 4.945 12.2 4.96 9 P 0 
L 12.04 4.96 12.055 4.945 9 P 0 
L 12.055 4.945 12.055 4.915 9 P 0 
L 12.025 4.915 12.025 4.945 9 P 0 
L 12.025 4.945 12.04 4.96 9 P 0 
L 9.15751998 4.81401998 9.15751998 4.83046998 6 P 0 
L 9.15751998 4.83046998 9.15555 4.83243996 6 P 0 
L 9.15555 4.83243996 9.15555 4.85788002 6 P 0 
L 9.08045 4.81401998 9.08045 4.83145 6 P 0 
L 9.08045 4.83145 9.08468002 4.83568002 6 P 0 
L 9.08468002 4.83568002 9.08468002 4.85788002 6 P 0 
L 9.43901004 4.85788002 9.43901004 4.928 6 P 0 
L 9.50988002 4.85788002 9.50988002 4.92 6 P 0 
L 8.80121998 4.97913996 8.80121998 4.92 6 P 0 
L 8.87208996 4.97913996 8.87208996 4.92 6 P 0 
L 8.94295 4.97913996 8.94295 5.023 6 P 0 
L 9.01381998 4.97913996 9.01381998 5.023 6 P 0 
L 9.08468002 4.97913996 9.08468002 4.92 6 P 0 
L 9.15555 4.97913996 9.15555 4.93431998 6 P 0 
L 9.22641998 4.97913996 9.22641998 4.92 6 P 0 
L 9.29728002 4.97913996 9.29728002 4.93431998 6 P 0 
L 9.36815 4.97913996 9.36815 4.926 6 P 0 
L 9.43901004 4.97913996 9.43901004 5.023 6 P 0 
L 9.50988002 4.97913996 9.50988002 4.92 6 P 0 
L 8.80121998 4.85788002 8.80121998 4.92 6 P 0 
L 8.87208996 4.85788002 8.87208996 4.92 6 P 0 
L 8.94295 4.85788002 8.94295 4.9027 6 P 0 
L 9.01381998 4.85788002 9.01381998 4.92 6 P 0 
L 9.08468002 4.85788002 9.08468002 4.92 6 P 0 
L 9.15555 4.85788002 9.15555 4.9027 6 P 0 
L 9.22641998 4.85788002 9.22641998 4.92 6 P 0 
L 9.29728002 4.85788002 9.29728002 4.9027 6 P 0 
L 9.36815 4.85788002 9.36815 4.926 6 P 0 
L 8.27441004 4.85788002 8.27441004 4.9207 6 P 0 
L 8.34528002 4.85788002 8.34528002 4.9207 6 P 0 
L 7.63661998 4.97913996 7.63661998 4.92 6 P 0 
L 7.70748996 4.97913996 7.70748996 4.9207 6 P 0 
L 7.77835 4.97913996 7.77835 4.9207 6 P 0 
L 7.84921998 4.97913996 7.84921998 4.9207 6 P 0 
L 7.92008002 4.97913996 7.92008002 4.9207 6 P 0 
L 7.99095 4.97913996 7.99095 4.9207 6 P 0 
L 8.06181998 4.97913996 8.06181998 4.9207 6 P 0 
L 8.13268002 4.97913996 8.13268002 4.9207 6 P 0 
L 8.20355 4.97913996 8.20355 4.9267 6 P 0 
L 8.27441004 4.97913996 8.27441004 4.9207 6 P 0 
L 8.34528002 4.97913996 8.34528002 4.9207 6 P 0 
L 7.63661998 4.85788002 7.63661998 4.81661998 6 P 0 
L 7.63661998 4.81661998 7.63526998 4.81526998 6 P 0 
L 7.70748996 4.85788002 7.70748996 4.9207 6 P 0 
L 7.77835 4.85788002 7.77835 4.9207 6 P 0 
L 7.84921998 4.85788002 7.84921998 4.9207 6 P 0 
L 7.92008002 4.85788002 7.92008002 4.81346004 6 P 0 
L 7.92008002 4.81346004 7.92353996 4.81 6 P 0 
L 7.99095 4.85788002 7.99095 4.9207 6 P 0 
L 8.06181998 4.85788002 8.06181998 4.9207 6 P 0 
L 8.13268002 4.85788002 8.13268002 4.9207 6 P 0 
L 8.20355 4.85788002 8.20355 4.9267 6 P 0 
L 3.43546998 4.85788002 3.43546998 4.81401998 6 P 0 
L 3.50633996 4.85788002 3.50633996 4.81401998 6 P 0 
L 2.79768002 4.97913996 2.79768002 4.92 6 P 0 
L 2.86855 4.97913996 2.86855 4.92 6 P 0 
L 2.93941004 4.97913996 2.93941004 4.93528002 6 P 0 
L 3.01028002 4.97913996 3.01028002 4.92 6 P 0 
L 3.08113996 4.97913996 3.08113996 5.023 6 P 0 
L 3.15201004 4.97913996 3.15201004 4.94126004 6 P 0 
L 3.22288002 4.97913996 3.22288002 4.92 6 P 0 
L 3.29373996 4.97913996 3.29373996 4.93528002 6 P 0 
L 3.36461004 4.97913996 3.36461004 4.926 6 P 0 
L 3.43546998 4.97913996 3.43546998 5.023 6 P 0 
L 3.50633996 4.97913996 3.50633996 4.92 6 P 0 
L 2.79768002 4.85788002 2.79768002 4.92 6 P 0 
L 2.86855 4.85788002 2.86855 4.92 6 P 0 
L 2.93941004 4.85788002 2.93941004 4.90173996 6 P 0 
L 3.01028002 4.85788002 3.01028002 4.92 6 P 0 
L 3.08113996 4.85788002 3.08113996 4.92 6 P 0 
L 3.15201004 4.85788002 3.15201004 4.89576004 6 P 0 
L 3.22288002 4.85788002 3.22288002 4.92 6 P 0 
L 3.29373996 4.85788002 3.29373996 4.90173996 6 P 0 
L 3.36461004 4.85788002 3.36461004 4.926 6 P 0 
L 1.63308002 4.85788002 1.63308002 4.81661998 6 P 0 
L 1.63308002 4.81661998 1.63173002 4.81526998 6 P 0 
L 1.70395 4.85788002 1.70395 4.81595 6 P 0 
L 1.70395 4.81595 1.7 4.812 6 P 0 
L 1.77481004 4.85788002 1.77481004 4.92 6 P 0 
L 1.84568002 4.85788002 1.84568002 4.81 6 P 0 
L 1.91653996 4.85788002 1.91653996 4.81346004 6 P 0 
L 1.91653996 4.81346004 1.92 4.81 6 P 0 
L 1.98741004 4.85788002 1.98741004 4.81258996 6 P 0 
L 1.98741004 4.81258996 1.99 4.81 6 P 0 
L 2.05828002 4.85788002 2.05828002 4.81258996 6 P 0 
L 2.05828002 4.81258996 2.06086998 4.81 6 P 0 
L 2.12913996 4.85788002 2.12913996 4.92 6 P 0 
L 2.20001004 4.85788002 2.20001004 4.926 6 P 0 
L 2.27086998 4.85788002 2.27086998 4.81 6 P 0 
L 2.34173996 4.85788002 2.34173996 4.81 6 P 0 
L 1.63308002 4.97913996 1.63308002 5.023 6 P 0 
L 1.70395 4.97913996 1.70395 4.92 6 P 0 
L 1.77481004 4.97913996 1.77481004 4.92 6 P 0 
L 1.84568002 4.97913996 1.84568002 4.92 6 P 0 
L 1.91653996 4.97913996 1.91653996 5.023 6 P 0 
L 1.98741004 4.97913996 1.98741004 4.92 6 P 0 
L 2.05828002 4.97913996 2.05828002 5.023 6 P 0 
L 2.12913996 4.97913996 2.12913996 4.93528002 6 P 0 
L 2.20001004 4.97913996 2.20001004 4.926 6 P 0 
L 2.27086998 4.97913996 2.27086998 4.92 6 P 0 
L 2.34173996 4.97913996 2.34173996 4.92 6 P 0 
L 7.92008002 4.9207 7.92008002 4.85788002 6 P 0 
L 8.475 3.19115 8.5 3.21615 9 P 0 
L 8.425 3.19115 8.45 3.21615 9 P 0 
L 8.475 3.14115 8.5 3.16615 9 P 0 
L 8.425 3.04115 8.45 3.06615 9 P 0 
L 8.475 2.99115 8.5 3.01615 9 P 0 
L 8.425 3.14115 8.45 3.16615 9 P 0 
L 8.425 3.09115 8.45 3.11615 9 P 0 
L 8.475 3.09115 8.5 3.11615 9 P 0 
L 8.475 3.04115 8.5 3.06615 9 P 0 
L 8.425 2.99115 8.45 3.01615 9 P 0 
L 8.425 2.94115 8.45 2.96615 9 P 0 
L 8.475 2.94115 8.5 2.96615 9 P 0 
L 8.425 2.89115 8.45 2.91615 9 P 0 
L 8.425 2.84115 8.45 2.86615 9 P 0 
L 8.425 2.79115 8.45 2.81615 9 P 0 
L 8.475 2.84115 8.5 2.86615 9 P 0 
L 8.475 2.69115 8.5 2.71615 9 P 0 
L 8.475 2.89115 8.5 2.91615 9 P 0 
L 8.475 2.79115 8.5 2.81615 9 P 0 
L 8.475 2.74115 8.5 2.76615 9 P 0 
L 8.425 2.74115 8.45 2.76615 9 P 0 
L 8.425 2.69115 8.45 2.71615 9 P 0 
L 8.425 2.64115 8.45 2.66615 9 P 0 
L 8.425 2.49115 8.45 2.51615 9 P 0 
L 8.475 2.54115 8.5 2.56615 9 P 0 
L 8.475 2.49115 8.5 2.51615 9 P 0 
L 8.475 2.44115 8.5 2.46615 9 P 0 
L 8.425 2.59115 8.45 2.61615 9 P 0 
L 8.425 2.54115 8.45 2.56615 9 P 0 
L 8.475 2.64115 8.5 2.66615 9 P 0 
L 8.475 2.59115 8.5 2.61615 9 P 0 
L 8.425 2.44115 8.45 2.46615 9 P 0 
L 8.425 2.34115 8.45 2.36615 9 P 0 
L 8.475 2.29115 8.5 2.31615 9 P 0 
L 8.425 2.19115 8.45 2.16615 9 P 0 
L 8.425 2.19115 8.45 2.21615 9 P 0 
L 8.425 2.29115 8.45 2.31615 9 P 0 
L 8.425 2.24115 8.45 2.26615 9 P 0 
L 8.475 2.24115 8.5 2.26615 9 P 0 
L 8.475 2.19115 8.5 2.21615 9 P 0 
L 8.475 2.39115 8.5 2.41615 9 P 0 
L 8.475 2.34115 8.5 2.36615 9 P 0 
L 8.425 2.39115 8.45 2.41615 9 P 0 
L 8.425 2.04115 8.45 2.01615 9 P 0 
L 8.475 1.99115 8.5 1.96615 9 P 0 
L 8.475 2.14115 8.5 2.11615 9 P 0 
L 8.475 2.14115 8.5 2.16615 9 P 0 
L 8.425 1.94115 8.45 1.91615 9 P 0 
L 8.425 1.99115 8.45 1.96615 9 P 0 
L 8.475 1.94115 8.5 1.91615 9 P 0 
L 8.425 2.09115 8.45 2.06615 9 P 0 
L 8.425 2.14115 8.45 2.11615 9 P 0 
L 8.475 2.04115 8.5 2.01615 9 P 0 
L 8.475 2.09115 8.5 2.06615 9 P 0 
L 8.425 1.89115 8.45 1.86615 9 P 0 
L 8.475 1.89115 8.5 1.86615 9 P 0 
L 8.325 3.19115 8.35 3.21615 9 P 0 
L 8.175 3.19115 8.2 3.21615 9 P 0 
L 8.225 3.19115 8.25 3.21615 9 P 0 
L 8.275 3.19115 8.3 3.21615 9 P 0 
L 8.375 3.19115 8.4 3.21615 9 P 0 
L 8.375 3.14115 8.4 3.16615 9 P 0 
L 8.275 3.14115 8.3 3.16615 9 P 0 
L 8.225 3.14115 8.25 3.16615 9 P 0 
L 8.275 3.04115 8.3 3.06615 9 P 0 
L 8.275 3.09115 8.3 3.11615 9 P 0 
L 8.275 2.94115 8.3 2.96615 9 P 0 
L 8.275 2.99115 8.3 3.01615 9 P 0 
L 8.225 3.04115 8.25 3.06615 9 P 0 
L 8.225 3.09115 8.25 3.11615 9 P 0 
L 8.225 2.94115 8.25 2.96615 9 P 0 
L 8.225 2.99115 8.25 3.01615 9 P 0 
L 8.175 3.04115 8.2 3.06615 9 P 0 
L 8.375 2.99115 8.4 3.01615 9 P 0 
L 8.325 3.04115 8.35 3.06615 9 P 0 
L 8.175 3.14115 8.2 3.16615 9 P 0 
L 8.175 3.09115 8.2 3.11615 9 P 0 
L 8.325 3.14115 8.35 3.16615 9 P 0 
L 8.325 3.09115 8.35 3.11615 9 P 0 
L 8.375 3.04115 8.4 3.06615 9 P 0 
L 8.375 3.09115 8.4 3.11615 9 P 0 
L 8.175 2.99115 8.2 3.01615 9 P 0 
L 8.175 2.94115 8.2 2.96615 9 P 0 
L 8.325 2.99115 8.35 3.01615 9 P 0 
L 8.325 2.94115 8.35 2.96615 9 P 0 
L 8.375 2.94115 8.4 2.96615 9 P 0 
L 8.325 2.84115 8.35 2.86615 9 P 0 
L 8.325 2.89115 8.35 2.91615 9 P 0 
L 8.275 2.74115 8.3 2.76615 9 P 0 
L 8.275 2.79115 8.3 2.81615 9 P 0 
L 8.225 2.74115 8.25 2.76615 9 P 0 
L 8.225 2.79115 8.25 2.81615 9 P 0 
L 8.175 2.79115 8.2 2.81615 9 P 0 
L 8.175 2.89115 8.2 2.91615 9 P 0 
L 8.225 2.89115 8.25 2.91615 9 P 0 
L 8.275 2.89115 8.3 2.91615 9 P 0 
L 8.375 2.84115 8.4 2.86615 9 P 0 
L 8.325 2.79115 8.35 2.81615 9 P 0 
L 8.375 2.69115 8.4 2.71615 9 P 0 
L 8.275 2.69115 8.3 2.71615 9 P 0 
L 8.225 2.69115 8.25 2.71615 9 P 0 
L 8.175 2.84115 8.2 2.86615 9 P 0 
L 8.375 2.89115 8.4 2.91615 9 P 0 
L 8.375 2.79115 8.4 2.81615 9 P 0 
L 8.375 2.74115 8.4 2.76615 9 P 0 
L 8.325 2.74115 8.35 2.76615 9 P 0 
L 8.325 2.69115 8.35 2.71615 9 P 0 
L 8.175 2.74115 8.2 2.76615 9 P 0 
L 8.175 2.69115 8.2 2.71615 9 P 0 
L 8.325 2.64115 8.35 2.66615 9 P 0 
L 8.275 2.64115 8.3 2.66615 9 P 0 
L 8.225 2.64115 8.25 2.66615 9 P 0 
L 8.175 2.64115 8.2 2.66615 9 P 0 
L 8.225 2.59115 8.25 2.61615 9 P 0 
L 8.225 2.54115 8.25 2.56615 9 P 0 
L 8.275 2.59115 8.3 2.61615 9 P 0 
L 8.275 2.54115 8.3 2.56615 9 P 0 
L 8.325 2.49115 8.35 2.51615 9 P 0 
L 8.275 2.49115 8.3 2.51615 9 P 0 
L 8.225 2.49115 8.25 2.51615 9 P 0 
L 8.175 2.49115 8.2 2.51615 9 P 0 
L 8.225 2.44115 8.25 2.46615 9 P 0 
L 8.275 2.44115 8.3 2.46615 9 P 0 
L 8.375 2.44115 8.4 2.46615 9 P 0 
L 8.375 2.49115 8.4 2.51615 9 P 0 
L 8.375 2.54115 8.4 2.56615 9 P 0 
L 8.325 2.59115 8.35 2.61615 9 P 0 
L 8.325 2.54115 8.35 2.56615 9 P 0 
L 8.375 2.64115 8.4 2.66615 9 P 0 
L 8.375 2.59115 8.4 2.61615 9 P 0 
L 8.175 2.59115 8.2 2.61615 9 P 0 
L 8.175 2.54115 8.2 2.56615 9 P 0 
L 8.175 2.44115 8.2 2.46615 9 P 0 
L 8.325 2.44115 8.35 2.46615 9 P 0 
L 8.275 2.39115 8.3 2.41615 9 P 0 
L 8.225 2.39115 8.25 2.41615 9 P 0 
L 8.225 2.34115 8.25 2.36615 9 P 0 
L 8.175 2.34115 8.2 2.36615 9 P 0 
L 8.275 2.34115 8.3 2.36615 9 P 0 
L 8.375 2.29115 8.4 2.31615 9 P 0 
L 8.325 2.34115 8.35 2.36615 9 P 0 
L 8.275 2.29115 8.3 2.31615 9 P 0 
L 8.225 2.29115 8.25 2.31615 9 P 0 
L 8.325 2.19115 8.35 2.16615 9 P 0 
L 8.325 2.19115 8.35 2.21615 9 P 0 
L 8.275 2.19115 8.3 2.21615 9 P 0 
L 8.275 2.19115 8.3 2.16615 9 P 0 
L 8.225 2.19115 8.25 2.21615 9 P 0 
L 8.275 2.24115 8.3 2.26615 9 P 0 
L 8.225 2.24115 8.25 2.26615 9 P 0 
L 8.175 2.19115 8.2 2.21615 9 P 0 
L 8.175 2.19115 8.2 2.16615 9 P 0 
L 8.175 2.39115 8.2 2.41615 9 P 0 
L 8.175 2.29115 8.2 2.31615 9 P 0 
L 8.175 2.24115 8.2 2.26615 9 P 0 
L 8.325 2.29115 8.35 2.31615 9 P 0 
L 8.325 2.24115 8.35 2.26615 9 P 0 
L 8.375 2.24115 8.4 2.26615 9 P 0 
L 8.375 2.19115 8.4 2.21615 9 P 0 
L 8.375 2.39115 8.4 2.41615 9 P 0 
L 8.375 2.34115 8.4 2.36615 9 P 0 
L 8.325 2.39115 8.35 2.41615 9 P 0 
L 8.225 1.94115 8.25 1.91615 9 P 0 
L 8.275 1.94115 8.3 1.91615 9 P 0 
L 8.225 1.99115 8.25 1.96615 9 P 0 
L 8.275 1.99115 8.3 1.96615 9 P 0 
L 8.175 2.04115 8.2 2.01615 9 P 0 
L 8.225 2.04115 8.25 2.01615 9 P 0 
L 8.275 2.04115 8.3 2.01615 9 P 0 
L 8.325 2.04115 8.35 2.01615 9 P 0 
L 8.375 1.99115 8.4 1.96615 9 P 0 
L 8.375 2.14115 8.4 2.16615 9 P 0 
L 8.375 2.14115 8.4 2.11615 9 P 0 
L 8.275 2.09115 8.3 2.06615 9 P 0 
L 8.275 2.14115 8.3 2.11615 9 P 0 
L 8.225 2.14115 8.25 2.11615 9 P 0 
L 8.225 2.14115 8.25 2.16615 9 P 0 
L 8.225 2.09115 8.25 2.06615 9 P 0 
L 8.175 2.09115 8.2 2.06615 9 P 0 
L 8.175 2.14115 8.2 2.11615 9 P 0 
L 8.175 1.94115 8.2 1.91615 9 P 0 
L 8.175 1.99115 8.2 1.96615 9 P 0 
L 8.325 1.94115 8.35 1.91615 9 P 0 
L 8.325 1.99115 8.35 1.96615 9 P 0 
L 8.375 1.94115 8.4 1.91615 9 P 0 
L 8.375 2.04115 8.4 2.01615 9 P 0 
L 8.375 2.09115 8.4 2.06615 9 P 0 
L 8.325 2.09115 8.35 2.06615 9 P 0 
L 8.325 2.14115 8.35 2.11615 9 P 0 
L 8.175 1.89115 8.2 1.86615 9 P 0 
L 8.225 1.89115 8.25 1.86615 9 P 0 
L 8.275 1.89115 8.3 1.86615 9 P 0 
L 8.325 1.89115 8.35 1.86615 9 P 0 
L 8.375 1.89115 8.4 1.86615 9 P 0 
L 8.075 3.19115 8.1 3.21615 9 P 0 
L 8.025 3.19115 8.05 3.21615 9 P 0 
L 8.125 3.19115 8.15 3.21615 9 P 0 
L 8.025 3.14115 8.05 3.16615 9 P 0 
L 8.125 3.14115 8.15 3.16615 9 P 0 
L 8.125 2.99115 8.15 3.01615 9 P 0 
L 8.075 3.04115 8.1 3.06615 9 P 0 
L 8.025 2.99115 8.05 3.01615 9 P 0 
L 8.075 3.14115 8.1 3.16615 9 P 0 
L 8.075 3.09115 8.1 3.11615 9 P 0 
L 8.025 3.09115 8.05 3.11615 9 P 0 
L 8.125 3.09115 8.15 3.11615 9 P 0 
L 8.125 3.04115 8.15 3.06615 9 P 0 
L 8.025 3.04115 8.05 3.06615 9 P 0 
L 8.125 2.94115 8.15 2.96615 9 P 0 
L 8.075 2.94115 8.1 2.96615 9 P 0 
L 8.075 2.99115 8.1 3.01615 9 P 0 
L 8.025 2.94115 8.05 2.96615 9 P 0 
L 8.075 2.79115 8.1 2.81615 9 P 0 
L 8.075 2.84115 8.1 2.86615 9 P 0 
L 8.075 2.89115 8.1 2.91615 9 P 0 
L 8.125 2.84115 8.15 2.86615 9 P 0 
L 8.025 2.84115 8.05 2.86615 9 P 0 
L 8.125 2.69115 8.15 2.71615 9 P 0 
L 8.025 2.69115 8.05 2.71615 9 P 0 
L 8.025 2.69115 8 2.71615 9 P 0 
L 8.025 2.84115 8 2.86615 9 P 0 
L 8.075 2.84115 8.05 2.81615 9 P 0 
L 8.075 2.79115 8.05 2.76615 9 P 0 
L 8.125 2.89115 8.15 2.91615 9 P 0 
L 8.025 2.89115 8.05 2.91615 9 P 0 
L 8.125 2.79115 8.15 2.81615 9 P 0 
L 8.125 2.74115 8.15 2.76615 9 P 0 
L 8.075 2.74115 8.1 2.76615 9 P 0 
L 8.075 2.69115 8.1 2.71615 9 P 0 
L 8.025 2.79115 8 2.81615 9 P 0 
L 8.025 2.74115 8 2.76615 9 P 0 
L 8.075 2.64115 8.1 2.66615 9 P 0 
L 8.025 2.54115 8.05 2.56615 9 P 0 
L 8.025 2.49115 8.05 2.51615 9 P 0 
L 8.025 2.44115 8.05 2.46615 9 P 0 
L 8.075 2.49115 8.1 2.51615 9 P 0 
L 8.125 2.54115 8.15 2.56615 9 P 0 
L 8.125 2.44115 8.15 2.46615 9 P 0 
L 8.025 2.64115 8.05 2.66615 9 P 0 
L 8.025 2.59115 8.05 2.61615 9 P 0 
L 8.075 2.59115 8.1 2.61615 9 P 0 
L 8.075 2.54115 8.1 2.56615 9 P 0 
L 8.125 2.64115 8.15 2.66615 9 P 0 
L 8.125 2.59115 8.15 2.61615 9 P 0 
L 8.075 2.44115 8.1 2.46615 9 P 0 
L 8.025 2.29115 8.05 2.31615 9 P 0 
L 8.075 2.19115 8.1 2.21615 9 P 0 
L 8.075 2.19115 8.1 2.16615 9 P 0 
L 8.075 2.34115 8.1 2.36615 9 P 0 
L 8.125 2.29115 8.15 2.31615 9 P 0 
L 8.075 2.39115 8.1 2.41615 9 P 0 
L 8.025 2.39115 8.05 2.41615 9 P 0 
L 8.025 2.34115 8.05 2.36615 9 P 0 
L 8.125 2.39115 8.15 2.41615 9 P 0 
L 8.125 2.34115 8.15 2.36615 9 P 0 
L 8.075 2.29115 8.1 2.31615 9 P 0 
L 8.075 2.24115 8.1 2.26615 9 P 0 
L 8.125 2.24115 8.15 2.26615 9 P 0 
L 8.125 2.19115 8.15 2.21615 9 P 0 
L 8.025 2.24115 8.05 2.26615 9 P 0 
L 8.025 2.19115 8.05 2.21615 9 P 0 
L 8.025 2.14115 8.05 2.16615 9 P 0 
L 8.025 2.14115 8.05 2.11615 9 P 0 
L 8.025 1.99115 8.05 1.96615 9 P 0 
L 8.075 2.04115 8.1 2.01615 9 P 0 
L 8.125 1.99115 8.15 1.96615 9 P 0 
L 8.125 2.14115 8.15 2.11615 9 P 0 
L 8.125 2.14115 8.15 2.16615 9 P 0 
L 8.075 2.09115 8.1 2.06615 9 P 0 
L 8.075 2.14115 8.1 2.11615 9 P 0 
L 8.025 2.04115 8.05 2.01615 9 P 0 
L 8.025 2.09115 8.05 2.06615 9 P 0 
L 8.125 2.04115 8.15 2.01615 9 P 0 
L 8.125 2.09115 8.15 2.06615 9 P 0 
L 8.075 1.94115 8.1 1.91615 9 P 0 
L 8.075 1.99115 8.1 1.96615 9 P 0 
L 8.025 1.94115 8.05 1.91615 9 P 0 
L 8.125 1.94115 8.15 1.91615 9 P 0 
L 8.075 1.89115 8.1 1.86615 9 P 0 
L 8.025 1.89115 8.05 1.86615 9 P 0 
L 8.125 1.89115 8.15 1.86615 9 P 0 
L 2.32106004 2.39115 2.34606004 2.41615 9 P 0 
L 2.32106004 2.44115 2.34606004 2.46615 9 P 0 
L 2.37106004 2.34115 2.39606004 2.36615 9 P 0 
L 2.37106004 2.39115 2.39606004 2.41615 9 P 0 
L 2.42106004 2.39115 2.44606004 2.41615 9 P 0 
L 2.42106004 2.44115 2.44606004 2.46615 9 P 0 
L 2.47106004 2.34115 2.49606004 2.36615 9 P 0 
L 2.47106004 2.39115 2.49606004 2.41615 9 P 0 
L 2.47106004 2.19115 2.49606004 2.21615 9 P 0 
L 2.47106004 2.24115 2.49606004 2.26615 9 P 0 
L 2.42106004 2.24115 2.44606004 2.26615 9 P 0 
L 2.42106004 2.29115 2.44606004 2.31615 9 P 0 
L 2.37106004 2.19115 2.39606004 2.21615 9 P 0 
L 2.37106004 2.24115 2.39606004 2.26615 9 P 0 
L 2.32106004 2.24115 2.34606004 2.26615 9 P 0 
L 2.32106004 2.29115 2.34606004 2.31615 9 P 0 
L 2.47106004 2.09115 2.49606004 2.06615 9 P 0 
L 2.47106004 2.04115 2.49606004 2.01615 9 P 0 
L 2.42106004 2.14115 2.44606004 2.11615 9 P 0 
L 2.42106004 2.09115 2.44606004 2.06615 9 P 0 
L 2.32106004 2.14115 2.34606004 2.11615 9 P 0 
L 2.32106004 2.09115 2.34606004 2.06615 9 P 0 
L 2.37106004 2.09115 2.39606004 2.06615 9 P 0 
L 2.37106004 2.04115 2.39606004 2.01615 9 P 0 
L 2.47106004 1.94115 2.49606004 1.91615 9 P 0 
L 2.47106004 1.89115 2.49606004 1.86615 9 P 0 
L 2.42106004 1.99115 2.44606004 1.96615 9 P 0 
L 2.42106004 1.94115 2.44606004 1.91615 9 P 0 
L 2.37106004 1.94115 2.39606004 1.91615 9 P 0 
L 2.37106004 1.89115 2.39606004 1.86615 9 P 0 
L 2.32106004 1.99115 2.34606004 1.96615 9 P 0 
L 2.32106004 1.94115 2.34606004 1.91615 9 P 0 
L 2.17106004 1.99115 2.19606004 1.96615 9 P 0 
L 2.17106004 1.94115 2.19606004 1.91615 9 P 0 
L 2.12106004 1.94115 2.14606004 1.91615 9 P 0 
L 2.12106004 1.89115 2.14606004 1.86615 9 P 0 
L 2.02106004 1.94115 2.04606004 1.91615 9 P 0 
L 2.02106004 1.89115 2.04606004 1.86615 9 P 0 
L 2.07106004 1.99115 2.09606004 1.96615 9 P 0 
L 2.07106004 1.94115 2.09606004 1.91615 9 P 0 
L 2.17106004 2.14115 2.19606004 2.11615 9 P 0 
L 2.17106004 2.09115 2.19606004 2.06615 9 P 0 
L 2.12106004 2.09115 2.14606004 2.06615 9 P 0 
L 2.12106004 2.04115 2.14606004 2.01615 9 P 0 
L 2.02106004 2.09115 2.04606004 2.06615 9 P 0 
L 2.02106004 2.04115 2.04606004 2.01615 9 P 0 
L 2.07106004 2.14115 2.09606004 2.11615 9 P 0 
L 2.07106004 2.09115 2.09606004 2.06615 9 P 0 
L 2.02106004 2.19115 2.04606004 2.21615 9 P 0 
L 2.02106004 2.24115 2.04606004 2.26615 9 P 0 
L 2.12106004 2.19115 2.14606004 2.21615 9 P 0 
L 2.12106004 2.24115 2.14606004 2.26615 9 P 0 
L 2.07106004 2.24115 2.09606004 2.26615 9 P 0 
L 2.07106004 2.29115 2.09606004 2.31615 9 P 0 
L 2.17106004 2.24115 2.19606004 2.26615 9 P 0 
L 2.17106004 2.29115 2.19606004 2.31615 9 P 0 
L 2.17106004 2.39115 2.19606004 2.41615 9 P 0 
L 2.17106004 2.44115 2.19606004 2.46615 9 P 0 
L 2.12106004 2.34115 2.14606004 2.36615 9 P 0 
L 2.12106004 2.39115 2.14606004 2.41615 9 P 0 
L 2.02106004 2.34115 2.04606004 2.36615 9 P 0 
L 2.02106004 2.39115 2.04606004 2.41615 9 P 0 
L 2.07106004 2.39115 2.09606004 2.41615 9 P 0 
L 2.07106004 2.44115 2.09606004 2.46615 9 P 0 
L 2.17106004 2.54115 2.19606004 2.56615 9 P 0 
L 2.17106004 2.59115 2.19606004 2.61615 9 P 0 
L 2.12106004 2.59115 2.14606004 2.61615 9 P 0 
L 2.12106004 2.64115 2.14606004 2.66615 9 P 0 
L 2.07106004 2.54115 2.09606004 2.56615 9 P 0 
L 2.07106004 2.59115 2.09606004 2.61615 9 P 0 
L 2.02106004 2.59115 2.04606004 2.61615 9 P 0 
L 2.02106004 2.64115 2.04606004 2.66615 9 P 0 
L 2.02106004 2.74115 1.99606004 2.76615 9 P 0 
L 2.02106004 2.79115 1.99606004 2.81615 9 P 0 
L 2.07106004 2.69115 2.09606004 2.71615 9 P 0 
L 2.07106004 2.74115 2.09606004 2.76615 9 P 0 
L 2.12106004 2.74115 2.14606004 2.76615 9 P 0 
L 2.12106004 2.79115 2.14606004 2.81615 9 P 0 
L 2.17106004 2.69115 2.19606004 2.71615 9 P 0 
L 2.17106004 2.74115 2.19606004 2.76615 9 P 0 
L 2.47106004 2.59115 2.49606004 2.61615 9 P 0 
L 2.47106004 2.64115 2.49606004 2.66615 9 P 0 
L 2.42106004 2.54115 2.44606004 2.56615 9 P 0 
L 2.42106004 2.59115 2.44606004 2.61615 9 P 0 
L 2.37106004 2.59115 2.39606004 2.61615 9 P 0 
L 2.37106004 2.64115 2.39606004 2.66615 9 P 0 
L 2.32106004 2.54115 2.34606004 2.56615 9 P 0 
L 2.32106004 2.59115 2.34606004 2.61615 9 P 0 
L 2.32106004 2.69115 2.34606004 2.71615 9 P 0 
L 2.32106004 2.74115 2.34606004 2.76615 9 P 0 
L 2.37106004 2.74115 2.39606004 2.76615 9 P 0 
L 2.37106004 2.79115 2.39606004 2.81615 9 P 0 
L 2.42106004 2.69115 2.44606004 2.71615 9 P 0 
L 2.42106004 2.74115 2.44606004 2.76615 9 P 0 
L 2.47106004 2.74115 2.49606004 2.76615 9 P 0 
L 2.47106004 2.79115 2.49606004 2.81615 9 P 0 
L 2.47106004 2.89115 2.49606004 2.91615 9 P 0 
L 2.47106004 2.94115 2.49606004 2.96615 9 P 0 
L 2.42106004 2.94115 2.44606004 2.96615 9 P 0 
L 2.42106004 2.99115 2.44606004 3.01615 9 P 0 
L 2.37106004 2.89115 2.39606004 2.91615 9 P 0 
L 2.37106004 2.94115 2.39606004 2.96615 9 P 0 
L 2.32106004 2.94115 2.34606004 2.96615 9 P 0 
L 2.32106004 2.99115 2.34606004 3.01615 9 P 0 
L 2.02106004 2.89115 2.04606004 2.91615 9 P 0 
L 2.02106004 2.94115 2.04606004 2.96615 9 P 0 
L 2.07106004 2.99115 2.09606004 3.01615 9 P 0 
L 2.07106004 2.94115 2.09606004 2.96615 9 P 0 
L 2.12106004 2.89115 2.14606004 2.91615 9 P 0 
L 2.12106004 2.94115 2.14606004 2.96615 9 P 0 
L 2.17106004 2.94115 2.19606004 2.96615 9 P 0 
L 2.17106004 2.99115 2.19606004 3.01615 9 P 0 
L 2.37106004 3.09115 2.39606004 3.11615 9 P 0 
L 2.37106004 3.04115 2.39606004 3.06615 9 P 0 
L 2.47106004 3.04115 2.49606004 3.06615 9 P 0 
L 2.47106004 3.09115 2.49606004 3.11615 9 P 0 
L 2.42106004 3.09115 2.44606004 3.11615 9 P 0 
L 2.42106004 3.14115 2.44606004 3.16615 9 P 0 
L 2.32106004 3.09115 2.34606004 3.11615 9 P 0 
L 2.32106004 3.14115 2.34606004 3.16615 9 P 0 
L 2.02106004 3.04115 2.04606004 3.06615 9 P 0 
L 2.12106004 3.04115 2.14606004 3.06615 9 P 0 
L 2.17106004 3.09115 2.19606004 3.11615 9 P 0 
L 2.12106004 3.09115 2.14606004 3.11615 9 P 0 
L 2.17106004 3.14115 2.19606004 3.16615 9 P 0 
L 2.02106004 3.09115 2.04606004 3.11615 9 P 0 
L 2.07106004 3.09115 2.09606004 3.11615 9 P 0 
L 2.07106004 3.14115 2.09606004 3.16615 9 P 0 
P 8.05 2.61615 8 P 0 0;4=12,6=1
P 8.05 2.66615 8 P 0 0;4=12,6=1
P 8.1 2.46615 8 P 0 0;4=12,6=1
P 8.1 2.41615 8 P 0 0;4=12,6=1
P 8.2 2.46615 8 P 0 0;4=12,6=1
P 8.2 2.41615 8 P 0 0;4=12,6=1
P 8.15 2.41615 8 P 0 0;4=12,6=1
P 8.15 2.36615 8 P 0 0;4=12,6=1
P 8.05 2.41615 8 P 0 0;4=12,6=1
P 8.05 2.36615 8 P 0 0;4=12,6=1
P 8.2 2.31615 8 P 0 0;4=12,6=1
P 8.2 2.26615 8 P 0 0;4=12,6=1
P 8.15 2.26615 8 P 0 0;4=12,6=1
P 8.15 2.21615 8 P 0 0;4=12,6=1
P 8.1 2.31615 8 P 0 0;4=12,6=1
P 8.1 2.26615 8 P 0 0;4=12,6=1
P 8.05 2.26615 8 P 0 0;4=12,6=1
P 8.05 2.21615 8 P 0 0;4=12,6=1
P 8.1 2.11615 8 P 0 0;4=12,6=1
P 8.1 2.06615 8 P 0 0;4=12,6=1
P 8.2 2.11615 8 P 0 0;4=12,6=1
P 8.2 2.06615 8 P 0 0;4=12,6=1
P 8.15 2.06615 8 P 0 0;4=12,6=1
P 8.15 2.01615 8 P 0 0;4=12,6=1
P 8.05 2.06615 8 P 0 0;4=12,6=1
P 8.05 2.01615 8 P 0 0;4=12,6=1
P 8.2 1.96615 8 P 0 0;4=12,6=1
P 8.2 1.91615 8 P 0 0;4=12,6=1
P 8.15 1.91615 8 P 0 0;4=12,6=1
P 8.15 1.86615 8 P 0 0;4=12,6=1
P 8.1 1.96615 8 P 0 0;4=12,6=1
P 8.1 1.91615 8 P 0 0;4=12,6=1
P 8.05 1.91615 8 P 0 0;4=12,6=1
P 8.05 1.86615 8 P 0 0;4=12,6=1
P 8.1 3.16615 8 P 0 0;4=12,6=1
P 8.1 3.11615 8 P 0 0;4=12,6=1
P 8.2 3.16615 8 P 0 0;4=12,6=1
P 8.2 3.11615 8 P 0 0;4=12,6=1
P 8.15 3.11615 8 P 0 0;4=12,6=1
P 8.15 3.06615 8 P 0 0;4=12,6=1
P 8.05 3.11615 8 P 0 0;4=12,6=1
P 8.05 3.06615 8 P 0 0;4=12,6=1
P 8.2 3.01615 8 P 0 0;4=12,6=1
P 8.2 2.96615 8 P 0 0;4=12,6=1
P 8.15 2.96615 8 P 0 0;4=12,6=1
P 8.15 2.91615 8 P 0 0;4=12,6=1
P 8.1 3.01615 8 P 0 0;4=12,6=1
P 8.1 2.96615 8 P 0 0;4=12,6=1
P 8.05 2.96615 8 P 0 0;4=12,6=1
P 8.05 2.91615 8 P 0 0;4=12,6=1
P 8 2.81615 8 P 0 0;4=12,6=1
P 8 2.76615 8 P 0 0;4=12,6=1
P 8.15 2.81615 8 P 0 0;4=12,6=1
P 8.15 2.76615 8 P 0 0;4=12,6=1
P 8.2 2.76615 8 P 0 0;4=12,6=1
P 8.2 2.71615 8 P 0 0;4=12,6=1
P 8.1 2.76615 8 P 0 0;4=12,6=1
P 8.1 2.71615 8 P 0 0;4=12,6=1
P 8.15 2.66615 8 P 0 0;4=12,6=1
P 8.15 2.61615 8 P 0 0;4=12,6=1
P 8.2 2.61615 8 P 0 0;4=12,6=1
P 8.2 2.56615 8 P 0 0;4=12,6=1
P 8.1 2.61615 8 P 0 0;4=12,6=1
P 8.1 2.56615 8 P 0 0;4=12,6=1
P 8.35 2.56615 8 P 0 0;4=12,6=1
P 8.35 2.61615 8 P 0 0;4=12,6=1
P 8.35 2.46615 8 P 0 0;4=12,6=1
P 8.35 2.41615 8 P 0 0;4=12,6=1
P 8.45 2.46615 8 P 0 0;4=12,6=1
P 8.45 2.41615 8 P 0 0;4=12,6=1
P 8.5 2.41615 8 P 0 0;4=12,6=1
P 8.5 2.36615 8 P 0 0;4=12,6=1
P 8.4 2.41615 8 P 0 0;4=12,6=1
P 8.4 2.36615 8 P 0 0;4=12,6=1
P 8.45 2.31615 8 P 0 0;4=12,6=1
P 8.45 2.26615 8 P 0 0;4=12,6=1
P 8.5 2.26615 8 P 0 0;4=12,6=1
P 8.5 2.21615 8 P 0 0;4=12,6=1
P 8.4 2.26615 8 P 0 0;4=12,6=1
P 8.4 2.21615 8 P 0 0;4=12,6=1
P 8.35 2.31615 8 P 0 0;4=12,6=1
P 8.35 2.26615 8 P 0 0;4=12,6=1
P 8.35 2.11615 8 P 0 0;4=12,6=1
P 8.35 2.06615 8 P 0 0;4=12,6=1
P 8.45 2.11615 8 P 0 0;4=12,6=1
P 8.45 2.06615 8 P 0 0;4=12,6=1
P 8.5 2.06615 8 P 0 0;4=12,6=1
P 8.5 2.01615 8 P 0 0;4=12,6=1
P 8.4 2.06615 8 P 0 0;4=12,6=1
P 8.4 2.01615 8 P 0 0;4=12,6=1
P 8.45 1.96615 8 P 0 0;4=12,6=1
P 8.45 1.91615 8 P 0 0;4=12,6=1
P 8.5 1.91615 8 P 0 0;4=12,6=1
P 8.5 1.86615 8 P 0 0;4=12,6=1
P 8.4 1.91615 8 P 0 0;4=12,6=1
P 8.4 1.86615 8 P 0 0;4=12,6=1
P 8.35 1.96615 8 P 0 0;4=12,6=1
P 8.35 1.91615 8 P 0 0;4=12,6=1
P 8.35 3.16615 8 P 0 0;4=12,6=1
P 8.35 3.11615 8 P 0 0;4=12,6=1
P 8.45 3.16615 8 P 0 0;4=12,6=1
P 8.45 3.11615 8 P 0 0;4=12,6=1
P 8.5 3.11615 8 P 0 0;4=12,6=1
P 8.5 3.06615 8 P 0 0;4=12,6=1
P 8.4 3.11615 8 P 0 0;4=12,6=1
P 8.4 3.06615 8 P 0 0;4=12,6=1
P 8.45 3.01615 8 P 0 0;4=12,6=1
P 8.45 2.96615 8 P 0 0;4=12,6=1
P 8.5 2.96615 8 P 0 0;4=12,6=1
P 8.5 2.91615 8 P 0 0;4=12,6=1
P 8.4 2.96615 8 P 0 0;4=12,6=1
P 8.4 2.91615 8 P 0 0;4=12,6=1
P 8.35 3.01615 8 P 0 0;4=12,6=1
P 8.35 2.96615 8 P 0 0;4=12,6=1
P 8.4 2.81615 8 P 0 0;4=12,6=1
P 8.4 2.76615 8 P 0 0;4=12,6=1
P 8.5 2.81615 8 P 0 0;4=12,6=1
P 8.5 2.76615 8 P 0 0;4=12,6=1
P 8.45 2.76615 8 P 0 0;4=12,6=1
P 8.45 2.71615 8 P 0 0;4=12,6=1
P 8.35 2.76615 8 P 0 0;4=12,6=1
P 8.35 2.71615 8 P 0 0;4=12,6=1
P 8.5 2.66615 8 P 0 0;4=12,6=1
P 8.5 2.61615 8 P 0 0;4=12,6=1
P 8.45 2.61615 8 P 0 0;4=12,6=1
P 8.45 2.56615 8 P 0 0;4=12,6=1
P 8.4 2.66615 8 P 0 0;4=12,6=1
P 8.4 2.61615 8 P 0 0;4=12,6=1
P 2.04606004 2.61615 8 P 0 0;4=12,6=1
P 2.04606004 2.66615 8 P 0 0;4=12,6=1
P 2.09606004 2.46615 8 P 0 0;4=12,6=1
P 2.09606004 2.41615 8 P 0 0;4=12,6=1
P 2.19606004 2.46615 8 P 0 0;4=12,6=1
P 2.19606004 2.41615 8 P 0 0;4=12,6=1
P 2.14606004 2.41615 8 P 0 0;4=12,6=1
P 2.14606004 2.36615 8 P 0 0;4=12,6=1
P 2.04606004 2.41615 8 P 0 0;4=12,6=1
P 2.04606004 2.36615 8 P 0 0;4=12,6=1
P 2.19606004 2.31615 8 P 0 0;4=12,6=1
P 2.19606004 2.26615 8 P 0 0;4=12,6=1
P 2.14606004 2.26615 8 P 0 0;4=12,6=1
P 2.14606004 2.21615 8 P 0 0;4=12,6=1
P 2.09606004 2.31615 8 P 0 0;4=12,6=1
P 2.09606004 2.26615 8 P 0 0;4=12,6=1
P 2.04606004 2.26615 8 P 0 0;4=12,6=1
P 2.04606004 2.21615 8 P 0 0;4=12,6=1
P 2.09606004 2.11615 8 P 0 0;4=12,6=1
P 2.09606004 2.06615 8 P 0 0;4=12,6=1
P 2.19606004 2.11615 8 P 0 0;4=12,6=1
P 2.19606004 2.06615 8 P 0 0;4=12,6=1
P 2.14606004 2.06615 8 P 0 0;4=12,6=1
P 2.14606004 2.01615 8 P 0 0;4=12,6=1
P 2.04606004 2.06615 8 P 0 0;4=12,6=1
P 2.04606004 2.01615 8 P 0 0;4=12,6=1
P 2.19606004 1.96615 8 P 0 0;4=12,6=1
P 2.19606004 1.91615 8 P 0 0;4=12,6=1
P 2.14606004 1.91615 8 P 0 0;4=12,6=1
P 2.14606004 1.86615 8 P 0 0;4=12,6=1
P 2.09606004 1.96615 8 P 0 0;4=12,6=1
P 2.09606004 1.91615 8 P 0 0;4=12,6=1
P 2.04606004 1.91615 8 P 0 0;4=12,6=1
P 2.04606004 1.86615 8 P 0 0;4=12,6=1
P 2.09606004 3.16615 8 P 0 0;4=12,6=1
P 2.09606004 3.11615 8 P 0 0;4=12,6=1
P 2.19606004 3.16615 8 P 0 0;4=12,6=1
P 2.19606004 3.11615 8 P 0 0;4=12,6=1
P 2.14606004 3.11615 8 P 0 0;4=12,6=1
P 2.14606004 3.06615 8 P 0 0;4=12,6=1
P 2.04606004 3.11615 8 P 0 0;4=12,6=1
P 2.04606004 3.06615 8 P 0 0;4=12,6=1
P 2.19606004 3.01615 8 P 0 0;4=12,6=1
P 2.19606004 2.96615 8 P 0 0;4=12,6=1
P 2.14606004 2.96615 8 P 0 0;4=12,6=1
P 2.14606004 2.91615 8 P 0 0;4=12,6=1
P 2.09606004 3.01615 8 P 0 0;4=12,6=1
P 2.09606004 2.96615 8 P 0 0;4=12,6=1
P 2.04606004 2.96615 8 P 0 0;4=12,6=1
P 2.04606004 2.91615 8 P 0 0;4=12,6=1
P 1.99606004 2.81615 8 P 0 0;4=12,6=1
P 1.99606004 2.76615 8 P 0 0;4=12,6=1
P 2.14606004 2.81615 8 P 0 0;4=12,6=1
P 2.14606004 2.76615 8 P 0 0;4=12,6=1
P 2.19606004 2.76615 8 P 0 0;4=12,6=1
P 2.19606004 2.71615 8 P 0 0;4=12,6=1
P 2.09606004 2.76615 8 P 0 0;4=12,6=1
P 2.09606004 2.71615 8 P 0 0;4=12,6=1
P 2.14606004 2.66615 8 P 0 0;4=12,6=1
P 2.14606004 2.61615 8 P 0 0;4=12,6=1
P 2.19606004 2.61615 8 P 0 0;4=12,6=1
P 2.19606004 2.56615 8 P 0 0;4=12,6=1
P 2.09606004 2.61615 8 P 0 0;4=12,6=1
P 2.09606004 2.56615 8 P 0 0;4=12,6=1
P 2.34606004 2.56615 8 P 0 0;4=12,6=1
P 2.34606004 2.61615 8 P 0 0;4=12,6=1
P 2.34606004 2.46615 8 P 0 0;4=12,6=1
P 2.34606004 2.41615 8 P 0 0;4=12,6=1
P 2.44606004 2.46615 8 P 0 0;4=12,6=1
P 2.44606004 2.41615 8 P 0 0;4=12,6=1
P 2.49606004 2.41615 8 P 0 0;4=12,6=1
P 2.49606004 2.36615 8 P 0 0;4=12,6=1
P 2.39606004 2.41615 8 P 0 0;4=12,6=1
P 2.39606004 2.36615 8 P 0 0;4=12,6=1
P 2.44606004 2.31615 8 P 0 0;4=12,6=1
P 2.44606004 2.26615 8 P 0 0;4=12,6=1
P 2.49606004 2.26615 8 P 0 0;4=12,6=1
P 2.49606004 2.21615 8 P 0 0;4=12,6=1
P 2.39606004 2.26615 8 P 0 0;4=12,6=1
P 2.39606004 2.21615 8 P 0 0;4=12,6=1
P 2.34606004 2.31615 8 P 0 0;4=12,6=1
P 2.34606004 2.26615 8 P 0 0;4=12,6=1
P 2.34606004 2.11615 8 P 0 0;4=12,6=1
P 2.34606004 2.06615 8 P 0 0;4=12,6=1
P 2.44606004 2.11615 8 P 0 0;4=12,6=1
P 2.44606004 2.06615 8 P 0 0;4=12,6=1
P 2.49606004 2.06615 8 P 0 0;4=12,6=1
P 2.49606004 2.01615 8 P 0 0;4=12,6=1
P 2.39606004 2.06615 8 P 0 0;4=12,6=1
P 2.39606004 2.01615 8 P 0 0;4=12,6=1
P 2.44606004 1.96615 8 P 0 0;4=12,6=1
P 2.44606004 1.91615 8 P 0 0;4=12,6=1
P 2.49606004 1.91615 8 P 0 0;4=12,6=1
P 2.49606004 1.86615 8 P 0 0;4=12,6=1
P 2.39606004 1.91615 8 P 0 0;4=12,6=1
P 2.39606004 1.86615 8 P 0 0;4=12,6=1
P 2.34606004 1.96615 8 P 0 0;4=12,6=1
P 2.34606004 1.91615 8 P 0 0;4=12,6=1
P 2.34606004 3.16615 8 P 0 0;4=12,6=1
P 2.34606004 3.11615 8 P 0 0;4=12,6=1
P 2.44606004 3.16615 8 P 0 0;4=12,6=1
P 2.44606004 3.11615 8 P 0 0;4=12,6=1
P 2.49606004 3.11615 8 P 0 0;4=12,6=1
P 2.49606004 3.06615 8 P 0 0;4=12,6=1
P 2.39606004 3.11615 8 P 0 0;4=12,6=1
P 2.39606004 3.06615 8 P 0 0;4=12,6=1
P 2.44606004 3.01615 8 P 0 0;4=12,6=1
P 2.44606004 2.96615 8 P 0 0;4=12,6=1
P 2.49606004 2.96615 8 P 0 0;4=12,6=1
P 2.49606004 2.91615 8 P 0 0;4=12,6=1
P 2.39606004 2.96615 8 P 0 0;4=12,6=1
P 2.39606004 2.91615 8 P 0 0;4=12,6=1
P 2.34606004 3.01615 8 P 0 0;4=12,6=1
P 2.34606004 2.96615 8 P 0 0;4=12,6=1
P 2.39606004 2.81615 8 P 0 0;4=12,6=1
P 2.39606004 2.76615 8 P 0 0;4=12,6=1
P 2.49606004 2.81615 8 P 0 0;4=12,6=1
P 2.49606004 2.76615 8 P 0 0;4=12,6=1
P 2.44606004 2.76615 8 P 0 0;4=12,6=1
P 2.44606004 2.71615 8 P 0 0;4=12,6=1
P 2.34606004 2.76615 8 P 0 0;4=12,6=1
P 2.34606004 2.71615 8 P 0 0;4=12,6=1
P 2.49606004 2.66615 8 P 0 0;4=12,6=1
P 2.49606004 2.61615 8 P 0 0;4=12,6=1
P 2.44606004 2.61615 8 P 0 0;4=12,6=1
P 2.44606004 2.56615 8 P 0 0;4=12,6=1
P 2.39606004 2.66615 8 P 0 0;4=12,6=1
P 2.39606004 2.61615 8 P 0 0;4=12,6=1
L 4.96 5.408 4.96 5.375 7 P 0 
L 4.81 5.408 4.81 5.375 7 P 0 
L 9.48626004 4.97913996 9.48626004 4.93431998 6 P 0 
L 9.3209 4.85788002 9.3209 4.9027 6 P 0 
L 9.34453002 4.85788002 9.34453002 4.9027 6 P 0 
L 8.91933002 4.85788002 8.91933002 4.9027 6 P 0 
L 8.89571004 4.85788002 8.89571004 4.9027 6 P 0 
L 9.01381998 4.92 9.01381998 4.97913996 6 P 0 
L 8.89571004 4.97913996 8.89571004 4.93431998 6 P 0 
L 8.91933002 4.97913996 8.91933002 4.93431998 6 P 0 
L 8.94295 4.93431998 8.94295 4.97913996 6 P 0 
L 8.96656998 4.97913996 8.96656998 4.93431998 6 P 0 
L 8.9902 4.97913996 8.9902 4.93431998 6 P 0 
L 8.1563 4.85788002 8.1563 4.9027 6 P 0 
L 8.17993002 4.85788002 8.17993002 4.9027 6 P 0 
L 8.22716998 4.97913996 8.22716998 4.93431998 6 P 0 
L 8.25078996 4.97913996 8.25078996 4.93431998 6 P 0 
L 8.29803996 4.97913996 8.29803996 4.93431998 6 P 0 
L 8.32166004 4.97913996 8.32166004 4.93431998 6 P 0 
L 7.73111004 4.85788002 7.73111004 4.9027 6 P 0 
L 7.75473002 4.85788002 7.75473002 4.9027 6 P 0 
L 7.73111004 4.97913996 7.73111004 4.93431998 6 P 0 
L 7.75473002 4.97913996 7.75473002 4.93431998 6 P 0 
L 7.80196998 4.97913996 7.80196998 4.93431998 6 P 0 
L 7.8256 4.97913996 7.8256 4.93431998 6 P 0 
L 3.48271998 4.97913996 3.48271998 4.93983996 6 P 0 
L 3.34098996 4.85788002 3.34098996 4.90173996 6 P 0 
L 3.31736004 4.85788002 3.31736004 4.90173996 6 P 0 
L 2.91578996 4.85788002 2.91578996 4.90173996 6 P 0 
L 2.89216998 4.85788002 2.89216998 4.90173996 6 P 0 
L 2.91578996 4.97913996 2.91578996 4.93528002 6 P 0 
L 2.98666004 4.97913996 2.98666004 4.93528002 6 P 0 
L 2.96303002 4.97913996 2.96303002 4.93528002 6 P 0 
L 2.89216998 4.97913996 2.89216998 4.93528002 6 P 0 
L 1.75118996 4.85788002 1.75118996 4.90173996 6 P 0 
L 1.72756998 4.85788002 1.72756998 4.90173996 6 P 0 
L 1.75118996 4.97913996 1.75118996 4.93528002 6 P 0 
L 1.72756998 4.97913996 1.72756998 4.93528002 6 P 0 
L 1.82206004 4.97913996 1.82206004 4.93528002 6 P 0 
L 1.79843002 4.97913996 1.79843002 4.93528002 6 P 0 
L 2.17638996 4.85788002 2.17638996 4.90173996 6 P 0 
L 2.15276004 4.85788002 2.15276004 4.90173996 6 P 0 
L 2.31811998 4.97913996 2.31811998 4.93528002 6 P 0 
L 2.2945 4.97913996 2.2945 4.93528002 6 P 0 
L 2.24725 4.97913996 2.24725 4.93528002 6 P 0 
L 2.22363002 4.97913996 2.22363002 4.93528002 6 P 0 
S P 0
OB 8.946380019685 4.70573996063 I
OC 8.946380019685 4.70573996063 8.940619980315 4.70573996063 Y
OE
SE
P 8.94061998 4.70573996 9 P 0 0;4=13,6=1
S P 0
OB 9.02501003937 4.70573996063 I
OC 9.02501003937 4.70573996063 9.01925 4.70573996063 Y
OE
SE
P 9.01925 4.70573996 9 P 0 0;4=13,6=1
S P 0
OB 9.08501003937 4.70573996063 I
OC 9.08501003937 4.70573996063 9.07925 4.70573996063 Y
OE
SE
P 9.07925 4.70573996 9 P 0 0;4=13,6=1
S P 0
OB 8.74155 4.70573996063 I
OC 8.74155 4.70573996063 8.73578996063 4.70573996063 Y
OE
SE
P 8.73578996 4.70573996 9 P 0 0;4=13,6=1
S P 0
OB 8.80155 4.70573996063 I
OC 8.80155 4.70573996063 8.79578996063 4.70573996063 Y
OE
SE
P 8.79578996 4.70573996 9 P 0 0;4=13,6=1
S P 0
OB 8.87241003937 4.744180019685 I
OC 8.87241003937 4.744180019685 8.86665 4.744180019685 Y
OE
SE
P 8.86665 4.74418002 9 P 0 0;4=13,6=1
S P 0
OB 8.81241003937 4.744180019685 I
OC 8.81241003937 4.744180019685 8.80665 4.744180019685 Y
OE
SE
P 8.80665 4.74418002 9 P 0 0;4=13,6=1
S P 0
OB 9.43933996063 4.744180019685 I
OC 9.43933996063 4.744180019685 9.433580019685 4.744180019685 Y
OE
SE
P 9.43358002 4.74418002 9 P 0 0;4=13,6=1
S P 0
OB 9.521069980315 4.68098996063 I
OC 9.521069980315 4.68098996063 9.51531003937 4.68098996063 Y
OE
SE
P 9.51531004 4.68098996 9 P 0 0;4=13,6=1
S P 0
OB 9.581069980315 4.68098996063 I
OC 9.581069980315 4.68098996063 9.57531003937 4.68098996063 Y
OE
SE
P 9.57531004 4.68098996 9 P 0 0;4=13,6=1
S P 0
OB 9.45021003937 4.62573996063 I
OC 9.45021003937 4.62573996063 9.44445 4.62573996063 Y
OE
SE
P 9.44445 4.62573996 9 P 0 0;4=13,6=1
S P 0
OB 9.51021003937 4.62573996063 I
OC 9.51021003937 4.62573996063 9.50445 4.62573996063 Y
OE
SE
P 9.50445 4.62573996 9 P 0 0;4=13,6=1
S P 0
OB 9.23761003937 4.68073996063 I
OC 9.23761003937 4.68073996063 9.23185 4.68073996063 Y
OE
SE
P 9.23185 4.68073996 9 P 0 0;4=13,6=1
S P 0
OB 9.29761003937 4.68073996063 I
OC 9.29761003937 4.68073996063 9.29185 4.68073996063 Y
OE
SE
P 9.29185 4.68073996 9 P 0 0;4=13,6=1
S P 0
OB 9.16673996063 4.744180019685 I
OC 9.16673996063 4.744180019685 9.160980019685 4.744180019685 Y
OE
SE
P 9.16098002 4.74418002 9 P 0 0;4=13,6=1
S P 0
OB 9.37933996063 4.744180019685 I
OC 9.37933996063 4.744180019685 9.373580019685 4.744180019685 Y
OE
SE
P 9.37358002 4.74418002 9 P 0 0;4=13,6=1
S P 0
OB 9.22673996063 4.744180019685 I
OC 9.22673996063 4.744180019685 9.220980019685 4.744180019685 Y
OE
SE
P 9.22098002 4.74418002 9 P 0 0;4=13,6=1
S P 0
OB 9.521069980315 5.17873996063 I
OC 9.521069980315 5.17873996063 9.51531003937 5.17873996063 Y
OE
SE
P 9.51531004 5.17873996 9 P 0 0;4=13,6=1
S P 0
OB 9.581069980315 5.17873996063 I
OC 9.581069980315 5.17873996063 9.57531003937 5.17873996063 Y
OE
SE
P 9.57531004 5.17873996 9 P 0 0;4=13,6=1
S P 0
OB 9.43933996063 5.181280019685 I
OC 9.43933996063 5.181280019685 9.433580019685 5.181280019685 Y
OE
SE
P 9.43358002 5.18128002 9 P 0 0;4=13,6=1
S P 0
OB 9.23761003937 5.181280019685 I
OC 9.23761003937 5.181280019685 9.23185 5.181280019685 Y
OE
SE
P 9.23185 5.18128002 9 P 0 0;4=13,6=1
S P 0
OB 9.29761003937 5.181280019685 I
OC 9.29761003937 5.181280019685 9.29185 5.181280019685 Y
OE
SE
P 9.29185 5.18128002 9 P 0 0;4=13,6=1
S P 0
OB 9.37933996063 5.181280019685 I
OC 9.37933996063 5.181280019685 9.373580019685 5.181280019685 Y
OE
SE
P 9.37358002 5.18128002 9 P 0 0;4=13,6=1
S P 0
OB 9.368469980315 5.14223996063 I
OC 9.368469980315 5.14223996063 9.36271003937 5.14223996063 Y
OE
SE
P 9.36271004 5.14223996 9 P 0 0;4=13,6=1
S P 0
OB 9.308469980315 5.14223996063 I
OC 9.308469980315 5.14223996063 9.30271003937 5.14223996063 Y
OE
SE
P 9.30271004 5.14223996 9 P 0 0;4=13,6=1
S P 0
OB 9.155869980315 5.09223996063 I
OC 9.155869980315 5.09223996063 9.15011003937 5.09223996063 Y
OE
SE
P 9.15011004 5.09223996 9 P 0 0;4=13,6=1
S P 0
OB 9.095869980315 5.09223996063 I
OC 9.095869980315 5.09223996063 9.09011003937 5.09223996063 Y
OE
SE
P 9.09011004 5.09223996 9 P 0 0;4=13,6=1
S P 0
OB 9.08501003937 5.20373996063 I
OC 9.08501003937 5.20373996063 9.07925 5.20373996063 Y
OE
SE
P 9.07925 5.20373996 9 P 0 0;4=13,6=1
S P 0
OB 9.02501003937 5.20373996063 I
OC 9.02501003937 5.20373996063 9.01925 5.20373996063 Y
OE
SE
P 9.01925 5.20373996 9 P 0 0;4=13,6=1
S P 0
OB 8.940169980315 5.20876003937 I
OC 8.940169980315 5.20876003937 8.93441003937 5.20876003937 Y
OE
SE
P 8.93441004 5.20876004 9 P 0 0;4=13,6=1
S P 0
OB 8.74155 5.17873996063 I
OC 8.74155 5.17873996063 8.73578996063 5.17873996063 Y
OE
SE
P 8.73578996 5.17873996 9 P 0 0;4=13,6=1
S P 0
OB 8.80155 5.17873996063 I
OC 8.80155 5.17873996063 8.79578996063 5.17873996063 Y
OE
SE
P 8.79578996 5.17873996 9 P 0 0;4=13,6=1
S P 0
OB 8.880169980315 5.20876003937 I
OC 8.880169980315 5.20876003937 8.87441003937 5.20876003937 Y
OE
SE
P 8.87441004 5.20876004 9 P 0 0;4=13,6=1
S P 0
OB 7.64781003937 4.744180019685 I
OC 7.64781003937 4.744180019685 7.64205 4.744180019685 Y
OE
SE
P 7.64205 4.74418002 9 P 0 0;4=13,6=1
S P 0
OB 7.70781003937 4.744180019685 I
OC 7.70781003937 4.744180019685 7.70205 4.744180019685 Y
OE
SE
P 7.70205 4.74418002 9 P 0 0;4=13,6=1
S P 0
OB 7.63695 4.66826003937 I
OC 7.63695 4.66826003937 7.63118996063 4.66826003937 Y
OE
SE
P 7.63118996 4.66826004 9 P 0 0;4=13,6=1
S P 0
OB 7.57695 4.66826003937 I
OC 7.57695 4.66826003937 7.57118996063 4.66826003937 Y
OE
SE
P 7.57118996 4.66826004 9 P 0 0;4=13,6=1
S P 0
OB 7.92041003937 4.61826003937 I
OC 7.92041003937 4.61826003937 7.91465 4.61826003937 Y
OE
SE
P 7.91465 4.61826004 9 P 0 0;4=13,6=1
S P 0
OB 7.78955 4.744180019685 I
OC 7.78955 4.744180019685 7.78378996063 4.744180019685 Y
OE
SE
P 7.78378996 4.74418002 9 P 0 0;4=13,6=1
S P 0
OB 7.84955 4.744180019685 I
OC 7.84955 4.744180019685 7.84378996063 4.744180019685 Y
OE
SE
P 7.84378996 4.74418002 9 P 0 0;4=13,6=1
S P 0
OB 7.86041003937 4.61826003937 I
OC 7.86041003937 4.61826003937 7.85465 4.61826003937 Y
OE
SE
P 7.85465 4.61826004 9 P 0 0;4=13,6=1
S P 0
OB 8.07301003937 4.744180019685 I
OC 8.07301003937 4.744180019685 8.06725 4.744180019685 Y
OE
SE
P 8.06725 4.74418002 9 P 0 0;4=13,6=1
S P 0
OB 8.13301003937 4.744180019685 I
OC 8.13301003937 4.744180019685 8.12725 4.744180019685 Y
OE
SE
P 8.12725 4.74418002 9 P 0 0;4=13,6=1
S P 0
OB 8.027830019685 4.62815 I
OC 8.027830019685 4.62815 8.022069980315 4.62815 Y
OE
SE
P 8.02206998 4.62815 9 P 0 0;4=13,6=1
S P 0
OB 8.087830019685 4.62815 I
OC 8.087830019685 4.62815 8.082069980315 4.62815 Y
OE
SE
P 8.08206998 4.62815 9 P 0 0;4=13,6=1
S P 0
OB 8.416469980315 4.70326003937 I
OC 8.416469980315 4.70326003937 8.41071003937 4.70326003937 Y
OE
SE
P 8.41071004 4.70326004 9 P 0 0;4=13,6=1
S P 0
OB 8.356469980315 4.70326003937 I
OC 8.356469980315 4.70326003937 8.35071003937 4.70326003937 Y
OE
SE
P 8.35071004 4.70326004 9 P 0 0;4=13,6=1
S P 0
OB 8.21473996063 4.744180019685 I
OC 8.21473996063 4.744180019685 8.208980019685 4.744180019685 Y
OE
SE
P 8.20898002 4.74418002 9 P 0 0;4=13,6=1
S P 0
OB 8.27473996063 4.744180019685 I
OC 8.27473996063 4.744180019685 8.268980019685 4.744180019685 Y
OE
SE
P 8.26898002 4.74418002 9 P 0 0;4=13,6=1
S P 0
OB 8.21785 4.62826003937 I
OC 8.21785 4.62826003937 8.21208996063 4.62826003937 Y
OE
SE
P 8.21208996 4.62826004 9 P 0 0;4=13,6=1
S P 0
OB 8.27785 4.62826003937 I
OC 8.27785 4.62826003937 8.27208996063 4.62826003937 Y
OE
SE
P 8.27208996 4.62826004 9 P 0 0;4=13,6=1
S P 0
OB 8.203869980315 5.09223996063 I
OC 8.203869980315 5.09223996063 8.19811003937 5.09223996063 Y
OE
SE
P 8.19811004 5.09223996 9 P 0 0;4=13,6=1
S P 0
OB 8.13301003937 5.13026003937 I
OC 8.13301003937 5.13026003937 8.12725 5.13026003937 Y
OE
SE
P 8.12725 5.13026004 9 P 0 0;4=13,6=1
S P 0
OB 8.07301003937 5.13026003937 I
OC 8.07301003937 5.13026003937 8.06725 5.13026003937 Y
OE
SE
P 8.06725 5.13026004 9 P 0 0;4=13,6=1
S P 0
OB 7.92041003937 5.13026003937 I
OC 7.92041003937 5.13026003937 7.91465 5.13026003937 Y
OE
SE
P 7.91465 5.13026004 9 P 0 0;4=13,6=1
S P 0
OB 7.931269980315 5.09223996063 I
OC 7.931269980315 5.09223996063 7.92551003937 5.09223996063 Y
OE
SE
P 7.92551004 5.09223996 9 P 0 0;4=13,6=1
S P 0
OB 7.991269980315 5.09223996063 I
OC 7.991269980315 5.09223996063 7.98551003937 5.09223996063 Y
OE
SE
P 7.98551004 5.09223996 9 P 0 0;4=13,6=1
S P 0
OB 7.86041003937 5.13026003937 I
OC 7.86041003937 5.13026003937 7.85465 5.13026003937 Y
OE
SE
P 7.85465 5.13026004 9 P 0 0;4=13,6=1
S P 0
OB 7.6478 5.09223996063 I
OC 7.6478 5.09223996063 7.64203996063 5.09223996063 Y
OE
SE
P 7.64203996 5.09223996 9 P 0 0;4=13,6=1
S P 0
OB 7.7078 5.09223996063 I
OC 7.7078 5.09223996063 7.70203996063 5.09223996063 Y
OE
SE
P 7.70203996 5.09223996 9 P 0 0;4=13,6=1
S P 0
OB 7.57695 5.13026003937 I
OC 7.57695 5.13026003937 7.57118996063 5.13026003937 Y
OE
SE
P 7.57118996 5.13026004 9 P 0 0;4=13,6=1
S P 0
OB 7.63695 5.13026003937 I
OC 7.63695 5.13026003937 7.63118996063 5.13026003937 Y
OE
SE
P 7.63118996 5.13026004 9 P 0 0;4=13,6=1
L 9.43901004 4.928 9.43901004 4.97913996 6 P 0 
S P 0
OB 3.234069980315 4.68073996063 I
OC 3.234069980315 4.68073996063 3.22831003937 4.68073996063 Y
OE
SE
S P 0
OB 3.294069980315 4.68073996063 I
OC 3.294069980315 4.68073996063 3.28831003937 4.68073996063 Y
OE
SE
S P 0
OB 2.73801003937 4.70573996063 I
OC 2.73801003937 4.70573996063 2.73225 4.70573996063 Y
OE
SE
P 2.73225 4.70573996 9 P 0 0;4=13,6=1
S P 0
OB 2.79801003937 4.70573996063 I
OC 2.79801003937 4.70573996063 2.79225 4.70573996063 Y
OE
SE
P 2.79225 4.70573996 9 P 0 0;4=13,6=1
S P 0
OB 3.234069980315 5.181280019685 I
OC 3.234069980315 5.181280019685 3.22831003937 5.181280019685 Y
OE
SE
P 3.22831004 5.18128002 9 P 0 0;4=13,6=1
S P 0
OB 3.294069980315 5.181280019685 I
OC 3.294069980315 5.181280019685 3.28831003937 5.181280019685 Y
OE
SE
P 3.28831004 5.18128002 9 P 0 0;4=13,6=1
P 3.01571004 5.20373996 9 P 0 0;4=13,6=1
P 3.07571004 5.20373996 9 P 0 0;4=13,6=1
S P 0
OB 2.73801003937 5.17873996063 I
OC 2.73801003937 5.17873996063 2.73225 5.17873996063 Y
OE
SE
P 2.73225 5.17873996 9 P 0 0;4=13,6=1
S P 0
OB 2.79801003937 5.17873996063 I
OC 2.79801003937 5.17873996063 2.79225 5.17873996063 Y
OE
SE
P 2.79225 5.17873996 9 P 0 0;4=13,6=1
S P 0
OB 1.57341003937 4.66826003937 I
OC 1.57341003937 4.66826003937 1.56765 4.66826003937 Y
OE
SE
P 1.56765 4.66826004 9 P 0 0;4=13,6=1
S P 0
OB 1.63341003937 4.66826003937 I
OC 1.63341003937 4.66826003937 1.62765 4.66826003937 Y
OE
SE
P 1.62765 4.66826004 9 P 0 0;4=13,6=1
S P 0
OB 1.57341003937 5.13026003937 I
OC 1.57341003937 5.13026003937 1.56765 5.13026003937 Y
OE
SE
P 1.56765 5.13026004 9 P 0 0;4=13,6=1
S P 0
OB 1.63341003937 5.13026003937 I
OC 1.63341003937 5.13026003937 1.62765 5.13026003937 Y
OE
SE
P 1.62765 5.13026004 9 P 0 0;4=13,6=1
S P 0
OB 1.916869980315 5.13026003937 I
OC 1.916869980315 5.13026003937 1.91111003937 5.13026003937 Y
OE
SE
P 1.91111004 5.13026004 9 P 0 0;4=13,6=1
S P 0
OB 1.856869980315 5.13026003937 I
OC 1.856869980315 5.13026003937 1.85111003937 5.13026003937 Y
OE
SE
P 1.85111004 5.13026004 9 P 0 0;4=13,6=1
P 8.475 3.69115 10 P 0 0;2,4=11,6=0
P 8.475 3.84115 10 P 0 0;2,4=11,6=0
P 8.425 3.54115 10 P 0 0;2,4=11,6=0
P 8.475 3.54115 10 P 0 0;2,4=11,6=0
P 8.475 3.24115 10 P 0 0;2,4=11,6=0
P 8.425 3.34115 10 P 0 0;2,4=11,6=0
P 8.475 3.39115 10 P 0 0;2,4=11,6=0
P 8.225 3.69115 10 P 0 0;2,4=11,6=0
P 8.275 3.74115 10 P 0 0;2,4=11,6=0
P 8.225 3.74115 10 P 0 0;2,4=11,6=0
P 8.175 3.74115 10 P 0 0;2,4=11,6=0
P 8.225 3.79115 10 P 0 0;2,4=11,6=0
P 8.225 3.84115 10 P 0 0;2,4=11,6=0
P 8.225 3.44115 10 P 0 0;2,4=11,6=0
P 8.275 3.49115 10 P 0 0;2,4=11,6=0
P 8.225 3.49115 10 P 0 0;2,4=11,6=0
P 8.175 3.49115 10 P 0 0;2,4=11,6=0
P 8.175 3.54115 10 P 0 0;2,4=11,6=0
P 8.175 3.59115 10 P 0 0;2,4=11,6=0
P 8.225 3.59115 10 P 0 0;2,4=11,6=0
P 8.225 3.64115 10 P 0 0;2,4=11,6=0
P 8.275 3.59115 10 P 0 0;2,4=11,6=0
P 8.375 3.54115 10 P 0 0;2,4=11,6=0
P 8.225 3.24115 10 P 0 0;2,4=11,6=0
P 8.225 3.29115 10 P 0 0;2,4=11,6=0
P 8.175 3.34115 10 P 0 0;2,4=11,6=0
P 8.225 3.34115 10 P 0 0;2,4=11,6=0
P 8.275 3.34115 10 P 0 0;2,4=11,6=0
P 8.225 3.39115 10 P 0 0;2,4=11,6=0
P 8.075 3.49115 10 P 0 0;2,4=11,6=0
P 8.025 3.54115 10 P 0 0;2,4=11,6=0
P 8.125 3.54115 10 P 0 0;2,4=11,6=0
P 8.075 3.34115 10 P 0 0;2,4=11,6=0
P 8.025 3.39115 10 P 0 0;2,4=11,6=0
L 3.07691004 4.81401998 3.08113996 4.81825 6 P 0 
L 3.08113996 4.81825 3.08113996 4.85788002 6 P 0 
L 3.15398002 4.81401998 3.15201004 4.81598996 6 P 0 
L 3.15201004 4.81598996 3.15201004 4.85788002 6 P 0 
P 10.96161004 3.79115 10 P 0 0;2,4=11,6=0
P 11.01161004 3.79115 10 P 0 0;2,4=11,6=0
P 11.06161004 3.64115 10 P 0 0;2,4=11,6=0
P 10.96161004 3.64115 10 P 0 0;2,4=11,6=0
P 11.01161004 3.64115 10 P 0 0;2,4=11,6=0
P 11.06161004 3.49115 10 P 0 0;2,4=11,6=0
P 10.96161004 3.49115 10 P 0 0;2,4=11,6=0
P 11.01161004 3.49115 10 P 0 0;2,4=11,6=0
P 11.06161004 3.34115 10 P 0 0;2,4=11,6=0
P 10.96161004 3.34115 10 P 0 0;2,4=11,6=0
P 11.01161004 3.34115 10 P 0 0;2,4=11,6=0
P 11.01161004 3.19115 10 P 0 0;2,4=11,6=0
P 10.96161004 3.19115 10 P 0 0;2,4=11,6=0
P 11.06161004 3.19115 10 P 0 0;2,4=11,6=0
P 11.01161004 3.04115 10 P 0 0;2,4=11,6=0
P 10.96161004 3.04115 10 P 0 0;2,4=11,6=0
P 11.06161004 3.04115 10 P 0 0;2,4=11,6=0
P 11.01161004 2.89115 10 P 0 0;2,4=11,6=0
P 10.96161004 2.89115 10 P 0 0;2,4=11,6=0
P 11.06161004 2.89115 10 P 0 0;2,4=11,6=0
P 10.71161004 3.79115 10 P 0 0;2,4=11,6=0
P 10.76161004 3.79115 10 P 0 0;2,4=11,6=0
P 10.81161004 3.79115 10 P 0 0;2,4=11,6=0
P 10.91161004 3.64115 10 P 0 0;2,4=11,6=0
P 10.91161004 3.79115 10 P 0 0;2,4=11,6=0
P 10.86161004 3.79115 10 P 0 0;2,4=11,6=0
P 10.71161004 3.49115 10 P 0 0;2,4=11,6=0
P 10.76161004 3.49115 10 P 0 0;2,4=11,6=0
P 10.81161004 3.49115 10 P 0 0;2,4=11,6=0
P 10.71161004 3.64115 10 P 0 0;2,4=11,6=0
P 10.76161004 3.64115 10 P 0 0;2,4=11,6=0
P 10.81161004 3.64115 10 P 0 0;2,4=11,6=0
P 10.86161004 3.64115 10 P 0 0;2,4=11,6=0
P 10.91161004 3.49115 10 P 0 0;2,4=11,6=0
P 10.86161004 3.49115 10 P 0 0;2,4=11,6=0
P 10.71161004 3.19115 10 P 0 0;2,4=11,6=0
P 10.71161004 3.34115 10 P 0 0;2,4=11,6=0
P 10.76161004 3.19115 10 P 0 0;2,4=11,6=0
P 10.81161004 3.19115 10 P 0 0;2,4=11,6=0
P 10.76161004 3.34115 10 P 0 0;2,4=11,6=0
P 10.81161004 3.34115 10 P 0 0;2,4=11,6=0
P 10.91161004 3.34115 10 P 0 0;2,4=11,6=0
P 10.86161004 3.34115 10 P 0 0;2,4=11,6=0
P 10.86161004 3.19115 10 P 0 0;2,4=11,6=0
P 10.91161004 3.19115 10 P 0 0;2,4=11,6=0
P 10.71161004 3.04115 10 P 0 0;2,4=11,6=0
P 10.76161004 3.04115 10 P 0 0;2,4=11,6=0
P 10.81161004 3.04115 10 P 0 0;2,4=11,6=0
P 10.86161004 3.04115 10 P 0 0;2,4=11,6=0
P 10.91161004 3.04115 10 P 0 0;2,4=11,6=0
P 10.91161004 2.89115 10 P 0 0;2,4=11,6=0
P 10.71161004 2.89115 10 P 0 0;2,4=11,6=0
P 10.76161004 2.89115 10 P 0 0;2,4=11,6=0
P 10.81161004 2.89115 10 P 0 0;2,4=11,6=0
P 10.86161004 2.89115 10 P 0 0;2,4=11,6=0
P 10.61161004 3.79115 10 P 0 0;2,4=11,6=0
P 10.66161004 3.64115 10 P 0 0;2,4=11,6=0
P 10.66161004 3.79115 10 P 0 0;2,4=11,6=0
P 10.61161004 3.49115 10 P 0 0;2,4=11,6=0
P 10.66161004 3.49115 10 P 0 0;2,4=11,6=0
P 10.61161004 3.64115 10 P 0 0;2,4=11,6=0
P 10.61161004 3.19115 10 P 0 0;2,4=11,6=0
P 10.66161004 3.19115 10 P 0 0;2,4=11,6=0
P 10.61161004 3.34115 10 P 0 0;2,4=11,6=0
P 10.66161004 3.34115 10 P 0 0;2,4=11,6=0
P 10.61161004 3.04115 10 P 0 0;2,4=11,6=0
P 10.66161004 3.04115 10 P 0 0;2,4=11,6=0
P 10.61161004 2.89115 10 P 0 0;2,4=11,6=0
P 10.66161004 2.89115 10 P 0 0;2,4=11,6=0
P 4.65768002 2.19115 10 P 0 0;2,4=11,6=0
P 4.80768002 2.79115 10 P 0 0;2,4=11,6=0
P 4.75768002 2.79115 10 P 0 0;2,4=11,6=0
P 4.65768002 2.79115 10 P 0 0;2,4=11,6=0
P 4.65768002 2.74115 10 P 0 0;2,4=11,6=0
P 4.75768002 2.74115 10 P 0 0;2,4=11,6=0
P 4.60768002 2.69115 10 P 0 0;2,4=11,6=0
P 4.70768002 2.69115 10 P 0 0;2,4=11,6=0
P 4.80768002 2.69115 10 P 0 0;2,4=11,6=0
P 4.80768002 2.64115 10 P 0 0;2,4=11,6=0
P 4.80768002 2.59115 10 P 0 0;2,4=11,6=0
P 4.75768002 2.59115 10 P 0 0;2,4=11,6=0
P 4.65768002 2.59115 10 P 0 0;2,4=11,6=0
P 4.60768002 2.54115 10 P 0 0;2,4=11,6=0
P 4.65768002 2.54115 10 P 0 0;2,4=11,6=0
P 4.70768002 2.54115 10 P 0 0;2,4=11,6=0
P 4.75768002 2.54115 10 P 0 0;2,4=11,6=0
P 4.80768002 2.54115 10 P 0 0;2,4=11,6=0
P 5.05768002 2.89115 10 P 0 0;2,4=11,6=0
P 4.95768002 2.89115 10 P 0 0;2,4=11,6=0
P 5.00768002 2.89115 10 P 0 0;2,4=11,6=0
P 4.90768002 2.89115 10 P 0 0;2,4=11,6=0
P 4.85768002 2.89115 10 P 0 0;2,4=11,6=0
P 5.05768002 3.04115 10 P 0 0;2,4=11,6=0
P 4.95768002 3.04115 10 P 0 0;2,4=11,6=0
P 5.00768002 3.04115 10 P 0 0;2,4=11,6=0
P 4.90768002 3.04115 10 P 0 0;2,4=11,6=0
P 4.85768002 3.04115 10 P 0 0;2,4=11,6=0
P 5.05768002 3.19115 10 P 0 0;2,4=11,6=0
P 4.95768002 3.19115 10 P 0 0;2,4=11,6=0
P 5.00768002 3.19115 10 P 0 0;2,4=11,6=0
P 4.90768002 3.19115 10 P 0 0;2,4=11,6=0
P 4.85768002 3.19115 10 P 0 0;2,4=11,6=0
P 5.00768002 3.34115 10 P 0 0;2,4=11,6=0
P 4.95768002 3.34115 10 P 0 0;2,4=11,6=0
P 5.05768002 3.34115 10 P 0 0;2,4=11,6=0
P 4.85768002 3.34115 10 P 0 0;2,4=11,6=0
P 4.90768002 3.34115 10 P 0 0;2,4=11,6=0
P 5.00768002 3.79115 10 P 0 0;2,4=11,6=0
P 4.95768002 3.79115 10 P 0 0;2,4=11,6=0
P 4.85768002 3.79115 10 P 0 0;2,4=11,6=0
P 4.90768002 3.79115 10 P 0 0;2,4=11,6=0
P 5.00768002 3.49115 10 P 0 0;2,4=11,6=0
P 4.95768002 3.49115 10 P 0 0;2,4=11,6=0
P 5.05768002 3.49115 10 P 0 0;2,4=11,6=0
P 4.85768002 3.49115 10 P 0 0;2,4=11,6=0
P 4.90768002 3.49115 10 P 0 0;2,4=11,6=0
P 5.00768002 3.64115 10 P 0 0;2,4=11,6=0
P 4.95768002 3.64115 10 P 0 0;2,4=11,6=0
P 5.05768002 3.64115 10 P 0 0;2,4=11,6=0
P 4.85768002 3.64115 10 P 0 0;2,4=11,6=0
P 4.90768002 3.64115 10 P 0 0;2,4=11,6=0
L 5.05768002 2.79115 5.08268002 2.76615 9 P 0 
P 5.05768002 2.79115 10 P 0 0;2,4=11,6=0
P 5.08268002 2.76615 8 P 0 0;4=12,6=1
L 5.00768002 2.79115 5.03268002 2.76615 9 P 0 
P 5.00768002 2.79115 10 P 0 0;2,4=11,6=0
P 5.03268002 2.76615 8 P 0 0;4=12,6=1
L 5.00768002 2.74115 5.03268002 2.71615 9 P 0 
P 5.00768002 2.74115 10 P 0 0;2,4=11,6=0
P 5.03268002 2.71615 8 P 0 0;4=12,6=1
L 4.90768002 2.79115 4.93268002 2.76615 9 P 0 
P 4.90768002 2.79115 10 P 0 0;2,4=11,6=0
P 4.93268002 2.76615 8 P 0 0;4=12,6=1
L 4.95768002 2.79115 4.98268002 2.76615 9 P 0 
P 4.95768002 2.79115 10 P 0 0;2,4=11,6=0
P 4.98268002 2.76615 8 P 0 0;4=12,6=1
L 4.90768002 2.74115 4.93268002 2.71615 9 P 0 
P 4.90768002 2.74115 10 P 0 0;2,4=11,6=0
P 4.93268002 2.71615 8 P 0 0;4=12,6=1
L 5.05768002 2.69115 5.08268002 2.66615 9 P 0 
P 5.05768002 2.69115 10 P 0 0;2,4=11,6=0
P 5.08268002 2.66615 8 P 0 0;4=12,6=1
L 4.95768002 2.69115 4.98268002 2.66615 9 P 0 
P 4.95768002 2.69115 10 P 0 0;2,4=11,6=0
P 4.98268002 2.66615 8 P 0 0;4=12,6=1
L 5.00768002 2.59115 5.03268002 2.56615 9 P 0 
P 5.00768002 2.59115 10 P 0 0;2,4=11,6=0
P 5.03268002 2.56615 8 P 0 0;4=12,6=1
L 4.90768002 2.59115 4.93268002 2.56615 9 P 0 
P 4.90768002 2.59115 10 P 0 0;2,4=11,6=0
P 4.93268002 2.56615 8 P 0 0;4=12,6=1
P 4.95768002 2.49115 10 P 0 0;2,4=11,6=0
L 4.95768002 2.49115 4.98268002 2.46615 9 P 0 
P 4.98268002 2.46615 8 P 0 0;4=12,6=1
L 4.98268002 2.51615 5.00768002 2.54115 9 P 0 
P 5.00768002 2.54115 10 P 0 0;2,4=11,6=0
P 4.95768002 2.54115 10 P 0 0;2,4=11,6=0
L 4.95768002 2.54115 4.98268002 2.51615 9 P 0 
P 4.98268002 2.51615 8 P 0 0;4=12,6=1
P 4.90768002 2.54115 10 P 0 0;2,4=11,6=0
L 4.90768002 2.54115 4.93268002 2.51615 9 P 0 
P 4.93268002 2.51615 8 P 0 0;4=12,6=1
P 5.05768002 2.54115 10 P 0 0;2,4=11,6=0
L 5.05768002 2.54115 5.08268002 2.51615 9 P 0 
P 5.08268002 2.51615 8 P 0 0;4=12,6=1
P 5.05768002 2.49115 10 P 0 0;2,4=11,6=0
L 5.05768002 2.49115 5.08268002 2.46615 9 P 0 
P 5.08268002 2.46615 8 P 0 0;4=12,6=1
P 5.00768002 2.24115 10 P 0 0;2,4=11,6=0
L 5.00768002 2.24115 5.03268002 2.21615 9 P 0 
P 5.03268002 2.21615 8 P 0 0;4=12,6=1
P 4.90768002 2.24115 10 P 0 0;2,4=11,6=0
L 4.90768002 2.24115 4.93268002 2.21615 9 P 0 
P 4.93268002 2.21615 8 P 0 0;4=12,6=1
P 4.95768002 2.34115 10 P 0 0;2,4=11,6=0
L 4.95768002 2.34115 4.98268002 2.31615 9 P 0 
P 4.98268002 2.31615 8 P 0 0;4=12,6=1
P 4.90768002 2.39115 10 P 0 0;2,4=11,6=0
L 4.90768002 2.39115 4.93268002 2.36615 9 P 0 
P 4.93268002 2.36615 8 P 0 0;4=12,6=1
P 5.05768002 2.34115 10 P 0 0;2,4=11,6=0
L 5.05768002 2.34115 5.08268002 2.31615 9 P 0 
P 5.08268002 2.31615 8 P 0 0;4=12,6=1
P 5.05768002 2.19115 10 P 0 0;2,4=11,6=0
L 5.05768002 2.19115 5.08268002 2.16615 9 P 0 
P 5.08268002 2.16615 8 P 0 0;4=12,6=1
P 4.90768002 2.19115 10 P 0 0;2,4=11,6=0
L 4.90768002 2.19115 4.93268002 2.16615 9 P 0 
P 4.93268002 2.16615 8 P 0 0;4=12,6=1
P 4.95768002 2.19115 10 P 0 0;2,4=11,6=0
L 4.95768002 2.19115 4.98268002 2.16615 9 P 0 
P 4.98268002 2.16615 8 P 0 0;4=12,6=1
P 4.90768002 1.99115 10 P 0 0;2,4=11,6=0
L 4.90768002 1.99115 4.93268002 1.96615 9 P 0 
P 4.93268002 1.96615 8 P 0 0;4=12,6=1
P 5.00768002 1.99115 10 P 0 0;2,4=11,6=0
L 5.00768002 1.99115 5.03268002 1.96615 9 P 0 
P 5.03268002 1.96615 8 P 0 0;4=12,6=1
P 5.00768002 2.14115 10 P 0 0;2,4=11,6=0
L 5.00768002 2.14115 5.03268002 2.11615 9 P 0 
P 5.03268002 2.11615 8 P 0 0;4=12,6=1
P 4.90768002 2.14115 10 P 0 0;2,4=11,6=0
L 4.90768002 2.14115 4.93268002 2.11615 9 P 0 
P 4.93268002 2.11615 8 P 0 0;4=12,6=1
P 4.95768002 2.04115 10 P 0 0;2,4=11,6=0
L 4.95768002 2.04115 4.98268002 2.01615 9 P 0 
P 4.98268002 2.01615 8 P 0 0;4=12,6=1
P 5.05768002 2.04115 10 P 0 0;2,4=11,6=0
L 5.05768002 2.04115 5.08268002 2.01615 9 P 0 
P 5.08268002 2.01615 8 P 0 0;4=12,6=1
P 4.95768002 1.89115 10 P 0 0;2,4=11,6=0
L 4.95768002 1.89115 4.98268002 1.86615 9 P 0 
P 4.98268002 1.86615 8 P 0 0;4=12,6=1
P 5.05768002 1.89115 10 P 0 0;2,4=11,6=0
L 5.05768002 1.89115 5.08268002 1.86615 9 P 0 
P 5.08268002 1.86615 8 P 0 0;4=12,6=1
L 4.80768002 3.79115 4.78268002 3.81615 9 P 0 
P 4.80768002 3.79115 10 P 0 0;2,4=11,6=0
P 4.78268002 3.81615 8 P 0 0;4=12,6=1
L 4.80768002 3.64115 4.78268002 3.66615 9 P 0 
P 4.80768002 3.64115 10 P 0 0;2,4=11,6=0
P 4.78268002 3.66615 8 P 0 0;4=12,6=1
L 4.75768002 3.79115 4.73268002 3.81615 9 P 0 
P 4.75768002 3.79115 10 P 0 0;2,4=11,6=0
P 4.73268002 3.81615 8 P 0 0;4=12,6=1
L 4.75768002 3.64115 4.73268002 3.66615 9 P 0 
P 4.75768002 3.64115 10 P 0 0;2,4=11,6=0
P 4.73268002 3.66615 8 P 0 0;4=12,6=1
L 4.70768002 3.79115 4.68268002 3.81615 9 P 0 
P 4.70768002 3.79115 10 P 0 0;2,4=11,6=0
P 4.68268002 3.81615 8 P 0 0;4=12,6=1
L 4.70768002 3.64115 4.68268002 3.66615 9 P 0 
P 4.70768002 3.64115 10 P 0 0;2,4=11,6=0
P 4.68268002 3.66615 8 P 0 0;4=12,6=1
L 4.80768002 3.49115 4.78268002 3.51615 9 P 0 
P 4.80768002 3.49115 10 P 0 0;2,4=11,6=0
P 4.78268002 3.51615 8 P 0 0;4=12,6=1
L 4.75768002 3.49115 4.73268002 3.51615 9 P 0 
P 4.75768002 3.49115 10 P 0 0;2,4=11,6=0
P 4.73268002 3.51615 8 P 0 0;4=12,6=1
L 4.70768002 3.49115 4.68268002 3.51615 9 P 0 
P 4.70768002 3.49115 10 P 0 0;2,4=11,6=0
P 4.68268002 3.51615 8 P 0 0;4=12,6=1
L 4.80768002 3.34115 4.78268002 3.36615 9 P 0 
P 4.80768002 3.34115 10 P 0 0;2,4=11,6=0
P 4.78268002 3.36615 8 P 0 0;4=12,6=1
L 4.75768002 3.34115 4.73268002 3.36615 9 P 0 
P 4.75768002 3.34115 10 P 0 0;2,4=11,6=0
P 4.73268002 3.36615 8 P 0 0;4=12,6=1
L 4.80768002 3.19115 4.78268002 3.21615 9 P 0 
P 4.80768002 3.19115 10 P 0 0;2,4=11,6=0
P 4.78268002 3.21615 8 P 0 0;4=12,6=1
L 4.75768002 3.19115 4.73268002 3.21615 9 P 0 
P 4.75768002 3.19115 10 P 0 0;2,4=11,6=0
P 4.73268002 3.21615 8 P 0 0;4=12,6=1
L 4.70768002 3.34115 4.68268002 3.36615 9 P 0 
P 4.70768002 3.34115 10 P 0 0;2,4=11,6=0
P 4.68268002 3.36615 8 P 0 0;4=12,6=1
L 4.70768002 3.19115 4.68268002 3.21615 9 P 0 
P 4.70768002 3.19115 10 P 0 0;2,4=11,6=0
P 4.68268002 3.21615 8 P 0 0;4=12,6=1
L 4.80768002 3.04115 4.78268002 3.06615 9 P 0 
P 4.80768002 3.04115 10 P 0 0;2,4=11,6=0
P 4.78268002 3.06615 8 P 0 0;4=12,6=1
L 4.75768002 3.04115 4.73268002 3.06615 9 P 0 
P 4.75768002 3.04115 10 P 0 0;2,4=11,6=0
P 4.73268002 3.06615 8 P 0 0;4=12,6=1
L 4.70768002 3.04115 4.68268002 3.06615 9 P 0 
P 4.70768002 3.04115 10 P 0 0;2,4=11,6=0
P 4.68268002 3.06615 8 P 0 0;4=12,6=1
L 4.80768002 2.89115 4.78268002 2.91615 9 P 0 
P 4.80768002 2.89115 10 P 0 0;2,4=11,6=0
P 4.78268002 2.91615 8 P 0 0;4=12,6=1
L 4.75768002 2.89115 4.73268002 2.91615 9 P 0 
P 4.75768002 2.89115 10 P 0 0;2,4=11,6=0
P 4.73268002 2.91615 8 P 0 0;4=12,6=1
L 4.70768002 2.89115 4.68268002 2.91615 9 P 0 
P 4.70768002 2.89115 10 P 0 0;2,4=11,6=0
P 4.68268002 2.91615 8 P 0 0;4=12,6=1
L 4.85768002 2.79115 4.88268002 2.76615 9 P 0 
P 4.85768002 2.79115 10 P 0 0;2,4=11,6=0
P 4.88268002 2.76615 8 P 0 0;4=12,6=1
L 4.85768002 2.69115 4.88268002 2.66615 9 P 0 
P 4.85768002 2.69115 10 P 0 0;2,4=11,6=0
P 4.88268002 2.66615 8 P 0 0;4=12,6=1
L 4.80768002 2.49115 4.78268002 2.46615 9 P 0 
P 4.80768002 2.49115 10 P 0 0;2,4=11,6=0
P 4.78268002 2.46615 8 P 0 0;4=12,6=1
L 4.85768002 2.59115 4.88268002 2.56615 9 P 0 
P 4.85768002 2.59115 10 P 0 0;2,4=11,6=0
P 4.88268002 2.56615 8 P 0 0;4=12,6=1
L 4.85768002 2.64115 4.88268002 2.61615 9 P 0 
P 4.85768002 2.64115 10 P 0 0;2,4=11,6=0
P 4.88268002 2.61615 8 P 0 0;4=12,6=1
P 4.70768002 2.49115 10 P 0 0;2,4=11,6=0
L 4.70768002 2.49115 4.68268002 2.46615 9 P 0 
P 4.68268002 2.46615 8 P 0 0;4=12,6=1
P 4.85768002 2.49115 10 P 0 0;2,4=11,6=0
L 4.85768002 2.49115 4.88268002 2.46615 9 P 0 
P 4.88268002 2.46615 8 P 0 0;4=12,6=1
P 4.85768002 2.54115 10 P 0 0;2,4=11,6=0
L 4.85768002 2.54115 4.88268002 2.51615 9 P 0 
P 4.88268002 2.51615 8 P 0 0;4=12,6=1
L 4.80768002 2.44115 4.78268002 2.41615 9 P 0 
P 4.80768002 2.44115 10 P 0 0;2,4=11,6=0
P 4.78268002 2.41615 8 P 0 0;4=12,6=1
P 4.85768002 2.44115 10 P 0 0;2,4=11,6=0
L 4.85768002 2.44115 4.88268002 2.41615 9 P 0 
P 4.88268002 2.41615 8 P 0 0;4=12,6=1
L 4.80768002 2.39115 4.78268002 2.36615 9 P 0 
P 4.80768002 2.39115 10 P 0 0;2,4=11,6=0
P 4.78268002 2.36615 8 P 0 0;4=12,6=1
L 4.80768002 2.34115 4.78268002 2.31615 9 P 0 
P 4.80768002 2.34115 10 P 0 0;2,4=11,6=0
P 4.78268002 2.31615 8 P 0 0;4=12,6=1
L 4.80768002 2.29115 4.78268002 2.26615 9 P 0 
P 4.80768002 2.29115 10 P 0 0;2,4=11,6=0
P 4.78268002 2.26615 8 P 0 0;4=12,6=1
L 4.80768002 2.24115 4.78268002 2.21615 9 P 0 
P 4.80768002 2.24115 10 P 0 0;2,4=11,6=0
P 4.78268002 2.21615 8 P 0 0;4=12,6=1
P 4.75768002 2.39115 10 P 0 0;2,4=11,6=0
L 4.75768002 2.39115 4.73268002 2.36615 9 P 0 
P 4.73268002 2.36615 8 P 0 0;4=12,6=1
P 4.70768002 2.34115 10 P 0 0;2,4=11,6=0
L 4.70768002 2.34115 4.68268002 2.31615 9 P 0 
P 4.68268002 2.31615 8 P 0 0;4=12,6=1
P 4.75768002 2.24115 10 P 0 0;2,4=11,6=0
L 4.75768002 2.24115 4.73268002 2.21615 9 P 0 
P 4.73268002 2.21615 8 P 0 0;4=12,6=1
P 4.85768002 2.24115 10 P 0 0;2,4=11,6=0
L 4.85768002 2.24115 4.88268002 2.21615 9 P 0 
P 4.88268002 2.21615 8 P 0 0;4=12,6=1
P 4.85768002 2.29115 10 P 0 0;2,4=11,6=0
L 4.85768002 2.29115 4.88268002 2.26615 9 P 0 
P 4.88268002 2.26615 8 P 0 0;4=12,6=1
P 4.85768002 2.34115 10 P 0 0;2,4=11,6=0
L 4.85768002 2.34115 4.88268002 2.31615 9 P 0 
P 4.88268002 2.31615 8 P 0 0;4=12,6=1
P 4.85768002 2.39115 10 P 0 0;2,4=11,6=0
L 4.85768002 2.39115 4.88268002 2.36615 9 P 0 
P 4.88268002 2.36615 8 P 0 0;4=12,6=1
P 4.75768002 2.19115 10 P 0 0;2,4=11,6=0
L 4.75768002 2.19115 4.73268002 2.16615 9 P 0 
P 4.73268002 2.16615 8 P 0 0;4=12,6=1
L 4.68268002 2.16615 4.70768002 2.19115 9 P 0 
P 4.70768002 2.19115 10 P 0 0;2,4=11,6=0
P 4.68268002 2.16615 8 P 0 0;4=12,6=1
P 4.80768002 1.99115 10 P 0 0;2,4=11,6=0
L 4.80768002 1.99115 4.78268002 1.96615 9 P 0 
P 4.78268002 1.96615 8 P 0 0;4=12,6=1
P 4.80768002 2.09115 10 P 0 0;2,4=11,6=0
L 4.80768002 2.09115 4.78268002 2.06615 9 P 0 
P 4.78268002 2.06615 8 P 0 0;4=12,6=1
P 4.80768002 2.04115 10 P 0 0;2,4=11,6=0
L 4.80768002 2.04115 4.78268002 2.01615 9 P 0 
P 4.78268002 2.01615 8 P 0 0;4=12,6=1
P 4.85768002 1.99115 10 P 0 0;2,4=11,6=0
L 4.85768002 1.99115 4.88268002 1.96615 9 P 0 
P 4.88268002 1.96615 8 P 0 0;4=12,6=1
P 4.85768002 2.09115 10 P 0 0;2,4=11,6=0
L 4.85768002 2.09115 4.88268002 2.06615 9 P 0 
P 4.88268002 2.06615 8 P 0 0;4=12,6=1
P 4.85768002 2.04115 10 P 0 0;2,4=11,6=0
L 4.85768002 2.04115 4.88268002 2.01615 9 P 0 
P 4.88268002 2.01615 8 P 0 0;4=12,6=1
P 4.80768002 2.14115 10 P 0 0;2,4=11,6=0
L 4.80768002 2.14115 4.78268002 2.11615 9 P 0 
P 4.78268002 2.11615 8 P 0 0;4=12,6=1
P 4.85768002 2.14115 10 P 0 0;2,4=11,6=0
L 4.85768002 2.14115 4.88268002 2.11615 9 P 0 
P 4.88268002 2.11615 8 P 0 0;4=12,6=1
P 4.75768002 2.14115 10 P 0 0;2,4=11,6=0
L 4.75768002 2.14115 4.73268002 2.11615 9 P 0 
P 4.73268002 2.11615 8 P 0 0;4=12,6=1
P 4.70768002 2.04115 10 P 0 0;2,4=11,6=0
L 4.70768002 2.04115 4.68268002 2.01615 9 P 0 
P 4.68268002 2.01615 8 P 0 0;4=12,6=1
P 4.75768002 1.99115 10 P 0 0;2,4=11,6=0
L 4.75768002 1.99115 4.73268002 1.96615 9 P 0 
P 4.73268002 1.96615 8 P 0 0;4=12,6=1
P 4.80768002 1.89115 10 P 0 0;2,4=11,6=0
L 4.80768002 1.89115 4.78268002 1.86615 9 P 0 
P 4.78268002 1.86615 8 P 0 0;4=12,6=1
P 4.80768002 1.94115 10 P 0 0;2,4=11,6=0
L 4.80768002 1.94115 4.78268002 1.91615 9 P 0 
P 4.85768002 1.89115 10 P 0 0;2,4=11,6=0
L 4.85768002 1.89115 4.88268002 1.86615 9 P 0 
P 4.88268002 1.86615 8 P 0 0;4=12,6=1
P 4.85768002 1.94115 10 P 0 0;2,4=11,6=0
L 4.85768002 1.94115 4.88268002 1.91615 9 P 0 
P 4.70768002 1.89115 10 P 0 0;2,4=11,6=0
L 4.70768002 1.89115 4.68268002 1.86615 9 P 0 
P 4.68268002 1.86615 8 P 0 0;4=12,6=1
L 4.65768002 3.79115 4.63268002 3.81615 9 P 0 
P 4.65768002 3.79115 10 P 0 0;2,4=11,6=0
P 4.63268002 3.81615 8 P 0 0;4=12,6=1
L 4.65768002 3.64115 4.63268002 3.66615 9 P 0 
P 4.65768002 3.64115 10 P 0 0;2,4=11,6=0
P 4.63268002 3.66615 8 P 0 0;4=12,6=1
L 4.60768002 3.79115 4.58268002 3.81615 9 P 0 
P 4.60768002 3.79115 10 P 0 0;2,4=11,6=0
P 4.58268002 3.81615 8 P 0 0;4=12,6=1
L 4.60768002 3.64115 4.58268002 3.66615 9 P 0 
P 4.60768002 3.64115 10 P 0 0;2,4=11,6=0
P 4.58268002 3.66615 8 P 0 0;4=12,6=1
L 4.65768002 3.49115 4.63268002 3.51615 9 P 0 
P 4.65768002 3.49115 10 P 0 0;2,4=11,6=0
P 4.63268002 3.51615 8 P 0 0;4=12,6=1
L 4.60768002 3.49115 4.58268002 3.51615 9 P 0 
P 4.60768002 3.49115 10 P 0 0;2,4=11,6=0
P 4.58268002 3.51615 8 P 0 0;4=12,6=1
L 4.65768002 3.34115 4.63268002 3.36615 9 P 0 
P 4.65768002 3.34115 10 P 0 0;2,4=11,6=0
P 4.63268002 3.36615 8 P 0 0;4=12,6=1
L 4.60768002 3.34115 4.58268002 3.36615 9 P 0 
P 4.60768002 3.34115 10 P 0 0;2,4=11,6=0
P 4.58268002 3.36615 8 P 0 0;4=12,6=1
L 4.65768002 3.19115 4.63268002 3.21615 9 P 0 
P 4.65768002 3.19115 10 P 0 0;2,4=11,6=0
P 4.63268002 3.21615 8 P 0 0;4=12,6=1
L 4.60768002 3.19115 4.58268002 3.21615 9 P 0 
P 4.60768002 3.19115 10 P 0 0;2,4=11,6=0
P 4.58268002 3.21615 8 P 0 0;4=12,6=1
L 4.65768002 3.04115 4.63268002 3.06615 9 P 0 
P 4.65768002 3.04115 10 P 0 0;2,4=11,6=0
P 4.63268002 3.06615 8 P 0 0;4=12,6=1
L 4.60768002 3.04115 4.58268002 3.06615 9 P 0 
P 4.60768002 3.04115 10 P 0 0;2,4=11,6=0
P 4.58268002 3.06615 8 P 0 0;4=12,6=1
L 4.65768002 2.89115 4.63268002 2.91615 9 P 0 
P 4.65768002 2.89115 10 P 0 0;2,4=11,6=0
P 4.63268002 2.91615 8 P 0 0;4=12,6=1
L 4.60768002 2.89115 4.58268002 2.91615 9 P 0 
P 4.60768002 2.89115 10 P 0 0;2,4=11,6=0
P 4.58268002 2.91615 8 P 0 0;4=12,6=1
P 4.60768002 2.49115 10 P 0 0;2,4=11,6=0
L 4.60768002 2.49115 4.58268002 2.46615 9 P 0 
P 4.58268002 2.46615 8 P 0 0;4=12,6=1
L 4.63268002 2.21615 4.65768002 2.24115 9 P 0 
P 4.60768002 2.19115 10 P 0 0;2,4=11,6=0
P 4.65768002 2.24115 10 P 0 0;2,4=11,6=0
L 4.60768002 2.19115 4.63268002 2.21615 9 P 0 
P 4.63268002 2.21615 8 P 0 0;4=12,6=1
P 4.60768002 2.34115 10 P 0 0;2,4=11,6=0
L 4.60768002 2.34115 4.58268002 2.31615 9 P 0 
P 4.58268002 2.31615 8 P 0 0;4=12,6=1
P 4.65768002 2.39115 10 P 0 0;2,4=11,6=0
L 4.65768002 2.39115 4.63268002 2.36615 9 P 0 
P 4.63268002 2.36615 8 P 0 0;4=12,6=1
P 4.60768002 2.04115 10 P 0 0;2,4=11,6=0
L 4.60768002 2.04115 4.58268002 2.01615 9 P 0 
P 4.58268002 2.01615 8 P 0 0;4=12,6=1
P 4.65768002 2.14115 10 P 0 0;2,4=11,6=0
L 4.65768002 2.14115 4.63268002 2.11615 9 P 0 
P 4.63268002 2.11615 8 P 0 0;4=12,6=1
P 4.65768002 1.99115 10 P 0 0;2,4=11,6=0
L 4.65768002 1.99115 4.63268002 1.96615 9 P 0 
P 4.63268002 1.96615 8 P 0 0;4=12,6=1
P 4.60768002 1.89115 10 P 0 0;2,4=11,6=0
L 4.60768002 1.89115 4.58268002 1.86615 9 P 0 
P 4.58268002 1.86615 8 P 0 0;4=12,6=1
L 2.12913996 4.93528002 2.12913996 4.92 6 P 0 
L 2.12913996 5.023 2.12913996 4.97913996 6 P 0 
L 1.98741004 4.92 1.98741004 4.85788002 6 P 0 
L 2.86555 4.81401998 2.86855 4.81701998 6 P 0 
L 2.86855 4.81701998 2.86855 4.85788002 6 P 0 
L 2.94141004 4.81401998 2.93941004 4.81601998 6 P 0 
L 2.93941004 4.81601998 2.93941004 4.85788002 6 P 0 
L 3.29373996 5.023 3.29373996 4.97913996 6 P 0 
L 3.43546998 4.928 3.43546998 4.97913996 6 P 0 
L 3.43546998 4.928 3.43546998 4.85788002 6 P 0 
P 2.12106004 2.29115 10 P 0 0;2,4=11,6=0
P 2.07106004 2.34115 10 P 0 0;2,4=11,6=0
P 2.07106004 2.19115 10 P 0 0;2,4=11,6=0
P 2.12106004 2.14115 10 P 0 0;2,4=11,6=0
P 2.17106004 2.19115 10 P 0 0;2,4=11,6=0
P 2.22106004 2.24115 10 P 0 0;2,4=11,6=0
P 2.27106004 2.24115 10 P 0 0;2,4=11,6=0
P 2.22106004 2.19115 10 P 0 0;2,4=11,6=0
P 2.22106004 2.09115 10 P 0 0;2,4=11,6=0
P 2.22106004 2.14115 10 P 0 0;2,4=11,6=0
P 2.27106004 2.14115 10 P 0 0;2,4=11,6=0
P 2.27106004 2.09115 10 P 0 0;2,4=11,6=0
P 2.27106004 2.19115 10 P 0 0;2,4=11,6=0
P 2.32106004 2.19115 10 P 0 0;2,4=11,6=0
P 2.37106004 2.14115 10 P 0 0;2,4=11,6=0
P 2.42106004 2.19115 10 P 0 0;2,4=11,6=0
P 2.47106004 2.14115 10 P 0 0;2,4=11,6=0
P 2.42106004 1.89115 10 P 0 0;2,4=11,6=0
P 2.47106004 1.99115 10 P 0 0;2,4=11,6=0
P 2.42106004 2.04115 10 P 0 0;2,4=11,6=0
P 2.37106004 1.99115 10 P 0 0;2,4=11,6=0
P 2.32106004 2.04115 10 P 0 0;2,4=11,6=0
P 2.27106004 2.04115 10 P 0 0;2,4=11,6=0
P 2.22106004 2.04115 10 P 0 0;2,4=11,6=0
P 2.17106004 2.04115 10 P 0 0;2,4=11,6=0
P 2.27106004 1.99115 10 P 0 0;2,4=11,6=0
P 2.22106004 1.99115 10 P 0 0;2,4=11,6=0
P 2.27106004 1.94115 10 P 0 0;2,4=11,6=0
P 2.22106004 1.94115 10 P 0 0;2,4=11,6=0
P 2.32106004 1.89115 10 P 0 0;2,4=11,6=0
P 2.27106004 1.89115 10 P 0 0;2,4=11,6=0
P 2.22106004 1.89115 10 P 0 0;2,4=11,6=0
P 2.17106004 1.89115 10 P 0 0;2,4=11,6=0
P 2.07106004 1.89115 10 P 0 0;2,4=11,6=0
P 2.12106004 1.99115 10 P 0 0;2,4=11,6=0
P 2.07106004 2.04115 10 P 0 0;2,4=11,6=0
P 2.02106004 1.99115 10 P 0 0;2,4=11,6=0
P 2.02106004 2.14115 10 P 0 0;2,4=11,6=0
P 2.02106004 2.29115 10 P 0 0;2,4=11,6=0
P 2.22106004 2.29115 10 P 0 0;2,4=11,6=0
P 2.27106004 2.29115 10 P 0 0;2,4=11,6=0
P 2.32106004 2.34115 10 P 0 0;2,4=11,6=0
P 2.37106004 2.29115 10 P 0 0;2,4=11,6=0
P 2.47106004 2.29115 10 P 0 0;2,4=11,6=0
P 2.42106004 2.34115 10 P 0 0;2,4=11,6=0
P 2.47106004 2.44115 10 P 0 0;2,4=11,6=0
P 2.47106004 2.49115 10 P 0 0;2,4=11,6=0
P 2.47106004 2.54115 10 P 0 0;2,4=11,6=0
P 2.42106004 2.49115 10 P 0 0;2,4=11,6=0
P 2.37106004 2.54115 10 P 0 0;2,4=11,6=0
P 2.37106004 2.49115 10 P 0 0;2,4=11,6=0
P 2.37106004 2.44115 10 P 0 0;2,4=11,6=0
P 2.27106004 2.34115 10 P 0 0;2,4=11,6=0
P 2.17106004 2.34115 10 P 0 0;2,4=11,6=0
P 2.22106004 2.34115 10 P 0 0;2,4=11,6=0
P 2.22106004 2.39115 10 P 0 0;2,4=11,6=0
P 2.27106004 2.39115 10 P 0 0;2,4=11,6=0
P 2.27106004 2.44115 10 P 0 0;2,4=11,6=0
P 2.22106004 2.44115 10 P 0 0;2,4=11,6=0
P 2.12106004 2.44115 10 P 0 0;2,4=11,6=0
P 2.17106004 2.49115 10 P 0 0;2,4=11,6=0
P 2.22106004 2.49115 10 P 0 0;2,4=11,6=0
P 2.27106004 2.49115 10 P 0 0;2,4=11,6=0
P 2.32106004 2.49115 10 P 0 0;2,4=11,6=0
P 2.27106004 2.54115 10 P 0 0;2,4=11,6=0
P 2.27106004 2.59115 10 P 0 0;2,4=11,6=0
P 2.22106004 2.54115 10 P 0 0;2,4=11,6=0
P 2.22106004 2.59115 10 P 0 0;2,4=11,6=0
P 2.12106004 2.54115 10 P 0 0;2,4=11,6=0
P 2.07106004 2.49115 10 P 0 0;2,4=11,6=0
P 2.02106004 2.44115 10 P 0 0;2,4=11,6=0
P 2.02106004 2.49115 10 P 0 0;2,4=11,6=0
P 2.02106004 2.54115 10 P 0 0;2,4=11,6=0
P 2.02106004 2.69115 10 P 0 0;2,4=11,6=0
P 2.07106004 2.64115 10 P 0 0;2,4=11,6=0
P 2.12106004 2.69115 10 P 0 0;2,4=11,6=0
P 2.17106004 2.64115 10 P 0 0;2,4=11,6=0
P 2.22106004 2.64115 10 P 0 0;2,4=11,6=0
P 2.22106004 2.69115 10 P 0 0;2,4=11,6=0
P 2.27106004 2.64115 10 P 0 0;2,4=11,6=0
P 2.27106004 2.69115 10 P 0 0;2,4=11,6=0
P 2.32106004 2.64115 10 P 0 0;2,4=11,6=0
P 2.37106004 2.69115 10 P 0 0;2,4=11,6=0
P 2.42106004 2.64115 10 P 0 0;2,4=11,6=0
P 2.47106004 2.69115 10 P 0 0;2,4=11,6=0
P 2.47106004 2.84115 10 P 0 0;2,4=11,6=0
P 2.42106004 2.79115 10 P 0 0;2,4=11,6=0
P 2.32106004 2.79115 10 P 0 0;2,4=11,6=0
P 2.37106004 2.84115 10 P 0 0;2,4=11,6=0
P 2.42106004 2.84115 10 P 0 0;2,4=11,6=0
P 2.42106004 2.89115 10 P 0 0;2,4=11,6=0
P 2.47106004 2.99115 10 P 0 0;2,4=11,6=0
P 2.42106004 3.04115 10 P 0 0;2,4=11,6=0
P 2.32106004 3.04115 10 P 0 0;2,4=11,6=0
P 2.37106004 2.99115 10 P 0 0;2,4=11,6=0
P 2.27106004 2.89115 10 P 0 0;2,4=11,6=0
P 2.22106004 2.89115 10 P 0 0;2,4=11,6=0
P 2.17106004 2.89115 10 P 0 0;2,4=11,6=0
P 2.02106004 2.84115 10 P 0 0;2,4=11,6=0
P 2.12106004 2.84115 10 P 0 0;2,4=11,6=0
P 2.07106004 2.89115 10 P 0 0;2,4=11,6=0
P 2.02106004 2.99115 10 P 0 0;2,4=11,6=0
P 2.07106004 3.04115 10 P 0 0;2,4=11,6=0
P 2.12106004 2.99115 10 P 0 0;2,4=11,6=0
P 2.17106004 3.04115 10 P 0 0;2,4=11,6=0
P 2.07106004 2.84115 10 P 0 0;2,4=11,6=0
P 2.07106004 2.79115 10 P 0 0;2,4=11,6=0
P 2.17106004 2.79115 10 P 0 0;2,4=11,6=0
P 2.22106004 2.79115 10 P 0 0;2,4=11,6=0
P 2.22106004 2.74115 10 P 0 0;2,4=11,6=0
P 2.27106004 2.79115 10 P 0 0;2,4=11,6=0
P 2.27106004 2.74115 10 P 0 0;2,4=11,6=0
P 2.32106004 2.89115 10 P 0 0;2,4=11,6=0
P 2.32106004 2.84115 10 P 0 0;2,4=11,6=0
P 2.22106004 2.99115 10 P 0 0;2,4=11,6=0
P 2.22106004 2.94115 10 P 0 0;2,4=11,6=0
P 2.22106004 3.09115 10 P 0 0;2,4=11,6=0
P 2.22106004 3.04115 10 P 0 0;2,4=11,6=0
P 2.27106004 2.99115 10 P 0 0;2,4=11,6=0
P 2.27106004 2.94115 10 P 0 0;2,4=11,6=0
P 2.27106004 3.09115 10 P 0 0;2,4=11,6=0
P 2.27106004 3.04115 10 P 0 0;2,4=11,6=0
L 2.37106004 3.14115 2.39606004 3.16615 9 P 0 
L 2.47106004 3.14115 2.49606004 3.16615 9 P 0 
L 2.47106004 3.24115 2.49606004 3.26615 9 P 0 
L 2.47106004 3.19115 2.49606004 3.21615 9 P 0 
L 2.42106004 3.19115 2.44606004 3.21615 9 P 0 
L 2.32106004 3.19115 2.34606004 3.21615 9 P 0 
L 2.27106004 3.14115 2.29606004 3.16615 9 P 0 
L 2.22106004 3.14115 2.24606004 3.16615 9 P 0 
L 2.02106004 3.14115 2.04606004 3.16615 9 P 0 
L 2.12106004 3.14115 2.14606004 3.16615 9 P 0 
L 2.07106004 3.19115 2.09606004 3.21615 9 P 0 
L 2.17106004 3.19115 2.19606004 3.21615 9 P 0 
L 2.22106004 3.19115 2.24606004 3.21615 9 P 0 
L 2.27106004 3.19115 2.29606004 3.21615 9 P 0 
L 2.22106004 3.24115 2.24606004 3.26615 9 P 0 
L 2.22106004 3.29115 2.24606004 3.31615 9 P 0 
L 2.07106004 3.34115 2.09606004 3.36615 9 P 0 
L 2.02106004 3.39115 2.04606004 3.41615 9 P 0 
P 2.04606004 3.41615 8 P 0 0;4=12,6=1
P 2.02106004 3.39115 10 P 0 0;2,4=11,6=0
L 2.02106004 3.39115 1.99606004 3.41615 9 P 0 
L 2.17106004 3.34115 2.19606004 3.36615 9 P 0 
L 2.22106004 3.34115 2.24606004 3.36615 9 P 0 
L 2.27106004 3.34115 2.29606004 3.36615 9 P 0 
L 2.22106004 3.39115 2.24606004 3.41615 9 P 0 
L 2.22106004 3.44115 2.24606004 3.46615 9 P 0 
L 2.42106004 3.34115 2.44606004 3.36615 9 P 0 
L 2.47106004 3.39115 2.49606004 3.41615 9 P 0 
L 2.27106004 3.49115 2.29606004 3.51615 9 P 0 
L 2.22106004 3.49115 2.24606004 3.51615 9 P 0 
L 2.17106004 3.49115 2.19606004 3.51615 9 P 0 
L 2.07106004 3.49115 2.09606004 3.51615 9 P 0 
P 2.09606004 3.51615 8 P 0 0;4=12,6=1
P 2.07106004 3.49115 10 P 0 0;2,4=11,6=0
L 2.07106004 3.49115 2.04606004 3.46615 9 P 0 
L 2.02106004 3.54115 2.04606004 3.51615 9 P 0 
L 2.02106004 3.54115 1.99606004 3.56615 9 P 0 
L 2.02106004 3.54115 2.04606004 3.56615 9 P 0 
L 2.12106004 3.54115 2.14606004 3.56615 9 P 0 
L 2.17106004 3.54115 2.19606004 3.56615 9 P 0 
L 2.17106004 3.59115 2.19606004 3.61615 9 P 0 
L 2.22106004 3.59115 2.24606004 3.61615 9 P 0 
L 2.22106004 3.64115 2.24606004 3.66615 9 P 0 
L 2.22106004 3.69115 2.24606004 3.71615 9 P 0 
L 2.27106004 3.59115 2.29606004 3.61615 9 P 0 
L 2.37106004 3.54115 2.39606004 3.56615 9 P 0 
L 2.42106004 3.54115 2.44606004 3.56615 9 P 0 
L 2.47106004 3.54115 2.49606004 3.56615 9 P 0 
L 2.47106004 3.69115 2.49606004 3.71615 9 P 0 
L 2.27106004 3.74115 2.29606004 3.76615 9 P 0 
L 2.22106004 3.74115 2.24606004 3.76615 9 P 0 
L 2.17106004 3.74115 2.19606004 3.76615 9 P 0 
L 2.22106004 3.79115 2.24606004 3.81615 9 P 0 
L 2.47106004 3.84115 2.49606004 3.86615 9 P 0 
L 2.22106004 3.84115 2.24606004 3.86615 9 P 0 
P 2.12106004 3.14115 10 P 0 0;2,4=11,6=0
P 2.02106004 3.14115 10 P 0 0;2,4=11,6=0
P 3.37003996 5.18128002 9 P 0 0;4=13,6=1
P 3.43003996 5.18128002 9 P 0 0;4=13,6=1
P 3.29916998 5.14223996 9 P 0 0;4=13,6=1
P 3.35916998 5.14223996 9 P 0 0;4=13,6=1
S P 0
OB 2.94283996063 4.70573996063 I
OC 2.94283996063 4.70573996063 2.937080019685 4.70573996063 Y
OE
SE
P 2.93708002 4.70573996 9 P 0 0;4=13,6=1
S P 0
OB 3.081469980315 4.70573996063 I
OC 3.081469980315 4.70573996063 3.07571003937 4.70573996063 Y
OE
SE
P 3.07571004 4.70573996 9 P 0 0;4=13,6=1
S P 0
OB 3.021469980315 4.70573996063 I
OC 3.021469980315 4.70573996063 3.01571003937 4.70573996063 Y
OE
SE
P 3.01571004 4.70573996 9 P 0 0;4=13,6=1
S P 0
OB 2.88283996063 4.70573996063 I
OC 2.88283996063 4.70573996063 2.877080019685 4.70573996063 Y
OE
SE
P 2.87708002 4.70573996 9 P 0 0;4=13,6=1
S P 0
OB 2.936630019685 5.20876003937 I
OC 2.936630019685 5.20876003937 2.930869980315 5.20876003937 Y
OE
SE
P 2.93086998 5.20876004 9 P 0 0;4=13,6=1
S P 0
OB 2.876630019685 5.20876003937 I
OC 2.876630019685 5.20876003937 2.870869980315 5.20876003937 Y
OE
SE
P 2.87086998 5.20876004 9 P 0 0;4=13,6=1
S P 0
OB 2.808869980315 4.744180019685 I
OC 2.808869980315 4.744180019685 2.80311003937 4.744180019685 Y
OE
SE
P 2.80311004 4.74418002 9 P 0 0;4=13,6=1
S P 0
OB 2.868869980315 4.744180019685 I
OC 2.868869980315 4.744180019685 2.86311003937 4.744180019685 Y
OE
SE
P 2.86311004 4.74418002 9 P 0 0;4=13,6=1
S P 0
OB 3.092330019685 5.09223996063 I
OC 3.092330019685 5.09223996063 3.086569980315 5.09223996063 Y
OE
SE
P 3.08656998 5.09223996 9 P 0 0;4=13,6=1
S P 0
OB 3.152330019685 5.09223996063 I
OC 3.152330019685 5.09223996063 3.146569980315 5.09223996063 Y
OE
SE
P 3.14656998 5.09223996 9 P 0 0;4=13,6=1
S P 0
OB 2.27431003937 4.62826003937 I
OC 2.27431003937 4.62826003937 2.26855 4.62826003937 Y
OE
SE
P 2.26855 4.62826004 9 P 0 0;4=13,6=1
S P 0
OB 2.21431003937 4.62826003937 I
OC 2.21431003937 4.62826003937 2.20855 4.62826003937 Y
OE
SE
P 2.20855 4.62826004 9 P 0 0;4=13,6=1
S P 0
OB 2.2712 4.744180019685 I
OC 2.2712 4.744180019685 2.26543996063 4.744180019685 Y
OE
SE
P 2.26543996 4.74418002 9 P 0 0;4=13,6=1
S P 0
OB 2.2112 4.744180019685 I
OC 2.2112 4.744180019685 2.20543996063 4.744180019685 Y
OE
SE
P 2.20543996 4.74418002 9 P 0 0;4=13,6=1
S P 0
OB 2.352930019685 4.70326003937 I
OC 2.352930019685 4.70326003937 2.347169980315 4.70326003937 Y
OE
SE
P 2.34716998 4.70326004 9 P 0 0;4=13,6=1
P 2.07853002 4.62815 9 P 0 0;4=13,6=1
P 2.01853002 4.62815 9 P 0 0;4=13,6=1
S P 0
OB 2.129469980315 4.744180019685 I
OC 2.129469980315 4.744180019685 2.12371003937 4.744180019685 Y
OE
SE
P 2.12371004 4.74418002 9 P 0 0;4=13,6=1
S P 0
OB 2.069469980315 4.744180019685 I
OC 2.069469980315 4.744180019685 2.06371003937 4.744180019685 Y
OE
SE
P 2.06371004 4.74418002 9 P 0 0;4=13,6=1
S P 0
OB 2.200330019685 5.09223996063 I
OC 2.200330019685 5.09223996063 2.194569980315 5.09223996063 Y
OE
SE
P 2.19456998 5.09223996 9 P 0 0;4=13,6=1
S P 0
OB 2.140330019685 5.09223996063 I
OC 2.140330019685 5.09223996063 2.134569980315 5.09223996063 Y
OE
SE
P 2.13456998 5.09223996 9 P 0 0;4=13,6=1
S P 0
OB 2.129469980315 5.13026003937 I
OC 2.129469980315 5.13026003937 2.12371003937 5.13026003937 Y
OE
SE
P 2.12371004 5.13026004 9 P 0 0;4=13,6=1
S P 0
OB 2.069469980315 5.13026003937 I
OC 2.069469980315 5.13026003937 2.06371003937 5.13026003937 Y
OE
SE
P 2.06371004 5.13026004 9 P 0 0;4=13,6=1
S P 0
OB 1.70426003937 5.09223996063 I
OC 1.70426003937 5.09223996063 1.6985 5.09223996063 Y
OE
SE
P 1.6985 5.09223996 9 P 0 0;4=13,6=1
S P 0
OB 1.64426003937 5.09223996063 I
OC 1.64426003937 5.09223996063 1.6385 5.09223996063 Y
OE
SE
P 1.6385 5.09223996 9 P 0 0;4=13,6=1
P 1.85111004 4.61826004 9 P 0 0;4=13,6=1
S P 0
OB 1.644269980315 4.744180019685 I
OC 1.644269980315 4.744180019685 1.63851003937 4.744180019685 Y
OE
SE
P 1.63851004 4.74418002 9 P 0 0;4=13,6=1
S P 0
OB 1.704269980315 4.744180019685 I
OC 1.704269980315 4.744180019685 1.69851003937 4.744180019685 Y
OE
SE
P 1.69851004 4.74418002 9 P 0 0;4=13,6=1
L 1.776 4.812 1.77481004 4.81318996 6 P 0 
L 1.77481004 4.81318996 1.77481004 4.85788002 6 P 0 
S P 0
OB 1.987730019685 5.09223996063 I
OC 1.987730019685 5.09223996063 1.981969980315 5.09223996063 Y
OE
SE
P 1.98196998 5.09223996 9 P 0 0;4=13,6=1
S P 0
OB 1.927730019685 5.09223996063 I
OC 1.927730019685 5.09223996063 1.921969980315 5.09223996063 Y
OE
SE
P 1.92196998 5.09223996 9 P 0 0;4=13,6=1
S P 0
OB 1.84601003937 4.744180019685 I
OC 1.84601003937 4.744180019685 1.84025 4.744180019685 Y
OE
SE
P 1.84025 4.74418002 9 P 0 0;4=13,6=1
S P 0
OB 1.78601003937 4.744180019685 I
OC 1.78601003937 4.744180019685 1.78025 4.744180019685 Y
OE
SE
P 1.78025 4.74418002 9 P 0 0;4=13,6=1
P 11.01161004 2.74115 10 P 0 0;2,4=11,6=0
L 11.01161004 2.74115 11.03661004 2.71615 9 P 0 
P 11.03661004 2.71615 8 P 0 0;4=12,6=1
P 10.91161004 2.74115 10 P 0 0;2,4=11,6=0
L 10.91161004 2.74115 10.93661004 2.71615 9 P 0 
P 10.93661004 2.71615 8 P 0 0;4=12,6=1
P 11.01161004 2.79115 10 P 0 0;2,4=11,6=0
L 11.01161004 2.79115 11.03661004 2.76615 9 P 0 
P 11.03661004 2.76615 8 P 0 0;4=12,6=1
P 10.96161004 2.79115 10 P 0 0;2,4=11,6=0
L 10.96161004 2.79115 10.98661004 2.76615 9 P 0 
P 10.98661004 2.76615 8 P 0 0;4=12,6=1
P 10.91161004 2.79115 10 P 0 0;2,4=11,6=0
L 10.91161004 2.79115 10.93661004 2.76615 9 P 0 
P 10.93661004 2.76615 8 P 0 0;4=12,6=1
P 11.06161004 2.79115 10 P 0 0;2,4=11,6=0
L 11.06161004 2.79115 11.08661004 2.76615 9 P 0 
P 11.08661004 2.76615 8 P 0 0;4=12,6=1
L 11.03661004 2.56615 11.01161004 2.54115 9 P 0 
P 11.01161004 2.54115 10 P 0 0;2,4=11,6=0
P 11.01161004 2.59115 10 P 0 0;2,4=11,6=0
L 11.01161004 2.59115 11.03661004 2.56615 9 P 0 
P 11.03661004 2.56615 8 P 0 0;4=12,6=1
P 10.91161004 2.59115 10 P 0 0;2,4=11,6=0
L 10.91161004 2.59115 10.93661004 2.56615 9 P 0 
P 10.93661004 2.56615 8 P 0 0;4=12,6=1
P 10.96161004 2.69115 10 P 0 0;2,4=11,6=0
L 10.96161004 2.69115 10.98661004 2.66615 9 P 0 
P 10.98661004 2.66615 8 P 0 0;4=12,6=1
P 10.96161004 2.54115 10 P 0 0;2,4=11,6=0
L 10.96161004 2.54115 10.98661004 2.51615 9 P 0 
P 10.98661004 2.51615 8 P 0 0;4=12,6=1
P 10.91161004 2.54115 10 P 0 0;2,4=11,6=0
L 10.91161004 2.54115 10.93661004 2.51615 9 P 0 
P 10.93661004 2.51615 8 P 0 0;4=12,6=1
P 11.06161004 2.69115 10 P 0 0;2,4=11,6=0
L 11.06161004 2.69115 11.08661004 2.66615 9 P 0 
P 11.08661004 2.66615 8 P 0 0;4=12,6=1
P 11.06161004 2.54115 10 P 0 0;2,4=11,6=0
L 11.06161004 2.54115 11.08661004 2.51615 9 P 0 
P 11.08661004 2.51615 8 P 0 0;4=12,6=1
P 11.06161004 2.49115 10 P 0 0;2,4=11,6=0
L 11.06161004 2.49115 11.08661004 2.46615 9 P 0 
P 11.08661004 2.46615 8 P 0 0;4=12,6=1
P 10.96161004 2.49115 10 P 0 0;2,4=11,6=0
L 10.96161004 2.49115 10.98661004 2.46615 9 P 0 
P 10.98661004 2.46615 8 P 0 0;4=12,6=1
P 11.06161004 2.34115 10 P 0 0;2,4=11,6=0
L 11.06161004 2.34115 11.08661004 2.31615 9 P 0 
P 11.08661004 2.31615 8 P 0 0;4=12,6=1
P 10.91161004 2.39115 10 P 0 0;2,4=11,6=0
L 10.91161004 2.39115 10.93661004 2.36615 9 P 0 
P 10.93661004 2.36615 8 P 0 0;4=12,6=1
P 10.96161004 2.34115 10 P 0 0;2,4=11,6=0
L 10.96161004 2.34115 10.98661004 2.31615 9 P 0 
P 10.98661004 2.31615 8 P 0 0;4=12,6=1
P 10.91161004 2.24115 10 P 0 0;2,4=11,6=0
L 10.91161004 2.24115 10.93661004 2.21615 9 P 0 
P 10.93661004 2.21615 8 P 0 0;4=12,6=1
P 11.01161004 2.24115 10 P 0 0;2,4=11,6=0
L 11.01161004 2.24115 11.03661004 2.21615 9 P 0 
P 11.03661004 2.21615 8 P 0 0;4=12,6=1
P 11.01161004 2.14115 10 P 0 0;2,4=11,6=0
L 11.01161004 2.14115 11.03661004 2.11615 9 P 0 
P 11.03661004 2.11615 8 P 0 0;4=12,6=1
P 10.91161004 2.14115 10 P 0 0;2,4=11,6=0
L 10.91161004 2.14115 10.93661004 2.11615 9 P 0 
P 10.93661004 2.11615 8 P 0 0;4=12,6=1
P 10.96161004 2.04115 10 P 0 0;2,4=11,6=0
L 10.96161004 2.04115 10.98661004 2.01615 9 P 0 
P 10.98661004 2.01615 8 P 0 0;4=12,6=1
P 10.91161004 1.99115 10 P 0 0;2,4=11,6=0
L 10.91161004 1.99115 10.93661004 1.96615 9 P 0 
P 10.93661004 1.96615 8 P 0 0;4=12,6=1
P 11.01161004 1.99115 10 P 0 0;2,4=11,6=0
L 11.01161004 1.99115 11.03661004 1.96615 9 P 0 
P 11.03661004 1.96615 8 P 0 0;4=12,6=1
P 11.06161004 2.04115 10 P 0 0;2,4=11,6=0
L 11.06161004 2.04115 11.08661004 2.01615 9 P 0 
P 11.08661004 2.01615 8 P 0 0;4=12,6=1
P 10.96161004 2.19115 10 P 0 0;2,4=11,6=0
L 10.96161004 2.19115 10.98661004 2.16615 9 P 0 
P 10.98661004 2.16615 8 P 0 0;4=12,6=1
P 10.91161004 2.19115 10 P 0 0;2,4=11,6=0
L 10.91161004 2.19115 10.93661004 2.16615 9 P 0 
P 10.93661004 2.16615 8 P 0 0;4=12,6=1
P 11.06161004 2.19115 10 P 0 0;2,4=11,6=0
L 11.06161004 2.19115 11.08661004 2.16615 9 P 0 
P 11.08661004 2.16615 8 P 0 0;4=12,6=1
P 10.96161004 1.89115 10 P 0 0;2,4=11,6=0
L 10.96161004 1.89115 10.98661004 1.86615 9 P 0 
P 10.98661004 1.86615 8 P 0 0;4=12,6=1
P 11.06161004 1.89115 10 P 0 0;2,4=11,6=0
L 11.06161004 1.89115 11.08661004 1.86615 9 P 0 
P 11.08661004 1.86615 8 P 0 0;4=12,6=1
P 10.76161004 2.74115 10 P 0 0;2,4=11,6=0
L 10.76161004 2.74115 10.73661004 2.71615 9 P 0 
P 10.73661004 2.71615 8 P 0 0;4=12,6=1
P 10.76161004 2.79115 10 P 0 0;2,4=11,6=0
L 10.76161004 2.79115 10.73661004 2.76615 9 P 0 
P 10.73661004 2.76615 8 P 0 0;4=12,6=1
P 10.86161004 2.79115 10 P 0 0;2,4=11,6=0
L 10.86161004 2.79115 10.88661004 2.76615 9 P 0 
P 10.88661004 2.76615 8 P 0 0;4=12,6=1
P 10.81161004 2.79115 10 P 0 0;2,4=11,6=0
L 10.81161004 2.79115 10.78661004 2.76615 9 P 0 
P 10.78661004 2.76615 8 P 0 0;4=12,6=1
P 10.76161004 2.59115 10 P 0 0;2,4=11,6=0
L 10.76161004 2.59115 10.73661004 2.56615 9 P 0 
P 10.73661004 2.56615 8 P 0 0;4=12,6=1
P 10.71161004 2.69115 10 P 0 0;2,4=11,6=0
L 10.71161004 2.69115 10.68661004 2.66615 9 P 0 
P 10.68661004 2.66615 8 P 0 0;4=12,6=1
P 10.76161004 2.54115 10 P 0 0;2,4=11,6=0
L 10.76161004 2.54115 10.73661004 2.51615 9 P 0 
P 10.73661004 2.51615 8 P 0 0;4=12,6=1
P 10.71161004 2.54115 10 P 0 0;2,4=11,6=0
L 10.71161004 2.54115 10.68661004 2.51615 9 P 0 
P 10.68661004 2.51615 8 P 0 0;4=12,6=1
P 10.86161004 2.64115 10 P 0 0;2,4=11,6=0
L 10.86161004 2.64115 10.88661004 2.61615 9 P 0 
P 10.88661004 2.61615 8 P 0 0;4=12,6=1
P 10.86161004 2.69115 10 P 0 0;2,4=11,6=0
L 10.86161004 2.69115 10.88661004 2.66615 9 P 0 
P 10.86161004 2.59115 10 P 0 0;2,4=11,6=0
L 10.86161004 2.59115 10.88661004 2.56615 9 P 0 
P 10.88661004 2.56615 8 P 0 0;4=12,6=1
P 10.86161004 2.54115 10 P 0 0;2,4=11,6=0
L 10.86161004 2.54115 10.88661004 2.51615 9 P 0 
P 10.88661004 2.51615 8 P 0 0;4=12,6=1
P 10.81161004 2.59115 10 P 0 0;2,4=11,6=0
L 10.81161004 2.59115 10.78661004 2.56615 9 P 0 
P 10.78661004 2.56615 8 P 0 0;4=12,6=1
P 10.81161004 2.64115 10 P 0 0;2,4=11,6=0
L 10.81161004 2.64115 10.78661004 2.61615 9 P 0 
P 10.78661004 2.61615 8 P 0 0;4=12,6=1
P 10.81161004 2.69115 10 P 0 0;2,4=11,6=0
L 10.81161004 2.69115 10.78661004 2.66615 9 P 0 
P 10.78661004 2.66615 8 P 0 0;4=12,6=1
P 10.81161004 2.54115 10 P 0 0;2,4=11,6=0
L 10.81161004 2.54115 10.78661004 2.51615 9 P 0 
P 10.78661004 2.51615 8 P 0 0;4=12,6=1
P 10.81161004 2.49115 10 P 0 0;2,4=11,6=0
L 10.81161004 2.49115 10.78661004 2.46615 9 P 0 
P 10.78661004 2.46615 8 P 0 0;4=12,6=1
P 10.71161004 2.49115 10 P 0 0;2,4=11,6=0
L 10.71161004 2.49115 10.68661004 2.46615 9 P 0 
P 10.68661004 2.46615 8 P 0 0;4=12,6=1
P 10.86161004 2.49115 10 P 0 0;2,4=11,6=0
L 10.86161004 2.49115 10.88661004 2.46615 9 P 0 
P 10.88661004 2.46615 8 P 0 0;4=12,6=1
P 10.81161004 2.24115 10 P 0 0;2,4=11,6=0
L 10.81161004 2.24115 10.78661004 2.21615 9 P 0 
P 10.78661004 2.21615 8 P 0 0;4=12,6=1
P 10.81161004 2.29115 10 P 0 0;2,4=11,6=0
L 10.81161004 2.29115 10.78661004 2.26615 9 P 0 
P 10.78661004 2.26615 8 P 0 0;4=12,6=1
P 10.81161004 2.34115 10 P 0 0;2,4=11,6=0
L 10.81161004 2.34115 10.78661004 2.31615 9 P 0 
P 10.78661004 2.31615 8 P 0 0;4=12,6=1
P 10.81161004 2.39115 10 P 0 0;2,4=11,6=0
L 10.81161004 2.39115 10.78661004 2.36615 9 P 0 
P 10.78661004 2.36615 8 P 0 0;4=12,6=1
P 10.71161004 2.34115 10 P 0 0;2,4=11,6=0
L 10.71161004 2.34115 10.68661004 2.31615 9 P 0 
P 10.68661004 2.31615 8 P 0 0;4=12,6=1
P 10.76161004 2.39115 10 P 0 0;2,4=11,6=0
L 10.76161004 2.39115 10.73661004 2.36615 9 P 0 
P 10.73661004 2.36615 8 P 0 0;4=12,6=1
P 10.76161004 2.24115 10 P 0 0;2,4=11,6=0
L 10.76161004 2.24115 10.73661004 2.21615 9 P 0 
P 10.73661004 2.21615 8 P 0 0;4=12,6=1
P 10.81161004 2.44115 10 P 0 0;2,4=11,6=0
L 10.81161004 2.44115 10.78661004 2.41615 9 P 0 
P 10.78661004 2.41615 8 P 0 0;4=12,6=1
P 10.86161004 2.44115 10 P 0 0;2,4=11,6=0
L 10.86161004 2.44115 10.88661004 2.41615 9 P 0 
P 10.86161004 2.39115 10 P 0 0;2,4=11,6=0
L 10.86161004 2.39115 10.88661004 2.36615 9 P 0 
P 10.88661004 2.36615 8 P 0 0;4=12,6=1
P 10.86161004 2.34115 10 P 0 0;2,4=11,6=0
L 10.86161004 2.34115 10.88661004 2.31615 9 P 0 
P 10.88661004 2.31615 8 P 0 0;4=12,6=1
P 10.86161004 2.29115 10 P 0 0;2,4=11,6=0
L 10.86161004 2.29115 10.88661004 2.26615 9 P 0 
P 10.88661004 2.26615 8 P 0 0;4=12,6=1
P 10.86161004 2.24115 10 P 0 0;2,4=11,6=0
L 10.86161004 2.24115 10.88661004 2.21615 9 P 0 
P 10.88661004 2.21615 8 P 0 0;4=12,6=1
P 10.76161004 1.99115 10 P 0 0;2,4=11,6=0
L 10.76161004 1.99115 10.73661004 1.96615 9 P 0 
P 10.73661004 1.96615 8 P 0 0;4=12,6=1
P 10.71161004 2.04115 10 P 0 0;2,4=11,6=0
L 10.71161004 2.04115 10.68661004 2.01615 9 P 0 
P 10.68661004 2.01615 8 P 0 0;4=12,6=1
P 10.76161004 2.14115 10 P 0 0;2,4=11,6=0
L 10.76161004 2.14115 10.73661004 2.11615 9 P 0 
P 10.73661004 2.11615 8 P 0 0;4=12,6=1
P 10.81161004 2.14115 10 P 0 0;2,4=11,6=0
L 10.81161004 2.14115 10.78661004 2.11615 9 P 0 
P 10.78661004 2.11615 8 P 0 0;4=12,6=1
P 10.81161004 2.04115 10 P 0 0;2,4=11,6=0
L 10.81161004 2.04115 10.78661004 2.01615 9 P 0 
P 10.78661004 2.01615 8 P 0 0;4=12,6=1
P 10.81161004 1.99115 10 P 0 0;2,4=11,6=0
L 10.81161004 1.99115 10.78661004 1.96615 9 P 0 
P 10.78661004 1.96615 8 P 0 0;4=12,6=1
P 10.81161004 2.09115 10 P 0 0;2,4=11,6=0
L 10.81161004 2.09115 10.78661004 2.06615 9 P 0 
P 10.78661004 2.06615 8 P 0 0;4=12,6=1
P 10.71161004 2.19115 10 P 0 0;2,4=11,6=0
L 10.68661004 2.16615 10.71161004 2.19115 9 P 0 
P 10.68661004 2.16615 8 P 0 0;4=12,6=1
P 10.76161004 2.19115 10 P 0 0;2,4=11,6=0
L 10.76161004 2.19115 10.73661004 2.16615 9 P 0 
P 10.73661004 2.16615 8 P 0 0;4=12,6=1
P 10.86161004 2.04115 10 P 0 0;2,4=11,6=0
L 10.86161004 2.04115 10.88661004 2.01615 9 P 0 
P 10.88661004 2.01615 8 P 0 0;4=12,6=1
P 10.86161004 2.09115 10 P 0 0;2,4=11,6=0
L 10.86161004 2.09115 10.88661004 2.06615 9 P 0 
P 10.88661004 2.06615 8 P 0 0;4=12,6=1
P 10.86161004 2.14115 10 P 0 0;2,4=11,6=0
L 10.86161004 2.14115 10.88661004 2.11615 9 P 0 
P 10.88661004 2.11615 8 P 0 0;4=12,6=1
P 10.86161004 1.99115 10 P 0 0;2,4=11,6=0
L 10.86161004 1.99115 10.88661004 1.96615 9 P 0 
P 10.88661004 1.96615 8 P 0 0;4=12,6=1
P 10.81161004 1.94115 10 P 0 0;2,4=11,6=0
L 10.81161004 1.94115 10.78661004 1.91615 9 P 0 
P 10.78661004 1.91615 8 P 0 0;4=12,6=1
P 10.71161004 1.89115 10 P 0 0;2,4=11,6=0
L 10.71161004 1.89115 10.68661004 1.86615 9 P 0 
P 10.68661004 1.86615 8 P 0 0;4=12,6=1
P 10.81161004 1.89115 10 P 0 0;2,4=11,6=0
L 10.81161004 1.89115 10.78661004 1.86615 9 P 0 
P 10.78661004 1.86615 8 P 0 0;4=12,6=1
P 10.86161004 1.89115 10 P 0 0;2,4=11,6=0
L 10.86161004 1.89115 10.88661004 1.86615 9 P 0 
P 10.88661004 1.86615 8 P 0 0;4=12,6=1
P 10.86161004 1.94115 10 P 0 0;2,4=11,6=0
L 10.86161004 1.94115 10.88661004 1.91615 9 P 0 
P 10.66161004 2.74115 10 P 0 0;2,4=11,6=0
L 10.66161004 2.74115 10.63661004 2.71615 9 P 0 
P 10.63661004 2.71615 8 P 0 0;4=12,6=1
P 10.66161004 2.79115 10 P 0 0;2,4=11,6=0
L 10.66161004 2.79115 10.63661004 2.76615 9 P 0 
P 10.63661004 2.76615 8 P 0 0;4=12,6=1
P 10.66161004 2.59115 10 P 0 0;2,4=11,6=0
L 10.66161004 2.59115 10.63661004 2.56615 9 P 0 
P 10.63661004 2.56615 8 P 0 0;4=12,6=1
P 10.61161004 2.69115 10 P 0 0;2,4=11,6=0
L 10.61161004 2.69115 10.58661004 2.66615 9 P 0 
P 10.58661004 2.66615 8 P 0 0;4=12,6=1
P 10.66161004 2.54115 10 P 0 0;2,4=11,6=0
L 10.66161004 2.54115 10.63661004 2.51615 9 P 0 
P 10.63661004 2.51615 8 P 0 0;4=12,6=1
P 10.61161004 2.54115 10 P 0 0;2,4=11,6=0
L 10.61161004 2.54115 10.58661004 2.51615 9 P 0 
P 10.58661004 2.51615 8 P 0 0;4=12,6=1
P 10.61161004 2.49115 10 P 0 0;2,4=11,6=0
L 10.61161004 2.49115 10.58661004 2.46615 9 P 0 
P 10.58661004 2.46615 8 P 0 0;4=12,6=1
P 10.66161004 2.39115 10 P 0 0;2,4=11,6=0
L 10.66161004 2.39115 10.63661004 2.36615 9 P 0 
P 10.63661004 2.36615 8 P 0 0;4=12,6=1
P 10.61161004 2.34115 10 P 0 0;2,4=11,6=0
L 10.61161004 2.34115 10.58661004 2.31615 9 P 0 
P 10.58661004 2.31615 8 P 0 0;4=12,6=1
L 10.63661004 2.21615 10.66161004 2.24115 9 P 0 
P 10.61161004 2.04115 10 P 0 0;2,4=11,6=0
L 10.61161004 2.04115 10.58661004 2.01615 9 P 0 
P 10.58661004 2.01615 8 P 0 0;4=12,6=1
P 10.66161004 1.99115 10 P 0 0;2,4=11,6=0
L 10.66161004 1.99115 10.63661004 1.96615 9 P 0 
P 10.63661004 1.96615 8 P 0 0;4=12,6=1
P 10.66161004 2.14115 10 P 0 0;2,4=11,6=0
L 10.66161004 2.14115 10.63661004 2.11615 9 P 0 
P 10.63661004 2.11615 8 P 0 0;4=12,6=1
P 10.66161004 2.19115 10 P 0 0;2,4=11,6=0
L 10.66161004 2.19115 10.63661004 2.16615 9 P 0 
P 10.61161004 1.89115 10 P 0 0;2,4=11,6=0
L 10.61161004 1.89115 10.58661004 1.86615 9 P 0 
P 10.58661004 1.86615 8 P 0 0;4=12,6=1
L 3.08113996 4.92 3.08113996 4.97913996 6 P 0 
P 1.92346004 5.377 9 P 0 0;4=13,6=1
P 2.14346004 5.377 9 P 0 0;4=13,6=1
L 2.27086998 4.92 2.27086998 4.85788002 6 P 0 
L 2.34173996 4.92 2.34173996 4.85788002 6 P 0 
L 1.91653996 4.92 1.91653996 4.85788002 6 P 0 
L 2.05828002 4.92 2.05828002 4.85788002 6 P 0 
L 1.70395 4.92 1.70395 4.85788002 6 P 0 
L 1.84568002 4.92 1.84568002 4.85788002 6 P 0 
L 1.63308002 4.92 1.63308002 4.85788002 6 P 0 
P 7.927 5.377 9 P 0 0;4=13,6=1
P 8.147 5.377 9 P 0 0;4=13,6=1
S P 0
OB 3.4358 4.744180019685 I
OC 3.4358 4.744180019685 3.43003996063 4.744180019685 Y
OE
SE
P 3.43003996 4.74418002 9 P 0 0;4=13,6=1
S P 0
OB 3.517530019685 4.68098996063 I
OC 3.517530019685 4.68098996063 3.511769980315 4.68098996063 Y
OE
SE
P 3.51176998 4.68098996 9 P 0 0;4=13,6=1
S P 0
OB 3.577530019685 4.68098996063 I
OC 3.577530019685 4.68098996063 3.571769980315 4.68098996063 Y
OE
SE
P 3.57176998 4.68098996 9 P 0 0;4=13,6=1
S P 0
OB 3.2232 4.744180019685 I
OC 3.2232 4.744180019685 3.21743996063 4.744180019685 Y
OE
SE
P 3.21743996 4.74418002 9 P 0 0;4=13,6=1
S P 0
OB 3.3758 4.744180019685 I
OC 3.3758 4.744180019685 3.37003996063 4.744180019685 Y
OE
SE
P 3.37003996 4.74418002 9 P 0 0;4=13,6=1
P 3.41 5.332 9 P 0 0;4=13,6=1
L 3.50633996 4.92 3.50633996 4.85788002 6 P 0 
S P 0
OB 5.38623996063 1.5957 I
OC 5.38623996063 1.5957 5.380480019685 1.5957 Y
OE
SE
P 5.38048002 1.5957 9 P 0 0;4=13,6=1
S P 0
OB 5.38623996063 1.7891 I
OC 5.38623996063 1.7891 5.380480019685 1.7891 Y
OE
SE
P 5.38048002 1.7891 9 P 0 0;4=13,6=1
S P 0
OB 5.38623996063 1.732 I
OC 5.38623996063 1.732 5.380480019685 1.732 Y
OE
SE
P 5.38048002 1.732 9 P 0 0;4=13,6=1
S P 0
OB 5.38623996063 1.6528 I
OC 5.38623996063 1.6528 5.380480019685 1.6528 Y
OE
SE
P 5.38048002 1.6528 9 P 0 0;4=13,6=1
S P 0
OB 5.541069980315 1.8603 I
OC 5.541069980315 1.8603 5.53531003937 1.8603 Y
OE
SE
P 5.53531004 1.8603 9 P 0 0;4=13,6=1
S P 0
OB 5.541069980315 1.8032 I
OC 5.541069980315 1.8032 5.53531003937 1.8032 Y
OE
SE
P 5.53531004 1.8032 9 P 0 0;4=13,6=1
S P 0
OB 5.541069980315 2.2727 I
OC 5.541069980315 2.2727 5.53531003937 2.2727 Y
OE
SE
P 5.53531004 2.2727 9 P 0 0;4=13,6=1
S P 0
OB 5.541069980315 2.1373 I
OC 5.541069980315 2.1373 5.53531003937 2.1373 Y
OE
SE
P 5.53531004 2.1373 9 P 0 0;4=13,6=1
S P 0
OB 5.541069980315 1.9964 I
OC 5.541069980315 1.9964 5.53531003937 1.9964 Y
OE
SE
P 5.53531004 1.9964 9 P 0 0;4=13,6=1
S P 0
OB 5.38623996063 2.3403 I
OC 5.38623996063 2.3403 5.380480019685 2.3403 Y
OE
SE
P 5.38048002 2.3403 9 P 0 0;4=13,6=1
S P 0
OB 5.38623996063 2.2832 I
OC 5.38623996063 2.2832 5.380480019685 2.2832 Y
OE
SE
P 5.38048002 2.2832 9 P 0 0;4=13,6=1
S P 0
OB 5.38623996063 2.2049 I
OC 5.38623996063 2.2049 5.380480019685 2.2049 Y
OE
SE
P 5.38048002 2.2049 9 P 0 0;4=13,6=1
S P 0
OB 5.38623996063 2.1478 I
OC 5.38623996063 2.1478 5.380480019685 2.1478 Y
OE
SE
P 5.38048002 2.1478 9 P 0 0;4=13,6=1
S P 0
OB 5.38623996063 2.0642 I
OC 5.38623996063 2.0642 5.380480019685 2.0642 Y
OE
SE
P 5.38048002 2.0642 9 P 0 0;4=13,6=1
S P 0
OB 5.38623996063 2.0071 I
OC 5.38623996063 2.0071 5.380480019685 2.0071 Y
OE
SE
P 5.38048002 2.0071 9 P 0 0;4=13,6=1
S P 0
OB 5.38623996063 1.9288 I
OC 5.38623996063 1.9288 5.380480019685 1.9288 Y
OE
SE
P 5.38048002 1.9288 9 P 0 0;4=13,6=1
S P 0
OB 5.38623996063 1.8717 I
OC 5.38623996063 1.8717 5.380480019685 1.8717 Y
OE
SE
P 5.38048002 1.8717 9 P 0 0;4=13,6=1
S P 0
OB 5.541069980315 2.351 I
OC 5.541069980315 2.351 5.53531003937 2.351 Y
OE
SE
P 5.53531004 2.351 9 P 0 0;4=13,6=1
S P 0
OB 5.38623996063 2.4757 I
OC 5.38623996063 2.4757 5.380480019685 2.4757 Y
OE
SE
P 5.38048002 2.4757 9 P 0 0;4=13,6=1
S P 0
OB 5.38623996063 2.4186 I
OC 5.38623996063 2.4186 5.380480019685 2.4186 Y
OE
SE
P 5.38048002 2.4186 9 P 0 0;4=13,6=1
S P 0
OB 5.541069980315 2.4902 I
OC 5.541069980315 2.4902 5.53531003937 2.4902 Y
OE
SE
P 5.53531004 2.4902 9 P 0 0;4=13,6=1
S P 0
OB 5.541069980315 2.6825 I
OC 5.541069980315 2.6825 5.53531003937 2.6825 Y
OE
SE
P 5.53531004 2.6825 9 P 0 0;4=13,6=1
S P 0
OB 5.541069980315 2.6254 I
OC 5.541069980315 2.6254 5.53531003937 2.6254 Y
OE
SE
P 5.53531004 2.6254 9 P 0 0;4=13,6=1
S P 0
OB 5.38623996063 2.5578 I
OC 5.38623996063 2.5578 5.380480019685 2.5578 Y
OE
SE
P 5.38048002 2.5578 9 P 0 0;4=13,6=1
S P 0
OB 5.38623996063 2.6149 I
OC 5.38623996063 2.6149 5.380480019685 2.6149 Y
OE
SE
P 5.38048002 2.6149 9 P 0 0;4=13,6=1
L 6.385 5.07 6.40123996 5.07 7 P 0 
L 6.40123996 5.07 6.42418996 5.04705 7 P 0 
L 6.42418996 5.04705 6.42418996 4.99705 7 P 0 
P 6.42418996 4.99705 28 P 0 0;2,4=4,6=0
P 6.42418996 5.04705 28 P 0 0;2,4=4,6=0
P 10.43 1.3341 9 P 0 0;4=13,6=1
P 10.43 1.277 9 P 0 0;4=13,6=1
P 10.4159 1.43 9 P 0 0;4=13,6=1
P 10.473 1.43 9 P 0 0;4=13,6=1
S P 0
OB 10.379019980315 1.553580019685 I
OC 10.379019980315 1.553580019685 10.37326003937 1.553580019685 Y
OE
SE
P 10.37313996 1.55336004 9 P 0 0;4=13,6=1
S P 0
OB 10.420269980315 1.511980019685 I
OC 10.420269980315 1.511980019685 10.41451003937 1.511980019685 Y
OE
SE
P 10.41451004 1.51198002 9 P 0 0;4=13,6=1
S P 0
OB 10.30076003937 1.713 I
OC 10.30076003937 1.713 10.295 1.713 Y
OE
SE
P 10.295 1.713 9 P 0 0;4=13,6=1
S P 0
OB 10.30076003937 1.6559 I
OC 10.30076003937 1.6559 10.295 1.6559 Y
OE
SE
P 10.295 1.6559 9 P 0 0;4=13,6=1
P 10.26 1.9179 9 P 0 0;4=13,6=1
P 10.29525 1.877 9 P 0 0;4=13,6=1
P 10.29525 1.8199 9 P 0 0;4=13,6=1
P 10.26 1.975 9 P 0 0;4=13,6=1
P 10.125 2.0651 9 P 0 0;4=13,6=1
S P 0
OB 10.13076003937 2.1224 I
OC 10.13076003937 2.1224 10.125 2.1224 Y
OE
SE
P 10.125 2.1224 9 P 0 0;4=13,6=1
S P 0
OB 10.13076003937 2.1795 I
OC 10.13076003937 2.1795 10.125 2.1795 Y
OE
SE
P 10.125 2.1795 9 P 0 0;4=13,6=1
S P 0
OB 10.01576003937 2.2481 I
OC 10.01576003937 2.2481 10.01 2.2481 Y
OE
SE
P 10.01 2.2481 9 P 0 0;4=13,6=1
S P 0
OB 10.01576003937 2.191 I
OC 10.01576003937 2.191 10.01 2.191 Y
OE
SE
P 10.01 2.191 9 P 0 0;4=13,6=1
S P 0
OB 10.01576003937 2.38435 I
OC 10.01576003937 2.38435 10.01 2.38435 Y
OE
SE
P 10.01 2.38435 9 P 0 0;4=13,6=1
S P 0
OB 10.01576003937 2.32725 I
OC 10.01576003937 2.32725 10.01 2.32725 Y
OE
SE
P 10.01 2.32725 9 P 0 0;4=13,6=1
S P 0
OB 10.13076003937 2.3168 I
OC 10.13076003937 2.3168 10.125 2.3168 Y
OE
SE
P 10.125 2.3168 9 P 0 0;4=13,6=1
S P 0
OB 10.13076003937 2.2597 I
OC 10.13076003937 2.2597 10.125 2.2597 Y
OE
SE
P 10.125 2.2597 9 P 0 0;4=13,6=1
S P 0
OB 10.13076003937 2.4519 I
OC 10.13076003937 2.4519 10.125 2.4519 Y
OE
SE
P 10.125 2.4519 9 P 0 0;4=13,6=1
S P 0
OB 10.13076003937 2.3948 I
OC 10.13076003937 2.3948 10.125 2.3948 Y
OE
SE
P 10.125 2.3948 9 P 0 0;4=13,6=1
S P 0
OB 10.01576003937 2.51945 I
OC 10.01576003937 2.51945 10.01 2.51945 Y
OE
SE
P 10.01 2.51945 9 P 0 0;4=13,6=1
S P 0
OB 10.01576003937 2.46235 I
OC 10.01576003937 2.46235 10.01 2.46235 Y
OE
SE
P 10.01 2.46235 9 P 0 0;4=13,6=1
S P 0
OB 10.13076003937 2.587 I
OC 10.13076003937 2.587 10.125 2.587 Y
OE
SE
P 10.125 2.587 9 P 0 0;4=13,6=1
S P 0
OB 10.13076003937 2.5299 I
OC 10.13076003937 2.5299 10.125 2.5299 Y
OE
SE
P 10.125 2.5299 9 P 0 0;4=13,6=1
S P 0
OB 10.01576003937 2.673 I
OC 10.01576003937 2.673 10.01 2.673 Y
OE
SE
P 10.01 2.673 9 P 0 0;4=13,6=1
S P 0
OB 10.01576003937 2.6159 I
OC 10.01576003937 2.6159 10.01 2.6159 Y
OE
SE
P 10.01 2.6159 9 P 0 0;4=13,6=1
P 11.74316004 1.7035 9 P 0 0;4=13,6=1
P 11.74316004 1.6405 9 P 0 0;4=13,6=1
S P 0
OB 11.699419980315 1.481 I
OC 11.699419980315 1.481 11.69366003937 1.481 Y
OE
SE
P 11.69316004 1.4805 9 P 0 0;4=13,6=1
S P 0
OB 11.699419980315 1.544 I
OC 11.699419980315 1.544 11.69366003937 1.544 Y
OE
SE
P 11.69316004 1.5435 9 P 0 0;4=13,6=1
S P 0
OB 11.499419980315 1.561 I
OC 11.499419980315 1.561 11.49366003937 1.561 Y
OE
SE
P 11.49316004 1.5605 9 P 0 0;4=13,6=1
S P 0
OB 11.499419980315 1.624 I
OC 11.499419980315 1.624 11.49366003937 1.624 Y
OE
SE
P 11.49316004 1.6235 9 P 0 0;4=13,6=1
S P 0
OB 11.499419980315 1.464 I
OC 11.499419980315 1.464 11.49366003937 1.464 Y
OE
SE
P 11.49316004 1.4635 9 P 0 0;4=13,6=1
S P 0
OB 11.499419980315 1.401 I
OC 11.499419980315 1.401 11.49366003937 1.401 Y
OE
SE
P 11.49366004 1.401 9 P 0 0;4=13,6=1
S P 0
OB 11.699419980315 2.601 I
OC 11.699419980315 2.601 11.69366003937 2.601 Y
OE
SE
P 11.69316004 2.6005 9 P 0 0;4=13,6=1
S P 0
OB 11.699419980315 2.504 I
OC 11.699419980315 2.504 11.69366003937 2.504 Y
OE
SE
P 11.69316004 2.5035 9 P 0 0;4=13,6=1
S P 0
OB 11.699419980315 2.441 I
OC 11.699419980315 2.441 11.69366003937 2.441 Y
OE
SE
P 11.69316004 2.4405 9 P 0 0;4=13,6=1
S P 0
OB 11.699419980315 2.344 I
OC 11.699419980315 2.344 11.69366003937 2.344 Y
OE
SE
P 11.69316004 2.3435 9 P 0 0;4=13,6=1
S P 0
OB 11.699419980315 2.281 I
OC 11.699419980315 2.281 11.69366003937 2.281 Y
OE
SE
P 11.69316004 2.2805 9 P 0 0;4=13,6=1
S P 0
OB 11.699419980315 2.184 I
OC 11.699419980315 2.184 11.69366003937 2.184 Y
OE
SE
P 11.69316004 2.1835 9 P 0 0;4=13,6=1
S P 0
OB 11.699419980315 1.961 I
OC 11.699419980315 1.961 11.69366003937 1.961 Y
OE
SE
P 11.69316004 1.9605 9 P 0 0;4=13,6=1
S P 0
OB 11.699419980315 2.024 I
OC 11.699419980315 2.024 11.69366003937 2.024 Y
OE
SE
P 11.69316004 2.0235 9 P 0 0;4=13,6=1
S P 0
OB 11.699419980315 2.121 I
OC 11.699419980315 2.121 11.69366003937 2.121 Y
OE
SE
P 11.69316004 2.1205 9 P 0 0;4=13,6=1
S P 0
OB 11.699419980315 1.801 I
OC 11.699419980315 1.801 11.69366003937 1.801 Y
OE
SE
P 11.69316004 1.8005 9 P 0 0;4=13,6=1
S P 0
OB 11.699419980315 1.864 I
OC 11.699419980315 1.864 11.69366003937 1.864 Y
OE
SE
P 11.69316004 1.8635 9 P 0 0;4=13,6=1
S P 0
OB 11.499419980315 2.521 I
OC 11.499419980315 2.521 11.49366003937 2.521 Y
OE
SE
P 11.49316004 2.5205 9 P 0 0;4=13,6=1
S P 0
OB 11.499419980315 2.584 I
OC 11.499419980315 2.584 11.49366003937 2.584 Y
OE
SE
P 11.49316004 2.5835 9 P 0 0;4=13,6=1
S P 0
OB 11.499419980315 2.424 I
OC 11.499419980315 2.424 11.49366003937 2.424 Y
OE
SE
P 11.49316004 2.4235 9 P 0 0;4=13,6=1
S P 0
OB 11.499419980315 2.361 I
OC 11.499419980315 2.361 11.49366003937 2.361 Y
OE
SE
P 11.49316004 2.3605 9 P 0 0;4=13,6=1
P 11.79316004 2.2635 9 P 0 0;4=13,6=1
P 11.79316004 2.2005 9 P 0 0;4=13,6=1
S P 0
OB 11.499419980315 1.944 I
OC 11.499419980315 1.944 11.49366003937 1.944 Y
OE
SE
P 11.49316004 1.9435 9 P 0 0;4=13,6=1
S P 0
OB 11.499419980315 2.104 I
OC 11.499419980315 2.104 11.49366003937 2.104 Y
OE
SE
P 11.49316004 2.1035 9 P 0 0;4=13,6=1
S P 0
OB 11.499419980315 2.041 I
OC 11.499419980315 2.041 11.49366003937 2.041 Y
OE
SE
P 11.49316004 2.0405 9 P 0 0;4=13,6=1
S P 0
OB 11.499419980315 1.881 I
OC 11.499419980315 1.881 11.49366003937 1.881 Y
OE
SE
P 11.49316004 1.8805 9 P 0 0;4=13,6=1
S P 0
OB 11.499419980315 1.721 I
OC 11.499419980315 1.721 11.49366003937 1.721 Y
OE
SE
P 11.49366004 1.721 9 P 0 0;4=13,6=1
S P 0
OB 11.499419980315 1.784 I
OC 11.499419980315 1.784 11.49366003937 1.784 Y
OE
SE
P 11.49316004 1.7835 9 P 0 0;4=13,6=1
L 11.01161004 2.39115 11.03661004 2.41615 9 P 0 
L 11.01161004 2.39115 11.03661004 2.36615 9 P 0 
L 10.61161004 2.19115 10.63661004 2.21615 9 P 0 
L 10.61161004 2.19115 10.58661004 2.16615 9 P 0 
L 3.82558996 4.63965 3.82558996 4.60941004 7 P 0 
L 3.82558996 4.60941004 3.835 4.6 7 P 0 
L 9.40795 0.29243002 9.40795 0.26133002 7 P 0 
L 9.61795 0.79643002 9.64796004 0.79643002 7 P 0 
L 3.60998996 0.2711 3.60998996 0.24 7 P 0 
S P 0
OB 10.13076003937 2.7451 I
OC 10.13076003937 2.7451 10.125 2.7451 Y
OE
SE
P 10.125 2.7451 9 P 0 0;4=13,6=1
S P 0
OB 10.13076003937 2.688 I
OC 10.13076003937 2.688 10.125 2.688 Y
OE
SE
P 10.125 2.688 9 P 0 0;4=13,6=1
L 4.29723996 2.86613996 4.23528002 2.9281 9 P 0 
L 4.23528002 2.9281 4.15221004 2.9281 9 P 0 
L 10.30118002 2.86613996 10.24503996 2.81 9 P 0 
L 10.24503996 2.81 10.16606998 2.81 9 P 0 
P 12.34 2.19 9 P 0 0;4=13,6=1
P 9.415 5.332 9 P 0 0;4=13,6=1
P 9.265 5.332 9 P 0 0;4=13,6=1
P 9.07 5.332 9 P 0 0;4=13,6=1
L 3.77 4.827 3.77 4.86 7 P 0 
L 3.64441004 4.67035 3.64441004 4.64558996 7 P 0 
L 3.64441004 4.64558996 3.66 4.63 7 P 0 
L 5.04441004 5.64035 5.04441004 5.605 7 P 0 
L 4.76 5.54928996 4.7 5.54928996 9 P 0 
P 4.76 5.54928996 54 P 0 0;2,4=9,6=0
P 4.7 5.54928996 9 P 0 0;4=13,6=1
P 4.81 5.408 28 P 0 0;2,4=4,6=0
P 4.81 5.375 9 P 0 0;4=13,6=1
P 4.96 5.408 28 P 0 0;2,4=4,6=0
P 4.96 5.375 9 P 0 0;4=13,6=1
L 5.16 5.645 5.16 5.617 9 P 0 
P 5.16 5.617 28 P 0 0;2,4=4,6=0
P 5.16 5.645 9 P 0 0;4=13,6=1
P 5.04441004 5.64035 37 P 0 0;2,4=8,6=0
P 5.04441004 5.605 9 P 0 0;4=13,6=1
L 4.92 5.65315 4.92 5.7 9 P 0 
P 4.92 5.65315 41 P 0 0;2,4=5,6=0
P 4.92 5.7 9 P 0 0;4=13,6=1
L 9.91 4.667 9.91 4.7 7 P 0 
P 9.91 4.667 28 P 0 0;2,4=4,6=0
P 9.91 4.7 9 P 0 0;4=13,6=1
L 3.57 4.483 3.57 4.45 7 P 0 
P 3.57 4.483 28 P 0 0;2,4=4,6=0
P 3.57 4.45 9 P 0 0;4=13,6=1
P 11.87126004 4.88 39 P 0 0;2,4=29,6=0
P 10.465 5.195 9 P 0 0;4=13,6=1
L 10.543 5.32 10.515 5.32 9 P 0 
P 10.515 5.32 9 P 0 0;4=13,6=1
P 10.465 5.275 9 P 0 0;4=13,6=1
P 12.025 4.915 9 P 0 0;4=13,6=1
L 12.12 4.993 12.12 4.965 9 P 0 
P 12.12 4.965 9 P 0 0;4=13,6=1
P 12.185 4.915 9 P 0 0;4=13,6=1
L 9.97441004 4.73035 9.97441004 4.70441004 7 P 0 
L 9.97441004 4.70441004 9.96 4.69 7 P 0 
L 3.72 4.483 3.72 4.45 7 P 0 
P 3.72 4.483 28 P 0 0;2,4=4,6=0
P 3.72 4.45 9 P 0 0;4=13,6=1
P 3.64441004 4.67035 37 P 0 0;2,4=8,6=0
P 3.66 4.63 9 P 0 0;4=13,6=1
P 3.77 4.827 28 P 0 0;2,4=4,6=0
P 3.77 4.86 9 P 0 0;4=13,6=1
P 9.97441004 4.73035 37 P 0 0;2,4=8,6=0
P 9.96 4.69 9 P 0 0;4=13,6=1
L 10.03 4.543 10.03 4.51 7 P 0 
P 10.03 4.543 28 P 0 0;2,4=4,6=0
P 10.03 4.51 9 P 0 0;4=13,6=1
P 3.835 4.6 9 P 0 0;4=13,6=1
P 3.99965 4.66441004 47 P 0 0;2,4=8,6=0
P 3.9865 4.635 9 P 0 0;4=13,6=1
L 4.14 4.683 4.14 4.655 7 P 0 
P 4.14 4.683 28 P 0 0;2,4=4,6=0
P 4.14 4.655 9 P 0 0;4=13,6=1
L 4.1049 4.79498996 4.1049 4.7649 7 P 0 
P 4.1049 4.79498996 28 P 0 0;2,4=4,6=0
P 4.1049 4.7649 9 P 0 0;4=13,6=1
P 1.28051004 5.53641998 48 P 0 0;2,4=16,6=0
L 1.28051004 5.70373996 1.28051004 5.78 9 P 0 
P 1.28051004 5.70373996 48 P 0 0;2,4=16,6=0
P 1.28051004 5.78 9 P 0 0;4=13,6=1
L 3.88313002 5.18321004 3.88313002 5.13813002 7 P 0 
L 3.88313002 5.13813002 3.87 5.125 7 P 0 
P 3.88313002 5.18321004 38 P 0 0;2,4=20,6=0
P 3.87 5.125 9 P 0 0;4=13,6=1
L 0.4826 5.85528002 0.4826 5.8976 9 P 0 
P 0.4826 5.85528002 40 P 0 0;2,4=27,6=0
P 0.4826 5.8976 9 P 0 0;4=13,6=1
L 0.73 5.267 0.7 5.267 9 P 0 
L 0.84953002 5.1239 0.84953002 5.17 6 P 0 
P 0.84953002 5.1239 35 P 0 0;2,4=10,6=0
P 0.84953002 5.17 9 P 0 0;4=13,6=1
L 0.955 5.325 0.97441004 5.30558996 7 P 0 
L 0.97441004 5.30558996 0.97441004 5.29035 7 P 0 
P 0.97441004 5.29035 37 P 0 0;2,4=8,6=0
P 0.955 5.325 9 P 0 0;4=13,6=1
P 1.03 5.093 28 P 0 0;2,4=4,6=0
P 0.73 5.147 28 P 0 0;2,4=4,6=0
P 0.73 5.267 28 P 0 0;2,4=4,6=0
P 0.705 5.383 28 P 0 0;2,4=4,6=0
P 1.455 5.857 28 P 0 0;2,4=4,6=0
P 1.405 5.857 28 P 0 0;2,4=4,6=0
P 1.355 5.857 28 P 0 0;2,4=4,6=0
P 1.305 5.857 28 P 0 0;2,4=4,6=0
P 1.46 5.383 28 P 0 0;2,4=4,6=0
P 1.41 5.383 28 P 0 0;2,4=4,6=0
P 1.36 5.383 28 P 0 0;2,4=4,6=0
L 1.31 5.383 1.31 5.355 9 P 0 
P 1.31 5.383 28 P 0 0;2,4=4,6=0
P 1.31 5.355 9 P 0 0;4=13,6=1
P 1.51673002 5.53641998 48 P 0 0;2,4=16,6=0
P 1.20176998 5.53641998 48 P 0 0;2,4=16,6=0
P 1.12303002 5.53641998 48 P 0 0;2,4=16,6=0
P 1.51673002 5.70373996 48 P 0 0;2,4=16,6=0
L 1.20176998 5.70373996 1.20176998 5.78 9 P 0 
P 1.20176998 5.70373996 48 P 0 0;2,4=16,6=0
P 1.20176998 5.78 9 P 0 0;4=13,6=1
L 6.87018996 4.88705 6.905 4.88705 9 P 0 
L 6.87018996 4.94705 6.905 4.94705 9 P 0 
P 6.31295 4.99705 9 P 0 0;4=13,6=1
L 6.837 5 6.87 5 9 P 0 
P 6.87 5 9 P 0 0;4=13,6=1
P 9.64796004 0.79643002 9 P 0 0;4=13,6=1
P 9.40795 0.26133002 9 P 0 0;4=13,6=1
P 9.45795 0.42821004 43 P 0 0;2,4=28,6=0
P 3.60998996 0.24 9 P 0 0;4=13,6=1
L 3.65998996 0.40688002 3.65998996 0.345 9 P 0 
P 3.65998996 0.40688002 43 P 0 0;2,4=28,6=0
P 3.65998996 0.345 9 P 0 0;4=13,6=1
P 3.86 0.7751 9 P 0 0;4=0,6=1
P 6.57318996 5.09705 28 P 0 0;2,4=4,6=0
P 6.87018996 4.94705 29 P 0 0;2,4=23,6=0
P 6.905 4.94705 9 P 0 0;4=13,6=1
P 6.87018996 4.88705 29 P 0 0;2,4=23,6=0
P 6.905 4.88705 9 P 0 0;4=13,6=1
P 6.91118996 4.81705 31 P 0 0;2,4=21,6=0
P 6.955 4.8 9 P 0 0;4=13,6=1
P 6.955 4.84 9 P 0 0;4=13,6=1
P 6.955 4.72 9 P 0 0;4=13,6=1
P 6.955 4.76 9 P 0 0;4=13,6=1
P 6.59708996 5.0502 9 P 0 0;4=13,6=1
P 6.67918996 4.77205 28 P 0 0;2,4=4,6=0
P 6.57618996 4.76905 28 P 0 0;2,4=4,6=0
P 6.65268996 4.82846998 49 P 0 0;2,4=19,6=0
P 6.63693996 4.82846998 49 P 0 0;2,4=19,6=0
P 6.62118996 4.82846998 49 P 0 0;2,4=19,6=0
P 6.60543996 4.82846998 49 P 0 0;2,4=19,6=0
P 6.58968996 4.82846998 49 P 0 0;2,4=19,6=0
P 6.66208996 4.6252 31 P 0 0;2,4=21,6=0
P 6.66208996 4.7052 31 P 0 0;2,4=21,6=0
P 6.65218996 4.77 9 P 0 0;4=13,6=1
P 6.69008996 4.96428996 46 P 0 0;2,4=19,6=0
P 6.62118996 4.95641998 9 P 0 0;4=30,6=1
P 6.6015 4.93673996 9 P 0 0;4=30,6=1
P 6.64088002 4.93673996 9 P 0 0;4=30,6=1
P 6.62118996 4.91705 9 P 0 0;4=30,6=1
P 6.62118996 4.87768002 9 P 0 0;4=30,6=1
P 6.6015 4.89736004 9 P 0 0;4=30,6=1
P 6.64088002 4.89736004 9 P 0 0;4=30,6=1
P 6.62118996 4.91705 56 P 0 0;2,4=31,6=0
L 6.69008996 4.96428996 6.66843002 4.96428996 3 P 0 
L 6.66843002 4.96428996 6.64088002 4.93673996 3 P 0 
P 6.62 4.69 9 P 0 0;4=13,6=1
P 6.62 4.725 9 P 0 0;4=13,6=1
P 6.385 5.07 9 P 0 0;4=13,6=1
P 5.53593996 4.5861 28 P 0 0;2,4=4,6=0
P 5.53593996 4.55505 9 P 0 0;4=13,6=1
L 5.53593996 4.5861 5.53593996 4.55505 7 P 0 
P 5.99708996 4.5552 31 P 0 0;2,4=21,6=0
P 5.91708996 4.5552 31 P 0 0;2,4=21,6=0
P 6.07708996 4.5552 31 P 0 0;2,4=21,6=0
P 5.75708996 4.5552 31 P 0 0;2,4=21,6=0
P 5.83708996 4.5552 31 P 0 0;2,4=21,6=0
P 5.67708996 4.5552 31 P 0 0;2,4=21,6=0
P 5.59778996 4.5552 31 P 0 0;2,4=21,6=0
P 6.05708996 4.5102 9 P 0 0;4=13,6=1
P 6.01708996 4.5102 9 P 0 0;4=13,6=1
P 5.97708996 4.5102 9 P 0 0;4=13,6=1
P 5.93708996 4.5102 9 P 0 0;4=13,6=1
P 5.89708996 4.5102 9 P 0 0;4=13,6=1
P 6.09708996 4.5102 9 P 0 0;4=13,6=1
P 5.61708996 4.5102 9 P 0 0;4=13,6=1
P 5.65708996 4.5102 9 P 0 0;4=13,6=1
P 5.85708996 4.5102 9 P 0 0;4=13,6=1
P 5.81708996 4.5102 9 P 0 0;4=13,6=1
P 5.77708996 4.5102 9 P 0 0;4=13,6=1
P 5.73708996 4.5102 9 P 0 0;4=13,6=1
P 5.69708996 4.5102 9 P 0 0;4=13,6=1
P 5.57708996 4.5102 9 P 0 0;4=13,6=1
S P 0
OB 0.046980019685 0.561019980315 I
OS 0.046980019685 0.07873996063
OC 0.07873996063 0.046980019685 0.07873996063 0.07873996063 N
OS 4.7756 0.046980019685
OC 4.80736003937 0.07873996063 4.775600098425 0.07873996063 N
OS 4.80736003937 0.35433996063
OC 4.933069980315 0.48006003937 4.933080019685 0.354340059055 Y
OS 6.507880019685 0.48006003937
OC 6.6336 0.354330019685 6.507880019685 0.354340059055 Y
OS 6.6336 0.07873996063
OC 6.66536003937 0.046980019685 6.665359940945 0.07873996063 N
OS 7.014 0.046980019685
OS 7.018 0.042980019685
OS 7.018 0.03001003937
OS 7.013 0.02501003937
OS 6.66536003937 0.02501003937
OC 6.611630019685 0.07873996063 6.665359940945 0.07873996063 Y
OS 6.611630019685 0.354330019685
OC 6.507880019685 0.458080019685 6.507880019685 0.354330019685 N
OS 4.933069980315 0.458080019685
OC 4.829330019685 0.35433996063 4.933080019685 0.354330019685 N
OS 4.829330019685 0.07873996063
OC 4.7756 0.02501003937 4.775600098425 0.07873996063 Y
OS 4.2527 0.02501003937
OC 4.251530019685 0.025 4.252728543307 -0.0465 N
OS 4.05388996063 0.025
OC 4.052719980315 0.02501003937 4.052691437008 -0.0465 N
OS 0.07873996063 0.02501003937
OC 0.02501003937 0.07873996063 0.07873996063 0.07873996063 Y
OS 0.02501003937 0.565
OS 0.02898996063 0.569
OS 0.039 0.569
OS 0.046980019685 0.561019980315
OE
SE
P 0.036 0.10868002 9 P 0 0;4=13,6=1
P 0.036 0.15868002 9 P 0 0;4=13,6=1
P 0.036 0.20868002 9 P 0 0;4=13,6=1
P 0.22873996 0.036 9 P 0 0;4=13,6=1
P 0.17873996 0.036 9 P 0 0;4=13,6=1
P 0.12873996 0.036 9 P 0 0;4=13,6=1
P 0.07873996 0.036 9 P 0 0;4=13,6=1
P 0.47873996 0.036 9 P 0 0;4=13,6=1
P 0.42873996 0.036 9 P 0 0;4=13,6=1
P 0.37873996 0.036 9 P 0 0;4=13,6=1
P 0.32873996 0.036 9 P 0 0;4=13,6=1
P 0.27873996 0.036 9 P 0 0;4=13,6=1
P 0.77873996 0.036 9 P 0 0;4=13,6=1
P 0.72873996 0.036 9 P 0 0;4=13,6=1
P 0.67873996 0.036 9 P 0 0;4=13,6=1
P 0.62873996 0.036 9 P 0 0;4=13,6=1
P 0.57873996 0.036 9 P 0 0;4=13,6=1
P 0.52873996 0.036 9 P 0 0;4=13,6=1
P 1.02873996 0.036 9 P 0 0;4=13,6=1
P 0.97873996 0.036 9 P 0 0;4=13,6=1
P 0.92873996 0.036 9 P 0 0;4=13,6=1
P 0.87873996 0.036 9 P 0 0;4=13,6=1
P 0.82873996 0.036 9 P 0 0;4=13,6=1
P 1.27873996 0.036 9 P 0 0;4=13,6=1
P 1.22873996 0.036 9 P 0 0;4=13,6=1
P 1.17873996 0.036 9 P 0 0;4=13,6=1
P 1.12873996 0.036 9 P 0 0;4=13,6=1
P 1.07873996 0.036 9 P 0 0;4=13,6=1
P 1.52873996 0.036 9 P 0 0;4=13,6=1
P 1.47873996 0.036 9 P 0 0;4=13,6=1
P 1.42873996 0.036 9 P 0 0;4=13,6=1
P 1.37873996 0.036 9 P 0 0;4=13,6=1
P 1.32873996 0.036 9 P 0 0;4=13,6=1
P 1.82873996 0.036 9 P 0 0;4=13,6=1
P 1.77873996 0.036 9 P 0 0;4=13,6=1
P 1.72873996 0.036 9 P 0 0;4=13,6=1
P 1.67873996 0.036 9 P 0 0;4=13,6=1
P 1.62873996 0.036 9 P 0 0;4=13,6=1
P 1.57873996 0.036 9 P 0 0;4=13,6=1
P 2.07873996 0.036 9 P 0 0;4=13,6=1
P 2.02873996 0.036 9 P 0 0;4=13,6=1
P 1.97873996 0.036 9 P 0 0;4=13,6=1
P 1.92873996 0.036 9 P 0 0;4=13,6=1
P 1.87873996 0.036 9 P 0 0;4=13,6=1
P 2.32873996 0.036 9 P 0 0;4=13,6=1
P 2.27873996 0.036 9 P 0 0;4=13,6=1
P 2.22873996 0.036 9 P 0 0;4=13,6=1
P 2.17873996 0.036 9 P 0 0;4=13,6=1
P 2.12873996 0.036 9 P 0 0;4=13,6=1
P 2.62873996 0.036 9 P 0 0;4=13,6=1
P 2.57873996 0.036 9 P 0 0;4=13,6=1
P 2.52873996 0.036 9 P 0 0;4=13,6=1
P 2.47873996 0.036 9 P 0 0;4=13,6=1
P 2.42873996 0.036 9 P 0 0;4=13,6=1
P 2.37873996 0.036 9 P 0 0;4=13,6=1
P 2.87873996 0.036 9 P 0 0;4=13,6=1
P 2.82873996 0.036 9 P 0 0;4=13,6=1
P 2.77873996 0.036 9 P 0 0;4=13,6=1
P 2.72873996 0.036 9 P 0 0;4=13,6=1
P 2.67873996 0.036 9 P 0 0;4=13,6=1
P 3.12873996 0.036 9 P 0 0;4=13,6=1
P 3.07873996 0.036 9 P 0 0;4=13,6=1
P 3.02873996 0.036 9 P 0 0;4=13,6=1
P 2.97873996 0.036 9 P 0 0;4=13,6=1
P 2.92873996 0.036 9 P 0 0;4=13,6=1
P 3.37873996 0.036 9 P 0 0;4=13,6=1
P 3.32873996 0.036 9 P 0 0;4=13,6=1
P 3.27873996 0.036 9 P 0 0;4=13,6=1
P 3.22873996 0.036 9 P 0 0;4=13,6=1
P 3.17873996 0.036 9 P 0 0;4=13,6=1
P 3.67873996 0.036 9 P 0 0;4=13,6=1
P 3.62873996 0.036 9 P 0 0;4=13,6=1
P 3.57873996 0.036 9 P 0 0;4=13,6=1
P 3.52873996 0.036 9 P 0 0;4=13,6=1
P 3.47873996 0.036 9 P 0 0;4=13,6=1
P 3.42873996 0.036 9 P 0 0;4=13,6=1
P 3.92873996 0.036 9 P 0 0;4=13,6=1
P 3.87873996 0.036 9 P 0 0;4=13,6=1
P 3.82873996 0.036 9 P 0 0;4=13,6=1
P 3.77873996 0.036 9 P 0 0;4=13,6=1
P 3.72873996 0.036 9 P 0 0;4=13,6=1
P 4.17873996 0.036 9 P 0 0;4=13,6=1
P 4.12873996 0.036 9 P 0 0;4=13,6=1
P 4.07873996 0.036 9 P 0 0;4=13,6=1
P 4.02873996 0.036 9 P 0 0;4=13,6=1
P 3.97873996 0.036 9 P 0 0;4=13,6=1
P 4.42873996 0.036 9 P 0 0;4=13,6=1
P 4.37873996 0.036 9 P 0 0;4=13,6=1
P 4.32873996 0.036 9 P 0 0;4=13,6=1
P 4.27873996 0.036 9 P 0 0;4=13,6=1
P 4.22873996 0.036 9 P 0 0;4=13,6=1
P 4.72873996 0.036 9 P 0 0;4=13,6=1
P 4.67873996 0.036 9 P 0 0;4=13,6=1
P 4.62873996 0.036 9 P 0 0;4=13,6=1
P 4.57873996 0.036 9 P 0 0;4=13,6=1
P 4.52873996 0.036 9 P 0 0;4=13,6=1
P 4.47873996 0.036 9 P 0 0;4=13,6=1
P 4.81833996 0.21825 9 P 0 0;4=13,6=1
P 4.81833996 0.16825 9 P 0 0;4=13,6=1
P 4.81833996 0.11825 9 P 0 0;4=13,6=1
P 4.81703996 0.06826004 9 P 0 0;4=13,6=1
P 4.77873996 0.03611998 9 P 0 0;4=13,6=1
P 6.80731004 0.036 9 P 0 0;4=13,6=1
P 6.75731004 0.036 9 P 0 0;4=13,6=1
P 6.70731004 0.036 9 P 0 0;4=13,6=1
P 6.65731004 0.03676004 9 P 0 0;4=13,6=1
P 6.62298996 0.07311998 9 P 0 0;4=13,6=1
P 6.62261998 0.12311998 9 P 0 0;4=13,6=1
P 6.62261998 0.17311998 9 P 0 0;4=13,6=1
P 6.62261998 0.22311998 9 P 0 0;4=13,6=1
P 7.00731004 0.036 9 P 0 0;4=13,6=1
P 6.95731004 0.036 9 P 0 0;4=13,6=1
P 6.90731004 0.036 9 P 0 0;4=13,6=1
P 6.85731004 0.036 9 P 0 0;4=13,6=1
P 0.036 0.25868002 9 P 0 0;4=13,6=1
P 0.036 0.30868002 9 P 0 0;4=13,6=1
P 0.036 0.35868002 9 P 0 0;4=13,6=1
P 0.036 0.40868002 9 P 0 0;4=13,6=1
P 0.036 0.45868002 9 P 0 0;4=13,6=1
P 4.96803996 0.46906998 9 P 0 0;4=13,6=1
P 4.91805 0.46808002 9 P 0 0;4=13,6=1
P 4.87108996 0.45088996 9 P 0 0;4=13,6=1
P 4.83591004 0.41536004 9 P 0 0;4=13,6=1
P 4.81918996 0.36823996 9 P 0 0;4=13,6=1
P 4.81833996 0.31825 9 P 0 0;4=13,6=1
P 4.81833996 0.26825 9 P 0 0;4=13,6=1
P 5.21803996 0.46906998 9 P 0 0;4=13,6=1
P 5.16803996 0.46906998 9 P 0 0;4=13,6=1
P 5.11803996 0.46906998 9 P 0 0;4=13,6=1
P 5.06803996 0.46906998 9 P 0 0;4=13,6=1
P 5.01803996 0.46906998 9 P 0 0;4=13,6=1
P 5.51803996 0.46906998 9 P 0 0;4=13,6=1
P 5.46803996 0.46906998 9 P 0 0;4=13,6=1
P 5.41803996 0.46906998 9 P 0 0;4=13,6=1
P 5.36803996 0.46906998 9 P 0 0;4=13,6=1
P 5.31803996 0.46906998 9 P 0 0;4=13,6=1
P 5.26803996 0.46906998 9 P 0 0;4=13,6=1
P 5.76803996 0.46906998 9 P 0 0;4=13,6=1
P 5.71803996 0.46906998 9 P 0 0;4=13,6=1
P 5.66803996 0.46906998 9 P 0 0;4=13,6=1
P 5.61803996 0.46906998 9 P 0 0;4=13,6=1
P 5.56803996 0.46906998 9 P 0 0;4=13,6=1
P 6.01803996 0.46906998 9 P 0 0;4=13,6=1
P 5.96803996 0.46906998 9 P 0 0;4=13,6=1
P 5.91803996 0.46906998 9 P 0 0;4=13,6=1
P 5.86803996 0.46906998 9 P 0 0;4=13,6=1
P 5.81803996 0.46906998 9 P 0 0;4=13,6=1
P 6.31803996 0.46906998 9 P 0 0;4=13,6=1
P 6.26803996 0.46906998 9 P 0 0;4=13,6=1
P 6.21803996 0.46906998 9 P 0 0;4=13,6=1
P 6.16803996 0.46906998 9 P 0 0;4=13,6=1
P 6.11803996 0.46906998 9 P 0 0;4=13,6=1
P 6.06803996 0.46906998 9 P 0 0;4=13,6=1
P 6.56568002 0.45345 9 P 0 0;4=13,6=1
P 6.51803002 0.46861998 9 P 0 0;4=13,6=1
P 6.46803996 0.46906998 9 P 0 0;4=13,6=1
P 6.41803996 0.46906998 9 P 0 0;4=13,6=1
P 6.36803996 0.46906998 9 P 0 0;4=13,6=1
P 6.62261998 0.27311998 9 P 0 0;4=13,6=1
P 6.62261998 0.32311998 9 P 0 0;4=13,6=1
P 6.62106998 0.3731 9 P 0 0;4=13,6=1
P 6.60233996 0.41946004 9 P 0 0;4=13,6=1
P 0.036 0.50868002 9 P 0 0;4=13,6=1
P 0.036 0.55868002 9 P 0 0;4=13,6=1
P 11.845 2.85 9 P 0 0;4=13,6=1
S P 0
OB 8.98691003937 2.7861 I
OC 8.98691003937 2.7861 8.98115 2.7861 Y
OE
SE
P 8.98115 2.7861 9 P 0 0;4=13,6=1
S P 0
OB 8.98691003937 2.8989 I
OC 8.98691003937 2.8989 8.98115 2.8989 Y
OE
SE
P 8.98115 2.8989 9 P 0 0;4=13,6=1
P 11.58613002 2.855 9 P 0 0;4=13,6=1
P 11.50361998 2.8 9 P 0 0;4=13,6=1
P 11.50361998 2.73 9 P 0 0;4=13,6=1
P 5.5722 3 9 P 0 0;4=13,6=1
P 5.75778996 3.02558996 9 P 0 0;4=13,6=1
P 5.9192 2.943 9 P 0 0;4=13,6=1
P 4.07386004 2.55 9 P 0 0;4=13,6=1
P 3.86826998 2.64558996 9 P 0 0;4=13,6=1
P 9.995 2.87558996 9 P 0 0;4=13,6=1
P 10.11778996 2.78 9 P 0 0;4=13,6=1
L 1.33656004 4.85601004 1.32745 4.8469 7 P 0 
L 1.32745 4.8469 1.32745 4.79681998 7 P 0 
P 1.32745 4.79681998 38 P 0 0;2,4=20,6=0
P 1.18906004 5.01551004 28 P 0 0;2,4=4,6=0
P 1.23906004 4.63151004 28 P 0 0;2,4=4,6=0
L 7.2426 4.63151004 7.2426 4.60351004 7 P 0 
P 7.2426 4.63151004 28 P 0 0;2,4=4,6=0
P 7.2426 4.60351004 9 P 0 0;4=13,6=1
P 7.33098996 4.79681998 38 P 0 0;2,4=20,6=0
P 7.3401 4.85601004 9 P 0 0;4=13,6=1
L 7.1926 5.01551004 7.1926 5.04351004 7 P 0 
P 7.1926 5.01551004 28 P 0 0;2,4=4,6=0
P 7.1926 5.04351004 9 P 0 0;4=13,6=1
P 0.66 2.045 9 P 0 0;4=0,6=1
P 1.792 2.4781 9 P 0 0;4=13,6=1
S P 0
OB 2.982969980315 2.8989 I
OC 2.982969980315 2.8989 2.97721003937 2.8989 Y
OE
SE
P 2.97721004 2.8989 9 P 0 0;4=13,6=1
S P 0
OB 2.982969980315 2.7861 I
OC 2.982969980315 2.7861 2.97721003937 2.7861 Y
OE
SE
P 2.97721004 2.7861 9 P 0 0;4=13,6=1
L 2.7815 2.86613996 2.84036004 2.925 9 P 0 
L 2.84036004 2.925 2.9422 2.925 9 P 0 
P 2.9422 2.925 9 P 0 0;4=13,6=1
L 8.78543996 2.86613996 8.8443 2.925 9 P 0 
L 8.8443 2.925 8.94278996 2.925 9 P 0 
P 8.94278996 2.925 9 P 0 0;4=13,6=1
P 5.5822 2.855 9 P 0 0;4=13,6=1
P 5.84968996 2.85 9 P 0 0;4=13,6=1
S P 0
OB 0.65925 1.85608996063 I
OC 0.65925 1.85608996063 0.65348996063 1.85608996063 Y
OE
SE
P 0.65348996 1.85608996 9 P 0 0;4=13,6=1
S P 0
OB 0.65925 1.91628996063 I
OC 0.65925 1.91628996063 0.65348996063 1.91628996063 Y
OE
SE
P 0.65348996 1.91628996 9 P 0 0;4=13,6=1
L 5.00768002 2.39115 5.03268002 2.41615 9 P 0 
L 5.00768002 2.39115 5.03268002 2.36615 9 P 0 
P 10.61161004 2.19115 10 P 0 0;2,4=11,6=0
P 11.01161004 2.39115 10 P 0 0;2,4=11,6=0
P 10.66161004 2.24115 10 P 0 0;2,4=11,6=0
P 5.00768002 2.39115 10 P 0 0;2,4=11,6=0
P 0.09448996 4.60236998 14 P 0 0;4=2,6=0
P 0.35038996 4.20866004 14 P 0 0;4=2,6=0
P 0.09448996 4.2874 14 P 0 0;4=2,6=0
P 0.09448996 4.12991998 14 P 0 0;4=2,6=0
P 0.17323002 4.16928996 14 P 0 0;4=2,6=0
P 0.27165 4.09055 14 P 0 0;4=2,6=0
P 0.27165 3.93306998 14 P 0 0;4=2,6=0
P 0.35038996 4.05118002 14 P 0 0;4=2,6=0
P 0.35038996 3.8937 14 P 0 0;4=2,6=0
P 0.09448996 3.97243996 14 P 0 0;4=2,6=0
P 0.09448996 3.81496004 14 P 0 0;4=2,6=0
P 0.17323002 4.01181004 14 P 0 0;4=2,6=0
P 0.17323002 3.85433002 14 P 0 0;4=2,6=0
P 0.27165 3.77558996 14 P 0 0;4=2,6=0
P 0.27165 3.61811004 14 P 0 0;4=2,6=0
P 0.35038996 3.73621998 14 P 0 0;4=2,6=0
P 0.35038996 3.57873996 14 P 0 0;4=2,6=0
P 0.09448996 3.65748002 14 P 0 0;4=2,6=0
P 0.09448996 3.5 14 P 0 0;4=2,6=0
P 0.17323002 3.69685 14 P 0 0;4=2,6=0
P 0.17323002 3.53936998 14 P 0 0;4=2,6=0
P 0.27165 3.46063002 14 P 0 0;4=2,6=0
P 0.35038996 3.42126004 14 P 0 0;4=2,6=0
P 0.27165 3.30315 14 P 0 0;4=2,6=0
P 0.27165 3.22441004 14 P 0 0;4=2,6=0
P 0.17323002 3.38188996 14 P 0 0;4=2,6=0
P 0.17323002 3.30315 14 P 0 0;4=2,6=0
P 0.35038996 3.1063 14 P 0 0;4=2,6=0
P 0.35038996 2.94881998 14 P 0 0;4=2,6=0
P 0.27165 3.06693002 14 P 0 0;4=2,6=0
P 0.27165 2.90945 14 P 0 0;4=2,6=0
P 0.17323002 3.14566998 14 P 0 0;4=2,6=0
P 0.17323002 2.98818996 14 P 0 0;4=2,6=0
P 0.09448996 3.18503996 14 P 0 0;4=2,6=0
P 0.09448996 3.02756004 14 P 0 0;4=2,6=0
P 0.35038996 2.79133996 14 P 0 0;4=2,6=0
P 0.27165 2.75196998 14 P 0 0;4=2,6=0
P 0.35038996 2.63386004 14 P 0 0;4=2,6=0
P 0.17323002 2.83071004 14 P 0 0;4=2,6=0
P 0.09448996 2.87008002 14 P 0 0;4=2,6=0
P 0.09448996 2.7126 14 P 0 0;4=2,6=0
P 0.35038996 2.39763996 14 P 0 0;4=2,6=0
P 0.27165 2.51575 14 P 0 0;4=2,6=0
P 0.27165 2.35826998 14 P 0 0;4=2,6=0
P 0.17323002 2.59448996 14 P 0 0;4=2,6=0
P 0.17323002 2.43701004 14 P 0 0;4=2,6=0
P 0.09448996 2.47638002 14 P 0 0;4=2,6=0
P 0.09448996 2.3189 14 P 0 0;4=2,6=0
P 0.35038996 2.24016004 14 P 0 0;4=2,6=0
P 0.35038996 2.08268002 14 P 0 0;4=2,6=0
P 0.35038996 2.00393996 14 P 0 0;4=2,6=0
P 0.27165 2.20078996 14 P 0 0;4=2,6=0
P 0.17323002 2.27953002 14 P 0 0;4=2,6=0
P 0.09448996 2.16141998 14 P 0 0;4=2,6=0
P 0.09448996 2.08268002 14 P 0 0;4=2,6=0
P 0.17323002 1.96456998 14 P 0 0;4=2,6=0
P 0.09448996 1.84646004 14 P 0 0;4=2,6=0
P 0.09448996 4.44488002 14 P 0 0;4=2,6=0
P 12.63778996 2.00393996 14 P 0 0;4=2,6=0
P 12.55905 2.12205 14 P 0 0;4=2,6=0
P 12.55905 1.88583002 14 P 0 0;4=2,6=0
P 12.81495 2.12205 14 P 0 0;4=2,6=0
P 12.81495 2.04331004 14 P 0 0;4=2,6=0
P 12.73621004 2.39763996 14 P 0 0;4=2,6=0
P 12.73621004 2.24016004 14 P 0 0;4=2,6=0
P 12.63778996 2.3189 14 P 0 0;4=2,6=0
P 12.55905 2.35826998 14 P 0 0;4=2,6=0
P 12.55905 2.20078996 14 P 0 0;4=2,6=0
P 12.81495 2.43701004 14 P 0 0;4=2,6=0
P 12.81495 2.27953002 14 P 0 0;4=2,6=0
P 12.73621004 2.55511998 14 P 0 0;4=2,6=0
P 12.63778996 2.63386004 14 P 0 0;4=2,6=0
P 12.63778996 2.47638002 14 P 0 0;4=2,6=0
P 12.55905 2.51575 14 P 0 0;4=2,6=0
P 12.81495 2.67323002 14 P 0 0;4=2,6=0
P 12.73621004 2.94881998 14 P 0 0;4=2,6=0
P 12.73621004 2.79133996 14 P 0 0;4=2,6=0
P 12.63778996 3.02756004 14 P 0 0;4=2,6=0
P 12.63778996 2.87008002 14 P 0 0;4=2,6=0
P 12.55905 2.90945 14 P 0 0;4=2,6=0
P 12.55905 2.75196998 14 P 0 0;4=2,6=0
P 12.81495 2.98818996 14 P 0 0;4=2,6=0
P 12.81495 2.83071004 14 P 0 0;4=2,6=0
P 12.73621004 3.26378002 14 P 0 0;4=2,6=0
P 12.73621004 3.1063 14 P 0 0;4=2,6=0
P 12.63778996 3.18503996 14 P 0 0;4=2,6=0
P 12.55905 3.22441004 14 P 0 0;4=2,6=0
P 12.55905 3.06693002 14 P 0 0;4=2,6=0
P 12.81495 3.14566998 14 P 0 0;4=2,6=0
P 12.55905 3.53936998 14 P 0 0;4=2,6=0
P 12.63778996 3.57873996 14 P 0 0;4=2,6=0
P 12.63778996 3.42126004 14 P 0 0;4=2,6=0
P 12.73621004 3.5 14 P 0 0;4=2,6=0
P 12.73621004 3.34251998 14 P 0 0;4=2,6=0
P 12.63778996 3.34251998 14 P 0 0;4=2,6=0
P 12.81495 3.61811004 14 P 0 0;4=2,6=0
P 12.81495 3.46063002 14 P 0 0;4=2,6=0
P 12.55905 3.85433002 14 P 0 0;4=2,6=0
P 12.55905 3.69685 14 P 0 0;4=2,6=0
P 12.63778996 3.8937 14 P 0 0;4=2,6=0
P 12.63778996 3.73621998 14 P 0 0;4=2,6=0
P 12.73621004 3.81496004 14 P 0 0;4=2,6=0
P 12.73621004 3.65748002 14 P 0 0;4=2,6=0
P 12.81495 3.93306998 14 P 0 0;4=2,6=0
P 12.81495 3.77558996 14 P 0 0;4=2,6=0
P 12.55905 4.16928996 14 P 0 0;4=2,6=0
P 12.55905 4.01181004 14 P 0 0;4=2,6=0
P 12.63778996 4.20866004 14 P 0 0;4=2,6=0
P 12.63778996 4.05118002 14 P 0 0;4=2,6=0
P 12.73621004 4.12991998 14 P 0 0;4=2,6=0
P 12.73621004 3.97243996 14 P 0 0;4=2,6=0
P 12.81495 4.09055 14 P 0 0;4=2,6=0
P 12.55905 4.48425 14 P 0 0;4=2,6=0
P 12.55905 4.32676998 14 P 0 0;4=2,6=0
P 12.63778996 4.52361998 14 P 0 0;4=2,6=0
P 12.63778996 4.36613996 14 P 0 0;4=2,6=0
P 12.73621004 4.44488002 14 P 0 0;4=2,6=0
P 12.73621004 4.2874 14 P 0 0;4=2,6=0
P 12.81495 4.40551004 14 P 0 0;4=2,6=0
P 12.81495 4.24803002 14 P 0 0;4=2,6=0
P 12.55905 4.64173996 14 P 0 0;4=2,6=0
P 12.81495 4.56298996 14 P 0 0;4=2,6=0
P 0.27165 4.40551004 14 P 0 0;4=2,6=0
P 0.35038996 4.52361998 14 P 0 0;4=2,6=0
P 0.17323002 4.48425 14 P 0 0;4=2,6=0
P 0.27165 4.24803002 14 P 0 0;4=2,6=0
P 0.35038996 4.36613996 14 P 0 0;4=2,6=0
P 0.17323002 4.32676998 14 P 0 0;4=2,6=0
P 5.49221004 2.73 9 P 0 0;4=13,6=1
P 5.44886004 2.9414 9 P 0 0;4=13,6=1
P 5.44886004 3.0214 9 P 0 0;4=13,6=1
P 5.44886004 3.0564 9 P 0 0;4=13,6=1
P 5.44886004 3.1014 9 P 0 0;4=13,6=1
P 5.44886004 3.1364 9 P 0 0;4=13,6=1
P 5.44886004 3.2164 9 P 0 0;4=13,6=1
P 5.44886004 3.1814 9 P 0 0;4=13,6=1
P 5.44886004 2.9764 9 P 0 0;4=13,6=1
P 5.44886004 3.2614 9 P 0 0;4=13,6=1
P 5.44886004 3.2964 9 P 0 0;4=13,6=1
P 10.33998996 4.9231 9 P 0 0;4=13,6=1
P 10.38498996 4.9231 9 P 0 0;4=0,6=1
P 10.77498996 4.9231 9 P 0 0;4=13,6=1
P 10.72998996 4.9231 9 P 0 0;4=13,6=1
P 10.30498996 4.9431 9 P 0 0;4=13,6=1
P 10.26498996 4.9431 9 P 0 0;4=13,6=1
P 10.30498996 5.0281 9 P 0 0;4=13,6=1
P 10.30498996 5.0731 9 P 0 0;4=13,6=1
P 10.30498996 4.9831 9 P 0 0;4=13,6=1
P 10.26498996 5.0281 9 P 0 0;4=13,6=1
P 10.26498996 5.0731 9 P 0 0;4=13,6=1
P 10.26498996 4.9831 9 P 0 0;4=13,6=1
P 10.26498996 5.1181 9 P 0 0;4=13,6=1
P 10.30498996 5.1181 9 P 0 0;4=13,6=1
P 10.34498996 5.1181 9 P 0 0;4=13,6=1
P 10.42498996 4.9431 9 P 0 0;4=13,6=1
P 10.46498996 4.9431 9 P 0 0;4=13,6=1
P 10.38498996 5.1181 9 P 0 0;4=13,6=1
P 10.46498996 5.1181 9 P 0 0;4=13,6=1
P 10.42498996 5.1181 9 P 0 0;4=13,6=1
P 10.42498996 4.9831 9 P 0 0;4=13,6=1
P 10.42498996 5.0731 9 P 0 0;4=13,6=1
P 10.42498996 5.0281 9 P 0 0;4=13,6=1
P 10.46498996 4.9831 9 P 0 0;4=13,6=1
P 10.46498996 5.0731 9 P 0 0;4=13,6=1
P 10.46498996 5.0281 9 P 0 0;4=13,6=1
P 10.85498996 4.9431 9 P 0 0;4=13,6=1
P 10.81498996 4.9431 9 P 0 0;4=13,6=1
P 10.65498996 4.9431 9 P 0 0;4=13,6=1
P 10.69498996 4.9431 9 P 0 0;4=13,6=1
P 10.85498996 5.0281 9 P 0 0;4=13,6=1
P 10.85498996 5.0731 9 P 0 0;4=13,6=1
P 10.85498996 4.9831 9 P 0 0;4=13,6=1
P 10.81498996 5.0281 9 P 0 0;4=13,6=1
P 10.81498996 5.0731 9 P 0 0;4=13,6=1
P 10.81498996 4.9831 9 P 0 0;4=13,6=1
P 10.81498996 5.1181 9 P 0 0;4=13,6=1
P 10.85498996 5.1181 9 P 0 0;4=13,6=1
P 10.73498996 5.1181 9 P 0 0;4=13,6=1
P 10.69498996 5.1181 9 P 0 0;4=13,6=1
P 10.65498996 5.1181 9 P 0 0;4=13,6=1
P 10.77498996 5.1181 9 P 0 0;4=13,6=1
P 10.65498996 4.9831 9 P 0 0;4=13,6=1
P 10.65498996 5.0731 9 P 0 0;4=13,6=1
P 10.65498996 5.0281 9 P 0 0;4=13,6=1
P 10.69498996 4.9831 9 P 0 0;4=13,6=1
P 10.69498996 5.0731 9 P 0 0;4=13,6=1
P 10.69498996 5.0281 9 P 0 0;4=13,6=1
L 7.3401 4.85601004 7.33098996 4.8469 7 P 0 
L 7.33098996 4.8469 7.33098996 4.79681998 7 P 0 
L 1.23906004 4.63151004 1.23906004 4.60351004 7 P 0 
P 1.23906004 4.60351004 9 P 0 0;4=13,6=1
L 1.18906004 5.01551004 1.18906004 5.04351004 7 P 0 
P 1.18906004 5.04351004 9 P 0 0;4=13,6=1
P 1.33656004 4.85601004 9 P 0 0;4=13,6=1
P 10.16606998 2.81 9 P 0 0;4=13,6=1
P 4.15221004 2.9281 9 P 0 0;4=13,6=1
P 11.45278996 2.9414 9 P 0 0;4=13,6=1
P 11.45278996 3.0214 9 P 0 0;4=13,6=1
P 11.45278996 3.0564 9 P 0 0;4=13,6=1
P 11.45278996 3.1014 9 P 0 0;4=13,6=1
P 11.45278996 3.1364 9 P 0 0;4=13,6=1
P 11.45278996 3.2164 9 P 0 0;4=13,6=1
P 11.45278996 3.1814 9 P 0 0;4=13,6=1
P 11.45278996 2.9764 9 P 0 0;4=13,6=1
P 11.45278996 3.2614 9 P 0 0;4=13,6=1
P 11.45278996 3.2964 9 P 0 0;4=13,6=1
P 0.09448996 1.45276004 14 P 0 0;4=2,6=0
P 0.27165 1.57086998 14 P 0 0;4=2,6=0
P 0.35038996 1.45276004 14 P 0 0;4=2,6=0
P 12.81495 1.49213002 14 P 0 0;4=2,6=0
P 12.73621004 1.61023996 14 P 0 0;4=2,6=0
P 12.55905 1.49213002 14 P 0 0;4=2,6=0
P 0.27165 1.88583002 14 P 0 0;4=2,6=0
P 12.73621004 1.9252 14 P 0 0;4=2,6=0
P 10.36698996 5.02086004 53 P 0 0;2,4=25,6=0
P 10.75698996 5.02086004 53 P 0 0;2,4=25,6=0
S P 0
OB 7.35 0.046980019685 I
OS 12.84646003937 0.046980019685
OC 12.878219980315 0.07873996063 12.84646003937 0.07873996063 N
OS 12.878219980315 0.629219980315
OS 12.885 0.636
OS 12.895 0.636
OS 12.9 0.631
OS 12.9 0.074230019685
OC 12.84646003937 0.02501003937 12.846459645669 0.07873996063 Y
OS 7.349 0.02501003937
OS 7.345 0.02901003937
OS 7.345 0.041980019685
OS 7.35 0.046980019685
OE
SE
P 7.35731004 0.036 9 P 0 0;4=13,6=1
P 7.60731004 0.036 9 P 0 0;4=13,6=1
P 7.55731004 0.036 9 P 0 0;4=13,6=1
P 7.50731004 0.036 9 P 0 0;4=13,6=1
P 7.45731004 0.036 9 P 0 0;4=13,6=1
P 7.40731004 0.036 9 P 0 0;4=13,6=1
P 7.85731004 0.036 9 P 0 0;4=13,6=1
P 7.80731004 0.036 9 P 0 0;4=13,6=1
P 7.75731004 0.036 9 P 0 0;4=13,6=1
P 7.70731004 0.036 9 P 0 0;4=13,6=1
P 7.65731004 0.036 9 P 0 0;4=13,6=1
P 8.15731004 0.036 9 P 0 0;4=13,6=1
P 8.10731004 0.036 9 P 0 0;4=13,6=1
P 8.05731004 0.036 9 P 0 0;4=13,6=1
P 8.00731004 0.036 9 P 0 0;4=13,6=1
P 7.95731004 0.036 9 P 0 0;4=13,6=1
P 7.90731004 0.036 9 P 0 0;4=13,6=1
P 8.40731004 0.036 9 P 0 0;4=13,6=1
P 8.35731004 0.036 9 P 0 0;4=13,6=1
P 8.30731004 0.036 9 P 0 0;4=13,6=1
P 8.25731004 0.036 9 P 0 0;4=13,6=1
P 8.20731004 0.036 9 P 0 0;4=13,6=1
P 8.65731004 0.036 9 P 0 0;4=13,6=1
P 8.60731004 0.036 9 P 0 0;4=13,6=1
P 8.55731004 0.036 9 P 0 0;4=13,6=1
P 8.50731004 0.036 9 P 0 0;4=13,6=1
P 8.45731004 0.036 9 P 0 0;4=13,6=1
P 8.90731004 0.036 9 P 0 0;4=13,6=1
P 8.85731004 0.036 9 P 0 0;4=13,6=1
P 8.80731004 0.036 9 P 0 0;4=13,6=1
P 8.75731004 0.036 9 P 0 0;4=13,6=1
P 8.70731004 0.036 9 P 0 0;4=13,6=1
P 9.20731004 0.036 9 P 0 0;4=13,6=1
P 9.15731004 0.036 9 P 0 0;4=13,6=1
P 9.10731004 0.036 9 P 0 0;4=13,6=1
P 9.05731004 0.036 9 P 0 0;4=13,6=1
P 9.00731004 0.036 9 P 0 0;4=13,6=1
P 8.95731004 0.036 9 P 0 0;4=13,6=1
P 9.45731004 0.036 9 P 0 0;4=13,6=1
P 9.40731004 0.036 9 P 0 0;4=13,6=1
P 9.35731004 0.036 9 P 0 0;4=13,6=1
P 9.30731004 0.036 9 P 0 0;4=13,6=1
P 9.25731004 0.036 9 P 0 0;4=13,6=1
P 9.70731004 0.036 9 P 0 0;4=13,6=1
P 9.65731004 0.036 9 P 0 0;4=13,6=1
P 9.60731004 0.036 9 P 0 0;4=13,6=1
P 9.55731004 0.036 9 P 0 0;4=13,6=1
P 9.50731004 0.036 9 P 0 0;4=13,6=1
P 10.00731004 0.036 9 P 0 0;4=13,6=1
P 9.95731004 0.036 9 P 0 0;4=13,6=1
P 9.90731004 0.036 9 P 0 0;4=13,6=1
P 9.85731004 0.036 9 P 0 0;4=13,6=1
P 9.80731004 0.036 9 P 0 0;4=13,6=1
P 9.75731004 0.036 9 P 0 0;4=13,6=1
P 10.25731004 0.036 9 P 0 0;4=13,6=1
P 10.20731004 0.036 9 P 0 0;4=13,6=1
P 10.15731004 0.036 9 P 0 0;4=13,6=1
P 10.10731004 0.036 9 P 0 0;4=13,6=1
P 10.05731004 0.036 9 P 0 0;4=13,6=1
P 10.50731004 0.036 9 P 0 0;4=13,6=1
P 10.45731004 0.036 9 P 0 0;4=13,6=1
P 10.40731004 0.036 9 P 0 0;4=13,6=1
P 10.35731004 0.036 9 P 0 0;4=13,6=1
P 10.30731004 0.036 9 P 0 0;4=13,6=1
P 10.75731004 0.036 9 P 0 0;4=13,6=1
P 10.70731004 0.036 9 P 0 0;4=13,6=1
P 10.65731004 0.036 9 P 0 0;4=13,6=1
P 10.60731004 0.036 9 P 0 0;4=13,6=1
P 10.55731004 0.036 9 P 0 0;4=13,6=1
P 11.05731004 0.036 9 P 0 0;4=13,6=1
P 11.00731004 0.036 9 P 0 0;4=13,6=1
P 10.95731004 0.036 9 P 0 0;4=13,6=1
P 10.90731004 0.036 9 P 0 0;4=13,6=1
P 10.85731004 0.036 9 P 0 0;4=13,6=1
P 10.80731004 0.036 9 P 0 0;4=13,6=1
P 11.30731004 0.036 9 P 0 0;4=13,6=1
P 11.25731004 0.036 9 P 0 0;4=13,6=1
P 11.20731004 0.036 9 P 0 0;4=13,6=1
P 11.15731004 0.036 9 P 0 0;4=13,6=1
P 11.10731004 0.036 9 P 0 0;4=13,6=1
P 11.55731004 0.036 9 P 0 0;4=13,6=1
P 11.50731004 0.036 9 P 0 0;4=13,6=1
P 11.45731004 0.036 9 P 0 0;4=13,6=1
P 11.40731004 0.036 9 P 0 0;4=13,6=1
P 11.35731004 0.036 9 P 0 0;4=13,6=1
P 11.80731004 0.036 9 P 0 0;4=13,6=1
P 11.75731004 0.036 9 P 0 0;4=13,6=1
P 11.70731004 0.036 9 P 0 0;4=13,6=1
P 11.65731004 0.036 9 P 0 0;4=13,6=1
P 11.60731004 0.036 9 P 0 0;4=13,6=1
P 12.10731004 0.036 9 P 0 0;4=13,6=1
P 12.05731004 0.036 9 P 0 0;4=13,6=1
P 12.00731004 0.036 9 P 0 0;4=13,6=1
P 11.95731004 0.036 9 P 0 0;4=13,6=1
P 11.90731004 0.036 9 P 0 0;4=13,6=1
P 11.85731004 0.036 9 P 0 0;4=13,6=1
P 12.35731004 0.036 9 P 0 0;4=13,6=1
P 12.30731004 0.036 9 P 0 0;4=13,6=1
P 12.25731004 0.036 9 P 0 0;4=13,6=1
P 12.20731004 0.036 9 P 0 0;4=13,6=1
P 12.15731004 0.036 9 P 0 0;4=13,6=1
P 12.60731004 0.036 9 P 0 0;4=13,6=1
P 12.55731004 0.036 9 P 0 0;4=13,6=1
P 12.50731004 0.036 9 P 0 0;4=13,6=1
P 12.45731004 0.036 9 P 0 0;4=13,6=1
P 12.40731004 0.036 9 P 0 0;4=13,6=1
P 12.8892 0.22596004 9 P 0 0;4=13,6=1
P 12.8892 0.17596004 9 P 0 0;4=13,6=1
P 12.8892 0.12596004 9 P 0 0;4=13,6=1
P 12.88911004 0.07596004 9 P 0 0;4=13,6=1
P 12.85728996 0.03738996 9 P 0 0;4=13,6=1
P 12.80731004 0.036 9 P 0 0;4=13,6=1
P 12.75731004 0.036 9 P 0 0;4=13,6=1
P 12.70731004 0.036 9 P 0 0;4=13,6=1
P 12.65731004 0.036 9 P 0 0;4=13,6=1
P 12.8892 0.47596004 9 P 0 0;4=13,6=1
P 12.8892 0.42596004 9 P 0 0;4=13,6=1
P 12.8892 0.37596004 9 P 0 0;4=13,6=1
P 12.8892 0.32596004 9 P 0 0;4=13,6=1
P 12.8892 0.27596004 9 P 0 0;4=13,6=1
P 12.8892 0.62596004 9 P 0 0;4=13,6=1
P 12.8892 0.57596004 9 P 0 0;4=13,6=1
P 12.8892 0.52596004 9 P 0 0;4=13,6=1
S P 0
OB 0.046980019685 4.765 I
OS 0.046980019685 1.004
OS 0.040980019685 0.998
OS 0.03101003937 0.998
OS 0.02501003937 1.004
OS 0.02501003937 4.765
OS 0.03001003937 4.77
OS 0.041980019685 4.77
OS 0.046980019685 4.765
OE
SE
P 0.036 1.00868002 9 P 0 0;4=13,6=1
P 0.036 1.05868002 9 P 0 0;4=13,6=1
P 0.036 1.10868002 9 P 0 0;4=13,6=1
P 0.036 1.15868002 9 P 0 0;4=13,6=1
P 0.036 1.20868002 9 P 0 0;4=13,6=1
P 0.036 1.25868002 9 P 0 0;4=13,6=1
P 0.036 1.30868002 9 P 0 0;4=13,6=1
P 0.036 1.35868002 9 P 0 0;4=13,6=1
P 0.036 1.40868002 9 P 0 0;4=13,6=1
P 0.036 1.45868002 9 P 0 0;4=13,6=1
P 0.036 1.50868002 9 P 0 0;4=13,6=1
P 0.036 1.55868002 9 P 0 0;4=13,6=1
P 0.036 1.60868002 9 P 0 0;4=13,6=1
P 0.036 1.65868002 9 P 0 0;4=13,6=1
P 0.036 1.70868002 9 P 0 0;4=13,6=1
P 0.036 1.75868002 9 P 0 0;4=13,6=1
P 0.036 1.80868002 9 P 0 0;4=13,6=1
P 0.036 1.85868002 9 P 0 0;4=13,6=1
P 0.036 1.90868002 9 P 0 0;4=13,6=1
P 0.036 1.95868002 9 P 0 0;4=13,6=1
P 0.036 2.00868002 9 P 0 0;4=13,6=1
P 0.036 2.05868002 9 P 0 0;4=13,6=1
P 0.036 2.10868002 9 P 0 0;4=13,6=1
P 0.036 2.15868002 9 P 0 0;4=13,6=1
P 0.036 2.20868002 9 P 0 0;4=13,6=1
P 0.036 2.25868002 9 P 0 0;4=13,6=1
P 0.036 2.30868002 9 P 0 0;4=13,6=1
P 0.036 2.35868002 9 P 0 0;4=13,6=1
P 0.036 2.40868002 9 P 0 0;4=13,6=1
P 0.036 2.45868002 9 P 0 0;4=13,6=1
P 0.036 2.50868002 9 P 0 0;4=13,6=1
P 0.036 2.55868002 9 P 0 0;4=13,6=1
P 0.036 2.60868002 9 P 0 0;4=13,6=1
P 0.036 2.65868002 9 P 0 0;4=13,6=1
P 0.036 2.70868002 9 P 0 0;4=13,6=1
P 0.036 2.75868002 9 P 0 0;4=13,6=1
P 0.036 2.80868002 9 P 0 0;4=13,6=1
P 0.036 2.85868002 9 P 0 0;4=13,6=1
P 0.036 2.90868002 9 P 0 0;4=13,6=1
P 0.036 2.95868002 9 P 0 0;4=13,6=1
P 0.036 3.00868002 9 P 0 0;4=13,6=1
P 0.036 3.05868002 9 P 0 0;4=13,6=1
P 0.036 3.10868002 9 P 0 0;4=13,6=1
P 0.036 3.15868002 9 P 0 0;4=13,6=1
P 0.036 3.20868002 9 P 0 0;4=13,6=1
P 0.036 3.25868002 9 P 0 0;4=13,6=1
P 0.036 3.30868002 9 P 0 0;4=13,6=1
P 0.036 3.35868002 9 P 0 0;4=13,6=1
P 0.036 3.40868002 9 P 0 0;4=13,6=1
P 0.036 3.45868002 9 P 0 0;4=13,6=1
P 0.036 3.50868002 9 P 0 0;4=13,6=1
P 0.036 3.55868002 9 P 0 0;4=13,6=1
P 0.036 3.60868002 9 P 0 0;4=13,6=1
P 0.036 3.65868002 9 P 0 0;4=13,6=1
P 0.036 3.70868002 9 P 0 0;4=13,6=1
P 0.036 3.75868002 9 P 0 0;4=13,6=1
P 0.036 3.80868002 9 P 0 0;4=13,6=1
P 0.036 3.85868002 9 P 0 0;4=13,6=1
P 0.036 3.90868002 9 P 0 0;4=13,6=1
P 0.036 3.95868002 9 P 0 0;4=13,6=1
P 0.036 4.00868002 9 P 0 0;4=13,6=1
P 0.036 4.05868002 9 P 0 0;4=13,6=1
P 0.036 4.10868002 9 P 0 0;4=13,6=1
P 0.036 4.15868002 9 P 0 0;4=13,6=1
P 0.036 4.20868002 9 P 0 0;4=13,6=1
P 0.036 4.25868002 9 P 0 0;4=13,6=1
P 0.036 4.30868002 9 P 0 0;4=13,6=1
P 0.036 4.35868002 9 P 0 0;4=13,6=1
P 0.036 4.40868002 9 P 0 0;4=13,6=1
P 0.036 4.45868002 9 P 0 0;4=13,6=1
P 0.036 4.50868002 9 P 0 0;4=13,6=1
P 0.036 4.55868002 9 P 0 0;4=13,6=1
P 0.036 4.60868002 9 P 0 0;4=13,6=1
P 0.036 4.65868002 9 P 0 0;4=13,6=1
P 0.036 4.70868002 9 P 0 0;4=13,6=1
P 0.036 4.75868002 9 P 0 0;4=13,6=1
S P 0
OB 12.878219980315 1.023 I
OS 12.878219980315 4.832
OS 12.883219980315 4.837
OS 12.896 4.837
OS 12.9 4.833
OS 12.9 1.023
OS 12.893 1.016
OS 12.885219980315 1.016
OS 12.878219980315 1.023
OE
SE
P 12.8892 1.02596004 9 P 0 0;4=13,6=1
P 12.8892 1.27596004 9 P 0 0;4=13,6=1
P 12.8892 1.22596004 9 P 0 0;4=13,6=1
P 12.8892 1.17596004 9 P 0 0;4=13,6=1
P 12.8892 1.12596004 9 P 0 0;4=13,6=1
P 12.8892 1.07596004 9 P 0 0;4=13,6=1
P 12.8892 1.52596004 9 P 0 0;4=13,6=1
P 12.8892 1.47596004 9 P 0 0;4=13,6=1
P 12.8892 1.42596004 9 P 0 0;4=13,6=1
P 12.8892 1.37596004 9 P 0 0;4=13,6=1
P 12.8892 1.32596004 9 P 0 0;4=13,6=1
P 12.8892 1.77596004 9 P 0 0;4=13,6=1
P 12.8892 1.72596004 9 P 0 0;4=13,6=1
P 12.8892 1.67596004 9 P 0 0;4=13,6=1
P 12.8892 1.62596004 9 P 0 0;4=13,6=1
P 12.8892 1.57596004 9 P 0 0;4=13,6=1
P 12.8892 2.07596004 9 P 0 0;4=13,6=1
P 12.8892 2.02596004 9 P 0 0;4=13,6=1
P 12.8892 1.97596004 9 P 0 0;4=13,6=1
P 12.8892 1.92596004 9 P 0 0;4=13,6=1
P 12.8892 1.87596004 9 P 0 0;4=13,6=1
P 12.8892 1.82596004 9 P 0 0;4=13,6=1
P 12.8892 2.32596004 9 P 0 0;4=13,6=1
P 12.8892 2.27596004 9 P 0 0;4=13,6=1
P 12.8892 2.22596004 9 P 0 0;4=13,6=1
P 12.8892 2.17596004 9 P 0 0;4=13,6=1
P 12.8892 2.57596004 9 P 0 0;4=13,6=1
P 12.8892 2.52596004 9 P 0 0;4=13,6=1
P 12.8892 2.47596004 9 P 0 0;4=13,6=1
P 12.8892 2.42596004 9 P 0 0;4=13,6=1
P 12.8892 2.37596004 9 P 0 0;4=13,6=1
P 12.8892 2.82596004 9 P 0 0;4=13,6=1
P 12.8892 2.77596004 9 P 0 0;4=13,6=1
P 12.8892 2.72596004 9 P 0 0;4=13,6=1
P 12.8892 2.67596004 9 P 0 0;4=13,6=1
P 12.8892 2.62596004 9 P 0 0;4=13,6=1
P 12.8892 3.12596004 9 P 0 0;4=13,6=1
P 12.8892 3.07596004 9 P 0 0;4=13,6=1
P 12.8892 3.02596004 9 P 0 0;4=13,6=1
P 12.8892 2.97596004 9 P 0 0;4=13,6=1
P 12.8892 2.92596004 9 P 0 0;4=13,6=1
P 12.8892 2.87596004 9 P 0 0;4=13,6=1
P 12.8892 3.37596004 9 P 0 0;4=13,6=1
P 12.8892 3.32596004 9 P 0 0;4=13,6=1
P 12.8892 3.27596004 9 P 0 0;4=13,6=1
P 12.8892 3.22596004 9 P 0 0;4=13,6=1
P 12.8892 3.17596004 9 P 0 0;4=13,6=1
P 12.8892 3.62596004 9 P 0 0;4=13,6=1
P 12.8892 3.57596004 9 P 0 0;4=13,6=1
P 12.8892 3.52596004 9 P 0 0;4=13,6=1
P 12.8892 3.47596004 9 P 0 0;4=13,6=1
P 12.8892 3.42596004 9 P 0 0;4=13,6=1
P 12.8892 3.92596004 9 P 0 0;4=13,6=1
P 12.8892 3.87596004 9 P 0 0;4=13,6=1
P 12.8892 3.82596004 9 P 0 0;4=13,6=1
P 12.8892 3.77596004 9 P 0 0;4=13,6=1
P 12.8892 3.72596004 9 P 0 0;4=13,6=1
P 12.8892 3.67596004 9 P 0 0;4=13,6=1
P 12.8892 4.17596004 9 P 0 0;4=13,6=1
P 12.8892 4.12596004 9 P 0 0;4=13,6=1
P 12.8892 4.07596004 9 P 0 0;4=13,6=1
P 12.8892 4.02596004 9 P 0 0;4=13,6=1
P 12.8892 3.97596004 9 P 0 0;4=13,6=1
P 12.8892 4.42596004 9 P 0 0;4=13,6=1
P 12.8892 4.37596004 9 P 0 0;4=13,6=1
P 12.8892 4.32596004 9 P 0 0;4=13,6=1
P 12.8892 4.27596004 9 P 0 0;4=13,6=1
P 12.8892 4.22596004 9 P 0 0;4=13,6=1
P 12.8892 4.67596004 9 P 0 0;4=13,6=1
P 12.8892 4.62596004 9 P 0 0;4=13,6=1
P 12.8892 4.57596004 9 P 0 0;4=13,6=1
P 12.8892 4.52596004 9 P 0 0;4=13,6=1
P 12.8892 4.47596004 9 P 0 0;4=13,6=1
P 12.8892 4.82596004 9 P 0 0;4=13,6=1
P 12.8892 4.77596004 9 P 0 0;4=13,6=1
P 12.8892 4.72596004 9 P 0 0;4=13,6=1
S P 0
OB 0.02501003937 5.25298996063 I
OS 0.02501003937 5.944880019685
OC 0.07873996063 5.99861003937 0.07873996063 5.94488011811 Y
OS 6.987 5.99861003937
OS 6.992 5.99361003937
OS 6.992 5.98263996063
OS 6.986 5.97663996063
OS 0.07873996063 5.97663996063
OC 0.046980019685 5.944880019685 0.07873996063 5.944880019685 N
OS 0.046980019685 5.253
OS 0.041980019685 5.248
OS 0.03 5.248
OS 0.02501003937 5.25298996063
OE
SE
P 0.036 5.25868002 9 P 0 0;4=13,6=1
P 0.036 5.30868002 9 P 0 0;4=13,6=1
P 0.036 5.35868002 9 P 0 0;4=13,6=1
P 0.036 5.40868002 9 P 0 0;4=13,6=1
P 0.036 5.45868002 9 P 0 0;4=13,6=1
P 0.036 5.50868002 9 P 0 0;4=13,6=1
P 0.036 5.55868002 9 P 0 0;4=13,6=1
P 0.036 5.60868002 9 P 0 0;4=13,6=1
P 0.036 5.65868002 9 P 0 0;4=13,6=1
P 0.036 5.70868002 9 P 0 0;4=13,6=1
P 0.036 5.75868002 9 P 0 0;4=13,6=1
P 0.036 5.80868002 9 P 0 0;4=13,6=1
P 0.036 5.85868002 9 P 0 0;4=13,6=1
P 0.036 5.90868002 9 P 0 0;4=13,6=1
P 0.03826998 5.95863002 9 P 0 0;4=13,6=1
P 0.07901004 5.98761998 9 P 0 0;4=13,6=1
P 0.12901004 5.98761998 9 P 0 0;4=13,6=1
P 0.17901004 5.98761998 9 P 0 0;4=13,6=1
P 0.22901004 5.98761998 9 P 0 0;4=13,6=1
P 0.27901004 5.98761998 9 P 0 0;4=13,6=1
P 0.32901004 5.98761998 9 P 0 0;4=13,6=1
P 0.37901004 5.98761998 9 P 0 0;4=13,6=1
P 0.42901004 5.98761998 9 P 0 0;4=13,6=1
P 0.47901004 5.98761998 9 P 0 0;4=13,6=1
P 0.52901004 5.98761998 9 P 0 0;4=13,6=1
P 0.57901004 5.98761998 9 P 0 0;4=13,6=1
P 0.62901004 5.98761998 9 P 0 0;4=13,6=1
P 0.67901004 5.98761998 9 P 0 0;4=13,6=1
P 0.72901004 5.98761998 9 P 0 0;4=13,6=1
P 0.77901004 5.98761998 9 P 0 0;4=13,6=1
P 0.82901004 5.98761998 9 P 0 0;4=13,6=1
P 0.87901004 5.98761998 9 P 0 0;4=13,6=1
P 0.92901004 5.98761998 9 P 0 0;4=13,6=1
P 0.97901004 5.98761998 9 P 0 0;4=13,6=1
P 1.02901004 5.98761998 9 P 0 0;4=13,6=1
P 1.07901004 5.98761998 9 P 0 0;4=13,6=1
P 1.12901004 5.98761998 9 P 0 0;4=13,6=1
P 1.17901004 5.98761998 9 P 0 0;4=13,6=1
P 1.22901004 5.98761998 9 P 0 0;4=13,6=1
P 1.27901004 5.98761998 9 P 0 0;4=13,6=1
P 1.32901004 5.98761998 9 P 0 0;4=13,6=1
P 1.37901004 5.98761998 9 P 0 0;4=13,6=1
P 1.42901004 5.98761998 9 P 0 0;4=13,6=1
P 1.47901004 5.98761998 9 P 0 0;4=13,6=1
P 1.52901004 5.98761998 9 P 0 0;4=13,6=1
P 1.57901004 5.98761998 9 P 0 0;4=13,6=1
P 1.62901004 5.98761998 9 P 0 0;4=13,6=1
P 1.67901004 5.98761998 9 P 0 0;4=13,6=1
P 1.72901004 5.98761998 9 P 0 0;4=13,6=1
P 1.77901004 5.98761998 9 P 0 0;4=13,6=1
P 1.82901004 5.98761998 9 P 0 0;4=13,6=1
P 1.87901004 5.98761998 9 P 0 0;4=13,6=1
P 1.92901004 5.98761998 9 P 0 0;4=13,6=1
P 1.97901004 5.98761998 9 P 0 0;4=13,6=1
P 2.02901004 5.98761998 9 P 0 0;4=13,6=1
P 2.07901004 5.98761998 9 P 0 0;4=13,6=1
P 2.12901004 5.98761998 9 P 0 0;4=13,6=1
P 2.17901004 5.98761998 9 P 0 0;4=13,6=1
P 2.22901004 5.98761998 9 P 0 0;4=13,6=1
P 2.27901004 5.98761998 9 P 0 0;4=13,6=1
P 2.32901004 5.98761998 9 P 0 0;4=13,6=1
P 2.37901004 5.98761998 9 P 0 0;4=13,6=1
P 2.42901004 5.98761998 9 P 0 0;4=13,6=1
P 2.47901004 5.98761998 9 P 0 0;4=13,6=1
P 2.52901004 5.98761998 9 P 0 0;4=13,6=1
P 2.57901004 5.98761998 9 P 0 0;4=13,6=1
P 2.62901004 5.98761998 9 P 0 0;4=13,6=1
P 2.67901004 5.98761998 9 P 0 0;4=13,6=1
P 2.72901004 5.98761998 9 P 0 0;4=13,6=1
P 2.77901004 5.98761998 9 P 0 0;4=13,6=1
P 2.82901004 5.98761998 9 P 0 0;4=13,6=1
P 2.87901004 5.98761998 9 P 0 0;4=13,6=1
P 2.92901004 5.98761998 9 P 0 0;4=13,6=1
P 2.97901004 5.98761998 9 P 0 0;4=13,6=1
P 3.02901004 5.98761998 9 P 0 0;4=13,6=1
P 3.07901004 5.98761998 9 P 0 0;4=13,6=1
P 3.12901004 5.98761998 9 P 0 0;4=13,6=1
P 3.17901004 5.98761998 9 P 0 0;4=13,6=1
P 3.22901004 5.98761998 9 P 0 0;4=13,6=1
P 3.27901004 5.98761998 9 P 0 0;4=13,6=1
P 3.32901004 5.98761998 9 P 0 0;4=13,6=1
P 3.37901004 5.98761998 9 P 0 0;4=13,6=1
P 3.42901004 5.98761998 9 P 0 0;4=13,6=1
P 3.47901004 5.98761998 9 P 0 0;4=13,6=1
P 3.52901004 5.98761998 9 P 0 0;4=13,6=1
P 3.57901004 5.98761998 9 P 0 0;4=13,6=1
P 3.62901004 5.98761998 9 P 0 0;4=13,6=1
P 3.67901004 5.98761998 9 P 0 0;4=13,6=1
P 3.72901004 5.98761998 9 P 0 0;4=13,6=1
P 3.77901004 5.98761998 9 P 0 0;4=13,6=1
P 3.82901004 5.98761998 9 P 0 0;4=13,6=1
P 3.87901004 5.98761998 9 P 0 0;4=13,6=1
P 3.92901004 5.98761998 9 P 0 0;4=13,6=1
P 3.97901004 5.98761998 9 P 0 0;4=13,6=1
P 4.02901004 5.98761998 9 P 0 0;4=13,6=1
P 4.07901004 5.98761998 9 P 0 0;4=13,6=1
P 4.12901004 5.98761998 9 P 0 0;4=13,6=1
P 4.17901004 5.98761998 9 P 0 0;4=13,6=1
P 4.22901004 5.98761998 9 P 0 0;4=13,6=1
P 4.27901004 5.98761998 9 P 0 0;4=13,6=1
P 4.32901004 5.98761998 9 P 0 0;4=13,6=1
P 4.37901004 5.98761998 9 P 0 0;4=13,6=1
P 4.42901004 5.98761998 9 P 0 0;4=13,6=1
P 4.47901004 5.98761998 9 P 0 0;4=13,6=1
P 4.52901004 5.98761998 9 P 0 0;4=13,6=1
P 4.57901004 5.98761998 9 P 0 0;4=13,6=1
P 4.62901004 5.98761998 9 P 0 0;4=13,6=1
P 4.67901004 5.98761998 9 P 0 0;4=13,6=1
P 4.72901004 5.98761998 9 P 0 0;4=13,6=1
P 4.77901004 5.98761998 9 P 0 0;4=13,6=1
P 4.82901004 5.98761998 9 P 0 0;4=13,6=1
P 4.87901004 5.98761998 9 P 0 0;4=13,6=1
P 4.92901004 5.98761998 9 P 0 0;4=13,6=1
P 4.97901004 5.98761998 9 P 0 0;4=13,6=1
P 5.02901004 5.98761998 9 P 0 0;4=13,6=1
P 5.07901004 5.98761998 9 P 0 0;4=13,6=1
P 5.12901004 5.98761998 9 P 0 0;4=13,6=1
P 5.17901004 5.98761998 9 P 0 0;4=13,6=1
P 5.22901004 5.98761998 9 P 0 0;4=13,6=1
P 5.27901004 5.98761998 9 P 0 0;4=13,6=1
P 5.32901004 5.98761998 9 P 0 0;4=13,6=1
P 5.37901004 5.98761998 9 P 0 0;4=13,6=1
P 5.42901004 5.98761998 9 P 0 0;4=13,6=1
P 5.47901004 5.98761998 9 P 0 0;4=13,6=1
P 5.52901004 5.98761998 9 P 0 0;4=13,6=1
P 5.57901004 5.98761998 9 P 0 0;4=13,6=1
P 5.62901004 5.98761998 9 P 0 0;4=13,6=1
P 5.67901004 5.98761998 9 P 0 0;4=13,6=1
P 5.72901004 5.98761998 9 P 0 0;4=13,6=1
P 5.77901004 5.98761998 9 P 0 0;4=13,6=1
P 5.82901004 5.98761998 9 P 0 0;4=13,6=1
P 5.87901004 5.98761998 9 P 0 0;4=13,6=1
P 5.92901004 5.98761998 9 P 0 0;4=13,6=1
P 5.97901004 5.98761998 9 P 0 0;4=13,6=1
P 6.02901004 5.98761998 9 P 0 0;4=13,6=1
P 6.07901004 5.98761998 9 P 0 0;4=13,6=1
P 6.12901004 5.98761998 9 P 0 0;4=13,6=1
P 6.17901004 5.98761998 9 P 0 0;4=13,6=1
P 6.22901004 5.98761998 9 P 0 0;4=13,6=1
P 6.27901004 5.98761998 9 P 0 0;4=13,6=1
P 6.32901004 5.98761998 9 P 0 0;4=13,6=1
P 6.37901004 5.98761998 9 P 0 0;4=13,6=1
P 6.42901004 5.98761998 9 P 0 0;4=13,6=1
P 6.47901004 5.98761998 9 P 0 0;4=13,6=1
P 6.52901004 5.98761998 9 P 0 0;4=13,6=1
P 6.57901004 5.98761998 9 P 0 0;4=13,6=1
P 6.62901004 5.98761998 9 P 0 0;4=13,6=1
P 6.67901004 5.98761998 9 P 0 0;4=13,6=1
P 6.72901004 5.98761998 9 P 0 0;4=13,6=1
P 6.77901004 5.98761998 9 P 0 0;4=13,6=1
P 6.82901004 5.98761998 9 P 0 0;4=13,6=1
P 6.87901004 5.98761998 9 P 0 0;4=13,6=1
P 6.92901004 5.98761998 9 P 0 0;4=13,6=1
P 6.97901004 5.98761998 9 P 0 0;4=13,6=1
S P 0
OB 12.878219980315 5.27 I
OS 12.878219980315 5.944880019685
OC 12.84646003937 5.97663996063 12.84646003937 5.944880019685 N
OS 7.37236003937 5.97663996063
OS 7.368 5.981
OS 7.368 5.99361003937
OS 7.373 5.99861003937
OS 12.84646003937 5.99861003937
OC 12.9 5.9494 12.846460433071 5.944880019685 Y
OS 12.9 5.272
OS 12.894 5.266
OS 12.882219980315 5.266
OS 12.878219980315 5.27
OE
SE
P 12.8892 5.47596004 9 P 0 0;4=13,6=1
P 12.8892 5.42596004 9 P 0 0;4=13,6=1
P 12.8892 5.37596004 9 P 0 0;4=13,6=1
P 12.8892 5.32596004 9 P 0 0;4=13,6=1
P 12.8892 5.27596004 9 P 0 0;4=13,6=1
P 12.8892 5.72596004 9 P 0 0;4=13,6=1
P 12.8892 5.67596004 9 P 0 0;4=13,6=1
P 12.8892 5.62596004 9 P 0 0;4=13,6=1
P 12.8892 5.57596004 9 P 0 0;4=13,6=1
P 12.8892 5.52596004 9 P 0 0;4=13,6=1
P 7.37901004 5.98761998 9 P 0 0;4=13,6=1
P 7.42901004 5.98761998 9 P 0 0;4=13,6=1
P 7.47901004 5.98761998 9 P 0 0;4=13,6=1
P 7.52901004 5.98761998 9 P 0 0;4=13,6=1
P 7.57901004 5.98761998 9 P 0 0;4=13,6=1
P 7.62901004 5.98761998 9 P 0 0;4=13,6=1
P 7.67901004 5.98761998 9 P 0 0;4=13,6=1
P 7.72901004 5.98761998 9 P 0 0;4=13,6=1
P 7.77901004 5.98761998 9 P 0 0;4=13,6=1
P 7.82901004 5.98761998 9 P 0 0;4=13,6=1
P 7.87901004 5.98761998 9 P 0 0;4=13,6=1
P 7.92901004 5.98761998 9 P 0 0;4=13,6=1
P 7.97901004 5.98761998 9 P 0 0;4=13,6=1
P 8.02901004 5.98761998 9 P 0 0;4=13,6=1
P 8.07901004 5.98761998 9 P 0 0;4=13,6=1
P 8.12901004 5.98761998 9 P 0 0;4=13,6=1
P 8.17901004 5.98761998 9 P 0 0;4=13,6=1
P 8.22901004 5.98761998 9 P 0 0;4=13,6=1
P 8.27901004 5.98761998 9 P 0 0;4=13,6=1
P 8.32901004 5.98761998 9 P 0 0;4=13,6=1
P 8.37901004 5.98761998 9 P 0 0;4=13,6=1
P 8.42901004 5.98761998 9 P 0 0;4=13,6=1
P 8.47901004 5.98761998 9 P 0 0;4=13,6=1
P 8.52901004 5.98761998 9 P 0 0;4=13,6=1
P 8.57901004 5.98761998 9 P 0 0;4=13,6=1
P 8.62901004 5.98761998 9 P 0 0;4=13,6=1
P 8.67901004 5.98761998 9 P 0 0;4=13,6=1
P 8.72901004 5.98761998 9 P 0 0;4=13,6=1
P 8.77901004 5.98761998 9 P 0 0;4=13,6=1
P 8.82901004 5.98761998 9 P 0 0;4=13,6=1
P 8.87901004 5.98761998 9 P 0 0;4=13,6=1
P 8.92901004 5.98761998 9 P 0 0;4=13,6=1
P 8.97901004 5.98761998 9 P 0 0;4=13,6=1
P 9.02901004 5.98761998 9 P 0 0;4=13,6=1
P 9.07901004 5.98761998 9 P 0 0;4=13,6=1
P 9.12901004 5.98761998 9 P 0 0;4=13,6=1
P 9.17901004 5.98761998 9 P 0 0;4=13,6=1
P 9.22901004 5.98761998 9 P 0 0;4=13,6=1
P 9.27901004 5.98761998 9 P 0 0;4=13,6=1
P 9.32901004 5.98761998 9 P 0 0;4=13,6=1
P 9.37901004 5.98761998 9 P 0 0;4=13,6=1
P 9.42901004 5.98761998 9 P 0 0;4=13,6=1
P 9.47901004 5.98761998 9 P 0 0;4=13,6=1
P 9.52901004 5.98761998 9 P 0 0;4=13,6=1
P 9.57901004 5.98761998 9 P 0 0;4=13,6=1
P 9.62901004 5.98761998 9 P 0 0;4=13,6=1
P 9.67901004 5.98761998 9 P 0 0;4=13,6=1
P 9.72901004 5.98761998 9 P 0 0;4=13,6=1
P 9.77901004 5.98761998 9 P 0 0;4=13,6=1
P 9.82901004 5.98761998 9 P 0 0;4=13,6=1
P 9.87901004 5.98761998 9 P 0 0;4=13,6=1
P 9.92901004 5.98761998 9 P 0 0;4=13,6=1
P 9.97901004 5.98761998 9 P 0 0;4=13,6=1
P 10.02901004 5.98761998 9 P 0 0;4=13,6=1
P 10.07901004 5.98761998 9 P 0 0;4=13,6=1
P 10.12901004 5.98761998 9 P 0 0;4=13,6=1
P 10.17901004 5.98761998 9 P 0 0;4=13,6=1
P 10.22901004 5.98761998 9 P 0 0;4=13,6=1
P 10.27901004 5.98761998 9 P 0 0;4=13,6=1
P 10.32901004 5.98761998 9 P 0 0;4=13,6=1
P 10.37901004 5.98761998 9 P 0 0;4=13,6=1
P 10.42901004 5.98761998 9 P 0 0;4=13,6=1
P 10.47901004 5.98761998 9 P 0 0;4=13,6=1
P 10.52901004 5.98761998 9 P 0 0;4=13,6=1
P 10.57901004 5.98761998 9 P 0 0;4=13,6=1
P 10.62901004 5.98761998 9 P 0 0;4=13,6=1
P 10.67901004 5.98761998 9 P 0 0;4=13,6=1
P 10.72901004 5.98761998 9 P 0 0;4=13,6=1
P 10.77901004 5.98761998 9 P 0 0;4=13,6=1
P 10.82901004 5.98761998 9 P 0 0;4=13,6=1
P 10.87901004 5.98761998 9 P 0 0;4=13,6=1
P 10.92901004 5.98761998 9 P 0 0;4=13,6=1
P 10.97901004 5.98761998 9 P 0 0;4=13,6=1
P 11.02901004 5.98761998 9 P 0 0;4=13,6=1
P 11.07901004 5.98761998 9 P 0 0;4=13,6=1
P 11.12901004 5.98761998 9 P 0 0;4=13,6=1
P 11.17901004 5.98761998 9 P 0 0;4=13,6=1
P 11.22901004 5.98761998 9 P 0 0;4=13,6=1
P 11.27901004 5.98761998 9 P 0 0;4=13,6=1
P 11.32901004 5.98761998 9 P 0 0;4=13,6=1
P 11.37901004 5.98761998 9 P 0 0;4=13,6=1
P 11.42901004 5.98761998 9 P 0 0;4=13,6=1
P 11.47901004 5.98761998 9 P 0 0;4=13,6=1
P 11.52901004 5.98761998 9 P 0 0;4=13,6=1
P 11.57901004 5.98761998 9 P 0 0;4=13,6=1
P 11.62901004 5.98761998 9 P 0 0;4=13,6=1
P 11.67901004 5.98761998 9 P 0 0;4=13,6=1
P 11.72901004 5.98761998 9 P 0 0;4=13,6=1
P 11.77901004 5.98761998 9 P 0 0;4=13,6=1
P 11.82901004 5.98761998 9 P 0 0;4=13,6=1
P 11.87901004 5.98761998 9 P 0 0;4=13,6=1
P 11.92901004 5.98761998 9 P 0 0;4=13,6=1
P 11.97901004 5.98761998 9 P 0 0;4=13,6=1
P 12.02901004 5.98761998 9 P 0 0;4=13,6=1
P 12.07901004 5.98761998 9 P 0 0;4=13,6=1
P 12.12901004 5.98761998 9 P 0 0;4=13,6=1
P 12.17901004 5.98761998 9 P 0 0;4=13,6=1
P 12.22901004 5.98761998 9 P 0 0;4=13,6=1
P 12.27901004 5.98761998 9 P 0 0;4=13,6=1
P 12.32901004 5.98761998 9 P 0 0;4=13,6=1
P 12.37901004 5.98761998 9 P 0 0;4=13,6=1
P 12.42901004 5.98761998 9 P 0 0;4=13,6=1
P 12.47901004 5.98761998 9 P 0 0;4=13,6=1
P 12.52901004 5.98761998 9 P 0 0;4=13,6=1
P 12.57901004 5.98761998 9 P 0 0;4=13,6=1
P 12.62901004 5.98761998 9 P 0 0;4=13,6=1
P 12.67901004 5.98761998 9 P 0 0;4=13,6=1
P 12.72901004 5.98761998 9 P 0 0;4=13,6=1
P 12.77901004 5.98761998 9 P 0 0;4=13,6=1
P 12.82901004 5.98761998 9 P 0 0;4=13,6=1
P 12.87726004 5.97451004 9 P 0 0;4=13,6=1
P 12.8892 5.92596004 9 P 0 0;4=13,6=1
P 12.8892 5.87596004 9 P 0 0;4=13,6=1
P 12.8892 5.82596004 9 P 0 0;4=13,6=1
P 12.8892 5.77596004 9 P 0 0;4=13,6=1
P 4.33605 4.9231 9 P 0 0;4=13,6=1
P 4.38105 4.9231 9 P 0 0;4=13,6=1
P 4.30105 4.9431 9 P 0 0;4=13,6=1
P 4.42105 4.9431 9 P 0 0;4=13,6=1
P 4.46105 4.9431 9 P 0 0;4=13,6=1
P 4.26105 4.9431 9 P 0 0;4=13,6=1
P 4.72605 4.9231 9 P 0 0;4=13,6=1
P 4.65105 4.9431 9 P 0 0;4=13,6=1
P 4.69105 4.9431 9 P 0 0;4=13,6=1
P 4.85105 4.9431 9 P 0 0;4=13,6=1
P 4.81105 4.9431 9 P 0 0;4=13,6=1
P 4.77105 4.9231 9 P 0 0;4=13,6=1
P 4.30105 5.0281 9 P 0 0;4=13,6=1
P 4.30105 5.0731 9 P 0 0;4=13,6=1
P 4.30105 4.9831 9 P 0 0;4=13,6=1
P 4.34105 5.1181 9 P 0 0;4=13,6=1
P 4.38105 5.1181 9 P 0 0;4=13,6=1
P 4.46105 5.1181 9 P 0 0;4=13,6=1
P 4.42105 5.1181 9 P 0 0;4=13,6=1
P 4.42105 4.9831 9 P 0 0;4=13,6=1
P 4.42105 5.0731 9 P 0 0;4=13,6=1
P 4.42105 5.0281 9 P 0 0;4=13,6=1
P 4.46105 4.9831 9 P 0 0;4=13,6=1
P 4.46105 5.0731 9 P 0 0;4=13,6=1
P 4.46105 5.0281 9 P 0 0;4=13,6=1
P 4.26105 5.0281 9 P 0 0;4=13,6=1
P 4.26105 5.0731 9 P 0 0;4=13,6=1
P 4.26105 4.9831 9 P 0 0;4=13,6=1
P 4.73105 5.1181 9 P 0 0;4=13,6=1
P 4.69105 5.1181 9 P 0 0;4=13,6=1
P 4.65105 5.1181 9 P 0 0;4=13,6=1
P 4.65105 4.9831 9 P 0 0;4=13,6=1
P 4.65105 5.0731 9 P 0 0;4=13,6=1
P 4.65105 5.0281 9 P 0 0;4=13,6=1
P 4.69105 4.9831 9 P 0 0;4=13,6=1
P 4.69105 5.0731 9 P 0 0;4=13,6=1
P 4.69105 5.0281 9 P 0 0;4=13,6=1
P 4.85105 5.0281 9 P 0 0;4=13,6=1
P 4.85105 5.0731 9 P 0 0;4=13,6=1
P 4.85105 4.9831 9 P 0 0;4=13,6=1
P 4.81105 5.0281 9 P 0 0;4=13,6=1
P 4.81105 5.0731 9 P 0 0;4=13,6=1
P 4.81105 4.9831 9 P 0 0;4=13,6=1
P 4.81105 5.1181 9 P 0 0;4=13,6=1
P 4.85105 5.1181 9 P 0 0;4=13,6=1
P 4.77105 5.1181 9 P 0 0;4=13,6=1
P 4.30105 5.1181 9 P 0 0;4=13,6=1
P 4.26105 5.1181 9 P 0 0;4=13,6=1
P 4.36305 5.02086004 53 P 0 0;2,4=25,6=0
P 4.75305 5.02086004 53 P 0 0;2,4=25,6=0
P 6.62418996 5.09705 28 P 0 0;2,4=4,6=0
P 6.58968996 5.00563002 50 P 0 0;2,4=19,6=0
P 6.60543996 5.00563002 50 P 0 0;2,4=19,6=0
L 9.45795 0.42821004 9.45795 0.36633002 9 P 0 
P 9.45795 0.36633002 9 P 0 0;4=13,6=1
P 6.62 4.645 9 P 0 0;4=13,6=1
P 6.62 4.61 9 P 0 0;4=13,6=1
P 6.605 4.77 9 P 0 0;4=13,6=1
P 6.315 4.9 9 P 0 0;4=13,6=1
P 6.315 4.865 9 P 0 0;4=13,6=1
P 6.315 4.82 9 P 0 0;4=13,6=1
P 6.315 4.785 9 P 0 0;4=13,6=1
P 6.315 4.705 9 P 0 0;4=13,6=1
P 6.315 4.74 9 P 0 0;4=13,6=1
P 6.315 4.66 9 P 0 0;4=13,6=1
P 6.315 4.625 9 P 0 0;4=13,6=1
P 6.837 5 28 P 0 0;2,4=4,6=0
L 1.51673002 5.70373996 1.51673002 5.78 9 P 0 
P 1.51673002 5.78 9 P 0 0;4=13,6=1
L 1.12303002 5.53641998 1.12303002 5.46016004 9 P 0 
P 1.12303002 5.46016004 9 P 0 0;4=13,6=1
L 1.20176998 5.53641998 1.20176998 5.46016004 9 P 0 
P 1.20176998 5.46016004 9 P 0 0;4=13,6=1
L 1.51673002 5.53641998 1.51673002 5.46016004 9 P 0 
P 1.51673002 5.46016004 9 P 0 0;4=13,6=1
L 1.36 5.383 1.36 5.355 9 P 0 
P 1.36 5.355 9 P 0 0;4=13,6=1
L 1.41 5.383 1.41 5.355 9 P 0 
P 1.41 5.355 9 P 0 0;4=13,6=1
L 1.46 5.383 1.46 5.355 9 P 0 
P 1.46 5.355 9 P 0 0;4=13,6=1
L 1.305 5.857 1.305 5.885 9 P 0 
P 1.305 5.885 9 P 0 0;4=13,6=1
L 1.355 5.857 1.355 5.885 9 P 0 
P 1.355 5.885 9 P 0 0;4=13,6=1
L 1.405 5.857 1.405 5.885 9 P 0 
P 1.405 5.885 9 P 0 0;4=13,6=1
L 1.455 5.857 1.455 5.885 9 P 0 
P 1.455 5.885 9 P 0 0;4=13,6=1
L 0.705 5.383 0.705 5.355 7 P 0 
P 0.705 5.355 9 P 0 0;4=13,6=1
P 0.7 5.267 9 P 0 0;4=0,6=1
L 0.73 5.147 0.73 5.175 7 P 0 
P 0.73 5.175 9 P 0 0;4=13,6=1
L 1.03 5.093 1.03 5.065 9 P 0 
P 1.03 5.065 9 P 0 0;4=13,6=1
L 1.28051004 5.53641998 1.28051004 5.46016004 9 P 0 
P 1.28051004 5.46016004 9 P 0 0;4=13,6=1
P 12.215 4.915 9 P 0 0;4=13,6=1
P 12.055 4.915 9 P 0 0;4=13,6=1
P 10.465 5.245 9 P 0 0;4=13,6=1
P 10.465 5.165 9 P 0 0;4=13,6=1
P 11.7719 4.80998996 9 P 0 0;4=13,6=1
P 11.7719 4.85498996 9 P 0 0;4=13,6=1
P 11.7719 4.90498996 9 P 0 0;4=13,6=1
P 11.7719 4.94998996 9 P 0 0;4=13,6=1
P 11.9719 4.94998996 9 P 0 0;4=13,6=1
P 11.9719 4.80998996 9 P 0 0;4=13,6=1
P 11.9719 4.85498996 9 P 0 0;4=13,6=1
P 11.9719 4.90498996 9 P 0 0;4=13,6=1
P 11.9219 4.94998996 9 P 0 0;4=13,6=1
P 11.9219 4.80998996 9 P 0 0;4=13,6=1
P 11.8719 4.94998996 9 P 0 0;4=13,6=1
P 11.8719 4.80998996 9 P 0 0;4=13,6=1
P 11.8219 4.80998996 9 P 0 0;4=13,6=1
P 11.8219 4.94998996 9 P 0 0;4=13,6=1
P 3.81998996 0.7751 28 P 0 0;2,4=4,6=0
P 3.60998996 0.2711 28 P 0 0;2,4=4,6=0
P 9.61795 0.79643002 28 P 0 0;2,4=4,6=0
P 9.40795 0.29243002 28 P 0 0;2,4=4,6=0
P 3.82558996 4.63965 37 P 0 0;2,4=8,6=0
P 11.69316004 2.6635 9 P 0 0;4=13,6=1
S P 0
OB 11.699419980315 2.664 I
OC 11.699419980315 2.664 11.69366003937 2.664 Y
OE
SE
S P 0
OB 11.799419980315 2.264 I
OC 11.799419980315 2.264 11.79366003937 2.264 Y
OE
SE
S P 0
OB 11.799419980315 2.201 I
OC 11.799419980315 2.201 11.79366003937 2.201 Y
OE
SE
S P 0
OB 11.749419980315 1.641 I
OC 11.749419980315 1.641 11.74366003937 1.641 Y
OE
SE
S P 0
OB 11.749419980315 1.704 I
OC 11.749419980315 1.704 11.74366003937 1.704 Y
OE
SE
S P 0
OB 10.30101003937 1.8199 I
OC 10.30101003937 1.8199 10.29525 1.8199 Y
OE
SE
S P 0
OB 10.30101003937 1.877 I
OC 10.30101003937 1.877 10.29525 1.877 Y
OE
SE
S P 0
OB 10.26576003937 1.975 I
OC 10.26576003937 1.975 10.26 1.975 Y
OE
SE
S P 0
OB 10.26576003937 1.9179 I
OC 10.26576003937 1.9179 10.26 1.9179 Y
OE
SE
S P 0
OB 10.13076003937 2.0651 I
OC 10.13076003937 2.0651 10.125 2.0651 Y
OE
SE
S P 0
OB 10.42166003937 1.43 I
OC 10.42166003937 1.43 10.4159 1.43 Y
OE
SE
S P 0
OB 10.47876003937 1.43 I
OC 10.47876003937 1.43 10.473 1.43 Y
OE
SE
S P 0
OB 10.43576003937 1.3341 I
OC 10.43576003937 1.3341 10.43 1.3341 Y
OE
SE
S P 0
OB 10.43576003937 1.277 I
OC 10.43576003937 1.277 10.43 1.277 Y
OE
SE
P 10.125 2.008 9 P 0 0;4=13,6=1
S P 0
OB 10.13076003937 2.008 I
OC 10.13076003937 2.008 10.125 2.008 Y
OE
SE
P 5.53531004 1.6642 9 P 0 0;4=13,6=1
S P 0
OB 5.541069980315 1.6642 I
OC 5.541069980315 1.6642 5.53531003937 1.6642 Y
OE
SE
S P 0
OB 5.541069980315 1.7213 I
OC 5.541069980315 1.7213 5.53531003937 1.7213 Y
OE
SE
P 5.53531004 1.7213 9 P 0 0;4=13,6=1
S P 0
OB 5.541069980315 2.0802 I
OC 5.541069980315 2.0802 5.53531003937 2.0802 Y
OE
SE
P 5.53531004 2.0802 9 P 0 0;4=13,6=1
S P 0
OB 5.541069980315 1.9393 I
OC 5.541069980315 1.9393 5.53531003937 1.9393 Y
OE
SE
P 5.53531004 1.9393 9 P 0 0;4=13,6=1
S P 0
OB 5.541069980315 2.2156 I
OC 5.541069980315 2.2156 5.53531003937 2.2156 Y
OE
SE
P 5.53531004 2.2156 9 P 0 0;4=13,6=1
S P 0
OB 5.541069980315 2.4081 I
OC 5.541069980315 2.4081 5.53531003937 2.4081 Y
OE
SE
P 5.53531004 2.4081 9 P 0 0;4=13,6=1
S P 0
OB 5.541069980315 2.5473 I
OC 5.541069980315 2.5473 5.53531003937 2.5473 Y
OE
SE
P 5.53531004 2.5473 9 P 0 0;4=13,6=1
P 2.86855 4.92 9 P 0 0;4=13,6=1
P 2.79768002 4.92 9 P 0 0;4=13,6=1
P 3.08113996 4.92 9 P 0 0;4=13,6=1
P 3.36461004 4.926 9 P 0 0;4=13,6=1
P 3.22288002 4.92 9 P 0 0;4=13,6=1
P 3.50633996 4.92 9 P 0 0;4=13,6=1
P 3.43546998 4.928 9 P 0 0;4=13,6=1
P 3.15398002 4.81401998 9 P 0 0;4=13,6=1
L 3.22288002 4.81401998 3.22288002 4.85788002 6 P 0 
P 3.22288002 4.81401998 9 P 0 0;4=13,6=1
L 3.36461004 4.81401998 3.36461004 4.85788002 6 P 0 
P 3.36461004 4.81401998 9 P 0 0;4=13,6=1
P 3.43546998 4.81401998 9 P 0 0;4=13,6=1
P 3.50633996 4.81401998 9 P 0 0;4=13,6=1
L 3.22288002 5.023 3.22288002 4.97913996 6 P 0 
P 3.22288002 5.023 9 P 0 0;4=13,6=1
L 3.50633996 5.023 3.50633996 4.97913996 6 P 0 
P 3.50633996 5.023 9 P 0 0;4=13,6=1
P 3.43546998 5.023 9 P 0 0;4=13,6=1
P 3.14 4.92 9 P 0 0;4=13,6=1
P 3.275 4.92 9 P 0 0;4=13,6=1
P 3.26 5.332 9 P 0 0;4=13,6=1
P 3.06791998 5.332 9 P 0 0;4=13,6=1
P 3.51176998 5.17873996 9 P 0 0;4=13,6=1
P 3.57176998 5.17873996 9 P 0 0;4=13,6=1
P 3.15743996 4.74418002 9 P 0 0;4=13,6=1
S P 0
OB 3.1632 4.744180019685 I
OC 3.1632 4.744180019685 3.15743996063 4.744180019685 Y
OE
SE
L 1.63308002 4.92 1.63308002 4.97913996 6 P 0 
P 1.63308002 4.92 9 P 0 0;4=13,6=1
P 1.84568002 4.92 9 P 0 0;4=13,6=1
P 1.77481004 4.92 9 P 0 0;4=13,6=1
P 1.70395 4.92 9 P 0 0;4=13,6=1
P 2.12913996 4.92 9 P 0 0;4=13,6=1
L 2.05828002 4.92 2.05828002 4.97913996 6 P 0 
P 2.05828002 4.92 9 P 0 0;4=13,6=1
P 1.98741004 4.92 9 P 0 0;4=13,6=1
L 1.91653996 4.92 1.91653996 4.97913996 6 P 0 
P 1.91653996 4.92 9 P 0 0;4=13,6=1
P 2.34173996 4.92 9 P 0 0;4=13,6=1
P 2.27086998 4.92 9 P 0 0;4=13,6=1
P 2.20001004 4.926 9 P 0 0;4=13,6=1
P 2.34173996 4.81 9 P 0 0;4=13,6=1
P 2.27086998 4.81 9 P 0 0;4=13,6=1
L 2.20001004 4.81 2.20001004 4.85788002 6 P 0 
P 2.20001004 4.81 9 P 0 0;4=13,6=1
P 1.63173002 4.81526998 9 P 0 0;4=13,6=1
P 1.7 4.812 9 P 0 0;4=13,6=1
P 1.84568002 4.81 9 P 0 0;4=13,6=1
P 1.776 4.812 9 P 0 0;4=13,6=1
L 2.12913996 4.81 2.12913996 4.85788002 6 P 0 
P 2.12913996 4.81 9 P 0 0;4=13,6=1
P 1.99 4.81 9 P 0 0;4=13,6=1
P 1.92 4.81 9 P 0 0;4=13,6=1
P 2.40716998 5.15373996 9 P 0 0;4=13,6=1
S P 0
OB 2.412930019685 5.15373996063 I
OC 2.412930019685 5.15373996063 2.407169980315 5.15373996063 Y
OE
SE
P 2.34716998 5.15373996 9 P 0 0;4=13,6=1
S P 0
OB 2.352930019685 5.15373996063 I
OC 2.352930019685 5.15373996063 2.347169980315 5.15373996063 Y
OE
SE
P 10.58661004 2.16615 8 P 0 0;4=12,6=1
P 10.63661004 2.16615 8 P 0 0;4=12,6=1
P 10.63661004 2.21615 8 P 0 0;4=12,6=1
P 10.88661004 1.91615 8 P 0 0;4=12,6=1
P 10.88661004 2.41615 8 P 0 0;4=12,6=1
P 10.88661004 2.66615 8 P 0 0;4=12,6=1
P 11.03661004 2.41615 8 P 0 0;4=12,6=1
P 11.03661004 2.36615 8 P 0 0;4=12,6=1
P 1.91111004 4.61826004 9 P 0 0;4=13,6=1
P 2.40716998 4.70326004 9 P 0 0;4=13,6=1
S P 0
OB 2.412930019685 4.70326003937 I
OC 2.412930019685 4.70326003937 2.407169980315 4.70326003937 Y
OE
SE
P 2.945 4.92 9 P 0 0;4=13,6=1
P 3.01028002 4.92 9 P 0 0;4=13,6=1
P 7.78 2.4781 9 P 0 0;4=0,6=1
P 2.24606004 3.86615 8 P 0 0;4=12,6=1
P 2.22106004 3.84115 10 P 0 0;2,4=11,6=0
P 2.49606004 3.86615 8 P 0 0;4=12,6=1
P 2.47106004 3.84115 10 P 0 0;2,4=11,6=0
P 2.24606004 3.81615 8 P 0 0;4=12,6=1
P 2.22106004 3.79115 10 P 0 0;2,4=11,6=0
P 2.19606004 3.76615 8 P 0 0;4=12,6=1
P 2.17106004 3.74115 10 P 0 0;2,4=11,6=0
P 2.24606004 3.76615 8 P 0 0;4=12,6=1
P 2.22106004 3.74115 10 P 0 0;2,4=11,6=0
P 2.29606004 3.76615 8 P 0 0;4=12,6=1
P 2.27106004 3.74115 10 P 0 0;2,4=11,6=0
P 2.49606004 3.71615 8 P 0 0;4=12,6=1
P 2.47106004 3.69115 10 P 0 0;2,4=11,6=0
P 2.49606004 3.56615 8 P 0 0;4=12,6=1
P 2.47106004 3.54115 10 P 0 0;2,4=11,6=0
P 2.44606004 3.56615 8 P 0 0;4=12,6=1
P 2.42106004 3.54115 10 P 0 0;2,4=11,6=0
P 2.39606004 3.56615 8 P 0 0;4=12,6=1
P 2.37106004 3.54115 10 P 0 0;2,4=11,6=0
P 2.29606004 3.61615 8 P 0 0;4=12,6=1
P 2.27106004 3.59115 10 P 0 0;2,4=11,6=0
P 2.24606004 3.71615 8 P 0 0;4=12,6=1
P 2.22106004 3.69115 10 P 0 0;2,4=11,6=0
P 2.24606004 3.66615 8 P 0 0;4=12,6=1
P 2.22106004 3.64115 10 P 0 0;2,4=11,6=0
P 2.24606004 3.61615 8 P 0 0;4=12,6=1
P 2.22106004 3.59115 10 P 0 0;2,4=11,6=0
P 2.19606004 3.61615 8 P 0 0;4=12,6=1
P 2.17106004 3.59115 10 P 0 0;2,4=11,6=0
P 2.19606004 3.56615 8 P 0 0;4=12,6=1
P 2.17106004 3.54115 10 P 0 0;2,4=11,6=0
P 2.14606004 3.56615 8 P 0 0;4=12,6=1
P 2.12106004 3.54115 10 P 0 0;2,4=11,6=0
P 2.04606004 3.56615 8 P 0 0;4=12,6=1
P 2.02106004 3.54115 10 P 0 0;2,4=11,6=0
P 1.99606004 3.56615 8 P 0 0;4=12,6=1
P 2.04606004 3.51615 8 P 0 0;4=12,6=1
P 2.04606004 3.46615 8 P 0 0;4=12,6=1
P 2.19606004 3.51615 8 P 0 0;4=12,6=1
P 2.17106004 3.49115 10 P 0 0;2,4=11,6=0
P 2.24606004 3.51615 8 P 0 0;4=12,6=1
P 2.22106004 3.49115 10 P 0 0;2,4=11,6=0
P 2.29606004 3.51615 8 P 0 0;4=12,6=1
P 2.27106004 3.49115 10 P 0 0;2,4=11,6=0
P 2.49606004 3.41615 8 P 0 0;4=12,6=1
P 2.47106004 3.39115 10 P 0 0;2,4=11,6=0
P 2.44606004 3.36615 8 P 0 0;4=12,6=1
P 2.42106004 3.34115 10 P 0 0;2,4=11,6=0
P 2.24606004 3.46615 8 P 0 0;4=12,6=1
P 2.22106004 3.44115 10 P 0 0;2,4=11,6=0
P 2.24606004 3.41615 8 P 0 0;4=12,6=1
P 2.22106004 3.39115 10 P 0 0;2,4=11,6=0
P 2.29606004 3.36615 8 P 0 0;4=12,6=1
P 2.27106004 3.34115 10 P 0 0;2,4=11,6=0
P 2.24606004 3.36615 8 P 0 0;4=12,6=1
P 2.22106004 3.34115 10 P 0 0;2,4=11,6=0
P 2.19606004 3.36615 8 P 0 0;4=12,6=1
P 2.17106004 3.34115 10 P 0 0;2,4=11,6=0
P 1.99606004 3.41615 8 P 0 0;4=12,6=1
P 2.09606004 3.36615 8 P 0 0;4=12,6=1
P 2.07106004 3.34115 10 P 0 0;2,4=11,6=0
P 2.24606004 3.31615 8 P 0 0;4=12,6=1
P 2.22106004 3.29115 10 P 0 0;2,4=11,6=0
P 2.24606004 3.26615 8 P 0 0;4=12,6=1
P 2.22106004 3.24115 10 P 0 0;2,4=11,6=0
P 2.29606004 3.21615 8 P 0 0;4=12,6=1
P 2.27106004 3.19115 10 P 0 0;2,4=11,6=0
P 2.24606004 3.21615 8 P 0 0;4=12,6=1
P 2.22106004 3.19115 10 P 0 0;2,4=11,6=0
P 2.19606004 3.21615 8 P 0 0;4=12,6=1
P 2.17106004 3.19115 10 P 0 0;2,4=11,6=0
P 2.09606004 3.21615 8 P 0 0;4=12,6=1
P 2.07106004 3.19115 10 P 0 0;2,4=11,6=0
P 2.14606004 3.16615 8 P 0 0;4=12,6=1
P 2.04606004 3.16615 8 P 0 0;4=12,6=1
P 2.24606004 3.16615 8 P 0 0;4=12,6=1
P 2.22106004 3.14115 10 P 0 0;2,4=11,6=0
P 2.29606004 3.16615 8 P 0 0;4=12,6=1
P 2.27106004 3.14115 10 P 0 0;2,4=11,6=0
P 2.34606004 3.21615 8 P 0 0;4=12,6=1
P 2.32106004 3.19115 10 P 0 0;2,4=11,6=0
P 2.44606004 3.21615 8 P 0 0;4=12,6=1
P 2.42106004 3.19115 10 P 0 0;2,4=11,6=0
P 2.49606004 3.21615 8 P 0 0;4=12,6=1
P 2.47106004 3.19115 10 P 0 0;2,4=11,6=0
P 2.49606004 3.26615 8 P 0 0;4=12,6=1
P 2.47106004 3.24115 10 P 0 0;2,4=11,6=0
P 2.49606004 3.16615 8 P 0 0;4=12,6=1
P 2.47106004 3.14115 10 P 0 0;2,4=11,6=0
P 2.39606004 3.16615 8 P 0 0;4=12,6=1
P 2.37106004 3.14115 10 P 0 0;2,4=11,6=0
L 2.27106004 3.04115 2.29606004 3.06615 9 P 0 
P 2.29606004 3.06615 8 P 0 0;4=12,6=1
L 2.27106004 3.09115 2.29606004 3.11615 9 P 0 
P 2.29606004 3.11615 8 P 0 0;4=12,6=1
L 2.27106004 2.94115 2.29606004 2.96615 9 P 0 
P 2.29606004 2.96615 8 P 0 0;4=12,6=1
L 2.27106004 2.99115 2.29606004 3.01615 9 P 0 
P 2.29606004 3.01615 8 P 0 0;4=12,6=1
L 2.22106004 3.04115 2.24606004 3.06615 9 P 0 
P 2.24606004 3.06615 8 P 0 0;4=12,6=1
L 2.22106004 3.09115 2.24606004 3.11615 9 P 0 
P 2.24606004 3.11615 8 P 0 0;4=12,6=1
L 2.22106004 2.94115 2.24606004 2.96615 9 P 0 
P 2.24606004 2.96615 8 P 0 0;4=12,6=1
L 2.22106004 2.99115 2.24606004 3.01615 9 P 0 
P 2.24606004 3.01615 8 P 0 0;4=12,6=1
L 2.32106004 2.84115 2.34606004 2.86615 9 P 0 
P 2.34606004 2.86615 8 P 0 0;4=12,6=1
L 2.32106004 2.89115 2.34606004 2.91615 9 P 0 
P 2.34606004 2.91615 8 P 0 0;4=12,6=1
L 2.27106004 2.74115 2.29606004 2.76615 9 P 0 
P 2.29606004 2.76615 8 P 0 0;4=12,6=1
L 2.27106004 2.79115 2.29606004 2.81615 9 P 0 
P 2.29606004 2.81615 8 P 0 0;4=12,6=1
L 2.22106004 2.74115 2.24606004 2.76615 9 P 0 
P 2.24606004 2.76615 8 P 0 0;4=12,6=1
L 2.22106004 2.79115 2.24606004 2.81615 9 P 0 
P 2.24606004 2.81615 8 P 0 0;4=12,6=1
L 2.17106004 2.79115 2.19606004 2.81615 9 P 0 
P 2.19606004 2.81615 8 P 0 0;4=12,6=1
L 2.07106004 2.79115 2.09606004 2.81615 9 P 0 
P 2.09606004 2.81615 8 P 0 0;4=12,6=1
L 2.07106004 2.84115 2.09606004 2.86615 9 P 0 
P 2.09606004 2.86615 8 P 0 0;4=12,6=1
L 2.17106004 3.04115 2.19606004 3.06615 9 P 0 
P 2.19606004 3.06615 8 P 0 0;4=12,6=1
L 2.12106004 2.99115 2.14606004 3.01615 9 P 0 
P 2.14606004 3.01615 8 P 0 0;4=12,6=1
L 2.07106004 3.04115 2.09606004 3.06615 9 P 0 
P 2.09606004 3.06615 8 P 0 0;4=12,6=1
L 2.02106004 2.99115 2.04606004 3.01615 9 P 0 
P 2.04606004 3.01615 8 P 0 0;4=12,6=1
L 2.07106004 2.89115 2.09606004 2.91615 9 P 0 
P 2.09606004 2.91615 8 P 0 0;4=12,6=1
L 2.12106004 2.84115 2.14606004 2.86615 9 P 0 
P 2.14606004 2.86615 8 P 0 0;4=12,6=1
L 2.02106004 2.84115 2.04606004 2.86615 9 P 0 
P 2.04606004 2.86615 8 P 0 0;4=12,6=1
L 2.17106004 2.89115 2.19606004 2.91615 9 P 0 
P 2.19606004 2.91615 8 P 0 0;4=12,6=1
L 2.22106004 2.89115 2.24606004 2.91615 9 P 0 
P 2.24606004 2.91615 8 P 0 0;4=12,6=1
L 2.27106004 2.89115 2.29606004 2.91615 9 P 0 
P 2.29606004 2.91615 8 P 0 0;4=12,6=1
L 2.37106004 2.99115 2.39606004 3.01615 9 P 0 
P 2.39606004 3.01615 8 P 0 0;4=12,6=1
L 2.32106004 3.04115 2.34606004 3.06615 9 P 0 
P 2.34606004 3.06615 8 P 0 0;4=12,6=1
L 2.42106004 3.04115 2.44606004 3.06615 9 P 0 
P 2.44606004 3.06615 8 P 0 0;4=12,6=1
L 2.47106004 2.99115 2.49606004 3.01615 9 P 0 
P 2.49606004 3.01615 8 P 0 0;4=12,6=1
L 2.42106004 2.89115 2.44606004 2.91615 9 P 0 
P 2.44606004 2.91615 8 P 0 0;4=12,6=1
L 2.42106004 2.84115 2.44606004 2.86615 9 P 0 
P 2.44606004 2.86615 8 P 0 0;4=12,6=1
L 2.37106004 2.84115 2.39606004 2.86615 9 P 0 
P 2.39606004 2.86615 8 P 0 0;4=12,6=1
L 2.32106004 2.79115 2.34606004 2.81615 9 P 0 
P 2.34606004 2.81615 8 P 0 0;4=12,6=1
L 2.42106004 2.79115 2.44606004 2.81615 9 P 0 
P 2.44606004 2.81615 8 P 0 0;4=12,6=1
L 2.47106004 2.84115 2.49606004 2.86615 9 P 0 
P 2.49606004 2.86615 8 P 0 0;4=12,6=1
L 2.47106004 2.69115 2.49606004 2.71615 9 P 0 
P 2.49606004 2.71615 8 P 0 0;4=12,6=1
L 2.42106004 2.64115 2.44606004 2.66615 9 P 0 
P 2.44606004 2.66615 8 P 0 0;4=12,6=1
L 2.37106004 2.69115 2.39606004 2.71615 9 P 0 
P 2.39606004 2.71615 8 P 0 0;4=12,6=1
L 2.32106004 2.64115 2.34606004 2.66615 9 P 0 
P 2.34606004 2.66615 8 P 0 0;4=12,6=1
L 2.27106004 2.69115 2.29606004 2.71615 9 P 0 
P 2.29606004 2.71615 8 P 0 0;4=12,6=1
L 2.27106004 2.64115 2.29606004 2.66615 9 P 0 
P 2.29606004 2.66615 8 P 0 0;4=12,6=1
L 2.22106004 2.69115 2.24606004 2.71615 9 P 0 
P 2.24606004 2.71615 8 P 0 0;4=12,6=1
L 2.22106004 2.64115 2.24606004 2.66615 9 P 0 
P 2.24606004 2.66615 8 P 0 0;4=12,6=1
L 2.17106004 2.64115 2.19606004 2.66615 9 P 0 
P 2.19606004 2.66615 8 P 0 0;4=12,6=1
L 2.12106004 2.69115 2.14606004 2.71615 9 P 0 
P 2.14606004 2.71615 8 P 0 0;4=12,6=1
L 2.07106004 2.64115 2.09606004 2.66615 9 P 0 
P 2.09606004 2.66615 8 P 0 0;4=12,6=1
L 2.02106004 2.69115 2.04606004 2.71615 9 P 0 
P 2.04606004 2.71615 8 P 0 0;4=12,6=1
L 2.02106004 2.54115 2.04606004 2.56615 9 P 0 
P 2.04606004 2.56615 8 P 0 0;4=12,6=1
L 2.02106004 2.49115 2.04606004 2.51615 9 P 0 
P 2.04606004 2.51615 8 P 0 0;4=12,6=1
L 2.02106004 2.44115 2.04606004 2.46615 9 P 0 
P 2.04606004 2.46615 8 P 0 0;4=12,6=1
L 2.07106004 2.49115 2.09606004 2.51615 9 P 0 
P 2.09606004 2.51615 8 P 0 0;4=12,6=1
L 2.12106004 2.54115 2.14606004 2.56615 9 P 0 
P 2.14606004 2.56615 8 P 0 0;4=12,6=1
L 2.22106004 2.59115 2.24606004 2.61615 9 P 0 
P 2.24606004 2.61615 8 P 0 0;4=12,6=1
L 2.22106004 2.54115 2.24606004 2.56615 9 P 0 
P 2.24606004 2.56615 8 P 0 0;4=12,6=1
L 2.27106004 2.59115 2.29606004 2.61615 9 P 0 
P 2.29606004 2.61615 8 P 0 0;4=12,6=1
L 2.27106004 2.54115 2.29606004 2.56615 9 P 0 
P 2.29606004 2.56615 8 P 0 0;4=12,6=1
L 2.32106004 2.49115 2.34606004 2.51615 9 P 0 
P 2.34606004 2.51615 8 P 0 0;4=12,6=1
L 2.27106004 2.49115 2.29606004 2.51615 9 P 0 
P 2.29606004 2.51615 8 P 0 0;4=12,6=1
L 2.22106004 2.49115 2.24606004 2.51615 9 P 0 
P 2.24606004 2.51615 8 P 0 0;4=12,6=1
L 2.17106004 2.49115 2.19606004 2.51615 9 P 0 
P 2.19606004 2.51615 8 P 0 0;4=12,6=1
L 2.12106004 2.44115 2.14606004 2.46615 9 P 0 
P 2.14606004 2.46615 8 P 0 0;4=12,6=1
L 2.22106004 2.44115 2.24606004 2.46615 9 P 0 
P 2.24606004 2.46615 8 P 0 0;4=12,6=1
L 2.27106004 2.44115 2.29606004 2.46615 9 P 0 
P 2.29606004 2.46615 8 P 0 0;4=12,6=1
L 2.27106004 2.39115 2.29606004 2.41615 9 P 0 
P 2.29606004 2.41615 8 P 0 0;4=12,6=1
L 2.22106004 2.39115 2.24606004 2.41615 9 P 0 
P 2.24606004 2.41615 8 P 0 0;4=12,6=1
L 2.22106004 2.34115 2.24606004 2.36615 9 P 0 
P 2.24606004 2.36615 8 P 0 0;4=12,6=1
L 2.17106004 2.34115 2.19606004 2.36615 9 P 0 
P 2.19606004 2.36615 8 P 0 0;4=12,6=1
L 2.27106004 2.34115 2.29606004 2.36615 9 P 0 
P 2.29606004 2.36615 8 P 0 0;4=12,6=1
L 2.37106004 2.44115 2.39606004 2.46615 9 P 0 
P 2.39606004 2.46615 8 P 0 0;4=12,6=1
L 2.37106004 2.49115 2.39606004 2.51615 9 P 0 
P 2.39606004 2.51615 8 P 0 0;4=12,6=1
L 2.37106004 2.54115 2.39606004 2.56615 9 P 0 
P 2.39606004 2.56615 8 P 0 0;4=12,6=1
L 2.42106004 2.49115 2.44606004 2.51615 9 P 0 
P 2.44606004 2.51615 8 P 0 0;4=12,6=1
L 2.47106004 2.54115 2.49606004 2.56615 9 P 0 
P 2.49606004 2.56615 8 P 0 0;4=12,6=1
L 2.47106004 2.49115 2.49606004 2.51615 9 P 0 
P 2.49606004 2.51615 8 P 0 0;4=12,6=1
L 2.47106004 2.44115 2.49606004 2.46615 9 P 0 
P 2.49606004 2.46615 8 P 0 0;4=12,6=1
L 2.42106004 2.34115 2.44606004 2.36615 9 P 0 
P 2.44606004 2.36615 8 P 0 0;4=12,6=1
L 2.47106004 2.29115 2.49606004 2.31615 9 P 0 
P 2.49606004 2.31615 8 P 0 0;4=12,6=1
L 2.37106004 2.29115 2.39606004 2.31615 9 P 0 
P 2.39606004 2.31615 8 P 0 0;4=12,6=1
L 2.32106004 2.34115 2.34606004 2.36615 9 P 0 
P 2.34606004 2.36615 8 P 0 0;4=12,6=1
L 2.27106004 2.29115 2.29606004 2.31615 9 P 0 
P 2.29606004 2.31615 8 P 0 0;4=12,6=1
L 2.22106004 2.29115 2.24606004 2.31615 9 P 0 
P 2.24606004 2.31615 8 P 0 0;4=12,6=1
L 2.02106004 2.29115 2.04606004 2.31615 9 P 0 
P 2.04606004 2.31615 8 P 0 0;4=12,6=1
L 2.02106004 2.14115 2.04606004 2.16615 9 P 0 
P 2.04606004 2.16615 8 P 0 0;4=12,6=1
L 2.02106004 2.14115 2.04606004 2.11615 9 P 0 
P 2.04606004 2.11615 8 P 0 0;4=12,6=1
L 2.02106004 1.99115 2.04606004 1.96615 9 P 0 
P 2.04606004 1.96615 8 P 0 0;4=12,6=1
L 2.07106004 2.04115 2.09606004 2.01615 9 P 0 
P 2.09606004 2.01615 8 P 0 0;4=12,6=1
L 2.12106004 1.99115 2.14606004 1.96615 9 P 0 
P 2.14606004 1.96615 8 P 0 0;4=12,6=1
L 2.07106004 1.89115 2.09606004 1.86615 9 P 0 
P 2.09606004 1.86615 8 P 0 0;4=12,6=1
L 2.17106004 1.89115 2.19606004 1.86615 9 P 0 
P 2.19606004 1.86615 8 P 0 0;4=12,6=1
L 2.22106004 1.89115 2.24606004 1.86615 9 P 0 
P 2.24606004 1.86615 8 P 0 0;4=12,6=1
L 2.27106004 1.89115 2.29606004 1.86615 9 P 0 
P 2.29606004 1.86615 8 P 0 0;4=12,6=1
L 2.32106004 1.89115 2.34606004 1.86615 9 P 0 
P 2.34606004 1.86615 8 P 0 0;4=12,6=1
L 2.22106004 1.94115 2.24606004 1.91615 9 P 0 
P 2.24606004 1.91615 8 P 0 0;4=12,6=1
L 2.27106004 1.94115 2.29606004 1.91615 9 P 0 
P 2.29606004 1.91615 8 P 0 0;4=12,6=1
L 2.22106004 1.99115 2.24606004 1.96615 9 P 0 
P 2.24606004 1.96615 8 P 0 0;4=12,6=1
L 2.27106004 1.99115 2.29606004 1.96615 9 P 0 
P 2.29606004 1.96615 8 P 0 0;4=12,6=1
L 2.17106004 2.04115 2.19606004 2.01615 9 P 0 
P 2.19606004 2.01615 8 P 0 0;4=12,6=1
L 2.22106004 2.04115 2.24606004 2.01615 9 P 0 
P 2.24606004 2.01615 8 P 0 0;4=12,6=1
L 2.27106004 2.04115 2.29606004 2.01615 9 P 0 
P 2.29606004 2.01615 8 P 0 0;4=12,6=1
L 2.32106004 2.04115 2.34606004 2.01615 9 P 0 
P 2.34606004 2.01615 8 P 0 0;4=12,6=1
L 2.37106004 1.99115 2.39606004 1.96615 9 P 0 
P 2.39606004 1.96615 8 P 0 0;4=12,6=1
L 2.42106004 2.04115 2.44606004 2.01615 9 P 0 
P 2.44606004 2.01615 8 P 0 0;4=12,6=1
L 2.47106004 1.99115 2.49606004 1.96615 9 P 0 
P 2.49606004 1.96615 8 P 0 0;4=12,6=1
L 2.42106004 1.89115 2.44606004 1.86615 9 P 0 
P 2.44606004 1.86615 8 P 0 0;4=12,6=1
L 2.47106004 2.14115 2.49606004 2.11615 9 P 0 
P 2.49606004 2.11615 8 P 0 0;4=12,6=1
L 2.42106004 2.19115 2.44606004 2.16615 9 P 0 
P 2.44606004 2.16615 8 P 0 0;4=12,6=1
L 2.47106004 2.14115 2.49606004 2.16615 9 P 0 
P 2.49606004 2.16615 8 P 0 0;4=12,6=1
L 2.42106004 2.19115 2.44606004 2.21615 9 P 0 
P 2.44606004 2.21615 8 P 0 0;4=12,6=1
L 2.37106004 2.14115 2.39606004 2.16615 9 P 0 
P 2.39606004 2.16615 8 P 0 0;4=12,6=1
L 2.37106004 2.14115 2.39606004 2.11615 9 P 0 
P 2.39606004 2.11615 8 P 0 0;4=12,6=1
L 2.32106004 2.19115 2.34606004 2.16615 9 P 0 
P 2.34606004 2.16615 8 P 0 0;4=12,6=1
L 2.32106004 2.19115 2.34606004 2.21615 9 P 0 
P 2.34606004 2.21615 8 P 0 0;4=12,6=1
L 2.27106004 2.19115 2.29606004 2.21615 9 P 0 
P 2.29606004 2.21615 8 P 0 0;4=12,6=1
L 2.27106004 2.19115 2.29606004 2.16615 9 P 0 
P 2.29606004 2.16615 8 P 0 0;4=12,6=1
L 2.27106004 2.09115 2.29606004 2.06615 9 P 0 
P 2.29606004 2.06615 8 P 0 0;4=12,6=1
L 2.27106004 2.14115 2.29606004 2.11615 9 P 0 
P 2.29606004 2.11615 8 P 0 0;4=12,6=1
L 2.22106004 2.14115 2.24606004 2.11615 9 P 0 
P 2.24606004 2.11615 8 P 0 0;4=12,6=1
L 2.22106004 2.14115 2.24606004 2.16615 9 P 0 
P 2.24606004 2.16615 8 P 0 0;4=12,6=1
L 2.22106004 2.09115 2.24606004 2.06615 9 P 0 
P 2.24606004 2.06615 8 P 0 0;4=12,6=1
L 2.22106004 2.19115 2.24606004 2.21615 9 P 0 
P 2.24606004 2.21615 8 P 0 0;4=12,6=1
L 2.27106004 2.24115 2.29606004 2.26615 9 P 0 
P 2.29606004 2.26615 8 P 0 0;4=12,6=1
L 2.22106004 2.24115 2.24606004 2.26615 9 P 0 
P 2.24606004 2.26615 8 P 0 0;4=12,6=1
L 2.17106004 2.19115 2.19606004 2.21615 9 P 0 
P 2.19606004 2.21615 8 P 0 0;4=12,6=1
L 2.17106004 2.19115 2.19606004 2.16615 9 P 0 
P 2.19606004 2.16615 8 P 0 0;4=12,6=1
L 2.12106004 2.14115 2.14606004 2.11615 9 P 0 
P 2.14606004 2.11615 8 P 0 0;4=12,6=1
L 2.12106004 2.14115 2.14606004 2.16615 9 P 0 
P 2.14606004 2.16615 8 P 0 0;4=12,6=1
L 2.07106004 2.19115 2.09606004 2.21615 9 P 0 
P 2.09606004 2.21615 8 P 0 0;4=12,6=1
L 2.07106004 2.19115 2.09606004 2.16615 9 P 0 
P 2.09606004 2.16615 8 P 0 0;4=12,6=1
L 2.07106004 2.34115 2.09606004 2.36615 9 P 0 
P 2.09606004 2.36615 8 P 0 0;4=12,6=1
L 2.12106004 2.29115 2.14606004 2.31615 9 P 0 
P 2.14606004 2.31615 8 P 0 0;4=12,6=1
L 2.02106004 2.69115 1.99606004 2.71615 9 P 0 
P 1.99606004 2.71615 8 P 0 0;4=12,6=1
L 2.02106004 2.84115 1.99606004 2.86615 9 P 0 
P 1.99606004 2.86615 8 P 0 0;4=12,6=1
L 2.07106004 2.84115 2.04606004 2.81615 9 P 0 
P 2.04606004 2.81615 8 P 0 0;4=12,6=1
L 2.07106004 2.79115 2.04606004 2.76615 9 P 0 
P 2.04606004 2.76615 8 P 0 0;4=12,6=1
P 3.29373996 5.023 9 P 0 0;4=13,6=1
L 2.12106004 3.24115 2.14606004 3.26615 9 P 0 
P 2.14606004 3.26615 8 P 0 0;4=12,6=1
P 2.12106004 3.24115 10 P 0 0;2,4=11,6=0
L 2.02106004 3.24115 2.04606004 3.26615 9 P 0 
P 2.04606004 3.26615 8 P 0 0;4=12,6=1
P 2.02106004 3.24115 10 P 0 0;2,4=11,6=0
L 2.02106004 3.19115 2.04606004 3.21615 9 P 0 
P 2.04606004 3.21615 8 P 0 0;4=12,6=1
P 2.02106004 3.19115 10 P 0 0;2,4=11,6=0
L 2.12106004 3.19115 2.14606004 3.21615 9 P 0 
P 2.14606004 3.21615 8 P 0 0;4=12,6=1
P 2.12106004 3.19115 10 P 0 0;2,4=11,6=0
L 2.37106004 3.19115 2.39606004 3.21615 9 P 0 
P 2.39606004 3.21615 8 P 0 0;4=12,6=1
P 2.37106004 3.19115 10 P 0 0;2,4=11,6=0
L 2.37106004 3.24115 2.39606004 3.26615 9 P 0 
P 2.39606004 3.26615 8 P 0 0;4=12,6=1
P 2.37106004 3.24115 10 P 0 0;2,4=11,6=0
L 2.27106004 3.24115 2.29606004 3.26615 9 P 0 
P 2.29606004 3.26615 8 P 0 0;4=12,6=1
P 2.27106004 3.24115 10 P 0 0;2,4=11,6=0
L 2.27106004 3.29115 2.29606004 3.31615 9 P 0 
P 2.29606004 3.31615 8 P 0 0;4=12,6=1
P 2.27106004 3.29115 10 P 0 0;2,4=11,6=0
L 2.32106004 3.34115 2.34606004 3.36615 9 P 0 
P 2.34606004 3.36615 8 P 0 0;4=12,6=1
P 2.32106004 3.34115 10 P 0 0;2,4=11,6=0
L 2.12106004 3.39115 2.14606004 3.41615 9 P 0 
P 2.14606004 3.41615 8 P 0 0;4=12,6=1
P 2.12106004 3.39115 10 P 0 0;2,4=11,6=0
L 2.07106004 3.59115 2.09606004 3.61615 9 P 0 
P 2.09606004 3.61615 8 P 0 0;4=12,6=1
P 2.07106004 3.59115 10 P 0 0;2,4=11,6=0
L 2.27106004 3.44115 2.29606004 3.46615 9 P 0 
P 2.29606004 3.46615 8 P 0 0;4=12,6=1
P 2.27106004 3.44115 10 P 0 0;2,4=11,6=0
L 2.27106004 3.39115 2.29606004 3.41615 9 P 0 
P 2.29606004 3.41615 8 P 0 0;4=12,6=1
P 2.27106004 3.39115 10 P 0 0;2,4=11,6=0
L 2.37106004 3.39115 2.39606004 3.41615 9 P 0 
P 2.39606004 3.41615 8 P 0 0;4=12,6=1
P 2.37106004 3.39115 10 P 0 0;2,4=11,6=0
L 2.32106004 3.49115 2.34606004 3.51615 9 P 0 
P 2.34606004 3.51615 8 P 0 0;4=12,6=1
P 2.32106004 3.49115 10 P 0 0;2,4=11,6=0
L 2.32106004 3.59115 2.34606004 3.61615 9 P 0 
P 2.34606004 3.61615 8 P 0 0;4=12,6=1
P 2.32106004 3.59115 10 P 0 0;2,4=11,6=0
L 2.32106004 3.54115 2.34606004 3.56615 9 P 0 
P 2.34606004 3.56615 8 P 0 0;4=12,6=1
P 2.32106004 3.54115 10 P 0 0;2,4=11,6=0
L 2.42106004 3.49115 2.44606004 3.51615 9 P 0 
P 2.44606004 3.51615 8 P 0 0;4=12,6=1
P 2.42106004 3.49115 10 P 0 0;2,4=11,6=0
L 2.42106004 3.59115 2.44606004 3.61615 9 P 0 
P 2.44606004 3.61615 8 P 0 0;4=12,6=1
P 2.42106004 3.59115 10 P 0 0;2,4=11,6=0
L 2.12106004 3.69115 2.14606004 3.71615 9 P 0 
P 2.14606004 3.71615 8 P 0 0;4=12,6=1
P 2.12106004 3.69115 10 P 0 0;2,4=11,6=0
L 2.02106004 3.69115 2.04606004 3.71615 9 P 0 
P 2.04606004 3.71615 8 P 0 0;4=12,6=1
P 2.02106004 3.69115 10 P 0 0;2,4=11,6=0
L 2.07106004 3.74115 2.09606004 3.76615 9 P 0 
P 2.09606004 3.76615 8 P 0 0;4=12,6=1
P 2.07106004 3.74115 10 P 0 0;2,4=11,6=0
L 2.12106004 3.84115 2.14606004 3.86615 9 P 0 
P 2.14606004 3.86615 8 P 0 0;4=12,6=1
P 2.12106004 3.84115 10 P 0 0;2,4=11,6=0
L 2.02106004 3.84115 2.04606004 3.86615 9 P 0 
P 2.04606004 3.86615 8 P 0 0;4=12,6=1
P 2.02106004 3.84115 10 P 0 0;2,4=11,6=0
L 2.27106004 3.69115 2.29606004 3.71615 9 P 0 
P 2.29606004 3.71615 8 P 0 0;4=12,6=1
P 2.27106004 3.69115 10 P 0 0;2,4=11,6=0
L 2.27106004 3.64115 2.29606004 3.66615 9 P 0 
P 2.29606004 3.66615 8 P 0 0;4=12,6=1
P 2.27106004 3.64115 10 P 0 0;2,4=11,6=0
L 2.37106004 3.69115 2.39606004 3.71615 9 P 0 
P 2.39606004 3.71615 8 P 0 0;4=12,6=1
P 2.37106004 3.69115 10 P 0 0;2,4=11,6=0
L 2.32106004 3.74115 2.34606004 3.76615 9 P 0 
P 2.34606004 3.76615 8 P 0 0;4=12,6=1
P 2.32106004 3.74115 10 P 0 0;2,4=11,6=0
L 2.27106004 3.79115 2.29606004 3.81615 9 P 0 
P 2.29606004 3.81615 8 P 0 0;4=12,6=1
P 2.27106004 3.79115 10 P 0 0;2,4=11,6=0
L 2.37106004 3.84115 2.39606004 3.86615 9 P 0 
P 2.39606004 3.86615 8 P 0 0;4=12,6=1
P 2.37106004 3.84115 10 P 0 0;2,4=11,6=0
L 2.27106004 3.84115 2.29606004 3.86615 9 P 0 
P 2.29606004 3.86615 8 P 0 0;4=12,6=1
P 2.27106004 3.84115 10 P 0 0;2,4=11,6=0
L 2.42106004 3.74115 2.44606004 3.76615 9 P 0 
P 2.44606004 3.76615 8 P 0 0;4=12,6=1
P 2.42106004 3.74115 10 P 0 0;2,4=11,6=0
P 2.17106004 2.84115 10 P 0 0;2,4=11,6=0
L 2.17106004 2.84115 2.19606004 2.86615 9 P 0 
P 2.19606004 2.86615 8 P 0 0;4=12,6=1
S P 0
OB 3.3758 5.181280019685 I
OC 3.3758 5.181280019685 3.37003996063 5.181280019685 Y
OE
SE
S P 0
OB 3.304930019685 5.14223996063 I
OC 3.304930019685 5.14223996063 3.299169980315 5.14223996063 Y
OE
SE
S P 0
OB 3.364930019685 5.14223996063 I
OC 3.364930019685 5.14223996063 3.359169980315 5.14223996063 Y
OE
SE
S P 0
OB 3.4358 5.181280019685 I
OC 3.4358 5.181280019685 3.43003996063 5.181280019685 Y
OE
SE
L 3.36461004 5.023 3.36461004 4.97913996 6 P 0 
P 3.36461004 5.023 9 P 0 0;4=13,6=1
L 3.29373996 4.81401998 3.29373996 4.85788002 6 P 0 
P 3.29373996 4.81401998 9 P 0 0;4=13,6=1
L 3.01028002 4.81401998 3.01028002 4.85788002 6 P 0 
P 3.01028002 4.81401998 9 P 0 0;4=13,6=1
P 2.94141004 4.81401998 9 P 0 0;4=13,6=1
P 2.86555 4.81401998 9 P 0 0;4=13,6=1
L 2.79768002 4.81401998 2.79768002 4.85788002 6 P 0 
P 2.79768002 4.81401998 9 P 0 0;4=13,6=1
L 3.15201004 5.023 3.15201004 4.97913996 6 P 0 
P 3.15201004 5.023 9 P 0 0;4=13,6=1
P 3.08113996 5.023 9 P 0 0;4=13,6=1
L 3.01028002 5.023 3.01028002 4.97913996 6 P 0 
P 3.01028002 5.023 9 P 0 0;4=13,6=1
L 2.93941004 5.023 2.93941004 4.97913996 6 P 0 
P 2.93941004 5.023 9 P 0 0;4=13,6=1
L 2.86855 5.023 2.86855 4.97913996 6 P 0 
P 2.86855 5.023 9 P 0 0;4=13,6=1
L 2.79768002 5.023 2.79768002 4.97913996 6 P 0 
P 2.79768002 5.023 9 P 0 0;4=13,6=1
L 1.70395 5.023 1.70395 4.97913996 6 P 0 
P 1.70395 5.023 9 P 0 0;4=13,6=1
P 1.63308002 5.023 9 P 0 0;4=13,6=1
L 1.77481004 5.023 1.77481004 4.97913996 6 P 0 
P 1.77481004 5.023 9 P 0 0;4=13,6=1
P 1.91653996 5.023 9 P 0 0;4=13,6=1
L 1.84568002 5.023 1.84568002 4.97913996 6 P 0 
P 1.84568002 5.023 9 P 0 0;4=13,6=1
L 1.98741004 5.023 1.98741004 4.97913996 6 P 0 
P 1.98741004 5.023 9 P 0 0;4=13,6=1
P 2.05828002 5.023 9 P 0 0;4=13,6=1
P 2.12913996 5.023 9 P 0 0;4=13,6=1
L 2.20001004 5.023 2.20001004 4.97913996 6 P 0 
P 2.20001004 5.023 9 P 0 0;4=13,6=1
L 2.27086998 5.023 2.27086998 4.97913996 6 P 0 
P 2.27086998 5.023 9 P 0 0;4=13,6=1
L 2.34173996 5.023 2.34173996 4.97913996 6 P 0 
P 2.34173996 5.023 9 P 0 0;4=13,6=1
L 1.56221004 4.97913996 1.56221004 5.023 6 P 0 
P 1.56221004 5.023 9 P 0 0;4=13,6=1
L 1.56221004 4.85788002 1.56221004 4.81401998 6 P 0 
P 1.56221004 4.81401998 9 P 0 0;4=13,6=1
P 2.06086998 4.81 9 P 0 0;4=13,6=1
S P 0
OB 2.08428996063 4.62815 I
OC 2.08428996063 4.62815 2.078530019685 4.62815 Y
OE
SE
S P 0
OB 2.02428996063 4.62815 I
OC 2.02428996063 4.62815 2.018530019685 4.62815 Y
OE
SE
S P 0
OB 1.856869980315 4.61826003937 I
OC 1.856869980315 4.61826003937 1.85111003937 4.61826003937 Y
OE
SE
S P 0
OB 1.916869980315 4.61826003937 I
OC 1.916869980315 4.61826003937 1.91111003937 4.61826003937 Y
OE
SE
L 2.41261004 4.97913996 2.41261004 5.023 6 P 0 
P 2.41261004 5.023 9 P 0 0;4=13,6=1
L 2.41261004 4.85788002 2.41261004 4.81401998 6 P 0 
P 2.41261004 4.81401998 9 P 0 0;4=13,6=1
L 2.72681004 4.97913996 2.72681004 5.023 6 P 0 
P 2.72681004 5.023 9 P 0 0;4=13,6=1
L 2.72681004 4.85788002 2.72681004 4.81401998 6 P 0 
P 2.72681004 4.81401998 9 P 0 0;4=13,6=1
L 3.57721004 4.85788002 3.57721004 4.81401998 6 P 0 
P 3.57721004 4.81401998 9 P 0 0;4=13,6=1
L 3.57721004 4.97913996 3.57721004 5.023 6 P 0 
P 3.57721004 5.023 9 P 0 0;4=13,6=1
P 4.88268002 1.91615 8 P 0 0;4=12,6=1
P 4.78268002 1.91615 8 P 0 0;4=12,6=1
P 5.03268002 2.36615 8 P 0 0;4=12,6=1
P 5.03268002 2.41615 8 P 0 0;4=12,6=1
L 4.90768002 3.64115 4.88268002 3.66615 9 P 0 
P 4.88268002 3.66615 8 P 0 0;4=12,6=1
L 4.85768002 3.64115 4.83268002 3.66615 9 P 0 
P 4.83268002 3.66615 8 P 0 0;4=12,6=1
L 5.05768002 3.64115 5.03268002 3.66615 9 P 0 
P 5.03268002 3.66615 8 P 0 0;4=12,6=1
L 4.95768002 3.64115 4.93268002 3.66615 9 P 0 
P 4.93268002 3.66615 8 P 0 0;4=12,6=1
L 5.00768002 3.64115 4.98268002 3.66615 9 P 0 
P 4.98268002 3.66615 8 P 0 0;4=12,6=1
L 4.90768002 3.49115 4.88268002 3.51615 9 P 0 
P 4.88268002 3.51615 8 P 0 0;4=12,6=1
L 4.85768002 3.49115 4.83268002 3.51615 9 P 0 
P 4.83268002 3.51615 8 P 0 0;4=12,6=1
L 5.05768002 3.49115 5.03268002 3.51615 9 P 0 
P 5.03268002 3.51615 8 P 0 0;4=12,6=1
L 4.95768002 3.49115 4.93268002 3.51615 9 P 0 
P 4.93268002 3.51615 8 P 0 0;4=12,6=1
L 5.00768002 3.49115 4.98268002 3.51615 9 P 0 
P 4.98268002 3.51615 8 P 0 0;4=12,6=1
L 4.90768002 3.79115 4.88268002 3.81615 9 P 0 
P 4.88268002 3.81615 8 P 0 0;4=12,6=1
L 4.85768002 3.79115 4.83268002 3.81615 9 P 0 
P 4.83268002 3.81615 8 P 0 0;4=12,6=1
L 4.95768002 3.79115 4.93268002 3.81615 9 P 0 
P 4.93268002 3.81615 8 P 0 0;4=12,6=1
L 5.00768002 3.79115 4.98268002 3.81615 9 P 0 
P 4.98268002 3.81615 8 P 0 0;4=12,6=1
L 4.90768002 3.34115 4.88268002 3.36615 9 P 0 
P 4.88268002 3.36615 8 P 0 0;4=12,6=1
L 4.85768002 3.34115 4.83268002 3.36615 9 P 0 
P 4.83268002 3.36615 8 P 0 0;4=12,6=1
L 5.05768002 3.34115 5.03268002 3.36615 9 P 0 
P 5.03268002 3.36615 8 P 0 0;4=12,6=1
L 4.95768002 3.34115 4.93268002 3.36615 9 P 0 
P 4.93268002 3.36615 8 P 0 0;4=12,6=1
L 5.00768002 3.34115 4.98268002 3.36615 9 P 0 
P 4.98268002 3.36615 8 P 0 0;4=12,6=1
L 4.85768002 3.19115 4.83268002 3.21615 9 P 0 
P 4.83268002 3.21615 8 P 0 0;4=12,6=1
L 4.90768002 3.19115 4.88268002 3.21615 9 P 0 
P 4.88268002 3.21615 8 P 0 0;4=12,6=1
L 5.00768002 3.19115 4.98268002 3.21615 9 P 0 
P 4.98268002 3.21615 8 P 0 0;4=12,6=1
L 4.95768002 3.19115 4.93268002 3.21615 9 P 0 
P 4.93268002 3.21615 8 P 0 0;4=12,6=1
L 5.05768002 3.19115 5.03268002 3.21615 9 P 0 
P 5.03268002 3.21615 8 P 0 0;4=12,6=1
L 4.85768002 3.04115 4.83268002 3.06615 9 P 0 
P 4.83268002 3.06615 8 P 0 0;4=12,6=1
L 4.90768002 3.04115 4.88268002 3.06615 9 P 0 
P 4.88268002 3.06615 8 P 0 0;4=12,6=1
L 5.00768002 3.04115 4.98268002 3.06615 9 P 0 
P 4.98268002 3.06615 8 P 0 0;4=12,6=1
L 4.95768002 3.04115 4.93268002 3.06615 9 P 0 
P 4.93268002 3.06615 8 P 0 0;4=12,6=1
L 5.05768002 3.04115 5.03268002 3.06615 9 P 0 
P 5.03268002 3.06615 8 P 0 0;4=12,6=1
L 4.85768002 2.89115 4.83268002 2.91615 9 P 0 
P 4.83268002 2.91615 8 P 0 0;4=12,6=1
L 4.90768002 2.89115 4.88268002 2.91615 9 P 0 
P 4.88268002 2.91615 8 P 0 0;4=12,6=1
L 5.00768002 2.89115 4.98268002 2.91615 9 P 0 
P 4.98268002 2.91615 8 P 0 0;4=12,6=1
L 4.95768002 2.89115 4.93268002 2.91615 9 P 0 
P 4.93268002 2.91615 8 P 0 0;4=12,6=1
L 5.05768002 2.89115 5.03268002 2.91615 9 P 0 
P 5.03268002 2.91615 8 P 0 0;4=12,6=1
L 4.80768002 2.54115 4.78268002 2.51615 9 P 0 
P 4.78268002 2.51615 8 P 0 0;4=12,6=1
L 4.75768002 2.54115 4.73268002 2.51615 9 P 0 
P 4.73268002 2.51615 8 P 0 0;4=12,6=1
L 4.70768002 2.54115 4.68268002 2.51615 9 P 0 
P 4.68268002 2.51615 8 P 0 0;4=12,6=1
L 4.65768002 2.54115 4.63268002 2.51615 9 P 0 
P 4.63268002 2.51615 8 P 0 0;4=12,6=1
L 4.60768002 2.54115 4.58268002 2.51615 9 P 0 
P 4.58268002 2.51615 8 P 0 0;4=12,6=1
L 4.65768002 2.59115 4.63268002 2.56615 9 P 0 
P 4.63268002 2.56615 8 P 0 0;4=12,6=1
L 4.75768002 2.59115 4.73268002 2.56615 9 P 0 
P 4.73268002 2.56615 8 P 0 0;4=12,6=1
L 4.80768002 2.59115 4.78268002 2.56615 9 P 0 
P 4.78268002 2.56615 8 P 0 0;4=12,6=1
L 4.80768002 2.64115 4.78268002 2.61615 9 P 0 
P 4.78268002 2.61615 8 P 0 0;4=12,6=1
L 4.80768002 2.69115 4.78268002 2.66615 9 P 0 
P 4.78268002 2.66615 8 P 0 0;4=12,6=1
L 4.70768002 2.69115 4.68268002 2.66615 9 P 0 
P 4.68268002 2.66615 8 P 0 0;4=12,6=1
L 4.60768002 2.69115 4.58268002 2.66615 9 P 0 
P 4.58268002 2.66615 8 P 0 0;4=12,6=1
L 4.75768002 2.74115 4.73268002 2.71615 9 P 0 
P 4.73268002 2.71615 8 P 0 0;4=12,6=1
L 4.65768002 2.74115 4.63268002 2.71615 9 P 0 
P 4.63268002 2.71615 8 P 0 0;4=12,6=1
L 4.65768002 2.79115 4.63268002 2.76615 9 P 0 
P 4.63268002 2.76615 8 P 0 0;4=12,6=1
L 4.75768002 2.79115 4.73268002 2.76615 9 P 0 
P 4.73268002 2.76615 8 P 0 0;4=12,6=1
L 4.80768002 2.79115 4.78268002 2.76615 9 P 0 
P 4.78268002 2.76615 8 P 0 0;4=12,6=1
L 4.65768002 2.19115 4.63268002 2.16615 9 P 0 
P 4.63268002 2.16615 8 P 0 0;4=12,6=1
L 4.75768002 2.19115 4.78268002 2.16615 9 P 0 
P 4.78268002 2.16615 8 P 0 0;4=12,6=1
L 10.66161004 2.89115 10.63661004 2.91615 9 P 0 
P 10.63661004 2.91615 8 P 0 0;4=12,6=1
L 10.61161004 2.89115 10.58661004 2.91615 9 P 0 
P 10.58661004 2.91615 8 P 0 0;4=12,6=1
L 10.66161004 3.04115 10.63661004 3.06615 9 P 0 
P 10.63661004 3.06615 8 P 0 0;4=12,6=1
L 10.61161004 3.04115 10.58661004 3.06615 9 P 0 
P 10.58661004 3.06615 8 P 0 0;4=12,6=1
L 10.66161004 3.34115 10.63661004 3.36615 9 P 0 
P 10.63661004 3.36615 8 P 0 0;4=12,6=1
L 10.61161004 3.34115 10.58661004 3.36615 9 P 0 
P 10.58661004 3.36615 8 P 0 0;4=12,6=1
L 10.66161004 3.19115 10.63661004 3.21615 9 P 0 
P 10.63661004 3.21615 8 P 0 0;4=12,6=1
L 10.61161004 3.19115 10.58661004 3.21615 9 P 0 
P 10.58661004 3.21615 8 P 0 0;4=12,6=1
L 10.61161004 3.64115 10.58661004 3.66615 9 P 0 
P 10.58661004 3.66615 8 P 0 0;4=12,6=1
L 10.66161004 3.49115 10.63661004 3.51615 9 P 0 
P 10.63661004 3.51615 8 P 0 0;4=12,6=1
L 10.61161004 3.49115 10.58661004 3.51615 9 P 0 
P 10.58661004 3.51615 8 P 0 0;4=12,6=1
L 10.66161004 3.79115 10.63661004 3.81615 9 P 0 
P 10.63661004 3.81615 8 P 0 0;4=12,6=1
L 10.66161004 3.64115 10.63661004 3.66615 9 P 0 
P 10.63661004 3.66615 8 P 0 0;4=12,6=1
L 10.61161004 3.79115 10.58661004 3.81615 9 P 0 
P 10.58661004 3.81615 8 P 0 0;4=12,6=1
L 10.86161004 2.89115 10.83661004 2.91615 9 P 0 
P 10.83661004 2.91615 8 P 0 0;4=12,6=1
L 10.81161004 2.89115 10.78661004 2.91615 9 P 0 
P 10.78661004 2.91615 8 P 0 0;4=12,6=1
L 10.76161004 2.89115 10.73661004 2.91615 9 P 0 
P 10.73661004 2.91615 8 P 0 0;4=12,6=1
L 10.71161004 2.89115 10.68661004 2.91615 9 P 0 
P 10.68661004 2.91615 8 P 0 0;4=12,6=1
L 10.91161004 2.89115 10.88661004 2.91615 9 P 0 
P 10.88661004 2.91615 8 P 0 0;4=12,6=1
L 10.91161004 3.04115 10.88661004 3.06615 9 P 0 
P 10.88661004 3.06615 8 P 0 0;4=12,6=1
L 10.86161004 3.04115 10.83661004 3.06615 9 P 0 
P 10.83661004 3.06615 8 P 0 0;4=12,6=1
L 10.81161004 3.04115 10.78661004 3.06615 9 P 0 
P 10.78661004 3.06615 8 P 0 0;4=12,6=1
L 10.76161004 3.04115 10.73661004 3.06615 9 P 0 
P 10.73661004 3.06615 8 P 0 0;4=12,6=1
L 10.71161004 3.04115 10.68661004 3.06615 9 P 0 
P 10.68661004 3.06615 8 P 0 0;4=12,6=1
L 10.91161004 3.19115 10.88661004 3.21615 9 P 0 
P 10.88661004 3.21615 8 P 0 0;4=12,6=1
L 10.86161004 3.19115 10.83661004 3.21615 9 P 0 
P 10.83661004 3.21615 8 P 0 0;4=12,6=1
L 10.86161004 3.34115 10.83661004 3.36615 9 P 0 
P 10.83661004 3.36615 8 P 0 0;4=12,6=1
L 10.91161004 3.34115 10.88661004 3.36615 9 P 0 
P 10.88661004 3.36615 8 P 0 0;4=12,6=1
L 10.81161004 3.34115 10.78661004 3.36615 9 P 0 
P 10.78661004 3.36615 8 P 0 0;4=12,6=1
L 10.76161004 3.34115 10.73661004 3.36615 9 P 0 
P 10.73661004 3.36615 8 P 0 0;4=12,6=1
L 10.81161004 3.19115 10.78661004 3.21615 9 P 0 
P 10.78661004 3.21615 8 P 0 0;4=12,6=1
L 10.76161004 3.19115 10.73661004 3.21615 9 P 0 
P 10.73661004 3.21615 8 P 0 0;4=12,6=1
L 10.71161004 3.34115 10.68661004 3.36615 9 P 0 
P 10.68661004 3.36615 8 P 0 0;4=12,6=1
L 10.71161004 3.19115 10.68661004 3.21615 9 P 0 
P 10.68661004 3.21615 8 P 0 0;4=12,6=1
L 10.86161004 3.49115 10.83661004 3.51615 9 P 0 
P 10.83661004 3.51615 8 P 0 0;4=12,6=1
L 10.91161004 3.49115 10.88661004 3.51615 9 P 0 
P 10.88661004 3.51615 8 P 0 0;4=12,6=1
L 10.86161004 3.64115 10.83661004 3.66615 9 P 0 
P 10.83661004 3.66615 8 P 0 0;4=12,6=1
L 10.81161004 3.64115 10.78661004 3.66615 9 P 0 
P 10.78661004 3.66615 8 P 0 0;4=12,6=1
L 10.76161004 3.64115 10.73661004 3.66615 9 P 0 
P 10.73661004 3.66615 8 P 0 0;4=12,6=1
L 10.71161004 3.64115 10.68661004 3.66615 9 P 0 
P 10.68661004 3.66615 8 P 0 0;4=12,6=1
L 10.81161004 3.49115 10.78661004 3.51615 9 P 0 
P 10.78661004 3.51615 8 P 0 0;4=12,6=1
L 10.76161004 3.49115 10.73661004 3.51615 9 P 0 
P 10.73661004 3.51615 8 P 0 0;4=12,6=1
L 10.71161004 3.49115 10.68661004 3.51615 9 P 0 
P 10.68661004 3.51615 8 P 0 0;4=12,6=1
L 10.86161004 3.79115 10.83661004 3.81615 9 P 0 
P 10.83661004 3.81615 8 P 0 0;4=12,6=1
L 10.91161004 3.79115 10.88661004 3.81615 9 P 0 
P 10.88661004 3.81615 8 P 0 0;4=12,6=1
L 10.91161004 3.64115 10.88661004 3.66615 9 P 0 
P 10.88661004 3.66615 8 P 0 0;4=12,6=1
L 10.81161004 3.79115 10.78661004 3.81615 9 P 0 
P 10.78661004 3.81615 8 P 0 0;4=12,6=1
L 10.76161004 3.79115 10.73661004 3.81615 9 P 0 
P 10.73661004 3.81615 8 P 0 0;4=12,6=1
L 10.71161004 3.79115 10.68661004 3.81615 9 P 0 
P 10.68661004 3.81615 8 P 0 0;4=12,6=1
L 11.06161004 2.89115 11.03661004 2.91615 9 P 0 
P 11.03661004 2.91615 8 P 0 0;4=12,6=1
L 10.96161004 2.89115 10.93661004 2.91615 9 P 0 
P 10.93661004 2.91615 8 P 0 0;4=12,6=1
L 11.01161004 2.89115 10.98661004 2.91615 9 P 0 
P 10.98661004 2.91615 8 P 0 0;4=12,6=1
L 11.06161004 3.04115 11.03661004 3.06615 9 P 0 
P 11.03661004 3.06615 8 P 0 0;4=12,6=1
L 10.96161004 3.04115 10.93661004 3.06615 9 P 0 
P 10.93661004 3.06615 8 P 0 0;4=12,6=1
L 11.01161004 3.04115 10.98661004 3.06615 9 P 0 
P 10.98661004 3.06615 8 P 0 0;4=12,6=1
L 11.06161004 3.19115 11.03661004 3.21615 9 P 0 
P 11.03661004 3.21615 8 P 0 0;4=12,6=1
L 10.96161004 3.19115 10.93661004 3.21615 9 P 0 
P 10.93661004 3.21615 8 P 0 0;4=12,6=1
L 11.01161004 3.19115 10.98661004 3.21615 9 P 0 
P 10.98661004 3.21615 8 P 0 0;4=12,6=1
L 11.01161004 3.34115 10.98661004 3.36615 9 P 0 
P 10.98661004 3.36615 8 P 0 0;4=12,6=1
L 10.96161004 3.34115 10.93661004 3.36615 9 P 0 
P 10.93661004 3.36615 8 P 0 0;4=12,6=1
L 11.06161004 3.34115 11.03661004 3.36615 9 P 0 
P 11.03661004 3.36615 8 P 0 0;4=12,6=1
L 11.01161004 3.49115 10.98661004 3.51615 9 P 0 
P 10.98661004 3.51615 8 P 0 0;4=12,6=1
L 10.96161004 3.49115 10.93661004 3.51615 9 P 0 
P 10.93661004 3.51615 8 P 0 0;4=12,6=1
L 11.06161004 3.49115 11.03661004 3.51615 9 P 0 
P 11.03661004 3.51615 8 P 0 0;4=12,6=1
L 11.01161004 3.64115 10.98661004 3.66615 9 P 0 
P 10.98661004 3.66615 8 P 0 0;4=12,6=1
L 10.96161004 3.64115 10.93661004 3.66615 9 P 0 
P 10.93661004 3.66615 8 P 0 0;4=12,6=1
L 11.06161004 3.64115 11.03661004 3.66615 9 P 0 
P 11.03661004 3.66615 8 P 0 0;4=12,6=1
L 11.01161004 3.79115 10.98661004 3.81615 9 P 0 
P 10.98661004 3.81615 8 P 0 0;4=12,6=1
L 10.96161004 3.79115 10.93661004 3.81615 9 P 0 
P 10.93661004 3.81615 8 P 0 0;4=12,6=1
P 3.07691004 4.81401998 9 P 0 0;4=13,6=1
P 8.1 1.86615 8 P 0 0;4=12,6=1
P 8.15 2.16615 8 P 0 0;4=12,6=1
P 8.15 2.11615 8 P 0 0;4=12,6=1
P 8.15 1.96615 8 P 0 0;4=12,6=1
P 8.1 2.01615 8 P 0 0;4=12,6=1
P 8.05 1.96615 8 P 0 0;4=12,6=1
P 8.05 2.11615 8 P 0 0;4=12,6=1
P 8.05 2.16615 8 P 0 0;4=12,6=1
P 8.15 2.31615 8 P 0 0;4=12,6=1
P 8.1 2.36615 8 P 0 0;4=12,6=1
P 8.1 2.16615 8 P 0 0;4=12,6=1
P 8.1 2.21615 8 P 0 0;4=12,6=1
P 8.05 2.31615 8 P 0 0;4=12,6=1
P 8.15 2.46615 8 P 0 0;4=12,6=1
P 8.15 2.56615 8 P 0 0;4=12,6=1
P 8.1 2.51615 8 P 0 0;4=12,6=1
P 8.05 2.46615 8 P 0 0;4=12,6=1
P 8.05 2.51615 8 P 0 0;4=12,6=1
P 8.05 2.56615 8 P 0 0;4=12,6=1
P 8.1 2.66615 8 P 0 0;4=12,6=1
P 8.05 2.76615 8 P 0 0;4=12,6=1
P 8.05 2.81615 8 P 0 0;4=12,6=1
P 8 2.86615 8 P 0 0;4=12,6=1
P 8 2.71615 8 P 0 0;4=12,6=1
P 8.05 2.71615 8 P 0 0;4=12,6=1
P 8.15 2.71615 8 P 0 0;4=12,6=1
P 8.05 2.86615 8 P 0 0;4=12,6=1
P 8.15 2.86615 8 P 0 0;4=12,6=1
P 8.1 2.91615 8 P 0 0;4=12,6=1
P 8.1 2.86615 8 P 0 0;4=12,6=1
P 8.1 2.81615 8 P 0 0;4=12,6=1
P 8.05 3.01615 8 P 0 0;4=12,6=1
P 8.1 3.06615 8 P 0 0;4=12,6=1
P 8.15 3.01615 8 P 0 0;4=12,6=1
P 8.15 3.16615 8 P 0 0;4=12,6=1
P 8.05 3.16615 8 P 0 0;4=12,6=1
L 8.025 3.39115 8 3.41615 9 P 0 
P 8 3.41615 8 P 0 0;4=12,6=1
L 8.025 3.39115 8.05 3.41615 9 P 0 
P 8.05 3.41615 8 P 0 0;4=12,6=1
L 8.075 3.34115 8.1 3.36615 9 P 0 
P 8.1 3.36615 8 P 0 0;4=12,6=1
P 8.1 3.21615 8 P 0 0;4=12,6=1
L 8.125 3.54115 8.15 3.56615 9 P 0 
P 8.15 3.56615 8 P 0 0;4=12,6=1
L 8.025 3.54115 8.05 3.56615 9 P 0 
P 8.05 3.56615 8 P 0 0;4=12,6=1
L 8.025 3.54115 8 3.56615 9 P 0 
P 8 3.56615 8 P 0 0;4=12,6=1
L 8.025 3.54115 8.05 3.51615 9 P 0 
P 8.05 3.51615 8 P 0 0;4=12,6=1
L 8.075 3.49115 8.05 3.46615 9 P 0 
P 8.05 3.46615 8 P 0 0;4=12,6=1
L 8.075 3.49115 8.1 3.51615 9 P 0 
P 8.1 3.51615 8 P 0 0;4=12,6=1
P 8.35 1.86615 8 P 0 0;4=12,6=1
P 8.3 1.86615 8 P 0 0;4=12,6=1
P 8.25 1.86615 8 P 0 0;4=12,6=1
P 8.2 1.86615 8 P 0 0;4=12,6=1
P 8.25 2.06615 8 P 0 0;4=12,6=1
P 8.25 2.16615 8 P 0 0;4=12,6=1
P 8.25 2.11615 8 P 0 0;4=12,6=1
P 8.3 2.11615 8 P 0 0;4=12,6=1
P 8.3 2.06615 8 P 0 0;4=12,6=1
P 8.4 2.11615 8 P 0 0;4=12,6=1
P 8.4 2.16615 8 P 0 0;4=12,6=1
P 8.4 1.96615 8 P 0 0;4=12,6=1
P 8.35 2.01615 8 P 0 0;4=12,6=1
P 8.3 2.01615 8 P 0 0;4=12,6=1
P 8.25 2.01615 8 P 0 0;4=12,6=1
P 8.2 2.01615 8 P 0 0;4=12,6=1
P 8.3 1.96615 8 P 0 0;4=12,6=1
P 8.25 1.96615 8 P 0 0;4=12,6=1
P 8.3 1.91615 8 P 0 0;4=12,6=1
P 8.25 1.91615 8 P 0 0;4=12,6=1
P 8.2 2.16615 8 P 0 0;4=12,6=1
P 8.2 2.21615 8 P 0 0;4=12,6=1
P 8.25 2.26615 8 P 0 0;4=12,6=1
P 8.3 2.26615 8 P 0 0;4=12,6=1
P 8.25 2.21615 8 P 0 0;4=12,6=1
P 8.3 2.16615 8 P 0 0;4=12,6=1
P 8.3 2.21615 8 P 0 0;4=12,6=1
P 8.35 2.21615 8 P 0 0;4=12,6=1
P 8.35 2.16615 8 P 0 0;4=12,6=1
P 8.25 2.31615 8 P 0 0;4=12,6=1
P 8.3 2.31615 8 P 0 0;4=12,6=1
P 8.35 2.36615 8 P 0 0;4=12,6=1
P 8.4 2.31615 8 P 0 0;4=12,6=1
P 8.3 2.36615 8 P 0 0;4=12,6=1
P 8.2 2.36615 8 P 0 0;4=12,6=1
P 8.25 2.36615 8 P 0 0;4=12,6=1
P 8.25 2.41615 8 P 0 0;4=12,6=1
P 8.3 2.41615 8 P 0 0;4=12,6=1
P 8.4 2.56615 8 P 0 0;4=12,6=1
P 8.4 2.51615 8 P 0 0;4=12,6=1
P 8.4 2.46615 8 P 0 0;4=12,6=1
P 8.3 2.46615 8 P 0 0;4=12,6=1
P 8.25 2.46615 8 P 0 0;4=12,6=1
P 8.2 2.51615 8 P 0 0;4=12,6=1
P 8.25 2.51615 8 P 0 0;4=12,6=1
P 8.3 2.51615 8 P 0 0;4=12,6=1
P 8.35 2.51615 8 P 0 0;4=12,6=1
P 8.3 2.56615 8 P 0 0;4=12,6=1
P 8.3 2.61615 8 P 0 0;4=12,6=1
P 8.25 2.56615 8 P 0 0;4=12,6=1
P 8.25 2.61615 8 P 0 0;4=12,6=1
P 8.2 2.66615 8 P 0 0;4=12,6=1
P 8.25 2.66615 8 P 0 0;4=12,6=1
P 8.3 2.66615 8 P 0 0;4=12,6=1
P 8.35 2.66615 8 P 0 0;4=12,6=1
P 8.25 2.71615 8 P 0 0;4=12,6=1
P 8.3 2.71615 8 P 0 0;4=12,6=1
P 8.4 2.71615 8 P 0 0;4=12,6=1
P 8.35 2.81615 8 P 0 0;4=12,6=1
P 8.4 2.86615 8 P 0 0;4=12,6=1
P 8.3 2.91615 8 P 0 0;4=12,6=1
P 8.25 2.91615 8 P 0 0;4=12,6=1
P 8.2 2.91615 8 P 0 0;4=12,6=1
P 8.2 2.81615 8 P 0 0;4=12,6=1
P 8.25 2.81615 8 P 0 0;4=12,6=1
P 8.25 2.76615 8 P 0 0;4=12,6=1
P 8.3 2.81615 8 P 0 0;4=12,6=1
P 8.3 2.76615 8 P 0 0;4=12,6=1
P 8.35 2.91615 8 P 0 0;4=12,6=1
P 8.35 2.86615 8 P 0 0;4=12,6=1
P 8.35 3.06615 8 P 0 0;4=12,6=1
P 8.4 3.01615 8 P 0 0;4=12,6=1
P 8.2 3.06615 8 P 0 0;4=12,6=1
P 8.25 3.01615 8 P 0 0;4=12,6=1
P 8.25 2.96615 8 P 0 0;4=12,6=1
P 8.25 3.11615 8 P 0 0;4=12,6=1
P 8.25 3.06615 8 P 0 0;4=12,6=1
P 8.3 3.01615 8 P 0 0;4=12,6=1
P 8.3 2.96615 8 P 0 0;4=12,6=1
P 8.3 3.11615 8 P 0 0;4=12,6=1
P 8.3 3.06615 8 P 0 0;4=12,6=1
P 8.25 3.16615 8 P 0 0;4=12,6=1
P 8.3 3.16615 8 P 0 0;4=12,6=1
P 8.4 3.16615 8 P 0 0;4=12,6=1
L 8.225 3.39115 8.25 3.41615 9 P 0 
P 8.25 3.41615 8 P 0 0;4=12,6=1
L 8.275 3.34115 8.3 3.36615 9 P 0 
P 8.3 3.36615 8 P 0 0;4=12,6=1
L 8.225 3.34115 8.25 3.36615 9 P 0 
P 8.25 3.36615 8 P 0 0;4=12,6=1
L 8.175 3.34115 8.2 3.36615 9 P 0 
P 8.2 3.36615 8 P 0 0;4=12,6=1
L 8.225 3.29115 8.25 3.31615 9 P 0 
P 8.25 3.31615 8 P 0 0;4=12,6=1
L 8.225 3.24115 8.25 3.26615 9 P 0 
P 8.25 3.26615 8 P 0 0;4=12,6=1
P 8.3 3.21615 8 P 0 0;4=12,6=1
P 8.25 3.21615 8 P 0 0;4=12,6=1
P 8.2 3.21615 8 P 0 0;4=12,6=1
P 8.35 3.21615 8 P 0 0;4=12,6=1
L 8.375 3.54115 8.4 3.56615 9 P 0 
P 8.4 3.56615 8 P 0 0;4=12,6=1
L 8.275 3.59115 8.3 3.61615 9 P 0 
P 8.3 3.61615 8 P 0 0;4=12,6=1
L 8.225 3.64115 8.25 3.66615 9 P 0 
P 8.25 3.66615 8 P 0 0;4=12,6=1
L 8.225 3.59115 8.25 3.61615 9 P 0 
P 8.25 3.61615 8 P 0 0;4=12,6=1
L 8.175 3.59115 8.2 3.61615 9 P 0 
P 8.2 3.61615 8 P 0 0;4=12,6=1
L 8.175 3.54115 8.2 3.56615 9 P 0 
P 8.2 3.56615 8 P 0 0;4=12,6=1
L 8.175 3.49115 8.2 3.51615 9 P 0 
P 8.2 3.51615 8 P 0 0;4=12,6=1
L 8.225 3.49115 8.25 3.51615 9 P 0 
P 8.25 3.51615 8 P 0 0;4=12,6=1
L 8.275 3.49115 8.3 3.51615 9 P 0 
P 8.3 3.51615 8 P 0 0;4=12,6=1
L 8.225 3.44115 8.25 3.46615 9 P 0 
P 8.25 3.46615 8 P 0 0;4=12,6=1
L 8.225 3.84115 8.25 3.86615 9 P 0 
P 8.25 3.86615 8 P 0 0;4=12,6=1
L 8.225 3.79115 8.25 3.81615 9 P 0 
P 8.25 3.81615 8 P 0 0;4=12,6=1
L 8.175 3.74115 8.2 3.76615 9 P 0 
P 8.2 3.76615 8 P 0 0;4=12,6=1
L 8.225 3.74115 8.25 3.76615 9 P 0 
P 8.25 3.76615 8 P 0 0;4=12,6=1
L 8.275 3.74115 8.3 3.76615 9 P 0 
P 8.3 3.76615 8 P 0 0;4=12,6=1
L 8.225 3.69115 8.25 3.71615 9 P 0 
P 8.25 3.71615 8 P 0 0;4=12,6=1
P 8.45 1.86615 8 P 0 0;4=12,6=1
P 8.5 2.16615 8 P 0 0;4=12,6=1
P 8.5 2.11615 8 P 0 0;4=12,6=1
P 8.5 1.96615 8 P 0 0;4=12,6=1
P 8.45 2.01615 8 P 0 0;4=12,6=1
P 8.45 2.21615 8 P 0 0;4=12,6=1
P 8.45 2.16615 8 P 0 0;4=12,6=1
P 8.5 2.31615 8 P 0 0;4=12,6=1
P 8.45 2.36615 8 P 0 0;4=12,6=1
P 8.5 2.46615 8 P 0 0;4=12,6=1
P 8.5 2.51615 8 P 0 0;4=12,6=1
P 8.5 2.56615 8 P 0 0;4=12,6=1
P 8.45 2.51615 8 P 0 0;4=12,6=1
P 8.45 2.66615 8 P 0 0;4=12,6=1
P 8.5 2.71615 8 P 0 0;4=12,6=1
P 8.5 2.86615 8 P 0 0;4=12,6=1
P 8.45 2.81615 8 P 0 0;4=12,6=1
P 8.45 2.86615 8 P 0 0;4=12,6=1
P 8.45 2.91615 8 P 0 0;4=12,6=1
P 8.5 3.01615 8 P 0 0;4=12,6=1
P 8.45 3.06615 8 P 0 0;4=12,6=1
P 8.5 3.16615 8 P 0 0;4=12,6=1
L 8.475 3.39115 8.5 3.41615 9 P 0 
P 8.5 3.41615 8 P 0 0;4=12,6=1
L 8.425 3.34115 8.45 3.36615 9 P 0 
P 8.45 3.36615 8 P 0 0;4=12,6=1
P 8.45 3.21615 8 P 0 0;4=12,6=1
P 8.5 3.21615 8 P 0 0;4=12,6=1
L 8.475 3.24115 8.5 3.26615 9 P 0 
P 8.5 3.26615 8 P 0 0;4=12,6=1
L 8.475 3.54115 8.5 3.56615 9 P 0 
P 8.5 3.56615 8 P 0 0;4=12,6=1
L 8.425 3.54115 8.45 3.56615 9 P 0 
P 8.45 3.56615 8 P 0 0;4=12,6=1
L 8.475 3.84115 8.5 3.86615 9 P 0 
P 8.5 3.86615 8 P 0 0;4=12,6=1
L 8.475 3.69115 8.5 3.71615 9 P 0 
P 8.5 3.71615 8 P 0 0;4=12,6=1
P 8.2 2.86615 8 P 0 0;4=12,6=1
P 8.025 3.24115 10 P 0 0;2,4=11,6=0
L 8.025 3.24115 8.05 3.26615 9 P 0 
P 8.05 3.26615 8 P 0 0;4=12,6=1
P 8.05 3.21615 8 P 0 0;4=12,6=1
P 8.275 3.24115 10 P 0 0;2,4=11,6=0
L 8.275 3.24115 8.3 3.26615 9 P 0 
P 8.3 3.26615 8 P 0 0;4=12,6=1
P 8.275 3.29115 10 P 0 0;2,4=11,6=0
L 8.275 3.29115 8.3 3.31615 9 P 0 
P 8.3 3.31615 8 P 0 0;4=12,6=1
P 8.325 3.34115 10 P 0 0;2,4=11,6=0
L 8.325 3.34115 8.35 3.36615 9 P 0 
P 8.35 3.36615 8 P 0 0;4=12,6=1
P 8.125 3.24115 10 P 0 0;2,4=11,6=0
L 8.125 3.24115 8.15 3.26615 9 P 0 
P 8.15 3.26615 8 P 0 0;4=12,6=1
P 8.15 3.21615 8 P 0 0;4=12,6=1
P 8.4 3.21615 8 P 0 0;4=12,6=1
P 8.375 3.24115 10 P 0 0;2,4=11,6=0
L 8.375 3.24115 8.4 3.26615 9 P 0 
P 8.4 3.26615 8 P 0 0;4=12,6=1
P 8.075 3.59115 10 P 0 0;2,4=11,6=0
L 8.075 3.59115 8.1 3.61615 9 P 0 
P 8.1 3.61615 8 P 0 0;4=12,6=1
P 8.275 3.44115 10 P 0 0;2,4=11,6=0
L 8.275 3.44115 8.3 3.46615 9 P 0 
P 8.3 3.46615 8 P 0 0;4=12,6=1
P 8.275 3.39115 10 P 0 0;2,4=11,6=0
L 8.275 3.39115 8.3 3.41615 9 P 0 
P 8.3 3.41615 8 P 0 0;4=12,6=1
P 8.325 3.49115 10 P 0 0;2,4=11,6=0
L 8.325 3.49115 8.35 3.51615 9 P 0 
P 8.35 3.51615 8 P 0 0;4=12,6=1
P 8.325 3.59115 10 P 0 0;2,4=11,6=0
L 8.325 3.59115 8.35 3.61615 9 P 0 
P 8.35 3.61615 8 P 0 0;4=12,6=1
P 8.325 3.54115 10 P 0 0;2,4=11,6=0
L 8.325 3.54115 8.35 3.56615 9 P 0 
P 8.35 3.56615 8 P 0 0;4=12,6=1
P 8.125 3.39115 10 P 0 0;2,4=11,6=0
L 8.125 3.39115 8.15 3.41615 9 P 0 
P 8.15 3.41615 8 P 0 0;4=12,6=1
P 8.425 3.49115 10 P 0 0;2,4=11,6=0
L 8.425 3.49115 8.45 3.51615 9 P 0 
P 8.45 3.51615 8 P 0 0;4=12,6=1
P 8.425 3.59115 10 P 0 0;2,4=11,6=0
L 8.425 3.59115 8.45 3.61615 9 P 0 
P 8.45 3.61615 8 P 0 0;4=12,6=1
P 8.375 3.39115 10 P 0 0;2,4=11,6=0
L 8.375 3.39115 8.4 3.41615 9 P 0 
P 8.4 3.41615 8 P 0 0;4=12,6=1
P 8.025 3.69115 10 P 0 0;2,4=11,6=0
L 8.025 3.69115 8.05 3.71615 9 P 0 
P 8.05 3.71615 8 P 0 0;4=12,6=1
P 8.075 3.74115 10 P 0 0;2,4=11,6=0
L 8.075 3.74115 8.1 3.76615 9 P 0 
P 8.1 3.76615 8 P 0 0;4=12,6=1
P 8.025 3.84115 10 P 0 0;2,4=11,6=0
L 8.025 3.84115 8.05 3.86615 9 P 0 
P 8.05 3.86615 8 P 0 0;4=12,6=1
P 8.275 3.69115 10 P 0 0;2,4=11,6=0
L 8.275 3.69115 8.3 3.71615 9 P 0 
P 8.3 3.71615 8 P 0 0;4=12,6=1
P 8.275 3.64115 10 P 0 0;2,4=11,6=0
L 8.275 3.64115 8.3 3.66615 9 P 0 
P 8.3 3.66615 8 P 0 0;4=12,6=1
P 8.325 3.74115 10 P 0 0;2,4=11,6=0
L 8.325 3.74115 8.35 3.76615 9 P 0 
P 8.35 3.76615 8 P 0 0;4=12,6=1
P 8.275 3.79115 10 P 0 0;2,4=11,6=0
L 8.275 3.79115 8.3 3.81615 9 P 0 
P 8.3 3.81615 8 P 0 0;4=12,6=1
P 8.275 3.84115 10 P 0 0;2,4=11,6=0
L 8.275 3.84115 8.3 3.86615 9 P 0 
P 8.3 3.86615 8 P 0 0;4=12,6=1
P 8.125 3.69115 10 P 0 0;2,4=11,6=0
L 8.125 3.69115 8.15 3.71615 9 P 0 
P 8.15 3.71615 8 P 0 0;4=12,6=1
P 8.125 3.84115 10 P 0 0;2,4=11,6=0
L 8.125 3.84115 8.15 3.86615 9 P 0 
P 8.15 3.86615 8 P 0 0;4=12,6=1
P 8.425 3.74115 10 P 0 0;2,4=11,6=0
L 8.425 3.74115 8.45 3.76615 9 P 0 
P 8.45 3.76615 8 P 0 0;4=12,6=1
P 8.375 3.69115 10 P 0 0;2,4=11,6=0
L 8.375 3.69115 8.4 3.71615 9 P 0 
P 8.4 3.71615 8 P 0 0;4=12,6=1
P 8.375 3.84115 10 P 0 0;2,4=11,6=0
L 8.375 3.84115 8.4 3.86615 9 P 0 
P 8.4 3.86615 8 P 0 0;4=12,6=1
S P 0
OB 3.517530019685 5.17873996063 I
OC 3.517530019685 5.17873996063 3.511769980315 5.17873996063 Y
OE
SE
S P 0
OB 3.577530019685 5.17873996063 I
OC 3.577530019685 5.17873996063 3.571769980315 5.17873996063 Y
OE
SE
S P 0
OB 3.081469980315 5.20373996063 I
OC 3.081469980315 5.20373996063 3.07571003937 5.20373996063 Y
OE
SE
S P 0
OB 3.021469980315 5.20373996063 I
OC 3.021469980315 5.20373996063 3.01571003937 5.20373996063 Y
OE
SE
P 3.28831004 4.68073996 9 P 0 0;4=13,6=1
P 3.22831004 4.68073996 9 P 0 0;4=13,6=1
P 3.50091004 4.62573996 9 P 0 0;4=13,6=1
P 3.44091004 4.62573996 9 P 0 0;4=13,6=1
S P 0
OB 3.506669980315 4.62573996063 I
OC 3.506669980315 4.62573996063 3.50091003937 4.62573996063 Y
OE
SE
S P 0
OB 3.446669980315 4.62573996063 I
OC 3.446669980315 4.62573996063 3.44091003937 4.62573996063 Y
OE
SE
L 7.56575 4.97913996 7.56575 5.023 6 P 0 
P 7.56575 5.023 9 P 0 0;4=13,6=1
L 7.63661998 5.023 7.63661998 4.97913996 6 P 0 
P 7.63661998 5.023 9 P 0 0;4=13,6=1
L 7.84921998 5.023 7.84921998 4.97913996 6 P 0 
P 7.84921998 5.023 9 P 0 0;4=13,6=1
L 7.77835 5.023 7.77835 4.97913996 6 P 0 
P 7.77835 5.023 9 P 0 0;4=13,6=1
L 7.70748996 5.023 7.70748996 4.97913996 6 P 0 
P 7.70748996 5.023 9 P 0 0;4=13,6=1
L 7.92008002 5.023 7.92008002 4.97913996 6 P 0 
P 7.92008002 5.023 9 P 0 0;4=13,6=1
L 8.06181998 5.023 8.06181998 4.97913996 6 P 0 
P 8.06181998 5.023 9 P 0 0;4=13,6=1
L 8.13268002 5.023 8.13268002 4.97913996 6 P 0 
P 8.13268002 5.023 9 P 0 0;4=13,6=1
L 7.99095 5.023 7.99095 4.97913996 6 P 0 
P 7.99095 5.023 9 P 0 0;4=13,6=1
L 8.34528002 5.023 8.34528002 4.97913996 6 P 0 
P 8.34528002 5.023 9 P 0 0;4=13,6=1
L 8.27441004 5.023 8.27441004 4.97913996 6 P 0 
P 8.27441004 5.023 9 P 0 0;4=13,6=1
L 8.20355 5.023 8.20355 4.97913996 6 P 0 
P 8.20355 5.023 9 P 0 0;4=13,6=1
L 8.41615 4.97913996 8.41615 5.023 6 P 0 
P 8.41615 5.023 9 P 0 0;4=13,6=1
L 7.63661998 4.92 7.63661998 4.85788002 6 P 0 
P 7.63661998 4.92 9 P 0 0;4=13,6=1
P 7.84921998 4.9207 9 P 0 0;4=13,6=1
P 7.70748996 4.9207 9 P 0 0;4=13,6=1
P 7.77835 4.9207 9 P 0 0;4=13,6=1
P 7.99095 4.9207 9 P 0 0;4=13,6=1
P 7.92008002 4.9207 9 P 0 0;4=13,6=1
P 8.06181998 4.9207 9 P 0 0;4=13,6=1
P 8.13268002 4.9207 9 P 0 0;4=13,6=1
P 8.27441004 4.9207 9 P 0 0;4=13,6=1
P 8.20355 4.9267 9 P 0 0;4=13,6=1
P 8.34528002 4.9207 9 P 0 0;4=13,6=1
P 7.63526998 4.81526998 9 P 0 0;4=13,6=1
L 7.84921998 4.81 7.84921998 4.85788002 6 P 0 
P 7.84921998 4.81 9 P 0 0;4=13,6=1
L 7.77953996 4.812 7.77835 4.81318996 6 P 0 
L 7.77835 4.81318996 7.77835 4.85788002 6 P 0 
P 7.77953996 4.812 9 P 0 0;4=13,6=1
L 7.70353996 4.812 7.70748996 4.81595 6 P 0 
L 7.70748996 4.81595 7.70748996 4.85788002 6 P 0 
P 7.70353996 4.812 9 P 0 0;4=13,6=1
L 8.13268002 4.81 8.13268002 4.85788002 6 P 0 
P 8.13268002 4.81 9 P 0 0;4=13,6=1
L 8.06441004 4.81 8.06181998 4.81258996 6 P 0 
L 8.06181998 4.81258996 8.06181998 4.85788002 6 P 0 
P 8.06441004 4.81 9 P 0 0;4=13,6=1
L 7.99353996 4.81 7.99095 4.81258996 6 P 0 
L 7.99095 4.81258996 7.99095 4.85788002 6 P 0 
P 7.99353996 4.81 9 P 0 0;4=13,6=1
P 7.92353996 4.81 9 P 0 0;4=13,6=1
L 8.27441004 4.81 8.27441004 4.85788002 6 P 0 
P 8.27441004 4.81 9 P 0 0;4=13,6=1
L 8.34528002 4.81 8.34528002 4.85788002 6 P 0 
P 8.34528002 4.81 9 P 0 0;4=13,6=1
L 8.20355 4.81 8.20355 4.85788002 6 P 0 
P 8.20355 4.81 9 P 0 0;4=13,6=1
L 8.41615 4.85788002 8.41615 4.81401998 6 P 0 
P 8.41615 4.81401998 9 P 0 0;4=13,6=1
L 8.86908996 4.81401998 8.87208996 4.81701998 6 P 0 
L 8.87208996 4.81701998 8.87208996 4.85788002 6 P 0 
P 8.86908996 4.81401998 9 P 0 0;4=13,6=1
L 8.73035 4.85788002 8.73035 4.81401998 6 P 0 
P 8.73035 4.81401998 9 P 0 0;4=13,6=1
L 8.80121998 4.81401998 8.80121998 4.85788002 6 P 0 
P 8.80121998 4.81401998 9 P 0 0;4=13,6=1
L 8.94495 4.81401998 8.94295 4.81601998 6 P 0 
L 8.94295 4.81601998 8.94295 4.85788002 6 P 0 
P 8.94495 4.81401998 9 P 0 0;4=13,6=1
P 9.08045 4.81401998 9 P 0 0;4=13,6=1
L 9.01381998 4.81401998 9.01381998 4.85788002 6 P 0 
P 9.01381998 4.81401998 9 P 0 0;4=13,6=1
L 9.36815 4.81401998 9.36815 4.85788002 6 P 0 
P 9.36815 4.81401998 9 P 0 0;4=13,6=1
L 9.29728002 4.81401998 9.29728002 4.85788002 6 P 0 
P 9.29728002 4.81401998 9 P 0 0;4=13,6=1
L 9.22641998 4.81401998 9.22641998 4.85788002 6 P 0 
P 9.22641998 4.81401998 9 P 0 0;4=13,6=1
P 9.15751998 4.81401998 9 P 0 0;4=13,6=1
L 9.43901004 4.81401998 9.43901004 4.85788002 6 P 0 
P 9.43901004 4.81401998 9 P 0 0;4=13,6=1
L 9.50988002 4.81401998 9.50988002 4.85788002 6 P 0 
P 9.50988002 4.81401998 9 P 0 0;4=13,6=1
L 9.58075 4.85788002 9.58075 4.81401998 6 P 0 
P 9.58075 4.81401998 9 P 0 0;4=13,6=1
L 8.80121998 5.023 8.80121998 4.97913996 6 P 0 
P 8.80121998 5.023 9 P 0 0;4=13,6=1
L 8.73035 4.97913996 8.73035 5.023 6 P 0 
P 8.73035 5.023 9 P 0 0;4=13,6=1
L 8.87208996 5.023 8.87208996 4.97913996 6 P 0 
P 8.87208996 5.023 9 P 0 0;4=13,6=1
L 9.08468002 5.023 9.08468002 4.97913996 6 P 0 
P 9.08468002 5.023 9 P 0 0;4=13,6=1
P 9.01381998 5.023 9 P 0 0;4=13,6=1
P 8.94295 5.023 9 P 0 0;4=13,6=1
P 8.87208996 4.92 9 P 0 0;4=13,6=1
P 8.80121998 4.92 9 P 0 0;4=13,6=1
P 9.01381998 4.92 9 P 0 0;4=13,6=1
P 9.08468002 4.92 9 P 0 0;4=13,6=1
P 9.22641998 4.92 9 P 0 0;4=13,6=1
P 9.36815 4.926 9 P 0 0;4=13,6=1
P 9.50988002 4.92 9 P 0 0;4=13,6=1
P 9.43901004 4.928 9 P 0 0;4=13,6=1
L 9.36815 5.023 9.36815 4.97913996 6 P 0 
P 9.36815 5.023 9 P 0 0;4=13,6=1
L 9.29728002 5.023 9.29728002 4.97913996 6 P 0 
P 9.29728002 5.023 9 P 0 0;4=13,6=1
L 9.22641998 5.023 9.22641998 4.97913996 6 P 0 
P 9.22641998 5.023 9 P 0 0;4=13,6=1
L 9.15555 5.023 9.15555 4.97913996 6 P 0 
P 9.15555 5.023 9 P 0 0;4=13,6=1
L 9.50988002 5.023 9.50988002 4.97913996 6 P 0 
P 9.50988002 5.023 9 P 0 0;4=13,6=1
P 9.43901004 5.023 9 P 0 0;4=13,6=1
L 9.58075 4.97913996 9.58075 5.023 6 P 0 
P 9.58075 5.023 9 P 0 0;4=13,6=1
P 8.94853996 4.92 9 P 0 0;4=13,6=1
P 9.27853996 4.92 9 P 0 0;4=13,6=1
P 9.14353996 4.92 9 P 0 0;4=13,6=1
P 8.13811004 5.09223996 9 P 0 0;4=13,6=1
S P 0
OB 8.143869980315 5.09223996063 I
OC 8.143869980315 5.09223996063 8.13811003937 5.09223996063 Y
OE
SE
P 8.35071004 5.15373996 9 P 0 0;4=13,6=1
S P 0
OB 8.356469980315 5.15373996063 I
OC 8.356469980315 5.15373996063 8.35071003937 5.15373996063 Y
OE
SE
P 8.41071004 5.15373996 9 P 0 0;4=13,6=1
S P 0
OB 8.416469980315 5.15373996063 I
OC 8.416469980315 5.15373996063 8.41071003937 5.15373996063 Y
OE
SE
L 7.56575 4.85788002 7.56575 4.81401998 6 P 0 
P 7.56575 4.81401998 9 P 0 0;4=13,6=1
P 8.88061998 4.70573996 9 P 0 0;4=13,6=1
S P 0
OB 8.886380019685 4.70573996063 I
OC 8.886380019685 4.70573996063 8.880619980315 4.70573996063 Y
OE
SE
P 2.37106004 2.59115 10 P 0 0;2,4=11,6=0
P 2.37106004 2.64115 10 P 0 0;2,4=11,6=0
P 2.42106004 2.54115 10 P 0 0;2,4=11,6=0
P 2.42106004 2.59115 10 P 0 0;2,4=11,6=0
P 2.47106004 2.59115 10 P 0 0;2,4=11,6=0
P 2.47106004 2.64115 10 P 0 0;2,4=11,6=0
P 2.32106004 2.69115 10 P 0 0;2,4=11,6=0
P 2.32106004 2.74115 10 P 0 0;2,4=11,6=0
P 2.42106004 2.69115 10 P 0 0;2,4=11,6=0
P 2.42106004 2.74115 10 P 0 0;2,4=11,6=0
P 2.47106004 2.74115 10 P 0 0;2,4=11,6=0
P 2.47106004 2.79115 10 P 0 0;2,4=11,6=0
P 2.37106004 2.74115 10 P 0 0;2,4=11,6=0
P 2.37106004 2.79115 10 P 0 0;2,4=11,6=0
P 2.32106004 2.94115 10 P 0 0;2,4=11,6=0
P 2.32106004 2.99115 10 P 0 0;2,4=11,6=0
P 2.37106004 2.89115 10 P 0 0;2,4=11,6=0
P 2.37106004 2.94115 10 P 0 0;2,4=11,6=0
P 2.47106004 2.89115 10 P 0 0;2,4=11,6=0
P 2.47106004 2.94115 10 P 0 0;2,4=11,6=0
P 2.42106004 2.94115 10 P 0 0;2,4=11,6=0
P 2.42106004 2.99115 10 P 0 0;2,4=11,6=0
P 2.37106004 3.04115 10 P 0 0;2,4=11,6=0
P 2.37106004 3.09115 10 P 0 0;2,4=11,6=0
P 2.47106004 3.04115 10 P 0 0;2,4=11,6=0
P 2.47106004 3.09115 10 P 0 0;2,4=11,6=0
P 2.42106004 3.09115 10 P 0 0;2,4=11,6=0
P 2.42106004 3.14115 10 P 0 0;2,4=11,6=0
P 2.32106004 3.09115 10 P 0 0;2,4=11,6=0
P 2.32106004 3.14115 10 P 0 0;2,4=11,6=0
P 2.32106004 1.94115 10 P 0 0;2,4=11,6=0
P 2.32106004 1.99115 10 P 0 0;2,4=11,6=0
P 2.37106004 1.89115 10 P 0 0;2,4=11,6=0
P 2.37106004 1.94115 10 P 0 0;2,4=11,6=0
P 2.47106004 1.89115 10 P 0 0;2,4=11,6=0
P 2.47106004 1.94115 10 P 0 0;2,4=11,6=0
P 2.42106004 1.94115 10 P 0 0;2,4=11,6=0
P 2.42106004 1.99115 10 P 0 0;2,4=11,6=0
P 2.37106004 2.04115 10 P 0 0;2,4=11,6=0
P 2.37106004 2.09115 10 P 0 0;2,4=11,6=0
P 2.47106004 2.04115 10 P 0 0;2,4=11,6=0
P 2.47106004 2.09115 10 P 0 0;2,4=11,6=0
P 2.42106004 2.09115 10 P 0 0;2,4=11,6=0
P 2.42106004 2.14115 10 P 0 0;2,4=11,6=0
P 2.32106004 2.09115 10 P 0 0;2,4=11,6=0
P 2.32106004 2.14115 10 P 0 0;2,4=11,6=0
P 2.32106004 2.24115 10 P 0 0;2,4=11,6=0
P 2.32106004 2.29115 10 P 0 0;2,4=11,6=0
P 2.37106004 2.19115 10 P 0 0;2,4=11,6=0
P 2.37106004 2.24115 10 P 0 0;2,4=11,6=0
P 2.47106004 2.19115 10 P 0 0;2,4=11,6=0
P 2.47106004 2.24115 10 P 0 0;2,4=11,6=0
P 2.42106004 2.24115 10 P 0 0;2,4=11,6=0
P 2.42106004 2.29115 10 P 0 0;2,4=11,6=0
P 2.37106004 2.34115 10 P 0 0;2,4=11,6=0
P 2.37106004 2.39115 10 P 0 0;2,4=11,6=0
P 2.47106004 2.34115 10 P 0 0;2,4=11,6=0
P 2.47106004 2.39115 10 P 0 0;2,4=11,6=0
P 2.42106004 2.39115 10 P 0 0;2,4=11,6=0
P 2.42106004 2.44115 10 P 0 0;2,4=11,6=0
P 2.32106004 2.39115 10 P 0 0;2,4=11,6=0
P 2.32106004 2.44115 10 P 0 0;2,4=11,6=0
P 2.32106004 2.59115 10 P 0 0;2,4=11,6=0
P 2.32106004 2.54115 10 P 0 0;2,4=11,6=0
P 2.07106004 2.54115 10 P 0 0;2,4=11,6=0
P 2.07106004 2.59115 10 P 0 0;2,4=11,6=0
P 2.17106004 2.54115 10 P 0 0;2,4=11,6=0
P 2.17106004 2.59115 10 P 0 0;2,4=11,6=0
P 2.12106004 2.59115 10 P 0 0;2,4=11,6=0
P 2.12106004 2.64115 10 P 0 0;2,4=11,6=0
P 2.07106004 2.69115 10 P 0 0;2,4=11,6=0
P 2.07106004 2.74115 10 P 0 0;2,4=11,6=0
P 2.17106004 2.69115 10 P 0 0;2,4=11,6=0
P 2.17106004 2.74115 10 P 0 0;2,4=11,6=0
P 2.12106004 2.74115 10 P 0 0;2,4=11,6=0
P 2.12106004 2.79115 10 P 0 0;2,4=11,6=0
P 2.02106004 2.74115 10 P 0 0;2,4=11,6=0
P 2.02106004 2.79115 10 P 0 0;2,4=11,6=0
P 2.02106004 2.89115 10 P 0 0;2,4=11,6=0
P 2.02106004 2.94115 10 P 0 0;2,4=11,6=0
P 2.07106004 2.94115 10 P 0 0;2,4=11,6=0
P 2.07106004 2.99115 10 P 0 0;2,4=11,6=0
P 2.12106004 2.89115 10 P 0 0;2,4=11,6=0
P 2.12106004 2.94115 10 P 0 0;2,4=11,6=0
P 2.17106004 2.94115 10 P 0 0;2,4=11,6=0
P 2.17106004 2.99115 10 P 0 0;2,4=11,6=0
P 2.02106004 3.04115 10 P 0 0;2,4=11,6=0
P 2.02106004 3.09115 10 P 0 0;2,4=11,6=0
P 2.12106004 3.04115 10 P 0 0;2,4=11,6=0
P 2.12106004 3.09115 10 P 0 0;2,4=11,6=0
P 2.17106004 3.09115 10 P 0 0;2,4=11,6=0
P 2.17106004 3.14115 10 P 0 0;2,4=11,6=0
P 2.07106004 3.09115 10 P 0 0;2,4=11,6=0
P 2.07106004 3.14115 10 P 0 0;2,4=11,6=0
P 2.02106004 1.89115 10 P 0 0;2,4=11,6=0
P 2.02106004 1.94115 10 P 0 0;2,4=11,6=0
P 2.07106004 1.94115 10 P 0 0;2,4=11,6=0
P 2.07106004 1.99115 10 P 0 0;2,4=11,6=0
P 2.12106004 1.89115 10 P 0 0;2,4=11,6=0
P 2.12106004 1.94115 10 P 0 0;2,4=11,6=0
P 2.17106004 1.94115 10 P 0 0;2,4=11,6=0
P 2.17106004 1.99115 10 P 0 0;2,4=11,6=0
P 2.02106004 2.04115 10 P 0 0;2,4=11,6=0
P 2.02106004 2.09115 10 P 0 0;2,4=11,6=0
P 2.12106004 2.04115 10 P 0 0;2,4=11,6=0
P 2.12106004 2.09115 10 P 0 0;2,4=11,6=0
P 2.17106004 2.09115 10 P 0 0;2,4=11,6=0
P 2.17106004 2.14115 10 P 0 0;2,4=11,6=0
P 2.07106004 2.09115 10 P 0 0;2,4=11,6=0
P 2.07106004 2.14115 10 P 0 0;2,4=11,6=0
P 2.02106004 2.19115 10 P 0 0;2,4=11,6=0
P 2.02106004 2.24115 10 P 0 0;2,4=11,6=0
P 2.07106004 2.24115 10 P 0 0;2,4=11,6=0
P 2.07106004 2.29115 10 P 0 0;2,4=11,6=0
P 2.12106004 2.19115 10 P 0 0;2,4=11,6=0
P 2.12106004 2.24115 10 P 0 0;2,4=11,6=0
P 2.17106004 2.24115 10 P 0 0;2,4=11,6=0
P 2.17106004 2.29115 10 P 0 0;2,4=11,6=0
P 2.02106004 2.34115 10 P 0 0;2,4=11,6=0
P 2.02106004 2.39115 10 P 0 0;2,4=11,6=0
P 2.12106004 2.34115 10 P 0 0;2,4=11,6=0
P 2.12106004 2.39115 10 P 0 0;2,4=11,6=0
P 2.17106004 2.39115 10 P 0 0;2,4=11,6=0
P 2.17106004 2.44115 10 P 0 0;2,4=11,6=0
P 2.07106004 2.39115 10 P 0 0;2,4=11,6=0
P 2.07106004 2.44115 10 P 0 0;2,4=11,6=0
P 2.02106004 2.64115 10 P 0 0;2,4=11,6=0
P 2.02106004 2.59115 10 P 0 0;2,4=11,6=0
P 8.125 1.89115 10 P 0 0;2,4=11,6=0
P 8.025 1.89115 10 P 0 0;2,4=11,6=0
P 8.075 1.89115 10 P 0 0;2,4=11,6=0
P 8.125 1.94115 10 P 0 0;2,4=11,6=0
P 8.025 1.94115 10 P 0 0;2,4=11,6=0
P 8.075 1.99115 10 P 0 0;2,4=11,6=0
P 8.075 1.94115 10 P 0 0;2,4=11,6=0
P 8.125 2.09115 10 P 0 0;2,4=11,6=0
P 8.125 2.04115 10 P 0 0;2,4=11,6=0
P 8.025 2.09115 10 P 0 0;2,4=11,6=0
P 8.025 2.04115 10 P 0 0;2,4=11,6=0
P 8.075 2.14115 10 P 0 0;2,4=11,6=0
P 8.075 2.09115 10 P 0 0;2,4=11,6=0
P 8.125 2.14115 10 P 0 0;2,4=11,6=0
P 8.125 1.99115 10 P 0 0;2,4=11,6=0
P 8.075 2.04115 10 P 0 0;2,4=11,6=0
P 8.025 1.99115 10 P 0 0;2,4=11,6=0
P 8.025 2.14115 10 P 0 0;2,4=11,6=0
P 8.025 2.19115 10 P 0 0;2,4=11,6=0
P 8.025 2.24115 10 P 0 0;2,4=11,6=0
P 8.125 2.19115 10 P 0 0;2,4=11,6=0
P 8.125 2.24115 10 P 0 0;2,4=11,6=0
P 8.075 2.24115 10 P 0 0;2,4=11,6=0
P 8.075 2.29115 10 P 0 0;2,4=11,6=0
P 8.125 2.34115 10 P 0 0;2,4=11,6=0
P 8.125 2.39115 10 P 0 0;2,4=11,6=0
P 8.025 2.34115 10 P 0 0;2,4=11,6=0
P 8.025 2.39115 10 P 0 0;2,4=11,6=0
P 8.075 2.39115 10 P 0 0;2,4=11,6=0
P 8.125 2.29115 10 P 0 0;2,4=11,6=0
P 8.075 2.34115 10 P 0 0;2,4=11,6=0
P 8.075 2.19115 10 P 0 0;2,4=11,6=0
P 8.025 2.29115 10 P 0 0;2,4=11,6=0
P 8.075 2.44115 10 P 0 0;2,4=11,6=0
P 8.125 2.59115 10 P 0 0;2,4=11,6=0
P 8.125 2.64115 10 P 0 0;2,4=11,6=0
P 8.075 2.54115 10 P 0 0;2,4=11,6=0
P 8.075 2.59115 10 P 0 0;2,4=11,6=0
P 8.025 2.59115 10 P 0 0;2,4=11,6=0
P 8.025 2.64115 10 P 0 0;2,4=11,6=0
P 8.125 2.44115 10 P 0 0;2,4=11,6=0
P 8.125 2.54115 10 P 0 0;2,4=11,6=0
P 8.075 2.49115 10 P 0 0;2,4=11,6=0
P 8.025 2.44115 10 P 0 0;2,4=11,6=0
P 8.025 2.49115 10 P 0 0;2,4=11,6=0
P 8.025 2.54115 10 P 0 0;2,4=11,6=0
P 8.075 2.64115 10 P 0 0;2,4=11,6=0
P 8.025 2.74115 10 P 0 0;2,4=11,6=0
P 8.025 2.79115 10 P 0 0;2,4=11,6=0
P 8.075 2.69115 10 P 0 0;2,4=11,6=0
P 8.075 2.74115 10 P 0 0;2,4=11,6=0
P 8.125 2.74115 10 P 0 0;2,4=11,6=0
P 8.125 2.79115 10 P 0 0;2,4=11,6=0
P 8.025 2.89115 10 P 0 0;2,4=11,6=0
P 8.125 2.89115 10 P 0 0;2,4=11,6=0
P 8.075 2.79115 10 P 0 0;2,4=11,6=0
P 8.075 2.84115 10 P 0 0;2,4=11,6=0
P 8.025 2.84115 10 P 0 0;2,4=11,6=0
P 8.025 2.69115 10 P 0 0;2,4=11,6=0
P 8.125 2.69115 10 P 0 0;2,4=11,6=0
P 8.125 2.84115 10 P 0 0;2,4=11,6=0
P 8.075 2.89115 10 P 0 0;2,4=11,6=0
P 8.025 2.94115 10 P 0 0;2,4=11,6=0
P 8.075 2.99115 10 P 0 0;2,4=11,6=0
P 8.075 2.94115 10 P 0 0;2,4=11,6=0
P 8.125 2.94115 10 P 0 0;2,4=11,6=0
P 8.025 3.04115 10 P 0 0;2,4=11,6=0
P 8.125 3.04115 10 P 0 0;2,4=11,6=0
P 8.125 3.09115 10 P 0 0;2,4=11,6=0
P 8.025 3.09115 10 P 0 0;2,4=11,6=0
P 8.075 3.09115 10 P 0 0;2,4=11,6=0
P 8.075 3.14115 10 P 0 0;2,4=11,6=0
P 8.025 2.99115 10 P 0 0;2,4=11,6=0
P 8.075 3.04115 10 P 0 0;2,4=11,6=0
P 8.125 2.99115 10 P 0 0;2,4=11,6=0
P 8.125 3.14115 10 P 0 0;2,4=11,6=0
P 8.025 3.14115 10 P 0 0;2,4=11,6=0
P 8.125 3.19115 10 P 0 0;2,4=11,6=0
P 8.025 3.19115 10 P 0 0;2,4=11,6=0
P 8.075 3.19115 10 P 0 0;2,4=11,6=0
P 8.375 1.89115 10 P 0 0;2,4=11,6=0
P 8.325 1.89115 10 P 0 0;2,4=11,6=0
P 8.275 1.89115 10 P 0 0;2,4=11,6=0
P 8.225 1.89115 10 P 0 0;2,4=11,6=0
P 8.175 1.89115 10 P 0 0;2,4=11,6=0
P 8.325 2.14115 10 P 0 0;2,4=11,6=0
P 8.325 2.09115 10 P 0 0;2,4=11,6=0
P 8.375 2.09115 10 P 0 0;2,4=11,6=0
P 8.375 2.04115 10 P 0 0;2,4=11,6=0
P 8.375 1.94115 10 P 0 0;2,4=11,6=0
P 8.325 1.99115 10 P 0 0;2,4=11,6=0
P 8.325 1.94115 10 P 0 0;2,4=11,6=0
P 8.175 1.99115 10 P 0 0;2,4=11,6=0
P 8.175 1.94115 10 P 0 0;2,4=11,6=0
P 8.175 2.14115 10 P 0 0;2,4=11,6=0
P 8.175 2.09115 10 P 0 0;2,4=11,6=0
P 8.225 2.09115 10 P 0 0;2,4=11,6=0
P 8.225 2.14115 10 P 0 0;2,4=11,6=0
P 8.275 2.14115 10 P 0 0;2,4=11,6=0
P 8.275 2.09115 10 P 0 0;2,4=11,6=0
P 8.375 2.14115 10 P 0 0;2,4=11,6=0
P 8.375 1.99115 10 P 0 0;2,4=11,6=0
P 8.325 2.04115 10 P 0 0;2,4=11,6=0
P 8.275 2.04115 10 P 0 0;2,4=11,6=0
P 8.225 2.04115 10 P 0 0;2,4=11,6=0
P 8.175 2.04115 10 P 0 0;2,4=11,6=0
P 8.275 1.99115 10 P 0 0;2,4=11,6=0
P 8.225 1.99115 10 P 0 0;2,4=11,6=0
P 8.275 1.94115 10 P 0 0;2,4=11,6=0
P 8.225 1.94115 10 P 0 0;2,4=11,6=0
P 8.325 2.39115 10 P 0 0;2,4=11,6=0
P 8.375 2.34115 10 P 0 0;2,4=11,6=0
P 8.375 2.39115 10 P 0 0;2,4=11,6=0
P 8.375 2.19115 10 P 0 0;2,4=11,6=0
P 8.375 2.24115 10 P 0 0;2,4=11,6=0
P 8.325 2.24115 10 P 0 0;2,4=11,6=0
P 8.325 2.29115 10 P 0 0;2,4=11,6=0
P 8.175 2.24115 10 P 0 0;2,4=11,6=0
P 8.175 2.29115 10 P 0 0;2,4=11,6=0
P 8.175 2.39115 10 P 0 0;2,4=11,6=0
P 8.175 2.19115 10 P 0 0;2,4=11,6=0
P 8.225 2.24115 10 P 0 0;2,4=11,6=0
P 8.275 2.24115 10 P 0 0;2,4=11,6=0
P 8.225 2.19115 10 P 0 0;2,4=11,6=0
P 8.275 2.19115 10 P 0 0;2,4=11,6=0
P 8.325 2.19115 10 P 0 0;2,4=11,6=0
P 8.225 2.29115 10 P 0 0;2,4=11,6=0
P 8.275 2.29115 10 P 0 0;2,4=11,6=0
P 8.325 2.34115 10 P 0 0;2,4=11,6=0
P 8.375 2.29115 10 P 0 0;2,4=11,6=0
P 8.275 2.34115 10 P 0 0;2,4=11,6=0
P 8.175 2.34115 10 P 0 0;2,4=11,6=0
P 8.225 2.34115 10 P 0 0;2,4=11,6=0
P 8.225 2.39115 10 P 0 0;2,4=11,6=0
P 8.275 2.39115 10 P 0 0;2,4=11,6=0
P 8.325 2.44115 10 P 0 0;2,4=11,6=0
P 8.175 2.44115 10 P 0 0;2,4=11,6=0
P 8.175 2.54115 10 P 0 0;2,4=11,6=0
P 8.175 2.59115 10 P 0 0;2,4=11,6=0
P 8.375 2.59115 10 P 0 0;2,4=11,6=0
P 8.375 2.64115 10 P 0 0;2,4=11,6=0
P 8.325 2.54115 10 P 0 0;2,4=11,6=0
P 8.325 2.59115 10 P 0 0;2,4=11,6=0
P 8.375 2.54115 10 P 0 0;2,4=11,6=0
P 8.375 2.49115 10 P 0 0;2,4=11,6=0
P 8.375 2.44115 10 P 0 0;2,4=11,6=0
P 8.275 2.44115 10 P 0 0;2,4=11,6=0
P 8.225 2.44115 10 P 0 0;2,4=11,6=0
P 8.175 2.49115 10 P 0 0;2,4=11,6=0
P 8.225 2.49115 10 P 0 0;2,4=11,6=0
P 8.275 2.49115 10 P 0 0;2,4=11,6=0
P 8.325 2.49115 10 P 0 0;2,4=11,6=0
P 8.275 2.54115 10 P 0 0;2,4=11,6=0
P 8.275 2.59115 10 P 0 0;2,4=11,6=0
P 8.225 2.54115 10 P 0 0;2,4=11,6=0
P 8.225 2.59115 10 P 0 0;2,4=11,6=0
P 8.175 2.64115 10 P 0 0;2,4=11,6=0
P 8.225 2.64115 10 P 0 0;2,4=11,6=0
P 8.275 2.64115 10 P 0 0;2,4=11,6=0
P 8.325 2.64115 10 P 0 0;2,4=11,6=0
P 8.175 2.69115 10 P 0 0;2,4=11,6=0
P 8.175 2.74115 10 P 0 0;2,4=11,6=0
P 8.325 2.69115 10 P 0 0;2,4=11,6=0
P 8.325 2.74115 10 P 0 0;2,4=11,6=0
P 8.375 2.74115 10 P 0 0;2,4=11,6=0
P 8.375 2.79115 10 P 0 0;2,4=11,6=0
P 8.375 2.89115 10 P 0 0;2,4=11,6=0
P 8.175 2.84115 10 P 0 0;2,4=11,6=0
P 8.225 2.69115 10 P 0 0;2,4=11,6=0
P 8.275 2.69115 10 P 0 0;2,4=11,6=0
P 8.375 2.69115 10 P 0 0;2,4=11,6=0
P 8.325 2.79115 10 P 0 0;2,4=11,6=0
P 8.375 2.84115 10 P 0 0;2,4=11,6=0
P 8.275 2.89115 10 P 0 0;2,4=11,6=0
P 8.225 2.89115 10 P 0 0;2,4=11,6=0
P 8.175 2.89115 10 P 0 0;2,4=11,6=0
P 8.175 2.79115 10 P 0 0;2,4=11,6=0
P 8.225 2.79115 10 P 0 0;2,4=11,6=0
P 8.225 2.74115 10 P 0 0;2,4=11,6=0
P 8.275 2.79115 10 P 0 0;2,4=11,6=0
P 8.275 2.74115 10 P 0 0;2,4=11,6=0
P 8.325 2.89115 10 P 0 0;2,4=11,6=0
P 8.325 2.84115 10 P 0 0;2,4=11,6=0
P 8.375 2.94115 10 P 0 0;2,4=11,6=0
P 8.325 2.94115 10 P 0 0;2,4=11,6=0
P 8.325 2.99115 10 P 0 0;2,4=11,6=0
P 8.175 2.94115 10 P 0 0;2,4=11,6=0
P 8.175 2.99115 10 P 0 0;2,4=11,6=0
P 8.375 3.09115 10 P 0 0;2,4=11,6=0
P 8.375 3.04115 10 P 0 0;2,4=11,6=0
P 8.325 3.09115 10 P 0 0;2,4=11,6=0
P 8.325 3.14115 10 P 0 0;2,4=11,6=0
P 8.175 3.09115 10 P 0 0;2,4=11,6=0
P 8.175 3.14115 10 P 0 0;2,4=11,6=0
P 8.325 3.04115 10 P 0 0;2,4=11,6=0
P 8.375 2.99115 10 P 0 0;2,4=11,6=0
P 8.175 3.04115 10 P 0 0;2,4=11,6=0
P 8.225 2.99115 10 P 0 0;2,4=11,6=0
P 8.225 2.94115 10 P 0 0;2,4=11,6=0
P 8.225 3.09115 10 P 0 0;2,4=11,6=0
P 8.225 3.04115 10 P 0 0;2,4=11,6=0
P 8.275 2.99115 10 P 0 0;2,4=11,6=0
P 8.275 2.94115 10 P 0 0;2,4=11,6=0
P 8.275 3.09115 10 P 0 0;2,4=11,6=0
P 8.275 3.04115 10 P 0 0;2,4=11,6=0
P 8.225 3.14115 10 P 0 0;2,4=11,6=0
P 8.275 3.14115 10 P 0 0;2,4=11,6=0
P 8.375 3.14115 10 P 0 0;2,4=11,6=0
P 8.375 3.19115 10 P 0 0;2,4=11,6=0
P 8.275 3.19115 10 P 0 0;2,4=11,6=0
P 8.225 3.19115 10 P 0 0;2,4=11,6=0
P 8.175 3.19115 10 P 0 0;2,4=11,6=0
P 8.325 3.19115 10 P 0 0;2,4=11,6=0
P 8.475 1.89115 10 P 0 0;2,4=11,6=0
P 8.425 1.89115 10 P 0 0;2,4=11,6=0
P 8.475 2.09115 10 P 0 0;2,4=11,6=0
P 8.475 2.04115 10 P 0 0;2,4=11,6=0
P 8.425 2.14115 10 P 0 0;2,4=11,6=0
P 8.425 2.09115 10 P 0 0;2,4=11,6=0
P 8.475 1.94115 10 P 0 0;2,4=11,6=0
P 8.425 1.99115 10 P 0 0;2,4=11,6=0
P 8.425 1.94115 10 P 0 0;2,4=11,6=0
P 8.475 2.14115 10 P 0 0;2,4=11,6=0
P 8.475 1.99115 10 P 0 0;2,4=11,6=0
P 8.425 2.04115 10 P 0 0;2,4=11,6=0
P 8.425 2.39115 10 P 0 0;2,4=11,6=0
P 8.475 2.34115 10 P 0 0;2,4=11,6=0
P 8.475 2.39115 10 P 0 0;2,4=11,6=0
P 8.475 2.19115 10 P 0 0;2,4=11,6=0
P 8.475 2.24115 10 P 0 0;2,4=11,6=0
P 8.425 2.24115 10 P 0 0;2,4=11,6=0
P 8.425 2.29115 10 P 0 0;2,4=11,6=0
P 8.425 2.19115 10 P 0 0;2,4=11,6=0
P 8.475 2.29115 10 P 0 0;2,4=11,6=0
P 8.425 2.34115 10 P 0 0;2,4=11,6=0
P 8.425 2.44115 10 P 0 0;2,4=11,6=0
P 8.475 2.59115 10 P 0 0;2,4=11,6=0
P 8.475 2.64115 10 P 0 0;2,4=11,6=0
P 8.425 2.54115 10 P 0 0;2,4=11,6=0
P 8.425 2.59115 10 P 0 0;2,4=11,6=0
P 8.475 2.44115 10 P 0 0;2,4=11,6=0
P 8.475 2.49115 10 P 0 0;2,4=11,6=0
P 8.475 2.54115 10 P 0 0;2,4=11,6=0
P 8.425 2.49115 10 P 0 0;2,4=11,6=0
P 8.425 2.64115 10 P 0 0;2,4=11,6=0
P 8.425 2.69115 10 P 0 0;2,4=11,6=0
P 8.425 2.74115 10 P 0 0;2,4=11,6=0
P 8.475 2.74115 10 P 0 0;2,4=11,6=0
P 8.475 2.79115 10 P 0 0;2,4=11,6=0
P 8.475 2.89115 10 P 0 0;2,4=11,6=0
P 8.475 2.69115 10 P 0 0;2,4=11,6=0
P 8.475 2.84115 10 P 0 0;2,4=11,6=0
P 8.425 2.79115 10 P 0 0;2,4=11,6=0
P 8.425 2.84115 10 P 0 0;2,4=11,6=0
P 8.425 2.89115 10 P 0 0;2,4=11,6=0
P 8.475 2.94115 10 P 0 0;2,4=11,6=0
P 8.425 2.94115 10 P 0 0;2,4=11,6=0
P 8.425 2.99115 10 P 0 0;2,4=11,6=0
P 8.475 3.04115 10 P 0 0;2,4=11,6=0
P 8.475 3.09115 10 P 0 0;2,4=11,6=0
P 8.425 3.09115 10 P 0 0;2,4=11,6=0
P 8.425 3.14115 10 P 0 0;2,4=11,6=0
P 8.475 2.99115 10 P 0 0;2,4=11,6=0
P 8.425 3.04115 10 P 0 0;2,4=11,6=0
P 8.475 3.14115 10 P 0 0;2,4=11,6=0
P 8.425 3.19115 10 P 0 0;2,4=11,6=0
P 8.475 3.19115 10 P 0 0;2,4=11,6=0
P 1.79843002 4.97913996 36 P 0 0;2,4=1,6=0
P 1.75118996 4.85788002 36 P 0 0;2,4=1,6=0
P 1.72756998 4.85788002 36 P 0 0;2,4=1,6=0
P 1.75118996 4.97913996 36 P 0 0;2,4=1,6=0
P 1.82206004 4.97913996 36 P 0 0;2,4=1,6=0
P 1.72756998 4.97913996 36 P 0 0;2,4=1,6=0
P 2.22363002 4.97913996 36 P 0 0;2,4=1,6=0
P 2.17638996 4.85788002 36 P 0 0;2,4=1,6=0
P 2.15276004 4.85788002 36 P 0 0;2,4=1,6=0
P 2.31811998 4.97913996 36 P 0 0;2,4=1,6=0
P 2.2945 4.97913996 36 P 0 0;2,4=1,6=0
P 2.24725 4.97913996 36 P 0 0;2,4=1,6=0
P 2.41261004 4.97913996 36 P 0 0;2,4=1,6=0
P 2.34173996 4.97913996 36 P 0 0;2,4=1,6=0
P 2.27086998 4.97913996 36 P 0 0;2,4=1,6=0
P 2.20001004 4.97913996 36 P 0 0;2,4=1,6=0
P 2.12913996 4.97913996 36 P 0 0;2,4=1,6=0
P 2.05828002 4.97913996 36 P 0 0;2,4=1,6=0
P 1.98741004 4.97913996 36 P 0 0;2,4=1,6=0
P 1.91653996 4.97913996 36 P 0 0;2,4=1,6=0
P 1.84568002 4.97913996 36 P 0 0;2,4=1,6=0
P 1.77481004 4.97913996 36 P 0 0;2,4=1,6=0
P 1.70395 4.97913996 36 P 0 0;2,4=1,6=0
P 1.63308002 4.97913996 36 P 0 0;2,4=1,6=0
P 1.56221004 4.97913996 36 P 0 0;2,4=1,6=0
P 2.41261004 4.85788002 36 P 0 0;2,4=1,6=0
P 2.34173996 4.85788002 36 P 0 0;2,4=1,6=0
P 2.27086998 4.85788002 36 P 0 0;2,4=1,6=0
P 2.20001004 4.85788002 36 P 0 0;2,4=1,6=0
P 2.12913996 4.85788002 36 P 0 0;2,4=1,6=0
P 2.05828002 4.85788002 36 P 0 0;2,4=1,6=0
P 1.98741004 4.85788002 36 P 0 0;2,4=1,6=0
P 1.91653996 4.85788002 36 P 0 0;2,4=1,6=0
P 1.84568002 4.85788002 36 P 0 0;2,4=1,6=0
P 1.77481004 4.85788002 36 P 0 0;2,4=1,6=0
P 1.70395 4.85788002 36 P 0 0;2,4=1,6=0
P 1.63308002 4.85788002 36 P 0 0;2,4=1,6=0
P 1.56221004 4.85788002 36 P 0 0;2,4=1,6=0
P 2.45985 4.77875 15 P 0 0;4=32,6=0
P 1.51496998 4.77875 15 P 0 0;4=32,6=0
P 2.44016998 5.05826998 15 P 0 0;4=32,6=0
P 1.53465 5.05826998 15 P 0 0;4=32,6=0
P 3.34098996 4.85788002 36 P 0 0;2,4=1,6=0
P 3.31736004 4.85788002 36 P 0 0;2,4=1,6=0
P 3.48271998 4.97913996 36 P 0 0;2,4=1,6=0
P 2.96303002 4.97913996 36 P 0 0;2,4=1,6=0
P 2.91578996 4.85788002 36 P 0 0;2,4=1,6=0
P 2.89216998 4.85788002 36 P 0 0;2,4=1,6=0
P 2.91578996 4.97913996 36 P 0 0;2,4=1,6=0
P 2.89216998 4.97913996 36 P 0 0;2,4=1,6=0
P 2.98666004 4.97913996 36 P 0 0;2,4=1,6=0
P 3.36461004 4.85788002 36 P 0 0;2,4=1,6=0
P 3.29373996 4.85788002 36 P 0 0;2,4=1,6=0
P 3.22288002 4.85788002 36 P 0 0;2,4=1,6=0
P 3.15201004 4.85788002 36 P 0 0;2,4=1,6=0
P 3.08113996 4.85788002 36 P 0 0;2,4=1,6=0
P 3.01028002 4.85788002 36 P 0 0;2,4=1,6=0
P 2.93941004 4.85788002 36 P 0 0;2,4=1,6=0
P 2.86855 4.85788002 36 P 0 0;2,4=1,6=0
P 2.79768002 4.85788002 36 P 0 0;2,4=1,6=0
P 2.72681004 4.85788002 36 P 0 0;2,4=1,6=0
P 3.60476998 4.77875 15 P 0 0;4=32,6=0
P 2.67956998 4.77875 15 P 0 0;4=32,6=0
P 3.60476998 5.05826998 15 P 0 0;4=32,6=0
P 2.69925 5.05826998 15 P 0 0;4=32,6=0
P 3.57721004 4.97913996 36 P 0 0;2,4=1,6=0
P 3.50633996 4.97913996 36 P 0 0;2,4=1,6=0
P 3.43546998 4.97913996 36 P 0 0;2,4=1,6=0
P 3.36461004 4.97913996 36 P 0 0;2,4=1,6=0
P 3.29373996 4.97913996 36 P 0 0;2,4=1,6=0
P 3.22288002 4.97913996 36 P 0 0;2,4=1,6=0
P 3.15201004 4.97913996 36 P 0 0;2,4=1,6=0
P 3.08113996 4.97913996 36 P 0 0;2,4=1,6=0
P 3.01028002 4.97913996 36 P 0 0;2,4=1,6=0
P 2.93941004 4.97913996 36 P 0 0;2,4=1,6=0
P 2.86855 4.97913996 36 P 0 0;2,4=1,6=0
P 2.79768002 4.97913996 36 P 0 0;2,4=1,6=0
P 2.72681004 4.97913996 36 P 0 0;2,4=1,6=0
P 3.57721004 4.85788002 36 P 0 0;2,4=1,6=0
P 3.50633996 4.85788002 36 P 0 0;2,4=1,6=0
P 3.43546998 4.85788002 36 P 0 0;2,4=1,6=0
P 8.25078996 4.97913996 36 P 0 0;2,4=1,6=0
P 8.22716998 4.97913996 36 P 0 0;2,4=1,6=0
P 8.17993002 4.85788002 36 P 0 0;2,4=1,6=0
P 8.1563 4.85788002 36 P 0 0;2,4=1,6=0
P 8.32166004 4.97913996 36 P 0 0;2,4=1,6=0
P 8.29803996 4.97913996 36 P 0 0;2,4=1,6=0
P 7.80196998 4.97913996 36 P 0 0;2,4=1,6=0
P 7.75473002 4.85788002 36 P 0 0;2,4=1,6=0
P 7.73111004 4.85788002 36 P 0 0;2,4=1,6=0
P 7.75473002 4.97913996 36 P 0 0;2,4=1,6=0
P 7.73111004 4.97913996 36 P 0 0;2,4=1,6=0
P 7.8256 4.97913996 36 P 0 0;2,4=1,6=0
P 8.20355 4.85788002 36 P 0 0;2,4=1,6=0
P 8.13268002 4.85788002 36 P 0 0;2,4=1,6=0
P 8.06181998 4.85788002 36 P 0 0;2,4=1,6=0
P 7.99095 4.85788002 36 P 0 0;2,4=1,6=0
P 7.92008002 4.85788002 36 P 0 0;2,4=1,6=0
P 7.84921998 4.85788002 36 P 0 0;2,4=1,6=0
P 7.77835 4.85788002 36 P 0 0;2,4=1,6=0
P 7.70748996 4.85788002 36 P 0 0;2,4=1,6=0
P 7.63661998 4.85788002 36 P 0 0;2,4=1,6=0
P 7.56575 4.85788002 36 P 0 0;2,4=1,6=0
P 8.46338996 4.77875 15 P 0 0;4=32,6=0
P 7.51851004 4.77875 15 P 0 0;4=32,6=0
P 8.44371004 5.05826998 15 P 0 0;4=32,6=0
P 7.53818996 5.05826998 15 P 0 0;4=32,6=0
P 8.41615 4.97913996 36 P 0 0;2,4=1,6=0
P 8.34528002 4.97913996 36 P 0 0;2,4=1,6=0
P 8.27441004 4.97913996 36 P 0 0;2,4=1,6=0
P 8.20355 4.97913996 36 P 0 0;2,4=1,6=0
P 8.13268002 4.97913996 36 P 0 0;2,4=1,6=0
P 8.06181998 4.97913996 36 P 0 0;2,4=1,6=0
P 7.99095 4.97913996 36 P 0 0;2,4=1,6=0
P 7.92008002 4.97913996 36 P 0 0;2,4=1,6=0
P 7.84921998 4.97913996 36 P 0 0;2,4=1,6=0
P 7.77835 4.97913996 36 P 0 0;2,4=1,6=0
P 7.70748996 4.97913996 36 P 0 0;2,4=1,6=0
P 7.63661998 4.97913996 36 P 0 0;2,4=1,6=0
P 7.56575 4.97913996 36 P 0 0;2,4=1,6=0
P 8.41615 4.85788002 36 P 0 0;2,4=1,6=0
P 8.34528002 4.85788002 36 P 0 0;2,4=1,6=0
P 8.27441004 4.85788002 36 P 0 0;2,4=1,6=0
P 9.34453002 4.85788002 36 P 0 0;2,4=1,6=0
P 9.3209 4.85788002 36 P 0 0;2,4=1,6=0
P 9.48626004 4.97913996 36 P 0 0;2,4=1,6=0
P 8.96656998 4.97913996 36 P 0 0;2,4=1,6=0
P 8.91933002 4.85788002 36 P 0 0;2,4=1,6=0
P 8.89571004 4.85788002 36 P 0 0;2,4=1,6=0
P 8.91933002 4.97913996 36 P 0 0;2,4=1,6=0
P 8.89571004 4.97913996 36 P 0 0;2,4=1,6=0
P 8.9902 4.97913996 36 P 0 0;2,4=1,6=0
P 9.36815 4.85788002 36 P 0 0;2,4=1,6=0
P 9.29728002 4.85788002 36 P 0 0;2,4=1,6=0
P 9.22641998 4.85788002 36 P 0 0;2,4=1,6=0
P 9.15555 4.85788002 36 P 0 0;2,4=1,6=0
P 9.08468002 4.85788002 36 P 0 0;2,4=1,6=0
P 9.01381998 4.85788002 36 P 0 0;2,4=1,6=0
P 8.94295 4.85788002 36 P 0 0;2,4=1,6=0
P 8.87208996 4.85788002 36 P 0 0;2,4=1,6=0
P 8.80121998 4.85788002 36 P 0 0;2,4=1,6=0
P 8.73035 4.85788002 36 P 0 0;2,4=1,6=0
P 9.60831004 4.77875 15 P 0 0;4=32,6=0
P 8.68311004 4.77875 15 P 0 0;4=32,6=0
P 9.60831004 5.05826998 15 P 0 0;4=32,6=0
P 8.70278996 5.05826998 15 P 0 0;4=32,6=0
P 9.58075 4.97913996 36 P 0 0;2,4=1,6=0
P 9.50988002 4.97913996 36 P 0 0;2,4=1,6=0
P 9.43901004 4.97913996 36 P 0 0;2,4=1,6=0
P 9.36815 4.97913996 36 P 0 0;2,4=1,6=0
P 9.29728002 4.97913996 36 P 0 0;2,4=1,6=0
P 9.22641998 4.97913996 36 P 0 0;2,4=1,6=0
P 9.15555 4.97913996 36 P 0 0;2,4=1,6=0
P 9.08468002 4.97913996 36 P 0 0;2,4=1,6=0
P 9.01381998 4.97913996 36 P 0 0;2,4=1,6=0
P 8.94295 4.97913996 36 P 0 0;2,4=1,6=0
P 8.87208996 4.97913996 36 P 0 0;2,4=1,6=0
P 8.80121998 4.97913996 36 P 0 0;2,4=1,6=0
P 8.73035 4.97913996 36 P 0 0;2,4=1,6=0
P 9.58075 4.85788002 36 P 0 0;2,4=1,6=0
P 9.50988002 4.85788002 36 P 0 0;2,4=1,6=0
P 9.43901004 4.85788002 36 P 0 0;2,4=1,6=0
P 10.82676998 5.49685 17 P 0 0;4=33,6=0
P 10.99213002 5.49685 17 P 0 0;4=33,6=0
P 11.15748002 5.49685 17 P 0 0;4=33,6=0
P 11.32283996 5.49685 17 P 0 0;4=33,6=0
P 11.48818996 5.49685 17 P 0 0;4=33,6=0
P 11.65353996 5.49685 17 P 0 0;4=33,6=0
P 11.8189 5.49685 17 P 0 0;4=33,6=0
P 11.98425 5.49685 17 P 0 0;4=33,6=0
P 12.14961004 5.49685 32 P 0 0;4=34,6=0
P 10.83662215 1.50786998 57 P 0 0;4=35,6=0
P 10.83661772 1.50788002 58 P 0 0;4=35,6=0
P 8.24999774 1.50788002 58 P 0 0;4=35,6=0
P 8.25000217 1.50786998 57 P 0 0;4=35,6=0
P 6.96457215 1.52755994 57 P 0 0;4=35,6=0
P 6.96456772 1.52755994 58 P 0 0;4=35,6=0
P 6.96457215 4.20471998 57 P 0 0;4=35,6=0
P 6.96456772 4.20473002 58 P 0 0;4=35,6=0
P 8.25000217 4.22440994 57 P 0 0;4=35,6=0
P 8.24999774 4.22440994 58 P 0 0;4=35,6=0
P 10.83662215 4.22440994 57 P 0 0;4=35,6=0
P 10.83661772 4.22440994 58 P 0 0;4=35,6=0
P 12.12205217 4.20471998 57 P 0 0;4=35,6=0
P 12.12204774 4.20473002 58 P 0 0;4=35,6=0
P 12.12204774 1.52755994 58 P 0 0;4=35,6=0
P 12.12205217 1.52755994 57 P 0 0;4=35,6=0
P 8.78543996 2.86613996 42 P 0 0;2,4=36,6=0
P 10.30118002 2.86613996 42 P 0 0;2,4=36,6=0
P 11.99213002 4.20473002 9 P 0 0;4=13,6=0
P 12.03018002 4.11286004 9 P 0 0;4=13,6=0
P 12.03018002 4.2966 9 P 0 0;4=13,6=0
P 12.21391998 4.11286004 9 P 0 0;4=13,6=0
P 12.25196998 4.20473002 9 P 0 0;4=13,6=0
P 12.21391998 4.2966 9 P 0 0;4=13,6=0
P 10.7067 4.22441004 9 P 0 0;4=13,6=0
P 10.74475 4.13253996 9 P 0 0;4=13,6=0
P 10.74475 4.31628002 9 P 0 0;4=13,6=0
P 10.92848996 4.13253996 9 P 0 0;4=13,6=0
P 10.96653996 4.22441004 9 P 0 0;4=13,6=0
P 10.92848996 4.31628002 9 P 0 0;4=13,6=0
P 8.12008002 4.22441004 9 P 0 0;4=13,6=0
P 8.15813002 4.13253996 9 P 0 0;4=13,6=0
P 8.15813002 4.31628002 9 P 0 0;4=13,6=0
P 8.34186998 4.13253996 9 P 0 0;4=13,6=0
P 8.37991998 4.22441004 9 P 0 0;4=13,6=0
P 8.34186998 4.31628002 9 P 0 0;4=13,6=0
P 6.83465 4.20473002 9 P 0 0;4=13,6=0
P 6.8727 4.11286004 9 P 0 0;4=13,6=0
P 6.8727 4.2966 9 P 0 0;4=13,6=0
P 7.05643996 4.11286004 9 P 0 0;4=13,6=0
P 7.09448996 4.20473002 9 P 0 0;4=13,6=0
P 7.05643996 4.2966 9 P 0 0;4=13,6=0
P 6.83465 1.52756004 9 P 0 0;4=13,6=0
P 6.8727 1.43568996 9 P 0 0;4=13,6=0
P 6.8727 1.61943002 9 P 0 0;4=13,6=0
P 7.05643996 1.43568996 9 P 0 0;4=13,6=0
P 7.09448996 1.52756004 9 P 0 0;4=13,6=0
P 7.05643996 1.61943002 9 P 0 0;4=13,6=0
P 8.15813002 1.416 9 P 0 0;4=13,6=0
P 8.12008002 1.50786998 9 P 0 0;4=13,6=0
P 8.15813002 1.59975 9 P 0 0;4=13,6=0
P 8.34186998 1.416 9 P 0 0;4=13,6=0
P 8.34186998 1.59975 9 P 0 0;4=13,6=0
P 8.37991998 1.50786998 9 P 0 0;4=13,6=0
P 10.74475 1.59975 9 P 0 0;4=13,6=0
P 10.92848996 1.59975 9 P 0 0;4=13,6=0
P 10.96653996 1.50786998 9 P 0 0;4=13,6=0
P 10.92848996 1.416 9 P 0 0;4=13,6=0
P 10.74475 1.416 9 P 0 0;4=13,6=0
P 10.7067 1.50786998 9 P 0 0;4=13,6=0
P 12.2126 1.43701004 9 P 0 0;4=13,6=0
P 12.25196998 1.52756004 9 P 0 0;4=13,6=0
P 12.2126 1.61811004 9 P 0 0;4=13,6=0
P 12.0315 1.61811004 9 P 0 0;4=13,6=0
P 11.99213002 1.52756004 9 P 0 0;4=13,6=0
P 12.0315 1.43701004 9 P 0 0;4=13,6=0
P 4.83268219 1.50786998 57 P 0 0;4=35,6=0
P 4.83267776 1.50788002 58 P 0 0;4=35,6=0
P 2.24605778 1.50788002 58 P 0 0;4=35,6=0
P 2.2460622 1.50786998 57 P 0 0;4=35,6=0
P 0.96063219 1.52755994 57 P 0 0;4=35,6=0
P 0.96062776 1.52755994 58 P 0 0;4=35,6=0
P 0.96063219 4.20471998 57 P 0 0;4=35,6=0
P 0.96062776 4.20473002 58 P 0 0;4=35,6=0
P 2.2460622 4.22440994 57 P 0 0;4=35,6=0
P 2.24605778 4.22440994 58 P 0 0;4=35,6=0
P 4.83268219 4.22440994 57 P 0 0;4=35,6=0
P 4.83267776 4.22440994 58 P 0 0;4=35,6=0
P 6.1181122 4.20471998 57 P 0 0;4=35,6=0
P 6.11810778 4.20473002 58 P 0 0;4=35,6=0
P 6.11810778 1.52755994 58 P 0 0;4=35,6=0
P 6.1181122 1.52755994 57 P 0 0;4=35,6=0
P 2.7815 2.86613996 42 P 0 0;2,4=36,6=0
P 4.29723996 2.86613996 42 P 0 0;2,4=36,6=0
P 5.98818996 4.20473002 9 P 0 0;4=13,6=0
P 6.02623996 4.11286004 9 P 0 0;4=13,6=0
P 6.02623996 4.2966 9 P 0 0;4=13,6=0
P 6.20998002 4.11286004 9 P 0 0;4=13,6=0
P 6.24803002 4.20473002 9 P 0 0;4=13,6=0
P 6.20998002 4.2966 9 P 0 0;4=13,6=0
P 4.70276004 4.22441004 9 P 0 0;4=13,6=0
P 4.74081004 4.13253996 9 P 0 0;4=13,6=0
P 4.74081004 4.31628002 9 P 0 0;4=13,6=0
P 4.92455 4.13253996 9 P 0 0;4=13,6=0
P 4.9626 4.22441004 9 P 0 0;4=13,6=0
P 4.92455 4.31628002 9 P 0 0;4=13,6=0
P 2.11613996 4.22441004 9 P 0 0;4=13,6=0
P 2.15418996 4.13253996 9 P 0 0;4=13,6=0
P 2.15418996 4.31628002 9 P 0 0;4=13,6=0
P 2.33793002 4.13253996 9 P 0 0;4=13,6=0
P 2.37598002 4.22441004 9 P 0 0;4=13,6=0
P 2.33793002 4.31628002 9 P 0 0;4=13,6=0
P 0.83071004 4.20473002 9 P 0 0;4=13,6=0
P 0.86876004 4.11286004 9 P 0 0;4=13,6=0
P 0.86876004 4.2966 9 P 0 0;4=13,6=0
P 1.0525 4.11286004 9 P 0 0;4=13,6=0
P 1.09055 4.20473002 9 P 0 0;4=13,6=0
P 1.0525 4.2966 9 P 0 0;4=13,6=0
P 0.83071004 1.52756004 9 P 0 0;4=13,6=0
P 0.86876004 1.43568996 9 P 0 0;4=13,6=0
P 0.86876004 1.61943002 9 P 0 0;4=13,6=0
P 1.0525 1.43568996 9 P 0 0;4=13,6=0
P 1.09055 1.52756004 9 P 0 0;4=13,6=0
P 1.0525 1.61943002 9 P 0 0;4=13,6=0
P 2.15418996 1.416 9 P 0 0;4=13,6=0
P 2.11613996 1.50786998 9 P 0 0;4=13,6=0
P 2.15418996 1.59975 9 P 0 0;4=13,6=0
P 2.33793002 1.416 9 P 0 0;4=13,6=0
P 2.33793002 1.59975 9 P 0 0;4=13,6=0
P 2.37598002 1.50786998 9 P 0 0;4=13,6=0
P 4.74081004 1.59975 9 P 0 0;4=13,6=0
P 4.92455 1.59975 9 P 0 0;4=13,6=0
P 4.9626 1.50786998 9 P 0 0;4=13,6=0
P 4.92455 1.416 9 P 0 0;4=13,6=0
P 4.74081004 1.416 9 P 0 0;4=13,6=0
P 4.70276004 1.50786998 9 P 0 0;4=13,6=0
P 6.20866004 1.43701004 9 P 0 0;4=13,6=0
P 6.24803002 1.52756004 9 P 0 0;4=13,6=0
P 6.20866004 1.61811004 9 P 0 0;4=13,6=0
P 6.02756004 1.61811004 9 P 0 0;4=13,6=0
P 5.98818996 1.52756004 9 P 0 0;4=13,6=0
P 6.02756004 1.43701004 9 P 0 0;4=13,6=0
P 12.59646998 0.8189 9 P 0 0;4=13,6=0
P 12.5571 0.72835 9 P 0 0;4=13,6=0
P 12.59646998 0.6378 9 P 0 0;4=13,6=0
P 12.68702215 0.72835 57 P 0 0;4=35,6=0
P 12.77756998 0.6378 9 P 0 0;4=13,6=0
P 12.81693996 0.72835 9 P 0 0;4=13,6=0
P 12.77756998 0.8189 9 P 0 0;4=13,6=0
P 12.68701772 0.72835 58 P 0 0;4=35,6=0
P 12.59646998 5.24803002 9 P 0 0;4=13,6=0
P 12.5571 5.15748002 9 P 0 0;4=13,6=0
P 12.59646998 5.06693002 9 P 0 0;4=13,6=0
P 12.68702215 5.15748002 57 P 0 0;4=35,6=0
P 12.77756998 5.06693002 9 P 0 0;4=13,6=0
P 12.81693996 5.15748002 9 P 0 0;4=13,6=0
P 12.77756998 5.24803002 9 P 0 0;4=13,6=0
P 12.68701772 5.15748002 58 P 0 0;4=35,6=0
P 0.1319 5.20866004 9 P 0 0;4=13,6=0
P 0.09253002 5.11811004 9 P 0 0;4=13,6=0
P 0.1319 5.02756004 9 P 0 0;4=13,6=0
P 0.22245217 5.11810994 57 P 0 0;4=35,6=0
P 0.313 5.02756004 9 P 0 0;4=13,6=0
P 0.35236998 5.11811004 9 P 0 0;4=13,6=0
P 0.313 5.20866004 9 P 0 0;4=13,6=0
P 0.22244774 5.11810994 58 P 0 0;4=35,6=0
P 0.1319 0.77953002 9 P 0 0;4=13,6=0
P 0.09253002 0.68898002 9 P 0 0;4=13,6=0
P 0.1319 0.59843002 9 P 0 0;4=13,6=0
P 0.22245217 0.68898002 57 P 0 0;4=35,6=0
P 0.313 0.59843002 9 P 0 0;4=13,6=0
P 0.35236998 0.68898002 9 P 0 0;4=13,6=0
P 0.313 0.77953002 9 P 0 0;4=13,6=0
P 0.22244774 0.68898002 58 P 0 0;4=35,6=0
P 12.04 4.96 31 P 0 0;2,4=21,6=0
P 12.2 4.96 31 P 0 0;2,4=21,6=0
P 12.12 4.993 28 P 0 0;2,4=4,6=0
P 10.51 5.18 31 P 0 0;2,4=21,6=0
P 10.51 5.26 31 P 0 0;2,4=21,6=0
P 10.543 5.32 28 P 0 0;2,4=4,6=0
P 10.80498996 5.56656004 9 P 0 0;4=13,6=1
P 10.84498996 5.56656004 9 P 0 0;4=13,6=1
P 10.80498996 5.42656004 9 P 0 0;4=13,6=1
P 10.84498996 5.42656004 9 P 0 0;4=13,6=1
P 11.01035 5.42656004 9 P 0 0;4=13,6=1
P 10.97035 5.42656004 9 P 0 0;4=13,6=1
P 11.01035 5.56656004 9 P 0 0;4=13,6=1
P 10.97035 5.56656004 9 P 0 0;4=13,6=1
P 11.17571004 5.42656004 9 P 0 0;4=13,6=1
P 11.13571004 5.42656004 9 P 0 0;4=13,6=1
P 11.17571004 5.56656004 9 P 0 0;4=13,6=1
P 11.13571004 5.56656004 9 P 0 0;4=13,6=1
P 11.34106998 5.42656004 9 P 0 0;4=13,6=1
P 11.30106998 5.42656004 9 P 0 0;4=13,6=1
P 11.34106998 5.56656004 9 P 0 0;4=13,6=1
P 11.30106998 5.56656004 9 P 0 0;4=13,6=1
P 11.50643002 5.42656004 9 P 0 0;4=13,6=1
P 11.46643002 5.42656004 9 P 0 0;4=13,6=1
P 11.50643002 5.56656004 9 P 0 0;4=13,6=1
P 11.46643002 5.56656004 9 P 0 0;4=13,6=1
P 11.67178996 5.42656004 9 P 0 0;4=13,6=1
P 11.63178996 5.42656004 9 P 0 0;4=13,6=1
P 11.67178996 5.56656004 9 P 0 0;4=13,6=1
P 11.63178996 5.56656004 9 P 0 0;4=13,6=1
P 11.83715 5.42656004 9 P 0 0;4=13,6=1
P 11.79715 5.42656004 9 P 0 0;4=13,6=1
P 11.83715 5.56656004 9 P 0 0;4=13,6=1
P 11.79715 5.56656004 9 P 0 0;4=13,6=1
P 12.00251004 5.42656004 9 P 0 0;4=13,6=1
P 11.96251004 5.42656004 9 P 0 0;4=13,6=1
P 12.00251004 5.56656004 9 P 0 0;4=13,6=1
P 11.96251004 5.56656004 9 P 0 0;4=13,6=1
P 12.16786998 5.42656004 9 P 0 0;4=13,6=1
P 12.12786998 5.42656004 9 P 0 0;4=13,6=1
P 12.16786998 5.56656004 9 P 0 0;4=13,6=1
P 12.12786998 5.56656004 9 P 0 0;4=13,6=1
P 7.32283996 0.23621998 9 P 0 0;4=13,6=0
P 7.28016998 0.33921998 9 P 0 0;4=13,6=0
P 7.17716801 0.23621998 59 P 0 0;4=37,6=0
P 7.28016998 0.13321998 9 P 0 0;4=13,6=0
P 7.17717195 0.23621998 60 P 0 0;4=37,6=0
P 7.07416998 0.13321998 9 P 0 0;4=13,6=0
P 7.0315 0.23621998 9 P 0 0;4=13,6=0
P 7.07416998 0.33921998 9 P 0 0;4=13,6=0
P 7.32283996 5.7874 9 P 0 0;4=13,6=0
P 7.28016998 5.8904 9 P 0 0;4=13,6=0
P 7.17716801 5.7874 59 P 0 0;4=37,6=0
P 7.28016998 5.6844 9 P 0 0;4=13,6=0
P 7.17717195 5.7874 60 P 0 0;4=37,6=0
P 7.07416998 5.6844 9 P 0 0;4=13,6=0
P 7.0315 5.7874 9 P 0 0;4=13,6=0
P 7.07416998 5.8904 9 P 0 0;4=13,6=0
S P 0
OB 8.780869980315 4.893469980315 I
OS 8.77233996063 4.902
OS 8.77233996063 4.9342
OS 8.77813996063 4.94355
OS 9.52158996063 4.94355
OS 9.53313996063 4.932
OS 9.53313996063 4.91
OS 9.52013996063 4.893469980315
OS 8.780869980315 4.893469980315
OE
SE
S P 0
OB 7.616269980315 4.893469980315 I
OS 7.60773996063 4.902
OS 7.60773996063 4.9342
OS 7.61353996063 4.94355
OS 8.35698996063 4.94355
OS 8.36853996063 4.932
OS 8.36853996063 4.91
OS 8.35553996063 4.893469980315
OS 7.616269980315 4.893469980315
OE
SE
S P 0
OB 1.612730019685 4.893469980315 I
OS 1.6042 4.902
OS 1.6042 4.9342
OS 1.61 4.94355
OS 2.35345 4.94355
OS 2.365 4.932
OS 2.365 4.91
OS 2.352 4.893469980315
OS 1.612730019685 4.893469980315
OE
SE
S P 0
OB 2.777330019685 4.893469980315 I
OS 2.7688 4.902
OS 2.7688 4.9342
OS 2.7746 4.94355
OS 3.51805 4.94355
OS 3.5296 4.932
OS 3.5296 4.91
OS 3.5166 4.893469980315
OS 2.777330019685 4.893469980315
OE
SE
S P 0
OB 11.765 4.775 I
OS 11.75 4.79
OS 11.75 4.965
OS 11.765 4.98
OS 11.99 4.98
OS 12 4.97
OS 12 4.79
OS 11.985 4.775
OS 11.765 4.775
OE
SE
S P 0
OB 4.86105 4.9231 I
OS 4.85105 4.9131
OS 4.26105 4.9131
OS 4.25105 4.9231
OS 4.25105 5.1231
OS 4.25605 5.1281
OS 4.85605 5.1281
OS 4.86105 5.1231
OS 4.86105 4.9231
OE
SE
S P 0
OB 6.88518996063 4.79205 I
OS 6.88518996063 4.84605
OS 6.89118996063 4.85205
OS 6.96618996063 4.85205
OS 6.97118996063 4.84705
OS 6.97118996063 4.79205
OS 6.96618996063 4.78705
OS 6.89018996063 4.78705
OS 6.88518996063 4.79205
OE
SE
S P 0
OB 6.58318996063 4.98905 I
OS 6.58068996063 4.99155
OS 6.58068996063 5.04255
OS 6.56318996063 5.06005
OS 6.56318996063 5.11305
OS 6.56718996063 5.11705
OS 6.63018996063 5.11705
OS 6.63418996063 5.11305
OS 6.63418996063 5.06256003937
OS 6.63401003937 5.062169980315
OC 6.63255 5.05661003937 6.65 5.054999311024 N
OS 6.63248996063 5.05588996063
OS 6.62773996063 5.05113996063
OC 6.62578996063 5.04865 6.636930019685 5.041934251969 N
OS 6.61018996063 5.03305
OS 6.61018996063 5.0294
OS 6.60923996063 5.0294
OS 6.60923996063 4.993819980315
OC 6.60945 4.99155 6.62118996063 4.993781003937 N
OS 6.60965 4.99051003937
OS 6.60818996063 4.98905
OS 6.58318996063 4.98905
OE
SE
S P 0
OB 6.59918996063 4.75905 I
OS 6.56418996063 4.75905
OS 6.56118996063 4.76205
OS 6.56118996063 4.81205
OS 6.57918996063 4.83005
OS 6.57918996063 4.97805
OS 6.57968996063 4.97855
OS 6.66268996063 4.97855
OS 6.66318996063 4.97805
OS 6.66318996063 4.81005
OS 6.68918996063 4.78405
OS 6.68918996063 4.74055
OS 6.68643996063 4.7378
OS 6.68643996063 4.60205
OS 6.68143996063 4.59705
OS 6.61118996063 4.59705
OS 6.60618996063 4.60205
OS 6.60618996063 4.75205
OS 6.59918996063 4.75905
OE
SE
S P 0
OB 6.10808996063 4.5742 I
OS 6.10808996063 4.5062
OS 6.09708996063 4.4952
OS 5.57728996063 4.4952
OS 5.56668996063 4.5058
OS 5.56668996063 4.574
OS 5.57288996063 4.5802
OS 6.10208996063 4.5802
OS 6.10808996063 4.5742
OE
SE
S P 0
OB 10.86498996063 4.9231 I
OS 10.85498996063 4.9131
OS 10.26498996063 4.9131
OS 10.25498996063 4.9231
OS 10.25498996063 5.1231
OS 10.25998996063 5.1281
OS 10.85998996063 5.1281
OS 10.86498996063 5.1231
OS 10.86498996063 4.9231
OE
SE
S P 0
OB 10.53 5.21 I
OS 10.535 5.205
OS 10.535 5.155
OS 10.53 5.15
OS 10.46 5.15
OS 10.455 5.155
OS 10.455 5.205
OS 10.46 5.21
OS 10.53 5.21
OE
SE
S P 0
OB 10.53 5.29 I
OS 10.535 5.285
OS 10.535 5.235
OS 10.53 5.23
OS 10.46 5.23
OS 10.455 5.235
OS 10.455 5.285
OS 10.46 5.29
OS 10.53 5.29
OE
SE
S P 0
OB 12.01 4.98 I
OS 12.015 4.985
OS 12.065 4.985
OS 12.07 4.98
OS 12.07 4.91
OS 12.065 4.905
OS 12.015 4.905
OS 12.01 4.91
OS 12.01 4.98
OE
SE
S P 0
OB 12.17 4.98 I
OS 12.175 4.985
OS 12.225 4.985
OS 12.23 4.98
OS 12.23 4.91
OS 12.225 4.905
OS 12.175 4.905
OS 12.17 4.91
OS 12.17 4.98
OE
SE
S P 0
OB 2.777330019685 4.893469980315 I
OS 2.7688 4.902
OS 2.7688 4.9342
OS 2.7746 4.94355
OS 3.51805 4.94355
OS 3.5296 4.932
OS 3.5296 4.91
OS 3.5166 4.893469980315
OS 2.777330019685 4.893469980315
OE
SE
S P 0
OB 1.612730019685 4.893469980315 I
OS 1.6042 4.902
OS 1.6042 4.9342
OS 1.61 4.94355
OS 2.35345 4.94355
OS 2.365 4.932
OS 2.365 4.91
OS 2.352 4.893469980315
OS 1.612730019685 4.893469980315
OE
SE
S P 0
OB 7.616269980315 4.893469980315 I
OS 7.60773996063 4.902
OS 7.60773996063 4.9342
OS 7.61353996063 4.94355
OS 8.35698996063 4.94355
OS 8.36853996063 4.932
OS 8.36853996063 4.91
OS 8.35553996063 4.893469980315
OS 7.616269980315 4.893469980315
OE
SE
S P 0
OB 8.780869980315 4.893469980315 I
OS 8.77233996063 4.902
OS 8.77233996063 4.9342
OS 8.77813996063 4.94355
OS 9.52158996063 4.94355
OS 9.53313996063 4.932
OS 9.53313996063 4.91
OS 9.52013996063 4.893469980315
OS 8.780869980315 4.893469980315
OE
SE
S P 0
OB 10.78 5.565 I
OS 10.8 5.585
OS 12.19 5.585
OS 12.205 5.57
OS 12.205 5.42
OS 12.19 5.405
OS 10.8 5.405
OS 10.78 5.425
OS 10.78 5.565
OE
SE
P 2.22106004 3.54115 10 P 0 0;2,4=11,6=0
L 2.22106004 3.54115 2.24606004 3.56615 5 P 0 
P 2.24606004 3.56615 8 P 0 0;4=12,6=1
P 8.2 3.26615 8 P 0 0;4=12,6=1
P 8.175 3.24115 10 P 0 0;2,4=11,6=0
L 8.2 3.26615 8.175 3.24115 5 P 0 
L 7.66023996 4.97913996 7.66023996 5.0017 2 P 0 
L 7.66023996 5.0017 7.66648996 5.00795 2 P 0 
L 7.66648996 5.00795 7.66648996 5.03905 2 P 0 
L 7.66648996 5.03905 7.65203996 5.0535 2 P 0 
P 7.65203996 5.0535 8 P 0 0;4=12,6=1
P 7.66023996 4.97913996 36 P 0 0;2,4=1,6=0
L 2.29606004 2.86615 2.27106004 2.84115 2 P 0 
P 2.27106004 2.84115 10 P 0 0;2,4=11,6=0
P 2.29606004 2.86615 8 P 0 0;4=12,6=1
L 2.27106004 3.54115 2.29606004 3.56615 5 P 0 
P 2.27106004 3.54115 10 P 0 0;2,4=11,6=0
P 2.29606004 3.56615 8 P 0 0;4=12,6=1
P 7.68386004 4.97913996 36 P 0 0;2,4=1,6=0
P 7.69203996 5.0535 8 P 0 0;4=12,6=1
L 7.68386004 4.97913996 7.68386004 5.00168002 2 P 0 
L 7.68386004 5.00168002 7.67758996 5.00795 2 P 0 
L 7.67758996 5.00795 7.67758996 5.03905 2 P 0 
L 7.67758996 5.03905 7.69203996 5.0535 2 P 0 
P 8.2 3.31615 8 P 0 0;4=12,6=1
P 8.175 3.29115 10 P 0 0;2,4=11,6=0
L 8.2 3.31615 8.175 3.29115 5 P 0 
L 1.33906004 4.69351004 1.33906004 4.71351004 5 P 0 
L 1.33906004 4.71351004 1.30186004 4.75071004 5 P 0 
L 1.30186004 4.75071004 1.30186004 4.79681998 5 P 0 
L 1.33906004 4.66551004 1.33906004 4.69351004 5 P 0 
P 1.33906004 4.69351004 9 P 0 0;4=0,6=1
P 1.30186004 4.79681998 38 P 0 0;2,4=20,6=0
P 1.33906004 4.66551004 28 P 0 0;2,4=4,6=0
L 0.80806998 5.46193996 0.80806998 5.53641998 5 P 0 
L 0.83 5.417 0.83 5.44001004 5 P 0 
L 0.83 5.44001004 0.80806998 5.46193996 5 P 0 
L 0.68 5.147 0.68 5.19 5 P 0 
L 0.68 5.19 0.665 5.205 5 P 0 
L 0.665 5.205 0.665 5.3 5 P 0 
L 0.665 5.3 0.68 5.315 5 P 0 
L 0.68 5.315 0.775 5.315 5 P 0 
L 0.775 5.315 0.795 5.335 5 P 0 
L 0.795 5.335 0.795 5.405 5 P 0 
L 0.795 5.405 0.807 5.417 5 P 0 
L 0.807 5.417 0.83 5.417 5 P 0 
P 0.80806998 5.53641998 48 P 0 0;2,4=16,6=0
P 0.83 5.417 28 P 0 0;2,4=4,6=0
P 0.68 5.147 28 P 0 0;2,4=4,6=0
P 0.80806998 5.46193996 9 P 0 0;4=0,6=1
L 3.733 5.075 3.726 5.068 5 P 0 
L 3.726 5.068 3.726 4.709 5 P 0 
L 3.726 4.709 3.77441004 4.66058996 5 P 0 
L 3.77441004 4.66058996 3.77441004 4.63965 5 P 0 
P 3.733 5.075 9 P 0 0;4=13,6=1
P 3.77441004 4.63965 37 P 0 0;2,4=8,6=0
L 1.28906004 4.69351004 1.28906004 4.72351004 5 P 0 
L 1.28906004 4.72351004 1.27626004 4.73631004 5 P 0 
L 1.27626004 4.73631004 1.27626004 4.79681998 5 P 0 
P 1.28906004 4.69351004 9 P 0 0;4=0,6=1
L 1.28906004 4.66551004 1.28906004 4.69351004 5 P 0 
P 1.28906004 4.66551004 28 P 0 0;2,4=4,6=0
P 1.27626004 4.79681998 38 P 0 0;2,4=20,6=0
P 8.2 3.41615 8 P 0 0;4=12,6=1
P 8.175 3.39115 10 P 0 0;2,4=11,6=0
L 8.2 3.41615 8.175 3.39115 5 P 0 
L 7.87283996 4.97913996 7.87283996 5.0023 2 P 0 
L 7.87283996 5.0023 7.8791 5.00856004 2 P 0 
L 7.8791 5.00856004 7.8791 5.15455 2 P 0 
L 7.8791 5.15455 7.86465 5.169 2 P 0 
P 7.86465 5.169 8 P 0 0;4=12,6=1
P 7.87283996 4.97913996 36 P 0 0;2,4=1,6=0
L 3.94 4.765 3.94 4.717 5 P 0 
L 3.9399 4.79498996 3.9399 4.7651 5 P 0 
L 3.9399 4.7651 3.94 4.765 5 P 0 
L 3.99965 4.71558996 3.94141004 4.71558996 5 P 0 
L 3.94141004 4.71558996 3.94 4.717 5 P 0 
P 3.9399 4.79498996 28 P 0 0;2,4=4,6=0
P 3.94 4.765 9 P 0 0;4=0,6=1
P 3.94 4.717 28 P 0 0;2,4=4,6=0
P 3.99965 4.71558996 47 P 0 0;2,4=8,6=0
P 2.34606004 3.26615 8 P 0 0;4=12,6=1
P 2.32106004 3.24115 10 P 0 0;2,4=11,6=0
L 2.34606004 3.26615 2.32106004 3.24115 5 P 0 
P 2.39716998 4.742 8 P 0 0;4=12,6=1
L 2.38898002 4.85788002 2.38898002 4.83598002 2 P 0 
L 2.38898002 4.83598002 2.38271998 4.82971998 2 P 0 
L 2.38271998 4.82971998 2.38271998 4.75645 2 P 0 
L 2.38271998 4.75645 2.39716998 4.742 2 P 0 
P 2.38898002 4.85788002 36 P 0 0;2,4=1,6=0
P 8.2 3.46615 8 P 0 0;4=12,6=1
P 8.175 3.44115 10 P 0 0;2,4=11,6=0
L 8.2 3.46615 8.175 3.44115 5 P 0 
L 7.89646004 4.97913996 7.89646004 5.00208002 2 P 0 
L 7.89646004 5.00208002 7.8902 5.00833996 2 P 0 
L 7.8902 5.00833996 7.8902 5.15455 2 P 0 
L 7.8902 5.15455 7.90465 5.169 2 P 0 
P 7.90465 5.169 8 P 0 0;4=12,6=1
P 7.89646004 4.97913996 36 P 0 0;2,4=1,6=0
P 2.06646004 5.29 9 P 0 0;4=0,6=1
L 2.03465 4.97913996 2.03465 5.00915 5 P 0 
L 2.03465 5.00915 2.03178002 5.01201998 5 P 0 
L 2.03178002 5.01201998 2.03178002 5.11821998 5 P 0 
L 2.03178002 5.11821998 2.01146004 5.13853996 5 P 0 
L 2.01146004 5.13853996 2.01146004 5.235 5 P 0 
L 2.01146004 5.235 2.06646004 5.29 5 P 0 
P 2.03465 4.97913996 36 P 0 0;2,4=1,6=0
L 2.36536004 4.85788002 2.36536004 4.83563996 2 P 0 
L 2.36536004 4.83563996 2.37161998 4.82938002 2 P 0 
L 2.37161998 4.82938002 2.37161998 4.75645 2 P 0 
L 2.37161998 4.75645 2.35716998 4.742 2 P 0 
P 2.34606004 3.31615 8 P 0 0;4=12,6=1
P 2.32106004 3.29115 10 P 0 0;2,4=11,6=0
L 2.34606004 3.31615 2.32106004 3.29115 5 P 0 
P 2.35716998 4.742 8 P 0 0;4=12,6=1
P 2.36536004 4.85788002 36 P 0 0;2,4=1,6=0
L 1.33906004 5.12551004 1.33906004 5.15351004 5 P 0 
P 1.33906004 5.15351004 9 P 0 0;4=0,6=1
P 1.33906004 5.12551004 28 P 0 0;2,4=4,6=0
P 3.105 4.47 9 P 0 0;4=13,6=1
L 3.105 4.47 3.1034 4.47 5 P 0 
L 3.1034 4.47 3.0957 4.4777 5 P 0 
L 3.0957 4.4777 3.0957 4.49523996 5 P 0 
L 3.0957 4.49523996 3.145 4.54453996 5 P 0 
L 3.145 4.54453996 3.145 4.71746004 5 P 0 
L 3.145 4.71746004 3.12746004 4.735 5 P 0 
L 3.12746004 4.735 3.12746004 4.82201004 5 P 0 
L 3.12746004 4.82201004 3.12838996 4.82293996 5 P 0 
L 3.12838996 4.82293996 3.12838996 4.85788002 5 P 0 
P 3.12838996 4.85788002 36 P 0 0;2,4=1,6=0
P 8 3.46615 8 P 0 0;4=12,6=1
P 8.025 3.44115 10 P 0 0;2,4=11,6=0
L 8 3.46615 8.025 3.44115 5 P 0 
L 7.94371004 4.97913996 7.94371004 5.00118002 2 P 0 
L 7.94371004 5.00118002 7.94996004 5.00743002 2 P 0 
L 7.94996004 5.00743002 7.94996004 5.03905 2 P 0 
L 7.94996004 5.03905 7.93551004 5.0535 2 P 0 
P 7.93551004 5.0535 8 P 0 0;4=12,6=1
P 7.94371004 4.97913996 36 P 0 0;2,4=1,6=0
L 2.01103002 4.97913996 2.01103002 5.00913996 5 P 0 
L 2.01103002 5.00913996 2.01391004 5.01201998 5 P 0 
L 2.01391004 5.01201998 2.01391004 5.03398002 5 P 0 
L 2.01391004 5.03398002 2.01381998 5.03406998 5 P 0 
L 2.01381998 5.03406998 2.01381998 5.09983002 5 P 0 
L 2.01381998 5.09983002 1.985 5.12865 5 P 0 
L 1.985 5.12865 1.985 5.27353996 5 P 0 
L 1.985 5.27353996 2.00146004 5.29 5 P 0 
P 2.00146004 5.29 9 P 0 0;4=0,6=1
P 2.01103002 4.97913996 36 P 0 0;2,4=1,6=0
P 2.31811998 4.85788002 36 P 0 0;2,4=1,6=0
L 2.31811998 4.85788002 2.31811998 4.83511998 2 P 0 
L 2.31811998 4.83511998 2.31186004 4.82886004 2 P 0 
L 2.31186004 4.82886004 2.31186004 4.72886004 2 P 0 
L 2.31186004 4.72886004 2.287 4.704 2 P 0 
L 2.287 4.704 2.2581 4.704 2 P 0 
L 2.2581 4.704 2.2441 4.69 2 P 0 
L 2.2441 4.69 2.2441 4.68145 2 P 0 
L 2.2441 4.68145 2.25855 4.667 2 P 0 
P 2.25855 4.667 8 P 0 0;4=12,6=1
L 2.39606004 3.31615 2.37106004 3.29115 5 P 0 
P 2.37106004 3.29115 10 P 0 0;2,4=11,6=0
P 2.39606004 3.31615 8 P 0 0;4=12,6=1
P 1.18906004 5.12551004 28 P 0 0;2,4=4,6=0
P 1.18906004 5.15351004 9 P 0 0;4=0,6=1
L 1.18906004 5.12551004 1.18906004 5.15351004 5 P 0 
P 3.07 4.42 9 P 0 0;4=13,6=1
L 3.07 4.42 3.07 4.50588996 5 P 0 
L 3.07 4.50588996 3.1193 4.55518996 5 P 0 
L 3.1193 4.55518996 3.1193 4.70681004 5 P 0 
L 3.1193 4.70681004 3.10346004 4.72265 5 P 0 
L 3.10346004 4.72265 3.10346004 4.826 5 P 0 
L 3.10346004 4.826 3.10476998 4.82731004 5 P 0 
L 3.10476998 4.82731004 3.10476998 4.85788002 5 P 0 
P 3.10476998 4.85788002 36 P 0 0;2,4=1,6=0
P 8 3.51615 8 P 0 0;4=12,6=1
P 8.025 3.49115 10 P 0 0;2,4=11,6=0
L 8 3.51615 8.025 3.49115 5 P 0 
L 7.96733002 4.97913996 7.96733002 5.00221998 2 P 0 
L 7.96733002 5.00221998 7.96106004 5.00848996 2 P 0 
L 7.96106004 5.00848996 7.96106004 5.03905 2 P 0 
L 7.96106004 5.03905 7.97551004 5.0535 2 P 0 
P 7.97551004 5.0535 8 P 0 0;4=12,6=1
P 7.96733002 4.97913996 36 P 0 0;2,4=1,6=0
P 2.2945 4.85788002 36 P 0 0;2,4=1,6=0
P 2.21855 4.667 8 P 0 0;4=12,6=1
L 2.2945 4.85788002 2.2945 4.8355 2 P 0 
L 2.2945 4.8355 2.30076004 4.82923996 2 P 0 
L 2.30076004 4.82923996 2.30076004 4.73346004 2 P 0 
L 2.30076004 4.73346004 2.2824 4.7151 2 P 0 
L 2.2824 4.7151 2.2535 4.7151 2 P 0 
L 2.2535 4.7151 2.233 4.6946 2 P 0 
L 2.233 4.6946 2.233 4.68145 2 P 0 
L 2.233 4.68145 2.21855 4.667 2 P 0 
L 2.39606004 3.36615 2.37106004 3.34115 5 P 0 
P 2.37106004 3.34115 10 P 0 0;2,4=11,6=0
P 2.39606004 3.36615 8 P 0 0;4=12,6=1
P 8.10906004 4.97913996 36 P 0 0;2,4=1,6=0
P 8.11725 5.169 8 P 0 0;4=12,6=1
L 8.10906004 4.97913996 8.10906004 5.00148002 2 P 0 
L 8.10906004 5.00148002 8.1028 5.00773996 2 P 0 
L 8.1028 5.00773996 8.1028 5.15455 2 P 0 
L 8.1028 5.15455 8.11725 5.169 2 P 0 
P 8.4 3.46615 8 P 0 0;4=12,6=1
P 8.375 3.44115 10 P 0 0;2,4=11,6=0
L 8.4 3.46615 8.375 3.44115 5 P 0 
L 3.635 0.715 3.635 0.7326 5 P 0 
L 3.635 0.7326 3.6265 0.7411 5 P 0 
L 3.6265 0.7411 3.60998996 0.7411 5 P 0 
L 3.60998996 0.62931998 3.60998996 0.68998996 5 P 0 
L 3.60998996 0.68998996 3.635 0.715 5 P 0 
P 3.60998996 0.62931998 43 P 0 0;2,4=28,6=0
P 3.635 0.715 9 P 0 0;4=0,6=1
P 3.60998996 0.7411 28 P 0 0;2,4=4,6=0
P 4.65768002 2.84115 10 P 0 0;2,4=11,6=0
L 4.65768002 2.84115 4.63268002 2.81615 5 P 0 
P 4.63268002 2.81615 8 P 0 0;4=12,6=1
L 2.38898002 4.97913996 2.38898002 5.00201998 2 P 0 
L 2.38898002 5.00201998 2.38271998 5.00828002 2 P 0 
L 2.38271998 5.00828002 2.38271998 5.10055 2 P 0 
L 2.38271998 5.10055 2.39716998 5.115 2 P 0 
L 2.44606004 3.26615 2.42106004 3.24115 5 P 0 
P 2.42106004 3.24115 10 P 0 0;2,4=11,6=0
P 2.44606004 3.26615 8 P 0 0;4=12,6=1
P 2.39716998 5.115 8 P 0 0;4=12,6=1
P 2.38898002 4.97913996 36 P 0 0;2,4=1,6=0
L 8.08543996 4.97913996 8.08543996 5.0009 2 P 0 
L 8.08543996 5.0009 8.0917 5.00716004 2 P 0 
L 8.0917 5.00716004 8.0917 5.15455 2 P 0 
L 8.0917 5.15455 8.07725 5.169 2 P 0 
P 8.07725 5.169 8 P 0 0;4=12,6=1
P 8.08543996 4.97913996 36 P 0 0;2,4=1,6=0
P 8.4 3.51615 8 P 0 0;4=12,6=1
P 8.375 3.49115 10 P 0 0;2,4=11,6=0
L 8.4 3.51615 8.375 3.49115 5 P 0 
L 2.36536004 4.97913996 2.36536004 5.00236004 2 P 0 
L 2.36536004 5.00236004 2.37161998 5.00861998 2 P 0 
L 2.37161998 5.00861998 2.37161998 5.10055 2 P 0 
L 2.37161998 5.10055 2.35716998 5.115 2 P 0 
L 2.44606004 3.31615 2.42106004 3.29115 5 P 0 
P 2.42106004 3.29115 10 P 0 0;2,4=11,6=0
P 2.44606004 3.31615 8 P 0 0;4=12,6=1
P 2.35716998 5.115 8 P 0 0;4=12,6=1
P 2.36536004 4.97913996 36 P 0 0;2,4=1,6=0
L 8.5 3.46615 8.475 3.44115 5 P 0 
P 8.475 3.44115 10 P 0 0;2,4=11,6=0
P 8.5 3.46615 8 P 0 0;4=12,6=1
P 8.03818996 4.85788002 36 P 0 0;2,4=1,6=0
P 8.07206998 4.66688996 8 P 0 0;4=12,6=1
L 8.03818996 4.85788002 8.03818996 4.83563996 2 P 0 
L 8.03818996 4.83563996 8.03193002 4.82938002 2 P 0 
L 8.03193002 4.82938002 8.03193002 4.73661998 2 P 0 
L 8.03193002 4.73661998 8.05761998 4.71093002 2 P 0 
L 8.05761998 4.71093002 8.05761998 4.68133996 2 P 0 
L 8.05761998 4.68133996 8.07206998 4.66688996 2 P 0 
P 2.25543996 4.78291998 8 P 0 0;4=12,6=1
L 2.24725 4.85788002 2.24725 4.83526004 2 P 0 
L 2.24725 4.83526004 2.24098996 4.829 2 P 0 
L 2.24098996 4.829 2.24098996 4.79736998 2 P 0 
L 2.24098996 4.79736998 2.25543996 4.78291998 2 P 0 
L 2.49606004 3.31615 2.47106004 3.29115 5 P 0 
P 2.47106004 3.29115 10 P 0 0;2,4=11,6=0
P 2.49606004 3.31615 8 P 0 0;4=12,6=1
P 2.24725 4.85788002 36 P 0 0;2,4=1,6=0
L 8.5 3.51615 8.475 3.49115 5 P 0 
P 8.475 3.49115 10 P 0 0;2,4=11,6=0
P 8.5 3.51615 8 P 0 0;4=12,6=1
P 8.01456998 4.85788002 36 P 0 0;2,4=1,6=0
P 8.03206998 4.66688996 8 P 0 0;4=12,6=1
L 8.01456998 4.85788002 8.01456998 4.83498002 2 P 0 
L 8.01456998 4.83498002 8.02083002 4.82871998 2 P 0 
L 8.02083002 4.82871998 8.02083002 4.73201998 2 P 0 
L 8.02083002 4.73201998 8.04651998 4.70633002 2 P 0 
L 8.04651998 4.70633002 8.04651998 4.68133996 2 P 0 
L 8.04651998 4.68133996 8.03206998 4.66688996 2 P 0 
L 4.03666998 5.18321004 4.03666998 5.30176004 5 P 0 
L 4.03666998 5.30176004 4.0599 5.32498996 5 P 0 
P 4.03666998 5.18321004 38 P 0 0;2,4=20,6=0
P 4.0599 5.32498996 28 P 0 0;2,4=4,6=0
P 4.02 4.42 9 P 0 0;4=0,6=1
L 4.02 4.42 4.1838 4.5838 5 P 0 
L 4.1838 4.5838 4.1838 4.855 5 P 0 
L 4.1838 4.855 4.07 4.9688 5 P 0 
L 4.07 4.9688 4.07 5.31488996 5 P 0 
L 4.07 5.31488996 4.0599 5.32498996 5 P 0 
P 4.60768002 2.79115 10 P 0 0;2,4=11,6=0
L 4.60768002 2.79115 4.58268002 2.76615 5 P 0 
P 4.58268002 2.76615 8 P 0 0;4=12,6=1
L 2.22363002 4.85788002 2.22361998 4.85786998 2 P 0 
L 2.22361998 4.85786998 2.22361998 4.83538002 2 P 0 
L 2.22361998 4.83538002 2.22988996 4.82911004 2 P 0 
L 2.22988996 4.82911004 2.22988996 4.79736998 2 P 0 
L 2.22988996 4.79736998 2.21543996 4.78291998 2 P 0 
P 2.21543996 4.78291998 8 P 0 0;4=12,6=1
L 2.49606004 3.36615 2.47106004 3.34115 5 P 0 
P 2.47106004 3.34115 10 P 0 0;2,4=11,6=0
P 2.49606004 3.36615 8 P 0 0;4=12,6=1
P 2.22363002 4.85788002 36 P 0 0;2,4=1,6=0
L 8.35 3.41615 8.325 3.39115 5 P 0 
P 8.325 3.39115 10 P 0 0;2,4=11,6=0
P 8.35 3.41615 8 P 0 0;4=12,6=1
P 8.10906004 4.85788002 36 P 0 0;2,4=1,6=0
P 8.11725 4.78291998 8 P 0 0;4=12,6=1
L 8.10906004 4.85788002 8.10906004 4.83551998 2 P 0 
L 8.10906004 4.83551998 8.1028 4.82926004 2 P 0 
L 8.1028 4.82926004 8.1028 4.79736998 2 P 0 
L 8.1028 4.79736998 8.11725 4.78291998 2 P 0 
P 4.80768002 2.74115 10 P 0 0;2,4=11,6=0
L 4.80768002 2.74115 4.78268002 2.71615 5 P 0 
P 4.78268002 2.71615 8 P 0 0;4=12,6=1
P 2.10551998 4.85788002 36 P 0 0;2,4=1,6=0
P 2.11371004 4.78291998 8 P 0 0;4=12,6=1
L 2.10551998 4.85788002 2.10551998 4.83551998 2 P 0 
L 2.10551998 4.83551998 2.09926004 4.82926004 2 P 0 
L 2.09926004 4.82926004 2.09926004 4.79736998 2 P 0 
L 2.09926004 4.79736998 2.11371004 4.78291998 2 P 0 
P 2.34606004 3.41615 8 P 0 0;4=12,6=1
P 2.32106004 3.39115 10 P 0 0;2,4=11,6=0
L 2.34606004 3.41615 2.32106004 3.39115 5 P 0 
L 8.35 3.46615 8.325 3.44115 5 P 0 
P 8.325 3.44115 10 P 0 0;2,4=11,6=0
P 8.35 3.46615 8 P 0 0;4=12,6=1
P 8.08543996 4.85788002 36 P 0 0;2,4=1,6=0
P 8.07725 4.78291998 8 P 0 0;4=12,6=1
L 8.08543996 4.85788002 8.08543002 4.85786998 2 P 0 
L 8.08543002 4.85786998 8.08543002 4.83511998 2 P 0 
L 8.08543002 4.83511998 8.0917 4.82885 2 P 0 
L 8.0917 4.82885 8.0917 4.79736998 2 P 0 
L 8.0917 4.79736998 8.07725 4.78291998 2 P 0 
L 4.06 4.86 4.06 4.874 5 P 0 
L 4.06 4.874 4.01108002 4.92291998 5 P 0 
L 4.01108002 4.92291998 4.01108002 4.96076998 5 P 0 
L 4.0399 4.82898996 4.06 4.84908996 5 P 0 
L 4.06 4.84908996 4.06 4.86 5 P 0 
P 5.05768002 2.74115 10 P 0 0;2,4=11,6=0
L 5.05768002 2.74115 5.08268002 2.71615 5 P 0 
P 5.08268002 2.71615 8 P 0 0;4=12,6=1
P 4.01108002 4.96076998 38 P 0 0;2,4=20,6=0
P 4.0399 4.82898996 28 P 0 0;2,4=4,6=0
P 4.06 4.86 9 P 0 0;4=0,6=1
P 2.0819 4.85788002 36 P 0 0;2,4=1,6=0
P 2.07371004 4.78291998 8 P 0 0;4=12,6=1
L 2.0819 4.85788002 2.08188996 4.85786998 2 P 0 
L 2.08188996 4.85786998 2.08188996 4.83511998 2 P 0 
L 2.08188996 4.83511998 2.08816004 4.82885 2 P 0 
L 2.08816004 4.82885 2.08816004 4.79736998 2 P 0 
L 2.08816004 4.79736998 2.07371004 4.78291998 2 P 0 
P 2.34606004 3.46615 8 P 0 0;4=12,6=1
P 2.32106004 3.44115 10 P 0 0;2,4=11,6=0
L 2.34606004 3.46615 2.32106004 3.44115 5 P 0 
P 2.17638996 4.97913996 36 P 0 0;2,4=1,6=0
P 2.18456998 5.0535 8 P 0 0;4=12,6=1
L 2.17638996 4.97913996 2.17638996 5.00161998 2 P 0 
L 2.17638996 5.00161998 2.17011998 5.00788996 2 P 0 
L 2.17011998 5.00788996 2.17011998 5.03905 2 P 0 
L 2.17011998 5.03905 2.18456998 5.0535 2 P 0 
P 2.44606004 3.41615 8 P 0 0;4=12,6=1
P 2.42106004 3.39115 10 P 0 0;2,4=11,6=0
L 2.44606004 3.41615 2.42106004 3.39115 5 P 0 
L 10.91161004 2.44115 10.93661004 2.41615 5 P 0 
P 10.93661004 2.41615 8 P 0 0;4=12,6=1
P 10.91161004 2.44115 10 P 0 0;2,4=11,6=0
P 2.15276004 4.97913996 36 P 0 0;2,4=1,6=0
P 2.14456998 5.0535 8 P 0 0;4=12,6=1
L 2.15276004 4.97913996 2.15276998 4.97915 2 P 0 
L 2.15276998 4.97915 2.15276998 5.00078002 2 P 0 
L 2.15276998 5.00078002 2.15901998 5.00703002 2 P 0 
L 2.15901998 5.00703002 2.15901998 5.03905 2 P 0 
L 2.15901998 5.03905 2.14456998 5.0535 2 P 0 
L 2.44606004 3.46615 2.42106004 3.44115 5 P 0 
P 2.42106004 3.44115 10 P 0 0;2,4=11,6=0
P 2.44606004 3.46615 8 P 0 0;4=12,6=1
L 10.91161004 2.49115 10.93661004 2.46615 5 P 0 
P 10.93661004 2.46615 8 P 0 0;4=12,6=1
P 10.91161004 2.49115 10 P 0 0;2,4=11,6=0
P 8.5 3.31615 8 P 0 0;4=12,6=1
P 8.475 3.29115 10 P 0 0;2,4=11,6=0
L 8.5 3.31615 8.475 3.29115 5 P 0 
P 8.25078996 4.85788002 36 P 0 0;2,4=1,6=0
P 8.25898002 4.78291998 8 P 0 0;4=12,6=1
L 8.25078996 4.85788002 8.25078996 4.83526004 2 P 0 
L 8.25078996 4.83526004 8.24453002 4.829 2 P 0 
L 8.24453002 4.829 8.24453002 4.79736998 2 P 0 
L 8.24453002 4.79736998 8.25898002 4.78291998 2 P 0 
L 4.85768002 2.74115 4.88268002 2.71615 5 P 0 
P 4.85768002 2.74115 10 P 0 0;2,4=11,6=0
P 4.88268002 2.71615 8 P 0 0;4=12,6=1
P 2.06853002 4.66688996 8 P 0 0;4=12,6=1
L 2.03465 4.85788002 2.03465 4.83563996 2 P 0 
L 2.03465 4.83563996 2.02838996 4.82938002 2 P 0 
L 2.02838996 4.82938002 2.02838996 4.73661998 2 P 0 
L 2.02838996 4.73661998 2.05408002 4.71093002 2 P 0 
L 2.05408002 4.71093002 2.05408002 4.68133996 2 P 0 
L 2.05408002 4.68133996 2.06853002 4.66688996 2 P 0 
P 2.03465 4.85788002 36 P 0 0;2,4=1,6=0
L 2.49606004 3.46615 2.47106004 3.44115 5 P 0 
P 2.47106004 3.44115 10 P 0 0;2,4=11,6=0
P 2.49606004 3.46615 8 P 0 0;4=12,6=1
P 8.5 3.36615 8 P 0 0;4=12,6=1
P 8.475 3.34115 10 P 0 0;2,4=11,6=0
L 8.5 3.36615 8.475 3.34115 5 P 0 
P 8.22716998 4.85788002 36 P 0 0;2,4=1,6=0
P 8.21898002 4.78291998 8 P 0 0;4=12,6=1
L 8.22716998 4.85788002 8.22716004 4.85786998 2 P 0 
L 8.22716004 4.85786998 8.22716004 4.83538002 2 P 0 
L 8.22716004 4.83538002 8.23343002 4.82911004 2 P 0 
L 8.23343002 4.82911004 8.23343002 4.79736998 2 P 0 
L 8.23343002 4.79736998 8.21898002 4.78291998 2 P 0 
L 2.01103002 4.85788002 2.01103002 4.83498002 2 P 0 
L 2.01103002 4.83498002 2.01728996 4.82871998 2 P 0 
L 2.01728996 4.82871998 2.01728996 4.73201998 2 P 0 
L 2.01728996 4.73201998 2.04298002 4.70633002 2 P 0 
L 2.04298002 4.70633002 2.04298002 4.68133996 2 P 0 
L 2.04298002 4.68133996 2.02853002 4.66688996 2 P 0 
P 2.02853002 4.66688996 8 P 0 0;4=12,6=1
P 2.01103002 4.85788002 36 P 0 0;2,4=1,6=0
L 2.49606004 3.51615 2.47106004 3.49115 5 P 0 
P 2.47106004 3.49115 10 P 0 0;2,4=11,6=0
P 2.49606004 3.51615 8 P 0 0;4=12,6=1
P 8.4 3.31615 8 P 0 0;4=12,6=1
P 8.375 3.29115 10 P 0 0;2,4=11,6=0
L 8.4 3.31615 8.375 3.29115 5 P 0 
P 8.32166004 4.85788002 36 P 0 0;2,4=1,6=0
P 8.26208996 4.667 8 P 0 0;4=12,6=1
L 8.32166004 4.85788002 8.32166004 4.83511998 2 P 0 
L 8.32166004 4.83511998 8.3154 4.82886004 2 P 0 
L 8.3154 4.82886004 8.3154 4.72886004 2 P 0 
L 8.3154 4.72886004 8.29053996 4.704 2 P 0 
L 8.29053996 4.704 8.26163996 4.704 2 P 0 
L 8.26163996 4.704 8.24763996 4.69 2 P 0 
L 8.24763996 4.69 8.24763996 4.68145 2 P 0 
L 8.24763996 4.68145 8.26208996 4.667 2 P 0 
P 2.10551998 4.97913996 36 P 0 0;2,4=1,6=0
P 2.11371004 5.169 8 P 0 0;4=12,6=1
L 2.10551998 4.97913996 2.10551998 5.00148002 2 P 0 
L 2.10551998 5.00148002 2.09926004 5.00773996 2 P 0 
L 2.09926004 5.00773996 2.09926004 5.15455 2 P 0 
L 2.09926004 5.15455 2.11371004 5.169 2 P 0 
P 2.39606004 3.46615 8 P 0 0;4=12,6=1
P 2.37106004 3.44115 10 P 0 0;2,4=11,6=0
L 2.39606004 3.46615 2.37106004 3.44115 5 P 0 
P 8.4 3.36615 8 P 0 0;4=12,6=1
P 8.375 3.34115 10 P 0 0;2,4=11,6=0
L 8.4 3.36615 8.375 3.34115 5 P 0 
P 8.29803996 4.85788002 36 P 0 0;2,4=1,6=0
P 8.22208996 4.667 8 P 0 0;4=12,6=1
L 8.29803996 4.85788002 8.29803996 4.8355 2 P 0 
L 8.29803996 4.8355 8.3043 4.82923996 2 P 0 
L 8.3043 4.82923996 8.3043 4.73346004 2 P 0 
L 8.3043 4.73346004 8.28593996 4.7151 2 P 0 
L 8.28593996 4.7151 8.25703996 4.7151 2 P 0 
L 8.25703996 4.7151 8.23653996 4.6946 2 P 0 
L 8.23653996 4.6946 8.23653996 4.68145 2 P 0 
L 8.23653996 4.68145 8.22208996 4.667 2 P 0 
L 3.84 0.69 3.84 0.72108996 5 P 0 
L 3.84 0.72108996 3.81998996 0.7411 5 P 0 
L 3.84 0.69 3.84 0.685 5 P 0 
L 3.84 0.685 3.80998996 0.65498996 5 P 0 
L 3.80998996 0.65498996 3.80998996 0.62931998 5 P 0 
P 3.81998996 0.7411 28 P 0 0;2,4=4,6=0
P 3.80998996 0.62931998 43 P 0 0;2,4=28,6=0
P 3.84 0.69 9 P 0 0;4=0,6=1
P 4.70768002 2.79115 10 P 0 0;2,4=11,6=0
L 4.70768002 2.79115 4.68268002 2.76615 5 P 0 
P 4.68268002 2.76615 8 P 0 0;4=12,6=1
P 2.0819 4.97913996 36 P 0 0;2,4=1,6=0
P 2.07371004 5.169 8 P 0 0;4=12,6=1
L 2.0819 4.97913996 2.0819 5.0009 2 P 0 
L 2.0819 5.0009 2.08816004 5.00716004 2 P 0 
L 2.08816004 5.00716004 2.08816004 5.15455 2 P 0 
L 2.08816004 5.15455 2.07371004 5.169 2 P 0 
L 2.39606004 3.51615 2.37106004 3.49115 5 P 0 
P 2.37106004 3.49115 10 P 0 0;2,4=11,6=0
P 2.39606004 3.51615 8 P 0 0;4=12,6=1
P 3.75998996 0.62931998 43 P 0 0;2,4=28,6=0
P 3.56 0.49 9 P 0 0;4=0,6=1
L 3.56 0.49 3.62 0.55 5 P 0 
L 3.62 0.55 3.735 0.55 5 P 0 
L 3.735 0.55 3.75998996 0.57498996 5 P 0 
L 3.75998996 0.57498996 3.75998996 0.62931998 5 P 0 
P 4.75768002 2.84115 10 P 0 0;2,4=11,6=0
L 4.75768002 2.84115 4.73268002 2.81615 5 P 0 
P 4.73268002 2.81615 8 P 0 0;4=12,6=1
L 1.58583996 4.97913996 1.58583996 5.00183996 2 P 0 
L 1.58583996 5.00183996 1.5921 5.0081 2 P 0 
L 1.5921 5.0081 1.5921 5.15455 2 P 0 
L 1.5921 5.15455 1.57765 5.169 2 P 0 
P 1.57765 5.169 8 P 0 0;4=12,6=1
L 2.04606004 3.31615 2.02106004 3.29115 5 P 0 
P 2.02106004 3.29115 10 P 0 0;2,4=11,6=0
P 2.04606004 3.31615 8 P 0 0;4=12,6=1
P 1.58583996 4.97913996 36 P 0 0;2,4=1,6=0
L 9.10853996 4.47 9.10693996 4.47 5 P 0 
L 9.10693996 4.47 9.09923996 4.4777 5 P 0 
L 9.09923996 4.4777 9.09923996 4.49523996 5 P 0 
L 9.09923996 4.49523996 9.14853996 4.54453996 5 P 0 
L 9.14853996 4.54453996 9.14853996 4.71746004 5 P 0 
L 9.14853996 4.71746004 9.131 4.735 5 P 0 
L 9.131 4.735 9.131 4.82201004 5 P 0 
L 9.131 4.82201004 9.13193002 4.82293996 5 P 0 
L 9.13193002 4.82293996 9.13193002 4.85788002 5 P 0 
P 9.10853996 4.47 9 P 0 0;4=13,6=1
P 7.3426 5.15351004 9 P 0 0;4=0,6=1
P 7.3426 5.12551004 28 P 0 0;2,4=4,6=0
L 7.3426 5.12551004 7.3426 5.15351004 5 P 0 
P 9.13193002 4.85788002 36 P 0 0;2,4=1,6=0
L 3.785 0.69 3.7339 0.7411 5 P 0 
L 3.7339 0.7411 3.66998996 0.7411 5 P 0 
L 3.65998996 0.62931998 3.65998996 0.68 5 P 0 
L 3.65998996 0.68 3.66998996 0.69 5 P 0 
L 3.66998996 0.69 3.66998996 0.7411 5 P 0 
P 3.66998996 0.7411 28 P 0 0;2,4=4,6=0
P 3.65998996 0.62931998 43 P 0 0;2,4=28,6=0
P 3.785 0.69 9 P 0 0;4=0,6=1
P 4.80768002 2.84115 10 P 0 0;2,4=11,6=0
L 4.80768002 2.84115 4.78268002 2.81615 5 P 0 
P 4.78268002 2.81615 8 P 0 0;4=12,6=1
P 1.61765 5.169 8 P 0 0;4=12,6=1
L 1.60946004 4.97913996 1.60946004 5.00153996 2 P 0 
L 1.60946004 5.00153996 1.6032 5.0078 2 P 0 
L 1.6032 5.0078 1.6032 5.15455 2 P 0 
L 1.6032 5.15455 1.61765 5.169 2 P 0 
L 2.04606004 3.36615 2.02106004 3.34115 5 P 0 
P 2.02106004 3.34115 10 P 0 0;2,4=11,6=0
P 2.04606004 3.36615 8 P 0 0;4=12,6=1
P 1.60946004 4.97913996 36 P 0 0;2,4=1,6=0
L 0.83 5.295 0.82983996 5.29483996 5 P 0 
L 0.82983996 5.29483996 0.82983996 5.2361 5 P 0 
L 0.88681004 5.53641998 0.88681004 5.46318996 5 P 0 
L 0.88681004 5.46318996 0.9 5.45 5 P 0 
L 0.9 5.45 0.9 5.417 5 P 0 
P 0.82983996 5.2361 35 P 0 0;2,4=10,6=0
P 0.9 5.417 28 P 0 0;2,4=4,6=0
P 0.88681004 5.53641998 48 P 0 0;2,4=16,6=0
P 0.83 5.295 11 P 0 0;3,4=6,6=1
L 0.83 5.295 0.83 5.305 5 P 0 
L 0.83 5.305 0.865 5.34 5 P 0 
L 0.865 5.34 0.865 5.4 5 P 0 
L 0.865 5.4 0.882 5.417 5 P 0 
L 0.882 5.417 0.9 5.417 5 P 0 
P 8.1 3.26615 8 P 0 0;4=12,6=1
P 8.075 3.24115 10 P 0 0;2,4=11,6=0
L 8.1 3.26615 8.075 3.24115 5 P 0 
L 7.58938002 4.85788002 7.58938002 4.83516004 2 P 0 
L 7.58938002 4.83516004 7.59563996 4.8289 2 P 0 
L 7.59563996 4.8289 7.59563996 4.72145 2 P 0 
L 7.59563996 4.72145 7.58118996 4.707 2 P 0 
P 7.58118996 4.707 8 P 0 0;4=12,6=1
P 7.58938002 4.85788002 36 P 0 0;2,4=1,6=0
L 1.58583996 4.85788002 1.58583996 4.83516004 2 P 0 
L 1.58583996 4.83516004 1.5921 4.8289 2 P 0 
L 1.5921 4.8289 1.5921 4.72145 2 P 0 
L 1.5921 4.72145 1.57765 4.707 2 P 0 
L 2.09606004 3.26615 2.07106004 3.24115 5 P 0 
P 2.07106004 3.24115 10 P 0 0;2,4=11,6=0
P 2.09606004 3.26615 8 P 0 0;4=12,6=1
P 1.57765 4.707 8 P 0 0;4=12,6=1
P 1.58583996 4.85788002 36 P 0 0;2,4=1,6=0
P 5.05768002 1.99115 10 P 0 0;2,4=11,6=0
L 5.08268002 1.96615 5.05768002 1.99115 5 P 0 
P 5.08268002 1.96615 8 P 0 0;4=12,6=1
P 8.1 3.31615 8 P 0 0;4=12,6=1
P 8.075 3.29115 10 P 0 0;2,4=11,6=0
L 8.1 3.31615 8.075 3.29115 5 P 0 
L 7.613 4.85788002 7.613 4.83546004 2 P 0 
L 7.613 4.83546004 7.60673996 4.8292 2 P 0 
L 7.60673996 4.8292 7.60673996 4.72145 2 P 0 
L 7.60673996 4.72145 7.62118996 4.707 2 P 0 
P 7.62118996 4.707 8 P 0 0;4=12,6=1
P 7.613 4.85788002 36 P 0 0;2,4=1,6=0
L 3.75998996 0.345 3.75998996 0.40688002 5 P 0 
L 3.75998996 0.3051 3.75998996 0.345 5 P 0 
P 3.75998996 0.3051 28 P 0 0;2,4=4,6=0
P 3.75998996 0.40688002 43 P 0 0;2,4=28,6=0
P 3.75998996 0.345 9 P 0 0;4=0,6=1
P 4.70768002 2.84115 10 P 0 0;2,4=11,6=0
L 4.70768002 2.84115 4.68268002 2.81615 5 P 0 
P 4.68268002 2.81615 8 P 0 0;4=12,6=1
L 1.60946004 4.85788002 1.60946004 4.83546004 2 P 0 
L 1.60946004 4.83546004 1.6032 4.8292 2 P 0 
L 1.6032 4.8292 1.6032 4.72145 2 P 0 
L 1.6032 4.72145 1.61765 4.707 2 P 0 
L 2.09606004 3.31615 2.07106004 3.29115 5 P 0 
P 2.07106004 3.29115 10 P 0 0;2,4=11,6=0
P 2.09606004 3.31615 8 P 0 0;4=12,6=1
P 1.61765 4.707 8 P 0 0;4=12,6=1
P 1.60946004 4.85788002 36 P 0 0;2,4=1,6=0
L 7.42603996 5.15895 7.4076 5.15895 7 P 0 
L 7.4076 5.15895 7.3926 5.14395 7 P 0 
L 7.3926 5.14395 7.3926 5.12551004 7 P 0 
L 0.52 5.591 0.58 5.591 7 P 0 
P 0.52 5.591 29 P 0 0;2,4=23,6=0
P 0.58 5.591 9 P 0 0;4=0,6=1
L 4.76 5.408 4.76 5.375 7 P 0 
P 11.67761998 2.85 9 P 0 0;4=13,6=1
P 11.865 4.455 9 P 0 0;4=0,6=1
P 5.67368996 2.85 9 P 0 0;4=13,6=1
P 5.855 3.07 9 P 0 0;4=13,6=1
P 5.8522 2.97 9 P 0 0;4=13,6=1
P 7.2926 5.15351004 9 P 0 0;4=13,6=1
P 7.2926 5.12551004 28 P 0 0;2,4=4,6=0
L 7.2926 5.12551004 7.2926 5.15351004 7 P 0 
P 7.2426 5.15351004 9 P 0 0;4=13,6=1
P 7.2426 5.12551004 28 P 0 0;2,4=4,6=0
L 7.2426 5.12551004 7.2426 5.15351004 7 P 0 
P 7.1926 4.95351004 9 P 0 0;4=13,6=1
L 7.1926 4.98151004 7.2106 4.98151004 7 P 0 
L 7.2106 4.98151004 7.22161004 4.99251998 7 P 0 
L 7.22161004 4.99251998 7.24358996 4.99251998 7 P 0 
L 7.24358996 4.99251998 7.25421004 4.9819 7 P 0 
L 7.25421004 4.9819 7.25421004 4.9602 7 P 0 
P 7.1926 4.98151004 28 P 0 0;2,4=4,6=0
P 7.25421004 4.9602 38 P 0 0;2,4=20,6=0
L 7.1926 4.98151004 7.1926 4.95351004 7 P 0 
P 7.42603996 5.15895 9 P 0 0;4=0,6=1
P 7.3926 5.12551004 28 P 0 0;2,4=4,6=0
L 3.94 4.655 3.94 4.683 7 P 0 
L 3.94 4.627 3.94 4.655 7 P 0 
P 3.94 4.627 28 P 0 0;2,4=4,6=0
P 3.94 4.655 9 P 0 0;4=13,6=1
P 3.94 4.683 28 P 0 0;2,4=4,6=0
L 3.77 4.765 3.77 4.793 7 P 0 
P 3.77 4.765 9 P 0 0;4=13,6=1
P 3.77441004 4.72035 37 P 0 0;2,4=8,6=0
P 3.77 4.793 28 P 0 0;2,4=4,6=0
L 3.77441004 4.72035 3.77441004 4.74558996 7 P 0 
L 3.77441004 4.74558996 3.77 4.75 7 P 0 
L 3.77 4.75 3.77 4.765 7 P 0 
P 4.14 4.745 9 P 0 0;4=13,6=1
P 4.08035 4.71558996 47 P 0 0;2,4=8,6=0
P 4.14 4.717 28 P 0 0;2,4=4,6=0
L 4.08035 4.71558996 4.13858996 4.71558996 7 P 0 
L 4.13858996 4.71558996 4.14 4.717 7 P 0 
L 4.14 4.717 4.14 4.745 7 P 0 
P 4.76 5.375 9 P 0 0;4=13,6=1
P 4.76 5.408 28 P 0 0;2,4=4,6=0
P 4.9574 5.54685 41 P 0 0;2,4=5,6=0
P 4.96 5.5 9 P 0 0;4=13,6=1
L 4.9574 5.54685 4.9574 5.5026 9 P 0 
L 4.9574 5.5026 4.96 5.5 9 P 0 
P 5.16 5.555 9 P 0 0;4=13,6=1
L 5.16 5.583 5.16 5.555 9 P 0 
P 5.09558996 5.55965 37 P 0 0;2,4=8,6=0
L 5.16 5.583 5.108 5.583 7 P 0 
L 5.108 5.583 5.09558996 5.57058996 7 P 0 
L 5.09558996 5.57058996 5.09558996 5.55965 7 P 0 
P 5.16 5.583 28 P 0 0;2,4=4,6=0
P 4.892 5.767 9 P 0 0;4=13,6=1
P 4.86 5.767 28 P 0 0;2,4=4,6=0
L 4.86 5.767 4.892 5.767 7 P 0 
P 5.088 5.767 9 P 0 0;4=13,6=1
P 5.06 5.767 28 P 0 0;2,4=4,6=0
L 5.06 5.767 5.088 5.767 7 P 0 
P 0.91 5.075 9 P 0 0;4=13,6=1
P 0.91 5.113 28 P 0 0;2,4=4,6=0
L 0.91 5.113 0.91 5.075 7 P 0 
P 1.03 4.96 9 P 0 0;4=13,6=1
P 1.03 4.993 28 P 0 0;2,4=4,6=0
L 1.03 4.993 1.03 4.96 7 P 0 
P 1.02558996 5.20965 37 P 0 0;2,4=8,6=0
P 1.03 5.155 9 P 0 0;4=13,6=1
L 1.03 5.127 1.03 5.155 9 P 0 
P 1.03 5.127 28 P 0 0;2,4=4,6=0
L 1.02558996 5.20965 1.02558996 5.15941004 7 P 0 
L 1.02558996 5.15941004 1.03 5.155 7 P 0 
P 1.38906004 5.12551004 28 P 0 0;2,4=4,6=0
L 1.38906004 5.12551004 1.38906004 5.15351004 7 P 0 
P 1.38906004 5.15351004 9 P 0 0;4=0,6=1
P 1.23906004 5.15351004 9 P 0 0;4=13,6=1
L 1.23906004 5.12551004 1.23906004 5.15351004 7 P 0 
P 1.23906004 5.12551004 28 P 0 0;2,4=4,6=0
P 1.28906004 5.15351004 9 P 0 0;4=13,6=1
L 1.28906004 5.12551004 1.28906004 5.15351004 7 P 0 
P 1.28906004 5.12551004 28 P 0 0;2,4=4,6=0
L 1.25066998 4.9602 1.25066998 4.97748002 7 P 0 
L 1.25066998 4.97748002 1.23813002 4.99001998 7 P 0 
L 1.23813002 4.99001998 1.21691004 4.99001998 7 P 0 
L 1.21691004 4.99001998 1.2084 4.98151004 7 P 0 
L 1.2084 4.98151004 1.18906004 4.98151004 7 P 0 
P 1.25066998 4.9602 38 P 0 0;2,4=20,6=0
P 1.18906004 4.95351004 9 P 0 0;4=13,6=1
L 1.18906004 4.98151004 1.18906004 4.95351004 7 P 0 
P 1.18906004 4.98151004 28 P 0 0;2,4=4,6=0
P 0.83 5.355 9 P 0 0;4=13,6=1
L 0.83 5.383 0.83 5.355 7 P 0 
P 0.83 5.383 28 P 0 0;2,4=4,6=0
P 0.948 5.383 28 P 0 0;2,4=4,6=0
P 0.9 5.355 9 P 0 0;4=13,6=1
L 0.9 5.383 0.9 5.355 7 P 0 
P 0.9 5.383 28 P 0 0;2,4=4,6=0
L 0.948 5.383 0.9 5.383 7 P 0 
P 0.755 5.355 9 P 0 0;4=13,6=1
L 0.755 5.383 0.755 5.355 7 P 0 
P 0.755 5.383 28 P 0 0;2,4=4,6=0
P 0.81016004 5.2361 35 P 0 0;2,4=10,6=0
P 0.73 5.205 9 P 0 0;4=13,6=1
L 0.73 5.233 0.73 5.205 9 P 0 
P 0.73 5.233 28 P 0 0;2,4=4,6=0
L 0.73 5.205 0.775 5.205 6 P 0 
L 0.775 5.205 0.79046998 5.22046998 6 P 0 
L 0.79046998 5.22046998 0.79046998 5.2361 6 P 0 
P 0.79046998 5.2361 35 P 0 0;2,4=10,6=0
P 0.81016004 5.17 9 P 0 0;4=13,6=1
P 0.81016004 5.1239 35 P 0 0;2,4=10,6=0
L 0.81016004 5.1239 0.81016004 5.17 6 P 0 
P 1.094 5.356 9 P 0 0;4=0,6=1
P 1.094 5.383 28 P 0 0;2,4=4,6=0
L 1.094 5.383 1.094 5.356 7 P 0 
P 1.044 5.448 9 P 0 0;4=13,6=1
P 1.044 5.417 28 P 0 0;2,4=4,6=0
L 1.044 5.417 1.044 5.448 7 P 0 
P 1.4 5.46 9 P 0 0;4=13,6=1
P 1.32 5.46 9 P 0 0;4=13,6=1
P 1.31 5.417 28 P 0 0;2,4=4,6=0
P 1.46 5.417 28 P 0 0;2,4=4,6=0
P 1.41 5.417 28 P 0 0;2,4=4,6=0
P 1.36 5.417 28 P 0 0;2,4=4,6=0
P 1.43798996 5.46016004 9 P 0 0;4=13,6=1
L 1.43798996 5.53641998 1.43798996 5.46016004 9 P 0 
P 1.43798996 5.53641998 48 P 0 0;2,4=16,6=0
P 1.35925 5.46016004 9 P 0 0;4=13,6=1
L 1.35925 5.53641998 1.35925 5.46016004 9 P 0 
P 1.35925 5.53641998 48 P 0 0;2,4=16,6=0
P 0.89 5.885 9 P 0 0;4=13,6=1
L 0.89 5.857 0.89 5.885 7 P 0 
P 0.89 5.857 28 P 0 0;2,4=4,6=0
P 0.81 5.885 9 P 0 0;4=13,6=1
L 0.81 5.857 0.81 5.885 7 P 0 
P 0.81 5.857 28 P 0 0;2,4=4,6=0
P 0.73 5.885 9 P 0 0;4=13,6=1
L 0.73 5.857 0.73 5.885 7 P 0 
P 0.73 5.857 28 P 0 0;2,4=4,6=0
P 0.97 5.885 9 P 0 0;4=13,6=1
L 0.97 5.857 0.97 5.885 7 P 0 
P 0.97 5.857 28 P 0 0;2,4=4,6=0
P 1.04 5.885 9 P 0 0;4=13,6=1
P 1.04 5.857 28 P 0 0;2,4=4,6=0
L 1.04 5.857 1.04 5.885 7 P 0 
P 1.12 5.885 9 P 0 0;4=13,6=1
L 1.12 5.857 1.12 5.885 7 P 0 
P 1.12 5.857 28 P 0 0;2,4=4,6=0
L 4.96 5.5 4.96 5.442 9 P 0 
P 4.96 5.442 28 P 0 0;2,4=4,6=0
S P 0
OB 0.715 5.24 I
OS 0.718 5.243
OS 0.748 5.243
OS 0.765 5.26
OS 0.81 5.26
OS 0.815 5.255
OS 0.815 5.2
OS 0.81 5.195
OS 0.72 5.195
OS 0.715 5.2
OS 0.715 5.24
OE
SE
S P 0
OB 1.46823996063 5.58176003937 I
OS 1.48 5.57
OS 1.48 5.415
OS 1.472 5.407
OS 1.3 5.407
OS 1.3 5.456
OS 1.331 5.487
OS 1.331 5.585
OS 1.341 5.595
OS 1.44698996063 5.595
OC 1.4563 5.586798129921 1.477352559055 5.620080019685 N
OC 1.4677 5.5819 1.477352165354 5.620080019685 N
OS 1.46823996063 5.58176003937
OE
SE
P 8.15 3.31615 8 P 0 0;4=12,6=1
P 8.125 3.29115 10 P 0 0;2,4=11,6=0
L 8.15 3.31615 8.125 3.29115 5 P 0 
L 7.66023996 4.85788002 7.66023996 4.8363 2 P 0 
L 7.66023996 4.8363 7.6665 4.83003996 2 P 0 
L 7.6665 4.83003996 7.6665 4.79736998 2 P 0 
L 7.6665 4.79736998 7.65205 4.78291998 2 P 0 
P 7.65205 4.78291998 8 P 0 0;4=12,6=1
P 7.66023996 4.85788002 36 P 0 0;2,4=1,6=0
P 11.235 3.3 9 P 0 0;4=13,6=1
P 5.815 0.925 9 P 0 0;4=0,6=1
L 3.635 0.49 3.60998996 0.46498996 5 P 0 
L 3.60998996 0.46498996 3.60998996 0.40688002 5 P 0 
L 3.60998996 0.40688002 3.60998996 0.3051 5 P 0 
P 3.60998996 0.3051 28 P 0 0;2,4=4,6=0
P 3.60998996 0.40688002 43 P 0 0;2,4=28,6=0
P 3.635 0.49 9 P 0 0;4=0,6=1
P 4.60768002 2.84115 10 P 0 0;2,4=11,6=0
L 4.60768002 2.84115 4.58268002 2.81615 5 P 0 
P 4.58268002 2.81615 8 P 0 0;4=12,6=1
L 2.19606004 3.26615 2.17106004 3.24115 5 P 0 
P 2.17106004 3.24115 10 P 0 0;2,4=11,6=0
P 2.19606004 3.26615 8 P 0 0;4=12,6=1
L 1.6567 4.97913996 1.6567 5.0017 2 P 0 
L 1.6567 5.0017 1.66295 5.00795 2 P 0 
L 1.66295 5.00795 1.66295 5.03905 2 P 0 
L 1.66295 5.03905 1.6485 5.0535 2 P 0 
P 1.6485 5.0535 8 P 0 0;4=12,6=1
P 1.6567 4.97913996 36 P 0 0;2,4=1,6=0
P 8.15 3.36615 8 P 0 0;4=12,6=1
P 8.125 3.34115 10 P 0 0;2,4=11,6=0
L 8.15 3.36615 8.125 3.34115 5 P 0 
L 7.68386004 4.85788002 7.68386004 4.83531998 2 P 0 
L 7.68386004 4.83531998 7.6776 4.82906004 2 P 0 
L 7.6776 4.82906004 7.6776 4.79736998 2 P 0 
L 7.6776 4.79736998 7.69205 4.78291998 2 P 0 
P 7.69205 4.78291998 8 P 0 0;4=12,6=1
P 7.68386004 4.85788002 36 P 0 0;2,4=1,6=0
L 2.19606004 3.31615 2.17106004 3.29115 5 P 0 
P 2.17106004 3.29115 10 P 0 0;2,4=11,6=0
P 2.19606004 3.31615 8 P 0 0;4=12,6=1
P 1.6885 5.0535 8 P 0 0;4=12,6=1
L 1.68031998 4.97913996 1.68031998 5.00168002 2 P 0 
L 1.68031998 5.00168002 1.67405 5.00795 2 P 0 
L 1.67405 5.00795 1.67405 5.03905 2 P 0 
L 1.67405 5.03905 1.6885 5.0535 2 P 0 
P 1.68031998 4.97913996 36 P 0 0;2,4=1,6=0
P 8.1 3.41615 8 P 0 0;4=12,6=1
P 8.075 3.39115 10 P 0 0;2,4=11,6=0
L 8.1 3.41615 8.075 3.39115 5 P 0 
P 7.80196998 4.85788002 36 P 0 0;2,4=1,6=0
P 7.79378996 4.78291998 8 P 0 0;4=12,6=1
L 7.80196998 4.85788002 7.80196998 4.83656004 2 P 0 
L 7.80196998 4.83656004 7.80823996 4.83028996 2 P 0 
L 7.80823996 4.83028996 7.80823996 4.79736998 2 P 0 
L 7.80823996 4.79736998 7.79378996 4.78291998 2 P 0 
L 1.6567 4.85788002 1.6567 4.8363 2 P 0 
L 1.6567 4.8363 1.66296004 4.83003996 2 P 0 
L 1.66296004 4.83003996 1.66296004 4.79736998 2 P 0 
L 1.66296004 4.79736998 1.64851004 4.78291998 2 P 0 
L 2.14606004 3.31615 2.12106004 3.29115 5 P 0 
P 2.12106004 3.29115 10 P 0 0;2,4=11,6=0
P 2.14606004 3.31615 8 P 0 0;4=12,6=1
P 1.64851004 4.78291998 8 P 0 0;4=12,6=1
P 1.6567 4.85788002 36 P 0 0;2,4=1,6=0
P 8.1 3.46615 8 P 0 0;4=12,6=1
P 8.075 3.44115 10 P 0 0;2,4=11,6=0
L 8.1 3.46615 8.075 3.44115 5 P 0 
P 7.8256 4.85788002 36 P 0 0;2,4=1,6=0
P 7.83378996 4.78291998 8 P 0 0;4=12,6=1
L 7.8256 4.85788002 7.8256 4.83606004 2 P 0 
L 7.8256 4.83606004 7.81933996 4.8298 2 P 0 
L 7.81933996 4.8298 7.81933996 4.79736998 2 P 0 
L 7.81933996 4.79736998 7.83378996 4.78291998 2 P 0 
L 1.68031998 4.85788002 1.68031998 4.83531998 2 P 0 
L 1.68031998 4.83531998 1.67406004 4.82906004 2 P 0 
L 1.67406004 4.82906004 1.67406004 4.79736998 2 P 0 
L 1.67406004 4.79736998 1.68851004 4.78291998 2 P 0 
L 2.14606004 3.36615 2.12106004 3.34115 5 P 0 
P 2.12106004 3.34115 10 P 0 0;2,4=11,6=0
P 2.14606004 3.36615 8 P 0 0;4=12,6=1
P 1.68851004 4.78291998 8 P 0 0;4=12,6=1
P 1.68031998 4.85788002 36 P 0 0;2,4=1,6=0
L 0.73 4.993 0.73 4.96 5 P 0 
P 0.73 4.96 9 P 0 0;4=0,6=1
P 0.73 4.993 28 P 0 0;2,4=4,6=0
L 3.795 4.6 3.8 4.605 5 P 0 
L 3.8 4.605 3.8 4.63965 5 P 0 
P 3.795 4.6 9 P 0 0;4=13,6=1
P 3.8 4.63965 37 P 0 0;2,4=8,6=0
L 4.86 5.408 4.86 5.375 5 P 0 
P 4.86 5.408 28 P 0 0;2,4=4,6=0
P 4.86 5.375 9 P 0 0;4=13,6=1
P 8.15 3.46615 8 P 0 0;4=12,6=1
P 8.125 3.44115 10 P 0 0;2,4=11,6=0
L 8.15 3.46615 8.125 3.44115 5 P 0 
L 7.87283996 4.85788002 7.87283996 4.8357 2 P 0 
L 7.87283996 4.8357 7.8791 4.82943996 2 P 0 
L 7.8791 4.82943996 7.8791 4.67145 2 P 0 
L 7.8791 4.67145 7.86465 4.657 2 P 0 
P 7.86465 4.657 8 P 0 0;4=12,6=1
P 7.87283996 4.85788002 36 P 0 0;2,4=1,6=0
L 2.09606004 3.41615 2.07106004 3.39115 5 P 0 
P 2.07106004 3.39115 10 P 0 0;2,4=11,6=0
P 2.09606004 3.41615 8 P 0 0;4=12,6=1
P 1.79843002 4.85788002 36 P 0 0;2,4=1,6=0
L 1.79843002 4.85788002 1.79843002 4.83656004 2 P 0 
L 1.79843002 4.83656004 1.8047 4.83028996 2 P 0 
L 1.8047 4.83028996 1.8047 4.79736998 2 P 0 
L 1.8047 4.79736998 1.79025 4.78291998 2 P 0 
P 1.79025 4.78291998 8 P 0 0;4=12,6=1
P 8.15 3.51615 8 P 0 0;4=12,6=1
P 8.125 3.49115 10 P 0 0;2,4=11,6=0
L 8.15 3.51615 8.125 3.49115 5 P 0 
L 7.89646004 4.85788002 7.89646004 4.83591998 2 P 0 
L 7.89646004 4.83591998 7.8902 4.82966004 2 P 0 
L 7.8902 4.82966004 7.8902 4.67145 2 P 0 
L 7.8902 4.67145 7.90465 4.657 2 P 0 
P 7.90465 4.657 8 P 0 0;4=12,6=1
P 7.89646004 4.85788002 36 P 0 0;2,4=1,6=0
P 2.09606004 3.46615 8 P 0 0;4=12,6=1
P 2.07106004 3.44115 10 P 0 0;2,4=11,6=0
L 2.09606004 3.46615 2.07106004 3.44115 5 P 0 
P 1.82206004 4.85788002 36 P 0 0;2,4=1,6=0
L 1.82206004 4.85788002 1.82206004 4.83606004 2 P 0 
L 1.82206004 4.83606004 1.8158 4.8298 2 P 0 
L 1.8158 4.8298 1.8158 4.79736998 2 P 0 
L 1.8158 4.79736998 1.83025 4.78291998 2 P 0 
P 1.83025 4.78291998 8 P 0 0;4=12,6=1
P 2.19606004 3.41615 8 P 0 0;4=12,6=1
P 2.17106004 3.39115 10 P 0 0;2,4=11,6=0
L 2.19606004 3.41615 2.17106004 3.39115 5 P 0 
P 1.86111004 5.169 8 P 0 0;4=12,6=1
L 1.8693 4.97913996 1.8693 5.0023 2 P 0 
L 1.8693 5.0023 1.87556004 5.00856004 2 P 0 
L 1.87556004 5.00856004 1.87556004 5.15455 2 P 0 
L 1.87556004 5.15455 1.86111004 5.169 2 P 0 
P 1.8693 4.97913996 36 P 0 0;2,4=1,6=0
L 1.89291998 4.97913996 1.89291998 5.00208002 2 P 0 
L 1.89291998 5.00208002 1.88666004 5.00833996 2 P 0 
L 1.88666004 5.00833996 1.88666004 5.15455 2 P 0 
L 1.88666004 5.15455 1.90111004 5.169 2 P 0 
L 2.19606004 3.46615 2.17106004 3.44115 5 P 0 
P 2.17106004 3.44115 10 P 0 0;2,4=11,6=0
P 2.19606004 3.46615 8 P 0 0;4=12,6=1
P 1.90111004 5.169 8 P 0 0;4=12,6=1
P 1.89291998 4.97913996 36 P 0 0;2,4=1,6=0
S P 0
OB 6.905 4.51 I
OS 6.725 4.51
OS 6.71618996063 4.51881003937
OS 6.71618996063 4.65205
OS 6.72118996063 4.65705
OS 6.91618996063 4.65705
OS 6.92118996063 4.65205
OS 6.92118996063 4.52618996063
OS 6.905 4.51
OE
SE
P 6.82978002 4.53096998 11 P 0 0;3,4=6,6=1
P 6.87618996 4.61586998 52 P 0 0;2,4=22,6=0
P 6.74208996 4.6252 31 P 0 0;2,4=21,6=0
P 6.72708996 4.5652 9 P 0 0;4=13,6=1
P 6.76208996 4.5652 9 P 0 0;4=13,6=1
P 6.79708996 4.5652 9 P 0 0;4=13,6=1
P 6.83708996 4.5652 9 P 0 0;4=0,6=1
P 6.90208996 4.5652 9 P 0 0;4=13,6=1
P 6.87208996 4.5652 9 P 0 0;4=13,6=1
P 10.99998996 4.9531 9 P 0 0;4=13,6=1
P 11.03998996 4.9531 9 P 0 0;4=13,6=1
P 10.99998996 4.9131 9 P 0 0;4=13,6=1
P 11.03998996 4.9131 9 P 0 0;4=13,6=1
P 11.21998996 4.9531 9 P 0 0;4=13,6=1
P 11.17998996 4.9531 9 P 0 0;4=13,6=1
P 11.13498996 4.9531 9 P 0 0;4=13,6=1
P 11.08498996 4.9531 9 P 0 0;4=13,6=1
P 11.21998996 4.9131 9 P 0 0;4=13,6=1
P 11.17998996 4.9131 9 P 0 0;4=13,6=1
P 11.08498996 4.9131 9 P 0 0;4=13,6=1
P 11.13498996 4.9131 9 P 0 0;4=13,6=1
P 10.99998996 5.1631 9 P 0 0;4=13,6=1
P 11.03998996 5.1631 9 P 0 0;4=13,6=1
P 10.99998996 5.1231 9 P 0 0;4=13,6=1
P 10.99998996 5.0381 9 P 0 0;4=13,6=1
P 10.99998996 5.0831 9 P 0 0;4=13,6=1
P 10.99998996 4.9931 9 P 0 0;4=13,6=1
P 11.03998996 4.9931 9 P 0 0;4=13,6=1
P 11.03998996 5.0831 9 P 0 0;4=13,6=1
P 11.03998996 5.0381 9 P 0 0;4=13,6=1
P 11.03998996 5.1231 9 P 0 0;4=13,6=1
P 11.10998996 5.03983002 34 P 0 0;2,4=26,6=0
P 11.21998996 5.1631 9 P 0 0;4=13,6=1
P 11.17998996 5.1631 9 P 0 0;4=13,6=1
P 11.08498996 5.1631 9 P 0 0;4=13,6=1
P 11.13498996 5.1631 9 P 0 0;4=13,6=1
P 11.21998996 5.1231 9 P 0 0;4=13,6=1
P 11.21998996 5.0381 9 P 0 0;4=13,6=1
P 11.21998996 5.0831 9 P 0 0;4=13,6=1
P 11.21998996 4.9931 9 P 0 0;4=13,6=1
P 11.17998996 4.9931 9 P 0 0;4=13,6=1
P 11.17998996 5.1231 9 P 0 0;4=13,6=1
P 11.17998996 5.0831 9 P 0 0;4=13,6=1
P 11.17998996 5.0381 9 P 0 0;4=13,6=1
P 11.13498996 5.1231 9 P 0 0;4=13,6=1
P 11.08498996 5.1231 9 P 0 0;4=13,6=1
P 11.52873996 4.88 39 P 0 0;2,4=29,6=0
P 10.577 5.32 28 P 0 0;2,4=4,6=0
P 10.59 5.18 31 P 0 0;2,4=21,6=0
P 10.59 5.26 31 P 0 0;2,4=21,6=0
P 12.04 5.04 31 P 0 0;2,4=21,6=0
P 12.12 5.027 28 P 0 0;2,4=4,6=0
P 12.2 5.04 31 P 0 0;2,4=21,6=0
P 11.6269 4.90498996 9 P 0 0;4=13,6=1
P 11.6269 4.85498996 9 P 0 0;4=13,6=1
P 11.4269 4.80998996 9 P 0 0;4=13,6=1
P 11.4269 4.85498996 9 P 0 0;4=13,6=1
P 11.4269 4.90498996 9 P 0 0;4=13,6=1
P 11.4269 4.94998996 9 P 0 0;4=13,6=1
P 11.4769 4.94998996 9 P 0 0;4=13,6=1
P 11.4769 4.80998996 9 P 0 0;4=13,6=1
P 11.5269 4.94998996 9 P 0 0;4=13,6=1
P 11.5269 4.80998996 9 P 0 0;4=13,6=1
P 11.5769 4.94998996 9 P 0 0;4=13,6=1
P 11.6269 4.94998996 9 P 0 0;4=13,6=1
P 11.6269 4.80998996 9 P 0 0;4=13,6=1
P 11.5769 4.80998996 9 P 0 0;4=13,6=1
P 10.82676998 5.71338996 17 P 0 0;4=33,6=0
P 10.99213002 5.71338996 17 P 0 0;4=33,6=0
P 11.15748002 5.71338996 17 P 0 0;4=33,6=0
P 11.32283996 5.71338996 17 P 0 0;4=33,6=0
P 11.48818996 5.71338996 17 P 0 0;4=33,6=0
P 11.65353996 5.71338996 17 P 0 0;4=33,6=0
P 11.8189 5.71338996 17 P 0 0;4=33,6=0
P 11.98425 5.71338996 17 P 0 0;4=33,6=0
P 12.14961004 5.71338996 17 P 0 0;4=33,6=0
P 10.80498996 5.7831 9 P 0 0;4=13,6=1
P 10.84498996 5.7831 9 P 0 0;4=13,6=1
P 10.80498996 5.6431 9 P 0 0;4=13,6=1
P 10.84498996 5.6431 9 P 0 0;4=13,6=1
P 11.01035 5.6431 9 P 0 0;4=13,6=1
P 10.97035 5.6431 9 P 0 0;4=13,6=1
P 11.01035 5.7831 9 P 0 0;4=13,6=1
P 10.97035 5.7831 9 P 0 0;4=13,6=1
P 11.17571004 5.6431 9 P 0 0;4=13,6=1
P 11.13571004 5.6431 9 P 0 0;4=13,6=1
P 11.17571004 5.7831 9 P 0 0;4=13,6=1
P 11.13571004 5.7831 9 P 0 0;4=13,6=1
P 11.34106998 5.6431 9 P 0 0;4=13,6=1
P 11.30106998 5.6431 9 P 0 0;4=13,6=1
P 11.34106998 5.7831 9 P 0 0;4=13,6=1
P 11.30106998 5.7831 9 P 0 0;4=13,6=1
P 11.50643002 5.6431 9 P 0 0;4=13,6=1
P 11.46643002 5.6431 9 P 0 0;4=13,6=1
P 11.50643002 5.7831 9 P 0 0;4=13,6=1
P 11.46643002 5.7831 9 P 0 0;4=13,6=1
P 11.67178996 5.6431 9 P 0 0;4=13,6=1
P 11.63178996 5.6431 9 P 0 0;4=13,6=1
P 11.67178996 5.7831 9 P 0 0;4=13,6=1
P 11.63178996 5.7831 9 P 0 0;4=13,6=1
P 11.83715 5.6431 9 P 0 0;4=13,6=1
P 11.79715 5.6431 9 P 0 0;4=13,6=1
P 11.83715 5.7831 9 P 0 0;4=13,6=1
P 11.79715 5.7831 9 P 0 0;4=13,6=1
P 12.00251004 5.6431 9 P 0 0;4=13,6=1
P 11.96251004 5.6431 9 P 0 0;4=13,6=1
P 12.00251004 5.7831 9 P 0 0;4=13,6=1
P 11.96251004 5.7831 9 P 0 0;4=13,6=1
P 12.16786998 5.6431 9 P 0 0;4=13,6=1
P 12.12786998 5.6431 9 P 0 0;4=13,6=1
P 12.16786998 5.7831 9 P 0 0;4=13,6=1
P 12.12786998 5.7831 9 P 0 0;4=13,6=1
S P 0
OB 11.31405 4.78405 I
OS 11.195 4.9031
OS 10.99498996063 4.9031
OS 10.98998996063 4.9081
OS 10.98998996063 5.12
OS 10.95498996063 5.155
OS 10.568 5.155
OS 10.567 5.156
OS 10.567 5.836
OS 10.616 5.885
OS 12.49 5.885
OS 12.52 5.855
OS 12.52 5.34
OS 12.22 5.04
OS 12.22 5.02
OS 11.730969980315 5.02
OS 11.7 4.989030019685
OS 11.7 4.825
OS 11.65905 4.78405
OS 11.31405 4.78405
OE
OB 10.79585 5.394980019685 H
OS 12.19415 5.394980019685
OS 12.215019980315 5.41585
OS 12.215019980315 5.57415
OS 12.19415 5.595019980315
OS 10.79585 5.595019980315
OS 10.769980019685 5.56915
OS 10.769980019685 5.42085
OS 10.79585 5.394980019685
OE
OB 12.415380019685 5.695280019685 H
OC 12.415380019685 5.695280019685 12.33465 5.695280019685 N
OE
SE
S P 0
OB 4.98605 5.20105 I
OS 5.01 5.225
OS 5.21 5.225
OS 5.22605 5.20895
OS 5.22605 4.9081
OS 5.22105 4.9031
OS 4.99105 4.9031
OS 4.98605 4.9081
OS 4.98605 5.20105
OE
SE
P 5.10605 5.03983002 34 P 0 0;2,4=26,6=0
P 5.03605 5.1631 9 P 0 0;4=13,6=1
P 5.03605 4.9931 9 P 0 0;4=13,6=1
P 5.03605 5.0831 9 P 0 0;4=13,6=1
P 5.03605 5.0381 9 P 0 0;4=13,6=1
P 5.03605 5.1231 9 P 0 0;4=13,6=1
P 5.21605 5.1631 9 P 0 0;4=13,6=1
P 5.17605 5.1631 9 P 0 0;4=13,6=1
P 5.08105 5.1631 9 P 0 0;4=13,6=1
P 5.13105 5.1631 9 P 0 0;4=13,6=1
P 5.21605 5.1231 9 P 0 0;4=13,6=1
P 5.21605 5.0381 9 P 0 0;4=13,6=1
P 5.21605 5.0831 9 P 0 0;4=13,6=1
P 5.21605 4.9931 9 P 0 0;4=13,6=1
P 5.17605 4.9931 9 P 0 0;4=13,6=1
P 5.17605 5.1231 9 P 0 0;4=13,6=1
P 5.17605 5.0831 9 P 0 0;4=13,6=1
P 5.17605 5.0381 9 P 0 0;4=13,6=1
P 5.13105 5.1231 9 P 0 0;4=13,6=1
P 5.08105 5.1231 9 P 0 0;4=13,6=1
P 4.99605 5.1631 9 P 0 0;4=13,6=1
P 4.99605 5.1231 9 P 0 0;4=13,6=1
P 4.99605 5.0381 9 P 0 0;4=13,6=1
P 4.99605 5.0831 9 P 0 0;4=13,6=1
P 4.99605 4.9931 9 P 0 0;4=13,6=1
P 5.03605 4.9531 9 P 0 0;4=13,6=1
P 5.03605 4.9131 9 P 0 0;4=13,6=1
P 5.21605 4.9531 9 P 0 0;4=13,6=1
P 5.17605 4.9531 9 P 0 0;4=13,6=1
P 5.13105 4.9531 9 P 0 0;4=13,6=1
P 5.08105 4.9531 9 P 0 0;4=13,6=1
P 5.21605 4.9131 9 P 0 0;4=13,6=1
P 5.17605 4.9131 9 P 0 0;4=13,6=1
P 5.08105 4.9131 9 P 0 0;4=13,6=1
P 5.13105 4.9131 9 P 0 0;4=13,6=1
P 4.99605 4.9531 9 P 0 0;4=13,6=1
P 4.99605 4.9131 9 P 0 0;4=13,6=1
P 5.205 5.205 11 P 0 0;3,4=6,6=1
L 6.34948996 4.99705 6.34948996 5.03 7 P 0 
P 6.34948996 4.99705 28 P 0 0;2,4=4,6=0
P 6.34948996 5.03 9 P 0 0;4=13,6=1
L 2.75043996 4.97913996 2.75043996 5.00243996 2 P 0 
L 2.75043996 5.00243996 2.7567 5.0087 2 P 0 
L 2.7567 5.0087 2.7567 5.12555 2 P 0 
L 2.7567 5.12555 2.74225 5.14 2 P 0 
P 2.74225 5.14 8 P 0 0;4=12,6=1
P 2.75043996 4.97913996 36 P 0 0;2,4=1,6=0
L 2.04606004 3.61615 2.02106004 3.59115 5 P 0 
P 2.02106004 3.59115 10 P 0 0;2,4=11,6=0
P 2.04606004 3.61615 8 P 0 0;4=12,6=1
L 1.8693 4.85788002 1.8693 4.8357 2 P 0 
L 1.8693 4.8357 1.87556004 4.82943996 2 P 0 
L 1.87556004 4.82943996 1.87556004 4.67145 2 P 0 
L 1.87556004 4.67145 1.86111004 4.657 2 P 0 
L 2.14606004 3.46615 2.12106004 3.44115 5 P 0 
P 2.12106004 3.44115 10 P 0 0;2,4=11,6=0
P 2.14606004 3.46615 8 P 0 0;4=12,6=1
P 1.86111004 4.657 8 P 0 0;4=12,6=1
P 1.8693 4.85788002 36 P 0 0;2,4=1,6=0
P 2.78225 5.14 8 P 0 0;4=12,6=1
L 2.77406004 4.97913996 2.77406004 5.00193996 2 P 0 
L 2.77406004 5.00193996 2.7678 5.0082 2 P 0 
L 2.7678 5.0082 2.7678 5.12555 2 P 0 
L 2.7678 5.12555 2.78225 5.14 2 P 0 
P 2.77406004 4.97913996 36 P 0 0;2,4=1,6=0
L 2.04606004 3.66615 2.02106004 3.64115 5 P 0 
P 2.02106004 3.64115 10 P 0 0;2,4=11,6=0
P 2.04606004 3.66615 8 P 0 0;4=12,6=1
P 2.14606004 3.51615 8 P 0 0;4=12,6=1
P 2.12106004 3.49115 10 P 0 0;2,4=11,6=0
L 2.14606004 3.51615 2.12106004 3.49115 5 P 0 
L 1.89291998 4.85788002 1.89291998 4.83591998 2 P 0 
L 1.89291998 4.83591998 1.88666004 4.82966004 2 P 0 
L 1.88666004 4.82966004 1.88666004 4.67145 2 P 0 
L 1.88666004 4.67145 1.90111004 4.657 2 P 0 
P 1.90111004 4.657 8 P 0 0;4=12,6=1
P 1.89291998 4.85788002 36 P 0 0;2,4=1,6=0
P 1.94016998 4.97913996 36 P 0 0;2,4=1,6=0
P 1.93196998 5.0535 8 P 0 0;4=12,6=1
L 1.94016998 4.97913996 1.94016998 5.00118002 2 P 0 
L 1.94016998 5.00118002 1.94641998 5.00743002 2 P 0 
L 1.94641998 5.00743002 1.94641998 5.03905 2 P 0 
L 1.94641998 5.03905 1.93196998 5.0535 2 P 0 
P 2.02106004 3.44115 10 P 0 0;2,4=11,6=0
L 1.99606004 3.46615 2.02106004 3.44115 5 P 0 
P 1.99606004 3.46615 8 P 0 0;4=12,6=1
P 4.60768002 2.59115 10 P 0 0;2,4=11,6=0
L 4.60768002 2.59115 4.58268002 2.56615 5 P 0 
P 4.58268002 2.56615 8 P 0 0;4=12,6=1
P 1.96378996 4.97913996 36 P 0 0;2,4=1,6=0
P 1.97196998 5.0535 8 P 0 0;4=12,6=1
L 1.96378996 4.97913996 1.96378996 5.00221998 2 P 0 
L 1.96378996 5.00221998 1.95751998 5.00848996 2 P 0 
L 1.95751998 5.00848996 1.95751998 5.03905 2 P 0 
L 1.95751998 5.03905 1.97196998 5.0535 2 P 0 
P 2.02106004 3.49115 10 P 0 0;2,4=11,6=0
L 1.99606004 3.51615 2.02106004 3.49115 5 P 0 
P 1.99606004 3.51615 8 P 0 0;4=12,6=1
P 2.88086998 5.17001998 8 P 0 0;4=12,6=1
L 2.8213 4.97913996 2.8213 5.0023 2 P 0 
L 2.8213 5.0023 2.82756004 5.00856004 2 P 0 
L 2.82756004 5.00856004 2.82756004 5.04326004 2 P 0 
L 2.82756004 5.04326004 2.89531998 5.11101998 2 P 0 
L 2.89531998 5.11101998 2.89531998 5.15556998 2 P 0 
L 2.89531998 5.15556998 2.88086998 5.17001998 2 P 0 
L 2.14606004 3.61615 2.12106004 3.59115 5 P 0 
P 2.12106004 3.59115 10 P 0 0;2,4=11,6=0
P 2.14606004 3.61615 8 P 0 0;4=12,6=1
P 2.8213 4.97913996 36 P 0 0;2,4=1,6=0
L 3.55358002 4.85788002 3.55358002 4.83558002 2 P 0 
L 3.55358002 4.83558002 3.54731998 4.82931998 2 P 0 
L 3.54731998 4.82931998 3.54731998 4.73418002 2 P 0 
L 3.54731998 4.73418002 3.56176998 4.71973002 2 P 0 
L 2.34606004 3.66615 2.32106004 3.64115 5 P 0 
P 2.32106004 3.64115 10 P 0 0;2,4=11,6=0
P 2.34606004 3.66615 8 P 0 0;4=12,6=1
P 3.56176998 4.71973002 8 P 0 0;4=12,6=1
P 3.55358002 4.85788002 36 P 0 0;2,4=1,6=0
L 2.84491998 4.97913996 2.84491998 5.00108002 2 P 0 
L 2.84491998 5.00108002 2.83866004 5.00733996 2 P 0 
L 2.83866004 5.00733996 2.83866004 5.03866004 2 P 0 
L 2.83866004 5.03866004 2.90641998 5.10641998 2 P 0 
L 2.90641998 5.10641998 2.90641998 5.15556998 2 P 0 
L 2.90641998 5.15556998 2.92086998 5.17001998 2 P 0 
P 2.92086998 5.17001998 8 P 0 0;4=12,6=1
L 2.14606004 3.66615 2.12106004 3.64115 5 P 0 
P 2.12106004 3.64115 10 P 0 0;2,4=11,6=0
P 2.14606004 3.66615 8 P 0 0;4=12,6=1
P 2.84491998 4.97913996 36 P 0 0;2,4=1,6=0
L 2.34606004 3.71615 2.32106004 3.69115 5 P 0 
P 2.32106004 3.69115 10 P 0 0;2,4=11,6=0
P 2.34606004 3.71615 8 P 0 0;4=12,6=1
P 3.52176998 4.71973002 8 P 0 0;4=12,6=1
L 3.52996004 4.85788002 3.52996004 4.83503996 2 P 0 
L 3.52996004 4.83503996 3.53621998 4.82878002 2 P 0 
L 3.53621998 4.82878002 3.53621998 4.73418002 2 P 0 
L 3.53621998 4.73418002 3.52176998 4.71973002 2 P 0 
P 3.52996004 4.85788002 36 P 0 0;2,4=1,6=0
L 3.48271998 4.85788002 3.48271998 4.83571998 2 P 0 
L 3.48271998 4.83571998 3.47646004 4.82946004 2 P 0 
L 3.47646004 4.82946004 3.47646004 4.60145 2 P 0 
L 3.47646004 4.60145 3.49091004 4.587 2 P 0 
P 2.39606004 3.61615 8 P 0 0;4=12,6=1
P 2.37106004 3.59115 10 P 0 0;2,4=11,6=0
L 2.39606004 3.61615 2.37106004 3.59115 5 P 0 
P 3.49091004 4.587 8 P 0 0;4=12,6=1
P 3.48271998 4.85788002 36 P 0 0;2,4=1,6=0
L 3.4591 4.85788002 3.4591 4.8359 2 P 0 
L 3.4591 4.8359 3.46536004 4.82963996 2 P 0 
L 3.46536004 4.82963996 3.46536004 4.60145 2 P 0 
L 3.46536004 4.60145 3.45091004 4.587 2 P 0 
P 2.39606004 3.66615 8 P 0 0;4=12,6=1
P 2.37106004 3.64115 10 P 0 0;2,4=11,6=0
L 2.39606004 3.66615 2.37106004 3.64115 5 P 0 
P 3.45091004 4.587 8 P 0 0;4=12,6=1
P 3.4591 4.85788002 36 P 0 0;2,4=1,6=0
L 2.49606004 3.61615 2.47106004 3.59115 5 P 0 
P 2.47106004 3.59115 10 P 0 0;2,4=11,6=0
P 2.49606004 3.61615 8 P 0 0;4=12,6=1
P 3.55358002 4.97913996 36 P 0 0;2,4=1,6=0
P 3.56176998 5.14 8 P 0 0;4=12,6=1
L 3.55358002 4.97913996 3.55358002 5.00141998 2 P 0 
L 3.55358002 5.00141998 3.54731998 5.00768002 2 P 0 
L 3.54731998 5.00768002 3.54731998 5.12555 2 P 0 
L 3.54731998 5.12555 3.56176998 5.14 2 P 0 
P 2.49606004 3.66615 8 P 0 0;4=12,6=1
P 2.47106004 3.64115 10 P 0 0;2,4=11,6=0
L 2.49606004 3.66615 2.47106004 3.64115 5 P 0 
L 3.52996004 4.97913996 3.52996004 5.00196004 2 P 0 
L 3.52996004 5.00196004 3.53621998 5.00821998 2 P 0 
L 3.53621998 5.00821998 3.53621998 5.12555 2 P 0 
L 3.53621998 5.12555 3.52176998 5.14 2 P 0 
P 3.52176998 5.14 8 P 0 0;4=12,6=1
P 3.52996004 4.97913996 36 P 0 0;2,4=1,6=0
P 2.44606004 3.66615 8 P 0 0;4=12,6=1
P 2.42106004 3.64115 10 P 0 0;2,4=11,6=0
L 2.44606004 3.66615 2.42106004 3.64115 5 P 0 
P 3.42003996 4.78291998 8 P 0 0;4=12,6=1
L 3.41185 4.85788002 3.41185 4.83583996 2 P 0 
L 3.41185 4.83583996 3.40558996 4.82958002 2 P 0 
L 3.40558996 4.82958002 3.40558996 4.79736998 2 P 0 
L 3.40558996 4.79736998 3.42003996 4.78291998 2 P 0 
P 3.41185 4.85788002 36 P 0 0;2,4=1,6=0
P 4.65768002 2.99115 10 P 0 0;2,4=11,6=0
L 4.65768002 2.99115 4.63268002 3.01615 9 P 0 
P 4.60768002 3.09115 10 P 0 0;2,4=11,6=0
L 4.60768002 3.09115 4.58268002 3.11615 9 P 0 
P 4.60768002 2.99115 10 P 0 0;2,4=11,6=0
L 4.60768002 2.99115 4.58268002 3.01615 9 P 0 
P 4.65768002 3.09115 10 P 0 0;2,4=11,6=0
L 4.65768002 3.09115 4.63268002 3.11615 9 P 0 
P 4.65768002 2.94115 10 P 0 0;2,4=11,6=0
L 4.65768002 2.94115 4.63268002 2.96615 9 P 0 
P 4.60768002 2.94115 10 P 0 0;2,4=11,6=0
L 4.60768002 2.94115 4.58268002 2.96615 9 P 0 
P 4.80768002 2.99115 10 P 0 0;2,4=11,6=0
L 4.80768002 2.99115 4.78268002 3.01615 9 P 0 
P 4.80768002 3.09115 10 P 0 0;2,4=11,6=0
L 4.80768002 3.09115 4.78268002 3.11615 9 P 0 
P 4.85768002 3.09115 10 P 0 0;2,4=11,6=0
P 4.85768002 2.99115 10 P 0 0;2,4=11,6=0
P 4.75768002 2.99115 10 P 0 0;2,4=11,6=0
L 4.75768002 2.99115 4.73268002 3.01615 9 P 0 
P 4.75768002 3.09115 10 P 0 0;2,4=11,6=0
L 4.75768002 3.09115 4.73268002 3.11615 9 P 0 
P 4.70768002 2.99115 10 P 0 0;2,4=11,6=0
L 4.70768002 2.99115 4.68268002 3.01615 9 P 0 
P 4.70768002 3.09115 10 P 0 0;2,4=11,6=0
L 4.70768002 3.09115 4.68268002 3.11615 9 P 0 
P 4.80768002 2.94115 10 P 0 0;2,4=11,6=0
L 4.80768002 2.94115 4.78268002 2.96615 9 P 0 
P 4.85768002 2.94115 10 P 0 0;2,4=11,6=0
P 4.75768002 2.94115 10 P 0 0;2,4=11,6=0
L 4.75768002 2.94115 4.73268002 2.96615 9 P 0 
P 4.70768002 2.94115 10 P 0 0;2,4=11,6=0
L 4.70768002 2.94115 4.68268002 2.96615 9 P 0 
P 5.00768002 2.99115 10 P 0 0;2,4=11,6=0
P 5.00768002 3.09115 10 P 0 0;2,4=11,6=0
P 5.05768002 2.99115 10 P 0 0;2,4=11,6=0
P 5.05768002 3.09115 10 P 0 0;2,4=11,6=0
P 4.90768002 2.99115 10 P 0 0;2,4=11,6=0
P 4.90768002 3.09115 10 P 0 0;2,4=11,6=0
P 4.95768002 3.09115 10 P 0 0;2,4=11,6=0
P 4.95768002 2.99115 10 P 0 0;2,4=11,6=0
P 5.05768002 2.94115 10 P 0 0;2,4=11,6=0
P 5.00768002 2.94115 10 P 0 0;2,4=11,6=0
P 4.90768002 2.94115 10 P 0 0;2,4=11,6=0
P 4.95768002 2.94115 10 P 0 0;2,4=11,6=0
P 4.65768002 3.24115 10 P 0 0;2,4=11,6=0
L 4.65768002 3.24115 4.63268002 3.26615 9 P 0 
P 4.60768002 3.29115 10 P 0 0;2,4=11,6=0
L 4.60768002 3.29115 4.58268002 3.31615 9 P 0 
P 4.60768002 3.24115 10 P 0 0;2,4=11,6=0
L 4.60768002 3.24115 4.58268002 3.26615 9 P 0 
P 4.65768002 3.29115 10 P 0 0;2,4=11,6=0
L 4.65768002 3.29115 4.63268002 3.31615 9 P 0 
P 4.60768002 3.14115 10 P 0 0;2,4=11,6=0
L 4.60768002 3.14115 4.58268002 3.16615 9 P 0 
P 4.65768002 3.14115 10 P 0 0;2,4=11,6=0
L 4.65768002 3.14115 4.63268002 3.16615 9 P 0 
P 4.80768002 3.29115 10 P 0 0;2,4=11,6=0
L 4.80768002 3.29115 4.78268002 3.31615 9 P 0 
P 4.80768002 3.24115 10 P 0 0;2,4=11,6=0
L 4.80768002 3.24115 4.78268002 3.26615 9 P 0 
P 4.85768002 3.24115 10 P 0 0;2,4=11,6=0
P 4.85768002 3.29115 10 P 0 0;2,4=11,6=0
P 4.70768002 3.29115 10 P 0 0;2,4=11,6=0
L 4.70768002 3.29115 4.68268002 3.31615 9 P 0 
P 4.70768002 3.24115 10 P 0 0;2,4=11,6=0
L 4.70768002 3.24115 4.68268002 3.26615 9 P 0 
P 4.75768002 3.24115 10 P 0 0;2,4=11,6=0
L 4.75768002 3.24115 4.73268002 3.26615 9 P 0 
P 4.75768002 3.29115 10 P 0 0;2,4=11,6=0
L 4.75768002 3.29115 4.73268002 3.31615 9 P 0 
P 4.80768002 3.14115 10 P 0 0;2,4=11,6=0
L 4.80768002 3.14115 4.78268002 3.16615 9 P 0 
P 4.85768002 3.14115 10 P 0 0;2,4=11,6=0
P 4.70768002 3.14115 10 P 0 0;2,4=11,6=0
L 4.70768002 3.14115 4.68268002 3.16615 9 P 0 
P 4.75768002 3.14115 10 P 0 0;2,4=11,6=0
L 4.75768002 3.14115 4.73268002 3.16615 9 P 0 
P 5.00768002 3.29115 10 P 0 0;2,4=11,6=0
P 5.05768002 3.29115 10 P 0 0;2,4=11,6=0
P 5.00768002 3.24115 10 P 0 0;2,4=11,6=0
P 5.05768002 3.24115 10 P 0 0;2,4=11,6=0
P 4.95768002 3.24115 10 P 0 0;2,4=11,6=0
P 4.95768002 3.29115 10 P 0 0;2,4=11,6=0
P 4.90768002 3.29115 10 P 0 0;2,4=11,6=0
P 4.90768002 3.24115 10 P 0 0;2,4=11,6=0
P 5.00768002 3.14115 10 P 0 0;2,4=11,6=0
P 5.05768002 3.14115 10 P 0 0;2,4=11,6=0
P 4.95768002 3.14115 10 P 0 0;2,4=11,6=0
P 4.90768002 3.14115 10 P 0 0;2,4=11,6=0
P 4.65768002 3.54115 10 P 0 0;2,4=11,6=0
L 4.65768002 3.54115 4.63268002 3.56615 9 P 0 
P 4.65768002 3.59115 10 P 0 0;2,4=11,6=0
L 4.65768002 3.59115 4.63268002 3.61615 9 P 0 
P 4.60768002 3.54115 10 P 0 0;2,4=11,6=0
L 4.60768002 3.54115 4.58268002 3.56615 9 P 0 
P 4.60768002 3.59115 10 P 0 0;2,4=11,6=0
L 4.60768002 3.59115 4.58268002 3.61615 9 P 0 
P 4.60768002 3.39115 10 P 0 0;2,4=11,6=0
L 4.60768002 3.39115 4.58268002 3.41615 9 P 0 
P 4.65768002 3.44115 10 P 0 0;2,4=11,6=0
L 4.65768002 3.44115 4.63268002 3.46615 9 P 0 
P 4.65768002 3.39115 10 P 0 0;2,4=11,6=0
L 4.65768002 3.39115 4.63268002 3.41615 9 P 0 
P 4.60768002 3.44115 10 P 0 0;2,4=11,6=0
L 4.60768002 3.44115 4.58268002 3.46615 9 P 0 
P 4.80768002 3.54115 10 P 0 0;2,4=11,6=0
L 4.80768002 3.54115 4.78268002 3.56615 9 P 0 
P 4.80768002 3.59115 10 P 0 0;2,4=11,6=0
L 4.80768002 3.59115 4.78268002 3.61615 9 P 0 
P 4.85768002 3.54115 10 P 0 0;2,4=11,6=0
P 4.85768002 3.59115 10 P 0 0;2,4=11,6=0
P 4.70768002 3.59115 10 P 0 0;2,4=11,6=0
L 4.70768002 3.59115 4.68268002 3.61615 9 P 0 
P 4.70768002 3.54115 10 P 0 0;2,4=11,6=0
L 4.70768002 3.54115 4.68268002 3.56615 9 P 0 
P 4.75768002 3.59115 10 P 0 0;2,4=11,6=0
L 4.75768002 3.59115 4.73268002 3.61615 9 P 0 
P 4.75768002 3.54115 10 P 0 0;2,4=11,6=0
L 4.75768002 3.54115 4.73268002 3.56615 9 P 0 
P 4.80768002 3.39115 10 P 0 0;2,4=11,6=0
L 4.80768002 3.39115 4.78268002 3.41615 9 P 0 
P 4.80768002 3.44115 10 P 0 0;2,4=11,6=0
L 4.80768002 3.44115 4.78268002 3.46615 9 P 0 
P 4.85768002 3.44115 10 P 0 0;2,4=11,6=0
P 4.85768002 3.39115 10 P 0 0;2,4=11,6=0
P 4.75768002 3.44115 10 P 0 0;2,4=11,6=0
L 4.75768002 3.44115 4.73268002 3.46615 9 P 0 
P 4.70768002 3.44115 10 P 0 0;2,4=11,6=0
L 4.70768002 3.44115 4.68268002 3.46615 9 P 0 
P 4.70768002 3.39115 10 P 0 0;2,4=11,6=0
L 4.70768002 3.39115 4.68268002 3.41615 9 P 0 
P 4.75768002 3.39115 10 P 0 0;2,4=11,6=0
L 4.75768002 3.39115 4.73268002 3.41615 9 P 0 
P 5.00768002 3.59115 10 P 0 0;2,4=11,6=0
P 5.05768002 3.59115 10 P 0 0;2,4=11,6=0
P 5.00768002 3.54115 10 P 0 0;2,4=11,6=0
P 5.05768002 3.54115 10 P 0 0;2,4=11,6=0
P 4.95768002 3.59115 10 P 0 0;2,4=11,6=0
P 4.95768002 3.54115 10 P 0 0;2,4=11,6=0
P 4.90768002 3.59115 10 P 0 0;2,4=11,6=0
P 4.90768002 3.54115 10 P 0 0;2,4=11,6=0
P 5.00768002 3.39115 10 P 0 0;2,4=11,6=0
P 5.05768002 3.39115 10 P 0 0;2,4=11,6=0
P 5.00768002 3.44115 10 P 0 0;2,4=11,6=0
P 5.05768002 3.44115 10 P 0 0;2,4=11,6=0
P 4.90768002 3.39115 10 P 0 0;2,4=11,6=0
P 4.90768002 3.44115 10 P 0 0;2,4=11,6=0
P 4.95768002 3.39115 10 P 0 0;2,4=11,6=0
P 4.95768002 3.44115 10 P 0 0;2,4=11,6=0
P 4.65768002 3.84115 10 P 0 0;2,4=11,6=0
L 4.65768002 3.84115 4.63268002 3.86615 9 P 0 
P 4.65768002 3.74115 10 P 0 0;2,4=11,6=0
L 4.65768002 3.74115 4.63268002 3.76615 9 P 0 
P 4.60768002 3.84115 10 P 0 0;2,4=11,6=0
L 4.60768002 3.84115 4.58268002 3.86615 9 P 0 
P 4.60768002 3.74115 10 P 0 0;2,4=11,6=0
L 4.60768002 3.74115 4.58268002 3.76615 9 P 0 
P 4.65768002 3.69115 10 P 0 0;2,4=11,6=0
L 4.65768002 3.69115 4.63268002 3.71615 9 P 0 
P 4.60768002 3.69115 10 P 0 0;2,4=11,6=0
L 4.60768002 3.69115 4.58268002 3.71615 9 P 0 
P 4.80768002 3.84115 10 P 0 0;2,4=11,6=0
L 4.80768002 3.84115 4.78268002 3.86615 9 P 0 
P 4.80768002 3.74115 10 P 0 0;2,4=11,6=0
L 4.80768002 3.74115 4.78268002 3.76615 9 P 0 
P 4.85768002 3.84115 10 P 0 0;2,4=11,6=0
P 4.85768002 3.74115 10 P 0 0;2,4=11,6=0
P 4.70768002 3.84115 10 P 0 0;2,4=11,6=0
L 4.70768002 3.84115 4.68268002 3.86615 9 P 0 
P 4.70768002 3.74115 10 P 0 0;2,4=11,6=0
L 4.70768002 3.74115 4.68268002 3.76615 9 P 0 
P 4.75768002 3.84115 10 P 0 0;2,4=11,6=0
L 4.75768002 3.84115 4.73268002 3.86615 9 P 0 
P 4.75768002 3.74115 10 P 0 0;2,4=11,6=0
L 4.75768002 3.74115 4.73268002 3.76615 9 P 0 
P 4.80768002 3.69115 10 P 0 0;2,4=11,6=0
L 4.80768002 3.69115 4.78268002 3.71615 9 P 0 
P 4.85768002 3.69115 10 P 0 0;2,4=11,6=0
P 4.70768002 3.69115 10 P 0 0;2,4=11,6=0
L 4.70768002 3.69115 4.68268002 3.71615 9 P 0 
P 4.75768002 3.69115 10 P 0 0;2,4=11,6=0
L 4.75768002 3.69115 4.73268002 3.71615 9 P 0 
P 5.00768002 3.84115 10 P 0 0;2,4=11,6=0
P 5.00768002 3.74115 10 P 0 0;2,4=11,6=0
P 5.05768002 3.84115 10 P 0 0;2,4=11,6=0
P 5.05768002 3.74115 10 P 0 0;2,4=11,6=0
P 4.90768002 3.84115 10 P 0 0;2,4=11,6=0
P 4.95768002 3.74115 10 P 0 0;2,4=11,6=0
P 4.90768002 3.74115 10 P 0 0;2,4=11,6=0
P 4.95768002 3.84115 10 P 0 0;2,4=11,6=0
P 5.00768002 3.69115 10 P 0 0;2,4=11,6=0
P 5.05768002 3.69115 10 P 0 0;2,4=11,6=0
P 4.95768002 3.69115 10 P 0 0;2,4=11,6=0
P 4.90768002 3.69115 10 P 0 0;2,4=11,6=0
P 4.36305 4.74133996 53 P 0 0;2,4=25,6=0
P 4.75305 4.74133996 53 P 0 0;2,4=25,6=0
P 5.10605 4.75636998 34 P 0 0;2,4=26,6=0
P 4.30605 4.6631 9 P 0 0;4=13,6=1
P 4.34105 4.6431 9 P 0 0;4=13,6=1
P 4.38605 4.6431 9 P 0 0;4=13,6=1
P 4.42605 4.6631 9 P 0 0;4=13,6=1
P 4.46605 4.6631 9 P 0 0;4=13,6=1
P 4.30605 4.7031 9 P 0 0;4=13,6=1
P 4.42605 4.7031 9 P 0 0;4=13,6=1
P 4.46605 4.7031 9 P 0 0;4=13,6=1
P 4.26605 4.6631 9 P 0 0;4=13,6=1
P 4.26605 4.7031 9 P 0 0;4=13,6=1
P 4.65605 4.6631 9 P 0 0;4=13,6=1
P 4.69605 4.6631 9 P 0 0;4=13,6=1
P 4.65605 4.7031 9 P 0 0;4=13,6=1
P 4.69605 4.7031 9 P 0 0;4=13,6=1
P 4.73105 4.6431 9 P 0 0;4=13,6=1
P 4.81605 4.6631 9 P 0 0;4=13,6=1
P 4.85605 4.6631 9 P 0 0;4=13,6=1
P 4.81605 4.7031 9 P 0 0;4=13,6=1
P 4.85605 4.7031 9 P 0 0;4=13,6=1
P 4.77605 4.6431 9 P 0 0;4=13,6=1
P 5.17605 4.7131 9 P 0 0;4=13,6=1
P 5.17605 4.6731 9 P 0 0;4=13,6=1
P 5.08105 4.6731 9 P 0 0;4=13,6=1
P 5.13105 4.6731 9 P 0 0;4=13,6=1
P 5.03605 4.6731 9 P 0 0;4=13,6=1
P 5.03605 4.7131 9 P 0 0;4=13,6=1
P 4.30605 4.7481 9 P 0 0;4=13,6=1
P 4.30605 4.7931 9 P 0 0;4=13,6=1
P 4.30605 4.8381 9 P 0 0;4=13,6=1
P 4.38605 4.8381 9 P 0 0;4=13,6=1
P 4.34605 4.8381 9 P 0 0;4=13,6=1
P 4.46605 4.8381 9 P 0 0;4=13,6=1
P 4.42605 4.8381 9 P 0 0;4=13,6=1
P 4.42605 4.7931 9 P 0 0;4=13,6=1
P 4.42605 4.7481 9 P 0 0;4=13,6=1
P 4.46605 4.7931 9 P 0 0;4=13,6=1
P 4.46605 4.7481 9 P 0 0;4=13,6=1
P 4.26605 4.7481 9 P 0 0;4=13,6=1
P 4.26605 4.7931 9 P 0 0;4=13,6=1
P 4.26605 4.8381 9 P 0 0;4=13,6=1
P 4.65605 4.8381 9 P 0 0;4=13,6=1
P 4.65605 4.7931 9 P 0 0;4=13,6=1
P 4.65605 4.7481 9 P 0 0;4=13,6=1
P 4.69605 4.8381 9 P 0 0;4=13,6=1
P 4.69605 4.7931 9 P 0 0;4=13,6=1
P 4.69605 4.7481 9 P 0 0;4=13,6=1
P 4.73605 4.8381 9 P 0 0;4=13,6=1
P 4.81605 4.8381 9 P 0 0;4=13,6=1
P 4.81605 4.7931 9 P 0 0;4=13,6=1
P 4.81605 4.7481 9 P 0 0;4=13,6=1
P 4.85605 4.8381 9 P 0 0;4=13,6=1
P 4.85605 4.7931 9 P 0 0;4=13,6=1
P 4.85605 4.7481 9 P 0 0;4=13,6=1
P 4.77605 4.8381 9 P 0 0;4=13,6=1
P 5.08105 4.8431 9 P 0 0;4=13,6=1
P 5.13105 4.8431 9 P 0 0;4=13,6=1
P 5.17605 4.8431 9 P 0 0;4=13,6=1
P 5.17605 4.8031 9 P 0 0;4=13,6=1
P 5.17605 4.7581 9 P 0 0;4=13,6=1
P 5.03605 4.8431 9 P 0 0;4=13,6=1
P 5.03605 4.8031 9 P 0 0;4=13,6=1
P 5.03605 4.7581 9 P 0 0;4=13,6=1
P 4.58268002 2.96615 8 P 0 0;4=12,6=1
P 4.63268002 2.96615 8 P 0 0;4=12,6=1
P 4.63268002 3.11615 8 P 0 0;4=12,6=1
P 4.58268002 3.01615 8 P 0 0;4=12,6=1
P 4.58268002 3.11615 8 P 0 0;4=12,6=1
P 4.63268002 3.01615 8 P 0 0;4=12,6=1
P 4.63268002 3.31615 8 P 0 0;4=12,6=1
P 4.58268002 3.26615 8 P 0 0;4=12,6=1
P 4.58268002 3.31615 8 P 0 0;4=12,6=1
P 4.63268002 3.26615 8 P 0 0;4=12,6=1
P 4.63268002 3.16615 8 P 0 0;4=12,6=1
P 4.58268002 3.16615 8 P 0 0;4=12,6=1
P 4.58268002 3.46615 8 P 0 0;4=12,6=1
P 4.63268002 3.41615 8 P 0 0;4=12,6=1
P 4.63268002 3.46615 8 P 0 0;4=12,6=1
P 4.58268002 3.41615 8 P 0 0;4=12,6=1
P 4.58268002 3.61615 8 P 0 0;4=12,6=1
P 4.58268002 3.56615 8 P 0 0;4=12,6=1
P 4.63268002 3.61615 8 P 0 0;4=12,6=1
P 4.63268002 3.56615 8 P 0 0;4=12,6=1
P 4.58268002 3.71615 8 P 0 0;4=12,6=1
P 4.63268002 3.71615 8 P 0 0;4=12,6=1
P 4.58268002 3.76615 8 P 0 0;4=12,6=1
P 4.58268002 3.86615 8 P 0 0;4=12,6=1
P 4.63268002 3.76615 8 P 0 0;4=12,6=1
P 4.63268002 3.86615 8 P 0 0;4=12,6=1
P 4.68268002 2.96615 8 P 0 0;4=12,6=1
P 4.73268002 2.96615 8 P 0 0;4=12,6=1
P 4.78268002 2.96615 8 P 0 0;4=12,6=1
P 4.68268002 3.11615 8 P 0 0;4=12,6=1
P 4.68268002 3.01615 8 P 0 0;4=12,6=1
P 4.73268002 3.11615 8 P 0 0;4=12,6=1
P 4.73268002 3.01615 8 P 0 0;4=12,6=1
P 4.78268002 3.11615 8 P 0 0;4=12,6=1
P 4.78268002 3.01615 8 P 0 0;4=12,6=1
P 4.73268002 3.31615 8 P 0 0;4=12,6=1
P 4.73268002 3.26615 8 P 0 0;4=12,6=1
P 4.68268002 3.26615 8 P 0 0;4=12,6=1
P 4.68268002 3.31615 8 P 0 0;4=12,6=1
P 4.78268002 3.26615 8 P 0 0;4=12,6=1
P 4.78268002 3.31615 8 P 0 0;4=12,6=1
P 4.73268002 3.16615 8 P 0 0;4=12,6=1
P 4.68268002 3.16615 8 P 0 0;4=12,6=1
P 4.78268002 3.16615 8 P 0 0;4=12,6=1
P 4.73268002 3.41615 8 P 0 0;4=12,6=1
P 4.68268002 3.41615 8 P 0 0;4=12,6=1
P 4.68268002 3.46615 8 P 0 0;4=12,6=1
P 4.73268002 3.46615 8 P 0 0;4=12,6=1
P 4.78268002 3.46615 8 P 0 0;4=12,6=1
P 4.78268002 3.41615 8 P 0 0;4=12,6=1
P 4.73268002 3.56615 8 P 0 0;4=12,6=1
P 4.73268002 3.61615 8 P 0 0;4=12,6=1
P 4.68268002 3.56615 8 P 0 0;4=12,6=1
P 4.68268002 3.61615 8 P 0 0;4=12,6=1
P 4.78268002 3.61615 8 P 0 0;4=12,6=1
P 4.78268002 3.56615 8 P 0 0;4=12,6=1
P 4.73268002 3.71615 8 P 0 0;4=12,6=1
P 4.68268002 3.71615 8 P 0 0;4=12,6=1
P 4.78268002 3.71615 8 P 0 0;4=12,6=1
P 4.73268002 3.76615 8 P 0 0;4=12,6=1
P 4.73268002 3.86615 8 P 0 0;4=12,6=1
P 4.68268002 3.76615 8 P 0 0;4=12,6=1
P 4.68268002 3.86615 8 P 0 0;4=12,6=1
P 4.78268002 3.76615 8 P 0 0;4=12,6=1
P 4.78268002 3.86615 8 P 0 0;4=12,6=1
L 4.90768002 3.84115 4.88268002 3.86615 9 P 0 
P 4.88268002 3.86615 8 P 0 0;4=12,6=1
L 4.85768002 3.84115 4.83268002 3.86615 9 P 0 
P 4.83268002 3.86615 8 P 0 0;4=12,6=1
L 5.05768002 3.84115 5.03268002 3.86615 9 P 0 
P 5.03268002 3.86615 8 P 0 0;4=12,6=1
L 4.95768002 3.84115 4.93268002 3.86615 9 P 0 
P 4.93268002 3.86615 8 P 0 0;4=12,6=1
L 5.00768002 3.84115 4.98268002 3.86615 9 P 0 
P 4.98268002 3.86615 8 P 0 0;4=12,6=1
L 4.90768002 3.74115 4.88268002 3.76615 9 P 0 
P 4.88268002 3.76615 8 P 0 0;4=12,6=1
L 4.85768002 3.74115 4.83268002 3.76615 9 P 0 
P 4.83268002 3.76615 8 P 0 0;4=12,6=1
L 5.05768002 3.74115 5.03268002 3.76615 9 P 0 
P 5.03268002 3.76615 8 P 0 0;4=12,6=1
L 4.95768002 3.74115 4.93268002 3.76615 9 P 0 
P 4.93268002 3.76615 8 P 0 0;4=12,6=1
L 5.00768002 3.74115 4.98268002 3.76615 9 P 0 
P 4.98268002 3.76615 8 P 0 0;4=12,6=1
L 4.90768002 3.69115 4.88268002 3.71615 9 P 0 
P 4.88268002 3.71615 8 P 0 0;4=12,6=1
L 4.85768002 3.69115 4.83268002 3.71615 9 P 0 
P 4.83268002 3.71615 8 P 0 0;4=12,6=1
L 5.05768002 3.69115 5.03268002 3.71615 9 P 0 
P 5.03268002 3.71615 8 P 0 0;4=12,6=1
L 4.95768002 3.69115 4.93268002 3.71615 9 P 0 
P 4.93268002 3.71615 8 P 0 0;4=12,6=1
L 5.00768002 3.69115 4.98268002 3.71615 9 P 0 
P 4.98268002 3.71615 8 P 0 0;4=12,6=1
L 4.90768002 3.59115 4.88268002 3.61615 9 P 0 
P 4.88268002 3.61615 8 P 0 0;4=12,6=1
L 4.85768002 3.59115 4.83268002 3.61615 9 P 0 
P 4.83268002 3.61615 8 P 0 0;4=12,6=1
L 5.05768002 3.59115 5.03268002 3.61615 9 P 0 
P 5.03268002 3.61615 8 P 0 0;4=12,6=1
L 4.95768002 3.59115 4.93268002 3.61615 9 P 0 
P 4.93268002 3.61615 8 P 0 0;4=12,6=1
L 5.00768002 3.59115 4.98268002 3.61615 9 P 0 
P 4.98268002 3.61615 8 P 0 0;4=12,6=1
L 4.90768002 3.54115 4.88268002 3.56615 9 P 0 
P 4.88268002 3.56615 8 P 0 0;4=12,6=1
L 4.85768002 3.54115 4.83268002 3.56615 9 P 0 
P 4.83268002 3.56615 8 P 0 0;4=12,6=1
L 5.05768002 3.54115 5.03268002 3.56615 9 P 0 
P 5.03268002 3.56615 8 P 0 0;4=12,6=1
L 4.95768002 3.54115 4.93268002 3.56615 9 P 0 
P 4.93268002 3.56615 8 P 0 0;4=12,6=1
L 5.00768002 3.54115 4.98268002 3.56615 9 P 0 
P 4.98268002 3.56615 8 P 0 0;4=12,6=1
L 4.90768002 3.44115 4.88268002 3.46615 9 P 0 
P 4.88268002 3.46615 8 P 0 0;4=12,6=1
L 4.85768002 3.44115 4.83268002 3.46615 9 P 0 
P 4.83268002 3.46615 8 P 0 0;4=12,6=1
L 5.05768002 3.44115 5.03268002 3.46615 9 P 0 
P 5.03268002 3.46615 8 P 0 0;4=12,6=1
L 4.95768002 3.44115 4.93268002 3.46615 9 P 0 
P 4.93268002 3.46615 8 P 0 0;4=12,6=1
L 5.00768002 3.44115 4.98268002 3.46615 9 P 0 
P 4.98268002 3.46615 8 P 0 0;4=12,6=1
L 4.90768002 3.39115 4.88268002 3.41615 9 P 0 
P 4.88268002 3.41615 8 P 0 0;4=12,6=1
L 4.85768002 3.39115 4.83268002 3.41615 9 P 0 
P 4.83268002 3.41615 8 P 0 0;4=12,6=1
L 5.05768002 3.39115 5.03268002 3.41615 9 P 0 
P 5.03268002 3.41615 8 P 0 0;4=12,6=1
L 4.95768002 3.39115 4.93268002 3.41615 9 P 0 
P 4.93268002 3.41615 8 P 0 0;4=12,6=1
L 5.00768002 3.39115 4.98268002 3.41615 9 P 0 
P 4.98268002 3.41615 8 P 0 0;4=12,6=1
L 4.90768002 3.29115 4.88268002 3.31615 9 P 0 
P 4.88268002 3.31615 8 P 0 0;4=12,6=1
L 4.85768002 3.29115 4.83268002 3.31615 9 P 0 
P 4.83268002 3.31615 8 P 0 0;4=12,6=1
L 5.05768002 3.29115 5.03268002 3.31615 9 P 0 
P 5.03268002 3.31615 8 P 0 0;4=12,6=1
L 4.95768002 3.29115 4.93268002 3.31615 9 P 0 
P 4.93268002 3.31615 8 P 0 0;4=12,6=1
L 5.00768002 3.29115 4.98268002 3.31615 9 P 0 
P 4.98268002 3.31615 8 P 0 0;4=12,6=1
L 4.85768002 3.24115 4.83268002 3.26615 9 P 0 
P 4.83268002 3.26615 8 P 0 0;4=12,6=1
L 4.90768002 3.24115 4.88268002 3.26615 9 P 0 
P 4.88268002 3.26615 8 P 0 0;4=12,6=1
L 5.00768002 3.24115 4.98268002 3.26615 9 P 0 
P 4.98268002 3.26615 8 P 0 0;4=12,6=1
L 4.95768002 3.24115 4.93268002 3.26615 9 P 0 
P 4.93268002 3.26615 8 P 0 0;4=12,6=1
L 5.05768002 3.24115 5.03268002 3.26615 9 P 0 
P 5.03268002 3.26615 8 P 0 0;4=12,6=1
L 4.85768002 3.14115 4.83268002 3.16615 9 P 0 
P 4.83268002 3.16615 8 P 0 0;4=12,6=1
L 4.90768002 3.14115 4.88268002 3.16615 9 P 0 
P 4.88268002 3.16615 8 P 0 0;4=12,6=1
L 5.00768002 3.14115 4.98268002 3.16615 9 P 0 
P 4.98268002 3.16615 8 P 0 0;4=12,6=1
L 4.95768002 3.14115 4.93268002 3.16615 9 P 0 
P 4.93268002 3.16615 8 P 0 0;4=12,6=1
L 5.05768002 3.14115 5.03268002 3.16615 9 P 0 
P 5.03268002 3.16615 8 P 0 0;4=12,6=1
L 4.85768002 3.09115 4.83268002 3.11615 9 P 0 
P 4.83268002 3.11615 8 P 0 0;4=12,6=1
L 4.90768002 3.09115 4.88268002 3.11615 9 P 0 
P 4.88268002 3.11615 8 P 0 0;4=12,6=1
L 5.00768002 3.09115 4.98268002 3.11615 9 P 0 
P 4.98268002 3.11615 8 P 0 0;4=12,6=1
L 4.95768002 3.09115 4.93268002 3.11615 9 P 0 
P 4.93268002 3.11615 8 P 0 0;4=12,6=1
L 5.05768002 3.09115 5.03268002 3.11615 9 P 0 
P 5.03268002 3.11615 8 P 0 0;4=12,6=1
L 4.85768002 2.99115 4.83268002 3.01615 9 P 0 
P 4.83268002 3.01615 8 P 0 0;4=12,6=1
L 4.90768002 2.99115 4.88268002 3.01615 9 P 0 
P 4.88268002 3.01615 8 P 0 0;4=12,6=1
L 5.00768002 2.99115 4.98268002 3.01615 9 P 0 
P 4.98268002 3.01615 8 P 0 0;4=12,6=1
L 4.95768002 2.99115 4.93268002 3.01615 9 P 0 
P 4.93268002 3.01615 8 P 0 0;4=12,6=1
L 5.05768002 2.99115 5.03268002 3.01615 9 P 0 
P 5.03268002 3.01615 8 P 0 0;4=12,6=1
L 4.85768002 2.94115 4.83268002 2.96615 9 P 0 
P 4.83268002 2.96615 8 P 0 0;4=12,6=1
L 4.90768002 2.94115 4.88268002 2.96615 9 P 0 
P 4.88268002 2.96615 8 P 0 0;4=12,6=1
L 5.00768002 2.94115 4.98268002 2.96615 9 P 0 
P 4.98268002 2.96615 8 P 0 0;4=12,6=1
L 4.95768002 2.94115 4.93268002 2.96615 9 P 0 
P 4.93268002 2.96615 8 P 0 0;4=12,6=1
L 5.05768002 2.94115 5.03268002 2.96615 9 P 0 
P 5.03268002 2.96615 8 P 0 0;4=12,6=1
S P 0
OB 4.47406003937 2.932 I
OS 4.46006003937 2.946
OS 4.46006003937 3.726
OS 4.25605 3.93001003937
OS 4.25605 4.8381
OS 4.26605 4.8481
OS 5.18105 4.8481
OS 5.22106003937 4.80808996063
OS 5.22106003937 2.947
OS 5.20606003937 2.932
OS 5.04123996063 2.932
OC 5.024119980315 2.932 5.032680019685 2.91615 N
OS 4.99123996063 2.932
OC 4.974119980315 2.932 4.982680019685 2.91615 N
OS 4.94123996063 2.932
OC 4.924119980315 2.932 4.932680019685 2.91615 N
OS 4.89123996063 2.932
OC 4.874119980315 2.932 4.882680019685 2.91615 N
OS 4.84123996063 2.932
OC 4.824119980315 2.932 4.832680019685 2.91615 N
OS 4.79123996063 2.932
OC 4.774119980315 2.932 4.782680019685 2.91615 N
OS 4.74123996063 2.932
OC 4.724119980315 2.932 4.732680019685 2.91615 N
OS 4.69123996063 2.932
OC 4.674119980315 2.932 4.682680019685 2.91615 N
OS 4.64123996063 2.932
OC 4.624119980315 2.932 4.632680019685 2.91615 N
OS 4.59123996063 2.932
OC 4.574119980315 2.932 4.582680019685 2.91615 N
OS 4.47406003937 2.932
OE
OB 4.60803996063 3.816269980315 H
OS 4.595419980315 3.82888996063
OC 4.56993996063 3.80341003937 4.582680019685 3.81615 N
OS 4.58783996063 3.78551003937
OS 4.58798996063 3.78503996063
OC 4.608590846457 3.770550098425 4.607683759843 3.79115 N
OC 4.62783996063 3.7868 4.607684153543 3.79115 N
OC 4.63061988189 3.789785137795 4.63175 3.785945767717 Y
OC 4.634569980315 3.788780019685 4.631746948819 3.78595 Y
OS 4.63783996063 3.78551003937
OS 4.63798996063 3.78503996063
OC 4.658590846457 3.770550098425 4.657683759843 3.79115 N
OC 4.67783996063 3.7868 4.657684153543 3.79115 N
OC 4.68061988189 3.789785137795 4.68175 3.785945767717 Y
OC 4.684569980315 3.788780019685 4.681746948819 3.78595 Y
OS 4.68783996063 3.78551003937
OS 4.68798996063 3.78503996063
OC 4.708590846457 3.770550098425 4.707683759843 3.79115 N
OC 4.72783996063 3.7868 4.707684153543 3.79115 N
OC 4.73061988189 3.789785137795 4.73175 3.785945767717 Y
OC 4.734569980315 3.788780019685 4.731746948819 3.78595 Y
OS 4.73783996063 3.78551003937
OS 4.73798996063 3.78503996063
OC 4.758590846457 3.770550098425 4.757683759843 3.79115 N
OC 4.77783996063 3.7868 4.757684153543 3.79115 N
OC 4.78061988189 3.789785137795 4.78175 3.785945767717 Y
OC 4.784569980315 3.788780019685 4.781746948819 3.78595 Y
OS 4.78783996063 3.78551003937
OS 4.78798996063 3.78503996063
OC 4.808590846457 3.770550098425 4.807683759843 3.79115 N
OC 4.82783996063 3.7868 4.807684153543 3.79115 N
OC 4.83061988189 3.789785137795 4.83175 3.785945767717 Y
OC 4.834569980315 3.788780019685 4.831746948819 3.78595 Y
OS 4.83783996063 3.78551003937
OS 4.83798996063 3.78503996063
OC 4.858590846457 3.770550098425 4.857683759843 3.79115 N
OC 4.87783996063 3.7868 4.857684153543 3.79115 N
OC 4.88061988189 3.789785137795 4.88175 3.785945767717 Y
OC 4.884569980315 3.788780019685 4.881746948819 3.78595 Y
OS 4.88783996063 3.78551003937
OS 4.88798996063 3.78503996063
OC 4.908590846457 3.770550098425 4.907683759843 3.79115 N
OC 4.92783996063 3.7868 4.907684153543 3.79115 N
OC 4.93061988189 3.789785137795 4.93175 3.785945767717 Y
OC 4.934569980315 3.788780019685 4.931746948819 3.78595 Y
OS 4.93783996063 3.78551003937
OS 4.93798996063 3.78503996063
OC 4.958590846457 3.770550098425 4.957683759843 3.79115 N
OC 4.97783996063 3.7868 4.957684153543 3.79115 N
OC 4.98061988189 3.789785137795 4.98175 3.785945767717 Y
OC 4.984569980315 3.788780019685 4.981746948819 3.78595 Y
OS 4.98783996063 3.78551003937
OS 4.98798996063 3.78503996063
OC 5.014085728346 3.771552755906 5.007681102362 3.79115 N
OC 5.027180019685 3.79785 5.007680019685 3.791151082677 N
OC 5.027571653543 3.799811515748 5.029069980315 3.798492519685 Y
OC 5.029469980315 3.80045 5.029072637795 3.79848996063 Y
OC 5.0312 3.8002 5.032623228346 3.81616003937 N
OS 5.031919980315 3.800130019685
OS 5.03735 3.79471003937
OS 5.037219980315 3.793730019685
OC 5.0551 3.81161003937 5.057680019685 3.79115 N
OS 5.054119980315 3.811480019685
OS 5.0487 3.81691003937
OS 5.048630019685 3.817630019685
OC 5.030331692913 3.831987992126 5.032678641732 3.81613996063 N
OC 5.016980019685 3.81293996063 5.032680019685 3.816138484252 N
OC 5.016341535433 3.811041633858 5.015019980315 3.81254261811 Y
OC 5.014380019685 3.81065 5.01502253937 3.81253996063 Y
OC 5.01378996063 3.81083996063 5.007767027559 3.791119980315 N
OS 5.013319980315 3.81098996063
OS 4.995419980315 3.82888996063
OC 4.976917716535 3.833218011811 4.982682480315 3.81615 N
OC 4.964830019685 3.81856003937 4.982680019685 3.816153051181 N
OC 4.962146751969 3.81530984252 4.960869980315 3.819096653543 Y
OC 4.95803996063 3.816269980315 4.960867224409 3.8191 Y
OS 4.945419980315 3.82888996063
OC 4.926917716535 3.833218011811 4.932682480315 3.81615 N
OC 4.914830019685 3.81856003937 4.932680019685 3.816153051181 N
OC 4.912146751969 3.81530984252 4.910869980315 3.819096653543 Y
OC 4.90803996063 3.816269980315 4.910867224409 3.8191 Y
OS 4.895419980315 3.82888996063
OC 4.876917716535 3.833218011811 4.882682480315 3.81615 N
OC 4.864830019685 3.81856003937 4.882680019685 3.816153051181 N
OC 4.862146751969 3.81530984252 4.860869980315 3.819096653543 Y
OC 4.85803996063 3.816269980315 4.860867224409 3.8191 Y
OS 4.845419980315 3.82888996063
OC 4.826917716535 3.833218011811 4.832682480315 3.81615 N
OC 4.814830019685 3.81856003937 4.832680019685 3.816153051181 N
OC 4.812146751969 3.81530984252 4.810869980315 3.819096653543 Y
OC 4.80803996063 3.816269980315 4.810867224409 3.8191 Y
OS 4.795419980315 3.82888996063
OC 4.776917716535 3.833218011811 4.782682480315 3.81615 N
OC 4.764830019685 3.81856003937 4.782680019685 3.816153051181 N
OC 4.762146751969 3.81530984252 4.760869980315 3.819096653543 Y
OC 4.75803996063 3.816269980315 4.760867224409 3.8191 Y
OS 4.745419980315 3.82888996063
OC 4.726917716535 3.833218011811 4.732682480315 3.81615 N
OC 4.714830019685 3.81856003937 4.732680019685 3.816153051181 N
OC 4.712146751969 3.81530984252 4.710869980315 3.819096653543 Y
OC 4.70803996063 3.816269980315 4.710867224409 3.8191 Y
OS 4.695419980315 3.82888996063
OC 4.676917716535 3.833218011811 4.682682480315 3.81615 N
OC 4.664830019685 3.81856003937 4.682680019685 3.816153051181 N
OC 4.662146751969 3.81530984252 4.660869980315 3.819096653543 Y
OC 4.65803996063 3.816269980315 4.660867224409 3.8191 Y
OS 4.645419980315 3.82888996063
OC 4.626917716535 3.833218011811 4.632682480315 3.81615 N
OC 4.614830019685 3.81856003937 4.632680019685 3.816153051181 N
OC 4.612146751969 3.81530984252 4.610869980315 3.819096653543 Y
OC 4.60803996063 3.816269980315 4.610867224409 3.8191 Y
OE
OB 4.60803996063 3.666269980315 H
OS 4.595419980315 3.67888996063
OC 4.56993996063 3.65341003937 4.582680019685 3.66615 N
OS 4.58783996063 3.63551003937
OS 4.58798996063 3.63503996063
OC 4.608590846457 3.620550098425 4.607683759843 3.64115 N
OC 4.62783996063 3.6368 4.607684153543 3.64115 N
OC 4.63061988189 3.639785137795 4.63175 3.635945767717 Y
OC 4.634569980315 3.638780019685 4.631746948819 3.63595 Y
OS 4.63783996063 3.63551003937
OS 4.63798996063 3.63503996063
OC 4.658590846457 3.620550098425 4.657683759843 3.64115 N
OC 4.67783996063 3.6368 4.657684153543 3.64115 N
OC 4.68061988189 3.639785137795 4.68175 3.635945767717 Y
OC 4.684569980315 3.638780019685 4.681746948819 3.63595 Y
OS 4.68783996063 3.63551003937
OS 4.68798996063 3.63503996063
OC 4.708590846457 3.620550098425 4.707683759843 3.64115 N
OC 4.72783996063 3.6368 4.707684153543 3.64115 N
OC 4.73061988189 3.639785137795 4.73175 3.635945767717 Y
OC 4.734569980315 3.638780019685 4.731746948819 3.63595 Y
OS 4.73783996063 3.63551003937
OS 4.73798996063 3.63503996063
OC 4.758590846457 3.620550098425 4.757683759843 3.64115 N
OC 4.77783996063 3.6368 4.757684153543 3.64115 N
OC 4.78061988189 3.639785137795 4.78175 3.635945767717 Y
OC 4.784569980315 3.638780019685 4.781746948819 3.63595 Y
OS 4.78783996063 3.63551003937
OS 4.78798996063 3.63503996063
OC 4.808590846457 3.620550098425 4.807683759843 3.64115 N
OC 4.82783996063 3.6368 4.807684153543 3.64115 N
OC 4.83061988189 3.639785137795 4.83175 3.635945767717 Y
OC 4.834569980315 3.638780019685 4.831746948819 3.63595 Y
OS 4.83783996063 3.63551003937
OS 4.83798996063 3.63503996063
OC 4.858590846457 3.620550098425 4.857683759843 3.64115 N
OC 4.87783996063 3.6368 4.857684153543 3.64115 N
OC 4.88061988189 3.639785137795 4.88175 3.635945767717 Y
OC 4.884569980315 3.638780019685 4.881746948819 3.63595 Y
OS 4.88783996063 3.63551003937
OS 4.88798996063 3.63503996063
OC 4.908590846457 3.620550098425 4.907683759843 3.64115 N
OC 4.92783996063 3.6368 4.907684153543 3.64115 N
OC 4.93061988189 3.639785137795 4.93175 3.635945767717 Y
OC 4.934569980315 3.638780019685 4.931746948819 3.63595 Y
OS 4.93783996063 3.63551003937
OS 4.93798996063 3.63503996063
OC 4.958590846457 3.620550098425 4.957683759843 3.64115 N
OC 4.97783996063 3.6368 4.957684153543 3.64115 N
OC 4.98061988189 3.639785137795 4.98175 3.635945767717 Y
OC 4.984569980315 3.638780019685 4.981746948819 3.63595 Y
OS 4.98783996063 3.63551003937
OS 4.98798996063 3.63503996063
OC 5.008590846457 3.620550098425 5.007683759843 3.64115 N
OC 5.02783996063 3.6368 5.007684153543 3.64115 N
OC 5.03061988189 3.639785137795 5.03175 3.635945767717 Y
OC 5.034569980315 3.638780019685 5.031746948819 3.63595 Y
OS 5.03783996063 3.63551003937
OS 5.03798996063 3.63503996063
OC 5.06378996063 3.66083996063 5.05767992126 3.64115 N
OS 5.063319980315 3.66098996063
OS 5.045419980315 3.67888996063
OC 5.026917716535 3.683218011811 5.032682480315 3.66615 N
OC 5.014830019685 3.66856003937 5.032680019685 3.666153051181 N
OC 5.012146751969 3.66530984252 5.010869980315 3.669096653543 Y
OC 5.00803996063 3.666269980315 5.010867224409 3.6691 Y
OS 4.995419980315 3.67888996063
OC 4.976917716535 3.683218011811 4.982682480315 3.66615 N
OC 4.964830019685 3.66856003937 4.982680019685 3.666153051181 N
OC 4.962146751969 3.66530984252 4.960869980315 3.669096653543 Y
OC 4.95803996063 3.666269980315 4.960867224409 3.6691 Y
OS 4.945419980315 3.67888996063
OC 4.926917716535 3.683218011811 4.932682480315 3.66615 N
OC 4.914830019685 3.66856003937 4.932680019685 3.666153051181 N
OC 4.912146751969 3.66530984252 4.910869980315 3.669096653543 Y
OC 4.90803996063 3.666269980315 4.910867224409 3.6691 Y
OS 4.895419980315 3.67888996063
OC 4.876917716535 3.683218011811 4.882682480315 3.66615 N
OC 4.864830019685 3.66856003937 4.882680019685 3.666153051181 N
OC 4.862146751969 3.66530984252 4.860869980315 3.669096653543 Y
OC 4.85803996063 3.666269980315 4.860867224409 3.6691 Y
OS 4.845419980315 3.67888996063
OC 4.826917716535 3.683218011811 4.832682480315 3.66615 N
OC 4.814830019685 3.66856003937 4.832680019685 3.666153051181 N
OC 4.812146751969 3.66530984252 4.810869980315 3.669096653543 Y
OC 4.80803996063 3.666269980315 4.810867224409 3.6691 Y
OS 4.795419980315 3.67888996063
OC 4.776917716535 3.683218011811 4.782682480315 3.66615 N
OC 4.764830019685 3.66856003937 4.782680019685 3.666153051181 N
OC 4.762146751969 3.66530984252 4.760869980315 3.669096653543 Y
OC 4.75803996063 3.666269980315 4.760867224409 3.6691 Y
OS 4.745419980315 3.67888996063
OC 4.726917716535 3.683218011811 4.732682480315 3.66615 N
OC 4.714830019685 3.66856003937 4.732680019685 3.666153051181 N
OC 4.712146751969 3.66530984252 4.710869980315 3.669096653543 Y
OC 4.70803996063 3.666269980315 4.710867224409 3.6691 Y
OS 4.695419980315 3.67888996063
OC 4.676917716535 3.683218011811 4.682682480315 3.66615 N
OC 4.664830019685 3.66856003937 4.682680019685 3.666153051181 N
OC 4.662146751969 3.66530984252 4.660869980315 3.669096653543 Y
OC 4.65803996063 3.666269980315 4.660867224409 3.6691 Y
OS 4.645419980315 3.67888996063
OC 4.626917716535 3.683218011811 4.632682480315 3.66615 N
OC 4.614830019685 3.66856003937 4.632680019685 3.666153051181 N
OC 4.612146751969 3.66530984252 4.610869980315 3.669096653543 Y
OC 4.60803996063 3.666269980315 4.610867224409 3.6691 Y
OE
OB 4.60803996063 3.516269980315 H
OS 4.595419980315 3.52888996063
OC 4.56993996063 3.50341003937 4.582680019685 3.51615 N
OS 4.58783996063 3.48551003937
OS 4.58798996063 3.48503996063
OC 4.608590846457 3.470550098425 4.607683759843 3.49115 N
OC 4.62783996063 3.4868 4.607684153543 3.49115 N
OC 4.63061988189 3.489785137795 4.63175 3.485945767717 Y
OC 4.634569980315 3.488780019685 4.631746948819 3.48595 Y
OS 4.63783996063 3.48551003937
OS 4.63798996063 3.48503996063
OC 4.658590846457 3.470550098425 4.657683759843 3.49115 N
OC 4.67783996063 3.4868 4.657684153543 3.49115 N
OC 4.68061988189 3.489785137795 4.68175 3.485945767717 Y
OC 4.684569980315 3.488780019685 4.681746948819 3.48595 Y
OS 4.68783996063 3.48551003937
OS 4.68798996063 3.48503996063
OC 4.708590846457 3.470550098425 4.707683759843 3.49115 N
OC 4.72783996063 3.4868 4.707684153543 3.49115 N
OC 4.73061988189 3.489785137795 4.73175 3.485945767717 Y
OC 4.734569980315 3.488780019685 4.731746948819 3.48595 Y
OS 4.73783996063 3.48551003937
OS 4.73798996063 3.48503996063
OC 4.758590846457 3.470550098425 4.757683759843 3.49115 N
OC 4.77783996063 3.4868 4.757684153543 3.49115 N
OC 4.78061988189 3.489785137795 4.78175 3.485945767717 Y
OC 4.784569980315 3.488780019685 4.781746948819 3.48595 Y
OS 4.78783996063 3.48551003937
OS 4.78798996063 3.48503996063
OC 4.808590846457 3.470550098425 4.807683759843 3.49115 N
OC 4.82783996063 3.4868 4.807684153543 3.49115 N
OC 4.83061988189 3.489785137795 4.83175 3.485945767717 Y
OC 4.834569980315 3.488780019685 4.831746948819 3.48595 Y
OS 4.83783996063 3.48551003937
OS 4.83798996063 3.48503996063
OC 4.858590846457 3.470550098425 4.857683759843 3.49115 N
OC 4.87783996063 3.4868 4.857684153543 3.49115 N
OC 4.88061988189 3.489785137795 4.88175 3.485945767717 Y
OC 4.884569980315 3.488780019685 4.881746948819 3.48595 Y
OS 4.88783996063 3.48551003937
OS 4.88798996063 3.48503996063
OC 4.908590846457 3.470550098425 4.907683759843 3.49115 N
OC 4.92783996063 3.4868 4.907684153543 3.49115 N
OC 4.93061988189 3.489785137795 4.93175 3.485945767717 Y
OC 4.934569980315 3.488780019685 4.931746948819 3.48595 Y
OS 4.93783996063 3.48551003937
OS 4.93798996063 3.48503996063
OC 4.958590846457 3.470550098425 4.957683759843 3.49115 N
OC 4.97783996063 3.4868 4.957684153543 3.49115 N
OC 4.98061988189 3.489785137795 4.98175 3.485945767717 Y
OC 4.984569980315 3.488780019685 4.981746948819 3.48595 Y
OS 4.98783996063 3.48551003937
OS 4.98798996063 3.48503996063
OC 5.008590846457 3.470550098425 5.007683759843 3.49115 N
OC 5.02783996063 3.4868 5.007684153543 3.49115 N
OC 5.03061988189 3.489785137795 5.03175 3.485945767717 Y
OC 5.034569980315 3.488780019685 5.031746948819 3.48595 Y
OS 5.03783996063 3.48551003937
OS 5.03798996063 3.48503996063
OC 5.06378996063 3.51083996063 5.05767992126 3.49115 N
OS 5.063319980315 3.51098996063
OS 5.045419980315 3.52888996063
OC 5.026917716535 3.533218011811 5.032682480315 3.51615 N
OC 5.014830019685 3.51856003937 5.032680019685 3.516153051181 N
OC 5.012146751969 3.51530984252 5.010869980315 3.519096653543 Y
OC 5.00803996063 3.516269980315 5.010867224409 3.5191 Y
OS 4.995419980315 3.52888996063
OC 4.976917716535 3.533218011811 4.982682480315 3.51615 N
OC 4.964830019685 3.51856003937 4.982680019685 3.516153051181 N
OC 4.962146751969 3.51530984252 4.960869980315 3.519096653543 Y
OC 4.95803996063 3.516269980315 4.960867224409 3.5191 Y
OS 4.945419980315 3.52888996063
OC 4.926917716535 3.533218011811 4.932682480315 3.51615 N
OC 4.914830019685 3.51856003937 4.932680019685 3.516153051181 N
OC 4.912146751969 3.51530984252 4.910869980315 3.519096653543 Y
OC 4.90803996063 3.516269980315 4.910867224409 3.5191 Y
OS 4.895419980315 3.52888996063
OC 4.876917716535 3.533218011811 4.882682480315 3.51615 N
OC 4.864830019685 3.51856003937 4.882680019685 3.516153051181 N
OC 4.862146751969 3.51530984252 4.860869980315 3.519096653543 Y
OC 4.85803996063 3.516269980315 4.860867224409 3.5191 Y
OS 4.845419980315 3.52888996063
OC 4.826917716535 3.533218011811 4.832682480315 3.51615 N
OC 4.814830019685 3.51856003937 4.832680019685 3.516153051181 N
OC 4.812146751969 3.51530984252 4.810869980315 3.519096653543 Y
OC 4.80803996063 3.516269980315 4.810867224409 3.5191 Y
OS 4.795419980315 3.52888996063
OC 4.776917716535 3.533218011811 4.782682480315 3.51615 N
OC 4.764830019685 3.51856003937 4.782680019685 3.516153051181 N
OC 4.762146751969 3.51530984252 4.760869980315 3.519096653543 Y
OC 4.75803996063 3.516269980315 4.760867224409 3.5191 Y
OS 4.745419980315 3.52888996063
OC 4.726917716535 3.533218011811 4.732682480315 3.51615 N
OC 4.714830019685 3.51856003937 4.732680019685 3.516153051181 N
OC 4.712146751969 3.51530984252 4.710869980315 3.519096653543 Y
OC 4.70803996063 3.516269980315 4.710867224409 3.5191 Y
OS 4.695419980315 3.52888996063
OC 4.676917716535 3.533218011811 4.682682480315 3.51615 N
OC 4.664830019685 3.51856003937 4.682680019685 3.516153051181 N
OC 4.662146751969 3.51530984252 4.660869980315 3.519096653543 Y
OC 4.65803996063 3.516269980315 4.660867224409 3.5191 Y
OS 4.645419980315 3.52888996063
OC 4.626917716535 3.533218011811 4.632682480315 3.51615 N
OC 4.614830019685 3.51856003937 4.632680019685 3.516153051181 N
OC 4.612146751969 3.51530984252 4.610869980315 3.519096653543 Y
OC 4.60803996063 3.516269980315 4.610867224409 3.5191 Y
OE
OB 4.60803996063 3.366269980315 H
OS 4.595419980315 3.37888996063
OC 4.56993996063 3.35341003937 4.582680019685 3.36615 N
OS 4.58783996063 3.33551003937
OS 4.58798996063 3.33503996063
OC 4.608590846457 3.320550098425 4.607683759843 3.34115 N
OC 4.62783996063 3.3368 4.607684153543 3.34115 N
OC 4.63061988189 3.339785137795 4.63175 3.335945767717 Y
OC 4.634569980315 3.338780019685 4.631746948819 3.33595 Y
OS 4.63783996063 3.33551003937
OS 4.63798996063 3.33503996063
OC 4.658590846457 3.320550098425 4.657683759843 3.34115 N
OC 4.67783996063 3.3368 4.657684153543 3.34115 N
OC 4.68061988189 3.339785137795 4.68175 3.335945767717 Y
OC 4.684569980315 3.338780019685 4.681746948819 3.33595 Y
OS 4.68783996063 3.33551003937
OS 4.68798996063 3.33503996063
OC 4.708590846457 3.320550098425 4.707683759843 3.34115 N
OC 4.72783996063 3.3368 4.707684153543 3.34115 N
OC 4.73061988189 3.339785137795 4.73175 3.335945767717 Y
OC 4.734569980315 3.338780019685 4.731746948819 3.33595 Y
OS 4.73783996063 3.33551003937
OS 4.73798996063 3.33503996063
OC 4.758590846457 3.320550098425 4.757683759843 3.34115 N
OC 4.77783996063 3.3368 4.757684153543 3.34115 N
OC 4.78061988189 3.339785137795 4.78175 3.335945767717 Y
OC 4.784569980315 3.338780019685 4.781746948819 3.33595 Y
OS 4.78783996063 3.33551003937
OS 4.78798996063 3.33503996063
OC 4.808590846457 3.320550098425 4.807683759843 3.34115 N
OC 4.82783996063 3.3368 4.807684153543 3.34115 N
OC 4.83061988189 3.339785137795 4.83175 3.335945767717 Y
OC 4.834569980315 3.338780019685 4.831746948819 3.33595 Y
OS 4.83783996063 3.33551003937
OS 4.83798996063 3.33503996063
OC 4.858590846457 3.320550098425 4.857683759843 3.34115 N
OC 4.87783996063 3.3368 4.857684153543 3.34115 N
OC 4.88061988189 3.339785137795 4.88175 3.335945767717 Y
OC 4.884569980315 3.338780019685 4.881746948819 3.33595 Y
OS 4.88783996063 3.33551003937
OS 4.88798996063 3.33503996063
OC 4.908590846457 3.320550098425 4.907683759843 3.34115 N
OC 4.92783996063 3.3368 4.907684153543 3.34115 N
OC 4.93061988189 3.339785137795 4.93175 3.335945767717 Y
OC 4.934569980315 3.338780019685 4.931746948819 3.33595 Y
OS 4.93783996063 3.33551003937
OS 4.93798996063 3.33503996063
OC 4.958590846457 3.320550098425 4.957683759843 3.34115 N
OC 4.97783996063 3.3368 4.957684153543 3.34115 N
OC 4.98061988189 3.339785137795 4.98175 3.335945767717 Y
OC 4.984569980315 3.338780019685 4.981746948819 3.33595 Y
OS 4.98783996063 3.33551003937
OS 4.98798996063 3.33503996063
OC 5.008590846457 3.320550098425 5.007683759843 3.34115 N
OC 5.02783996063 3.3368 5.007684153543 3.34115 N
OC 5.03061988189 3.339785137795 5.03175 3.335945767717 Y
OC 5.034569980315 3.338780019685 5.031746948819 3.33595 Y
OS 5.03783996063 3.33551003937
OS 5.03798996063 3.33503996063
OC 5.06378996063 3.36083996063 5.05767992126 3.34115 N
OS 5.063319980315 3.36098996063
OS 5.045419980315 3.37888996063
OC 5.026917716535 3.383218011811 5.032682480315 3.36615 N
OC 5.014830019685 3.36856003937 5.032680019685 3.366153051181 N
OC 5.012146751969 3.36530984252 5.010869980315 3.369096653543 Y
OC 5.00803996063 3.366269980315 5.010867224409 3.3691 Y
OS 4.995419980315 3.37888996063
OC 4.976917716535 3.383218011811 4.982682480315 3.36615 N
OC 4.964830019685 3.36856003937 4.982680019685 3.366153051181 N
OC 4.962146751969 3.36530984252 4.960869980315 3.369096653543 Y
OC 4.95803996063 3.366269980315 4.960867224409 3.3691 Y
OS 4.945419980315 3.37888996063
OC 4.926917716535 3.383218011811 4.932682480315 3.36615 N
OC 4.914830019685 3.36856003937 4.932680019685 3.366153051181 N
OC 4.912146751969 3.36530984252 4.910869980315 3.369096653543 Y
OC 4.90803996063 3.366269980315 4.910867224409 3.3691 Y
OS 4.895419980315 3.37888996063
OC 4.876917716535 3.383218011811 4.882682480315 3.36615 N
OC 4.864830019685 3.36856003937 4.882680019685 3.366153051181 N
OC 4.862146751969 3.36530984252 4.860869980315 3.369096653543 Y
OC 4.85803996063 3.366269980315 4.860867224409 3.3691 Y
OS 4.845419980315 3.37888996063
OC 4.826917716535 3.383218011811 4.832682480315 3.36615 N
OC 4.814830019685 3.36856003937 4.832680019685 3.366153051181 N
OC 4.812146751969 3.36530984252 4.810869980315 3.369096653543 Y
OC 4.80803996063 3.366269980315 4.810867224409 3.3691 Y
OS 4.795419980315 3.37888996063
OC 4.776917716535 3.383218011811 4.782682480315 3.36615 N
OC 4.764830019685 3.36856003937 4.782680019685 3.366153051181 N
OC 4.762146751969 3.36530984252 4.760869980315 3.369096653543 Y
OC 4.75803996063 3.366269980315 4.760867224409 3.3691 Y
OS 4.745419980315 3.37888996063
OC 4.726917716535 3.383218011811 4.732682480315 3.36615 N
OC 4.714830019685 3.36856003937 4.732680019685 3.366153051181 N
OC 4.712146751969 3.36530984252 4.710869980315 3.369096653543 Y
OC 4.70803996063 3.366269980315 4.710867224409 3.3691 Y
OS 4.695419980315 3.37888996063
OC 4.676917716535 3.383218011811 4.682682480315 3.36615 N
OC 4.664830019685 3.36856003937 4.682680019685 3.366153051181 N
OC 4.662146751969 3.36530984252 4.660869980315 3.369096653543 Y
OC 4.65803996063 3.366269980315 4.660867224409 3.3691 Y
OS 4.645419980315 3.37888996063
OC 4.626917716535 3.383218011811 4.632682480315 3.36615 N
OC 4.614830019685 3.36856003937 4.632680019685 3.366153051181 N
OC 4.612146751969 3.36530984252 4.610869980315 3.369096653543 Y
OC 4.60803996063 3.366269980315 4.610867224409 3.3691 Y
OE
OB 4.60803996063 3.216269980315 H
OS 4.595419980315 3.22888996063
OC 4.56993996063 3.20341003937 4.582680019685 3.21615 N
OS 4.58783996063 3.18551003937
OS 4.58798996063 3.18503996063
OC 4.608590846457 3.170550098425 4.607683759843 3.19115 N
OC 4.62783996063 3.1868 4.607684153543 3.19115 N
OC 4.63061988189 3.189785137795 4.63175 3.185945767717 Y
OC 4.634569980315 3.188780019685 4.631746948819 3.18595 Y
OS 4.63783996063 3.18551003937
OS 4.63798996063 3.18503996063
OC 4.658590846457 3.170550098425 4.657683759843 3.19115 N
OC 4.67783996063 3.1868 4.657684153543 3.19115 N
OC 4.68061988189 3.189785137795 4.68175 3.185945767717 Y
OC 4.684569980315 3.188780019685 4.681746948819 3.18595 Y
OS 4.68783996063 3.18551003937
OS 4.68798996063 3.18503996063
OC 4.708590846457 3.170550098425 4.707683759843 3.19115 N
OC 4.72783996063 3.1868 4.707684153543 3.19115 N
OC 4.73061988189 3.189785137795 4.73175 3.185945767717 Y
OC 4.734569980315 3.188780019685 4.731746948819 3.18595 Y
OS 4.73783996063 3.18551003937
OS 4.73798996063 3.18503996063
OC 4.758590846457 3.170550098425 4.757683759843 3.19115 N
OC 4.77783996063 3.1868 4.757684153543 3.19115 N
OC 4.78061988189 3.189785137795 4.78175 3.185945767717 Y
OC 4.784569980315 3.188780019685 4.781746948819 3.18595 Y
OS 4.78783996063 3.18551003937
OS 4.78798996063 3.18503996063
OC 4.808590846457 3.170550098425 4.807683759843 3.19115 N
OC 4.82783996063 3.1868 4.807684153543 3.19115 N
OC 4.83061988189 3.189785137795 4.83175 3.185945767717 Y
OC 4.834569980315 3.188780019685 4.831746948819 3.18595 Y
OS 4.83783996063 3.18551003937
OS 4.83798996063 3.18503996063
OC 4.858590846457 3.170550098425 4.857683759843 3.19115 N
OC 4.87783996063 3.1868 4.857684153543 3.19115 N
OC 4.88061988189 3.189785137795 4.88175 3.185945767717 Y
OC 4.884569980315 3.188780019685 4.881746948819 3.18595 Y
OS 4.88783996063 3.18551003937
OS 4.88798996063 3.18503996063
OC 4.908590846457 3.170550098425 4.907683759843 3.19115 N
OC 4.92783996063 3.1868 4.907684153543 3.19115 N
OC 4.93061988189 3.189785137795 4.93175 3.185945767717 Y
OC 4.934569980315 3.188780019685 4.931746948819 3.18595 Y
OS 4.93783996063 3.18551003937
OS 4.93798996063 3.18503996063
OC 4.958590846457 3.170550098425 4.957683759843 3.19115 N
OC 4.97783996063 3.1868 4.957684153543 3.19115 N
OC 4.98061988189 3.189785137795 4.98175 3.185945767717 Y
OC 4.984569980315 3.188780019685 4.981746948819 3.18595 Y
OS 4.98783996063 3.18551003937
OS 4.98798996063 3.18503996063
OC 5.008590846457 3.170550098425 5.007683759843 3.19115 N
OC 5.02783996063 3.1868 5.007684153543 3.19115 N
OC 5.03061988189 3.189785137795 5.03175 3.185945767717 Y
OC 5.034569980315 3.188780019685 5.031746948819 3.18595 Y
OS 5.03783996063 3.18551003937
OS 5.03798996063 3.18503996063
OC 5.06378996063 3.21083996063 5.05767992126 3.19115 N
OS 5.063319980315 3.21098996063
OS 5.045419980315 3.22888996063
OC 5.026917716535 3.233218011811 5.032682480315 3.21615 N
OC 5.014830019685 3.21856003937 5.032680019685 3.216153051181 N
OC 5.012146751969 3.21530984252 5.010869980315 3.219096653543 Y
OC 5.00803996063 3.216269980315 5.010867224409 3.2191 Y
OS 4.995419980315 3.22888996063
OC 4.976917716535 3.233218011811 4.982682480315 3.21615 N
OC 4.964830019685 3.21856003937 4.982680019685 3.216153051181 N
OC 4.962146751969 3.21530984252 4.960869980315 3.219096653543 Y
OC 4.95803996063 3.216269980315 4.960867224409 3.2191 Y
OS 4.945419980315 3.22888996063
OC 4.926917716535 3.233218011811 4.932682480315 3.21615 N
OC 4.914830019685 3.21856003937 4.932680019685 3.216153051181 N
OC 4.912146751969 3.21530984252 4.910869980315 3.219096653543 Y
OC 4.90803996063 3.216269980315 4.910867224409 3.2191 Y
OS 4.895419980315 3.22888996063
OC 4.876917716535 3.233218011811 4.882682480315 3.21615 N
OC 4.864830019685 3.21856003937 4.882680019685 3.216153051181 N
OC 4.862146751969 3.21530984252 4.860869980315 3.219096653543 Y
OC 4.85803996063 3.216269980315 4.860867224409 3.2191 Y
OS 4.845419980315 3.22888996063
OC 4.826917716535 3.233218011811 4.832682480315 3.21615 N
OC 4.814830019685 3.21856003937 4.832680019685 3.216153051181 N
OC 4.812146751969 3.21530984252 4.810869980315 3.219096653543 Y
OC 4.80803996063 3.216269980315 4.810867224409 3.2191 Y
OS 4.795419980315 3.22888996063
OC 4.776917716535 3.233218011811 4.782682480315 3.21615 N
OC 4.764830019685 3.21856003937 4.782680019685 3.216153051181 N
OC 4.762146751969 3.21530984252 4.760869980315 3.219096653543 Y
OC 4.75803996063 3.216269980315 4.760867224409 3.2191 Y
OS 4.745419980315 3.22888996063
OC 4.726917716535 3.233218011811 4.732682480315 3.21615 N
OC 4.714830019685 3.21856003937 4.732680019685 3.216153051181 N
OC 4.712146751969 3.21530984252 4.710869980315 3.219096653543 Y
OC 4.70803996063 3.216269980315 4.710867224409 3.2191 Y
OS 4.695419980315 3.22888996063
OC 4.676917716535 3.233218011811 4.682682480315 3.21615 N
OC 4.664830019685 3.21856003937 4.682680019685 3.216153051181 N
OC 4.662146751969 3.21530984252 4.660869980315 3.219096653543 Y
OC 4.65803996063 3.216269980315 4.660867224409 3.2191 Y
OS 4.645419980315 3.22888996063
OC 4.626917716535 3.233218011811 4.632682480315 3.21615 N
OC 4.614830019685 3.21856003937 4.632680019685 3.216153051181 N
OC 4.612146751969 3.21530984252 4.610869980315 3.219096653543 Y
OC 4.60803996063 3.216269980315 4.610867224409 3.2191 Y
OE
OB 4.60803996063 3.066269980315 H
OS 4.595419980315 3.07888996063
OC 4.56993996063 3.05341003937 4.582680019685 3.06615 N
OS 4.58783996063 3.03551003937
OS 4.58798996063 3.03503996063
OC 4.608590846457 3.020550098425 4.607683759843 3.04115 N
OC 4.62783996063 3.0368 4.607684153543 3.04115 N
OC 4.63061988189 3.039785137795 4.63175 3.035945767717 Y
OC 4.634569980315 3.038780019685 4.631746948819 3.03595 Y
OS 4.63783996063 3.03551003937
OS 4.63798996063 3.03503996063
OC 4.658590846457 3.020550098425 4.657683759843 3.04115 N
OC 4.67783996063 3.0368 4.657684153543 3.04115 N
OC 4.68061988189 3.039785137795 4.68175 3.035945767717 Y
OC 4.684569980315 3.038780019685 4.681746948819 3.03595 Y
OS 4.68783996063 3.03551003937
OS 4.68798996063 3.03503996063
OC 4.708590846457 3.020550098425 4.707683759843 3.04115 N
OC 4.72783996063 3.0368 4.707684153543 3.04115 N
OC 4.73061988189 3.039785137795 4.73175 3.035945767717 Y
OC 4.734569980315 3.038780019685 4.731746948819 3.03595 Y
OS 4.73783996063 3.03551003937
OS 4.73798996063 3.03503996063
OC 4.758590846457 3.020550098425 4.757683759843 3.04115 N
OC 4.77783996063 3.0368 4.757684153543 3.04115 N
OC 4.78061988189 3.039785137795 4.78175 3.035945767717 Y
OC 4.784569980315 3.038780019685 4.781746948819 3.03595 Y
OS 4.78783996063 3.03551003937
OS 4.78798996063 3.03503996063
OC 4.808590846457 3.020550098425 4.807683759843 3.04115 N
OC 4.82783996063 3.0368 4.807684153543 3.04115 N
OC 4.83061988189 3.039785137795 4.83175 3.035945767717 Y
OC 4.834569980315 3.038780019685 4.831746948819 3.03595 Y
OS 4.83783996063 3.03551003937
OS 4.83798996063 3.03503996063
OC 4.858590846457 3.020550098425 4.857683759843 3.04115 N
OC 4.87783996063 3.0368 4.857684153543 3.04115 N
OC 4.88061988189 3.039785137795 4.88175 3.035945767717 Y
OC 4.884569980315 3.038780019685 4.881746948819 3.03595 Y
OS 4.88783996063 3.03551003937
OS 4.88798996063 3.03503996063
OC 4.908590846457 3.020550098425 4.907683759843 3.04115 N
OC 4.92783996063 3.0368 4.907684153543 3.04115 N
OC 4.93061988189 3.039785137795 4.93175 3.035945767717 Y
OC 4.934569980315 3.038780019685 4.931746948819 3.03595 Y
OS 4.93783996063 3.03551003937
OS 4.93798996063 3.03503996063
OC 4.958590846457 3.020550098425 4.957683759843 3.04115 N
OC 4.97783996063 3.0368 4.957684153543 3.04115 N
OC 4.98061988189 3.039785137795 4.98175 3.035945767717 Y
OC 4.984569980315 3.038780019685 4.981746948819 3.03595 Y
OS 4.98783996063 3.03551003937
OS 4.98798996063 3.03503996063
OC 5.008590846457 3.020550098425 5.007683759843 3.04115 N
OC 5.02783996063 3.0368 5.007684153543 3.04115 N
OC 5.03061988189 3.039785137795 5.03175 3.035945767717 Y
OC 5.034569980315 3.038780019685 5.031746948819 3.03595 Y
OS 5.03783996063 3.03551003937
OS 5.03798996063 3.03503996063
OC 5.06378996063 3.06083996063 5.05767992126 3.04115 N
OS 5.063319980315 3.06098996063
OS 5.045419980315 3.07888996063
OC 5.026917716535 3.083218011811 5.032682480315 3.06615 N
OC 5.014830019685 3.06856003937 5.032680019685 3.066153051181 N
OC 5.012146751969 3.06530984252 5.010869980315 3.069096653543 Y
OC 5.00803996063 3.066269980315 5.010867224409 3.0691 Y
OS 4.995419980315 3.07888996063
OC 4.976917716535 3.083218011811 4.982682480315 3.06615 N
OC 4.964830019685 3.06856003937 4.982680019685 3.066153051181 N
OC 4.962146751969 3.06530984252 4.960869980315 3.069096653543 Y
OC 4.95803996063 3.066269980315 4.960867224409 3.0691 Y
OS 4.945419980315 3.07888996063
OC 4.926917716535 3.083218011811 4.932682480315 3.06615 N
OC 4.914830019685 3.06856003937 4.932680019685 3.066153051181 N
OC 4.912146751969 3.06530984252 4.910869980315 3.069096653543 Y
OC 4.90803996063 3.066269980315 4.910867224409 3.0691 Y
OS 4.895419980315 3.07888996063
OC 4.876917716535 3.083218011811 4.882682480315 3.06615 N
OC 4.864830019685 3.06856003937 4.882680019685 3.066153051181 N
OC 4.862146751969 3.06530984252 4.860869980315 3.069096653543 Y
OC 4.85803996063 3.066269980315 4.860867224409 3.0691 Y
OS 4.845419980315 3.07888996063
OC 4.826917716535 3.083218011811 4.832682480315 3.06615 N
OC 4.814830019685 3.06856003937 4.832680019685 3.066153051181 N
OC 4.812146751969 3.06530984252 4.810869980315 3.069096653543 Y
OC 4.80803996063 3.066269980315 4.810867224409 3.0691 Y
OS 4.795419980315 3.07888996063
OC 4.776917716535 3.083218011811 4.782682480315 3.06615 N
OC 4.764830019685 3.06856003937 4.782680019685 3.066153051181 N
OC 4.762146751969 3.06530984252 4.760869980315 3.069096653543 Y
OC 4.75803996063 3.066269980315 4.760867224409 3.0691 Y
OS 4.745419980315 3.07888996063
OC 4.726917716535 3.083218011811 4.732682480315 3.06615 N
OC 4.714830019685 3.06856003937 4.732680019685 3.066153051181 N
OC 4.712146751969 3.06530984252 4.710869980315 3.069096653543 Y
OC 4.70803996063 3.066269980315 4.710867224409 3.0691 Y
OS 4.695419980315 3.07888996063
OC 4.676917716535 3.083218011811 4.682682480315 3.06615 N
OC 4.664830019685 3.06856003937 4.682680019685 3.066153051181 N
OC 4.662146751969 3.06530984252 4.660869980315 3.069096653543 Y
OC 4.65803996063 3.066269980315 4.660867224409 3.0691 Y
OS 4.645419980315 3.07888996063
OC 4.626917716535 3.083218011811 4.632682480315 3.06615 N
OC 4.614830019685 3.06856003937 4.632680019685 3.066153051181 N
OC 4.612146751969 3.06530984252 4.610869980315 3.069096653543 Y
OC 4.60803996063 3.066269980315 4.610867224409 3.0691 Y
OE
OB 5.04018996063 4.22441003937 H
OC 5.04018996063 4.22441003937 4.832680019685 4.22441003937 N
OE
SE
L 3.38823002 4.85788002 3.38823002 4.83576004 2 P 0 
L 3.38823002 4.83576004 3.39448996 4.8295 2 P 0 
L 3.39448996 4.8295 3.39448996 4.79736998 2 P 0 
L 3.39448996 4.79736998 3.38003996 4.78291998 2 P 0 
L 2.44606004 3.71615 2.42106004 3.69115 5 P 0 
P 2.42106004 3.69115 10 P 0 0;2,4=11,6=0
P 2.44606004 3.71615 8 P 0 0;4=12,6=1
P 3.38003996 4.78291998 8 P 0 0;4=12,6=1
P 3.38823002 4.85788002 36 P 0 0;2,4=1,6=0
L 2.19606004 3.81615 2.17106004 3.79115 5 P 0 
P 2.17106004 3.79115 10 P 0 0;2,4=11,6=0
P 2.19606004 3.81615 8 P 0 0;4=12,6=1
L 3.0339 4.85788002 3.0339 4.8361 2 P 0 
L 3.0339 4.8361 3.04016004 4.82983996 2 P 0 
L 3.04016004 4.82983996 3.04016004 4.68145 2 P 0 
L 3.04016004 4.68145 3.02571004 4.667 2 P 0 
P 3.02571004 4.667 8 P 0 0;4=12,6=1
P 3.0339 4.85788002 36 P 0 0;2,4=1,6=0
P 2.19606004 3.86615 8 P 0 0;4=12,6=1
P 2.17106004 3.84115 10 P 0 0;2,4=11,6=0
L 2.19606004 3.86615 2.17106004 3.84115 5 P 0 
P 3.06571004 4.667 8 P 0 0;4=12,6=1
L 3.05751998 4.85788002 3.05751998 4.83551998 2 P 0 
L 3.05751998 4.83551998 3.05126004 4.82926004 2 P 0 
L 3.05126004 4.82926004 3.05126004 4.68145 2 P 0 
L 3.05126004 4.68145 3.06571004 4.667 2 P 0 
P 3.05751998 4.85788002 36 P 0 0;2,4=1,6=0
L 3.27011998 4.85788002 3.27011998 4.83551998 2 P 0 
L 3.27011998 4.83551998 3.26386004 4.82926004 2 P 0 
L 3.26386004 4.82926004 3.26386004 4.65645 2 P 0 
L 3.26386004 4.65645 3.27831004 4.642 2 P 0 
P 3.27831004 4.642 8 P 0 0;4=12,6=1
L 2.39606004 3.76615 2.37106004 3.74115 5 P 0 
P 2.37106004 3.74115 10 P 0 0;2,4=11,6=0
P 2.39606004 3.76615 8 P 0 0;4=12,6=1
P 3.27011998 4.85788002 36 P 0 0;2,4=1,6=0
P 4.75768002 2.69115 10 P 0 0;2,4=11,6=0
L 4.75768002 2.69115 4.73268002 2.66615 5 P 0 
P 4.73268002 2.66615 8 P 0 0;4=12,6=1
L 10.76161004 2.69115 10.73661004 2.66615 5 P 0 
P 10.76161004 2.69115 10 P 0 0;2,4=11,6=0
P 10.73661004 2.66615 8 P 0 0;4=12,6=1
L 3.2465 4.85788002 3.2465 4.8361 2 P 0 
L 3.2465 4.8361 3.25276004 4.82983996 2 P 0 
L 3.25276004 4.82983996 3.25276004 4.65645 2 P 0 
L 3.25276004 4.65645 3.23831004 4.642 2 P 0 
P 3.23831004 4.642 8 P 0 0;4=12,6=1
P 2.39606004 3.81615 8 P 0 0;4=12,6=1
P 2.37106004 3.79115 10 P 0 0;2,4=11,6=0
L 2.39606004 3.81615 2.37106004 3.79115 5 P 0 
P 3.2465 4.85788002 36 P 0 0;2,4=1,6=0
L 5.00768002 2.64115 5.03268002 2.61615 5 P 0 
P 5.00768002 2.64115 10 P 0 0;2,4=11,6=0
P 5.03268002 2.61615 8 P 0 0;4=12,6=1
L 3.34098996 4.97913996 3.34098996 5.00201998 2 P 0 
L 3.34098996 5.00201998 3.33471998 5.00828996 2 P 0 
L 3.33471998 5.00828996 3.33471998 5.08905 2 P 0 
L 3.33471998 5.08905 3.34916998 5.1035 2 P 0 
P 3.34916998 5.1035 8 P 0 0;4=12,6=1
L 2.49606004 3.76615 2.47106004 3.74115 5 P 0 
P 2.47106004 3.74115 10 P 0 0;2,4=11,6=0
P 2.49606004 3.76615 8 P 0 0;4=12,6=1
P 3.34098996 4.97913996 36 P 0 0;2,4=1,6=0
L 3.31736004 4.97913996 3.31736998 4.97915 2 P 0 
L 3.31736998 4.97915 3.31736998 5.00138002 2 P 0 
L 3.31736998 5.00138002 3.32361998 5.00763002 2 P 0 
L 3.32361998 5.00763002 3.32361998 5.08905 2 P 0 
L 3.32361998 5.08905 3.30916998 5.1035 2 P 0 
P 3.30916998 5.1035 8 P 0 0;4=12,6=1
L 2.49606004 3.81615 2.47106004 3.79115 5 P 0 
P 2.47106004 3.79115 10 P 0 0;2,4=11,6=0
P 2.49606004 3.81615 8 P 0 0;4=12,6=1
P 3.31736004 4.97913996 36 P 0 0;2,4=1,6=0
L 11.01161004 2.64115 11.03661004 2.61615 5 P 0 
P 11.01161004 2.64115 10 P 0 0;2,4=11,6=0
P 11.03661004 2.61615 8 P 0 0;4=12,6=1
L 2.75043996 4.85788002 2.75043996 4.8361 2 P 0 
L 2.75043996 4.8361 2.7567 4.82983996 2 P 0 
L 2.7567 4.82983996 2.7567 4.68145 2 P 0 
L 2.7567 4.68145 2.74225 4.667 2 P 0 
P 2.74225 4.667 8 P 0 0;4=12,6=1
P 2.09606004 3.66615 8 P 0 0;4=12,6=1
P 2.07106004 3.64115 10 P 0 0;2,4=11,6=0
L 2.09606004 3.66615 2.07106004 3.64115 5 P 0 
P 2.75043996 4.85788002 36 P 0 0;2,4=1,6=0
L 2.44606004 3.81615 2.42106004 3.79115 5 P 0 
P 2.42106004 3.79115 10 P 0 0;2,4=11,6=0
P 2.44606004 3.81615 8 P 0 0;4=12,6=1
L 3.19925 4.85788002 3.19925 4.83523996 2 P 0 
L 3.19925 4.83523996 3.19298996 4.82898002 2 P 0 
L 3.19298996 4.82898002 3.19298996 4.79736998 2 P 0 
L 3.19298996 4.79736998 3.20743996 4.78291998 2 P 0 
P 3.20743996 4.78291998 8 P 0 0;4=12,6=1
P 3.19925 4.85788002 36 P 0 0;2,4=1,6=0
L 2.77406004 4.85788002 2.77406004 4.83551998 2 P 0 
L 2.77406004 4.83551998 2.7678 4.82926004 2 P 0 
L 2.7678 4.82926004 2.7678 4.68145 2 P 0 
L 2.7678 4.68145 2.78225 4.667 2 P 0 
P 2.78225 4.667 8 P 0 0;4=12,6=1
L 2.09606004 3.71615 2.07106004 3.69115 5 P 0 
P 2.07106004 3.69115 10 P 0 0;2,4=11,6=0
P 2.09606004 3.71615 8 P 0 0;4=12,6=1
P 2.77406004 4.85788002 36 P 0 0;2,4=1,6=0
L 3.17563002 4.85788002 3.17563002 4.83536004 2 P 0 
L 3.17563002 4.83536004 3.18188996 4.8291 2 P 0 
L 3.18188996 4.8291 3.18188996 4.79736998 2 P 0 
L 3.18188996 4.79736998 3.16743996 4.78291998 2 P 0 
L 2.44606004 3.86615 2.42106004 3.84115 5 P 0 
P 2.42106004 3.84115 10 P 0 0;2,4=11,6=0
P 2.44606004 3.86615 8 P 0 0;4=12,6=1
P 3.16743996 4.78291998 8 P 0 0;4=12,6=1
P 3.17563002 4.85788002 36 P 0 0;2,4=1,6=0
L 3.27011998 4.97913996 3.27011998 5.00216004 2 P 0 
L 3.27011998 5.00216004 3.26386004 5.00841998 2 P 0 
L 3.26386004 5.00841998 3.26386004 5.20556998 2 P 0 
L 3.26386004 5.20556998 3.27831004 5.22001998 2 P 0 
P 2.34606004 3.81615 8 P 0 0;4=12,6=1
P 2.32106004 3.79115 10 P 0 0;2,4=11,6=0
L 2.34606004 3.81615 2.32106004 3.79115 5 P 0 
P 3.27831004 5.22001998 8 P 0 0;4=12,6=1
P 3.27011998 4.97913996 36 P 0 0;2,4=1,6=0
L 3.2465 4.97913996 3.2465 5.00221998 2 P 0 
L 3.2465 5.00221998 3.25276004 5.00848002 2 P 0 
L 3.25276004 5.00848002 3.25276004 5.20556998 2 P 0 
L 3.25276004 5.20556998 3.23831004 5.22001998 2 P 0 
P 2.34606004 3.86615 8 P 0 0;4=12,6=1
P 2.32106004 3.84115 10 P 0 0;2,4=11,6=0
L 2.34606004 3.86615 2.32106004 3.84115 5 P 0 
P 3.23831004 5.22001998 8 P 0 0;4=12,6=1
P 3.2465 4.97913996 36 P 0 0;2,4=1,6=0
P 4.65768002 2.64115 10 P 0 0;2,4=11,6=0
L 4.65768002 2.64115 4.63268002 2.61615 5 P 0 
P 4.63268002 2.61615 8 P 0 0;4=12,6=1
L 10.96161004 2.64115 10.98661004 2.61615 5 P 0 
P 10.96161004 2.64115 10 P 0 0;2,4=11,6=0
P 10.98661004 2.61615 8 P 0 0;4=12,6=1
P 2.19606004 3.66615 8 P 0 0;4=12,6=1
P 2.17106004 3.64115 10 P 0 0;2,4=11,6=0
L 2.19606004 3.66615 2.17106004 3.64115 5 P 0 
L 2.8213 4.85788002 2.8213 4.8347 2 P 0 
L 2.8213 4.8347 2.82756004 4.82843996 2 P 0 
L 2.82756004 4.82843996 2.82756004 4.79736998 2 P 0 
L 2.82756004 4.79736998 2.81311004 4.78291998 2 P 0 
P 2.81311004 4.78291998 8 P 0 0;4=12,6=1
P 2.8213 4.85788002 36 P 0 0;2,4=1,6=0
L 10.96161004 2.59115 10.98661004 2.56615 5 P 0 
P 10.96161004 2.59115 10 P 0 0;2,4=11,6=0
P 10.98661004 2.56615 8 P 0 0;4=12,6=1
L 2.19606004 3.71615 2.17106004 3.69115 5 P 0 
P 2.17106004 3.69115 10 P 0 0;2,4=11,6=0
P 2.19606004 3.71615 8 P 0 0;4=12,6=1
L 2.84491998 4.85788002 2.84491998 4.83591998 2 P 0 
L 2.84491998 4.83591998 2.83866004 4.82966004 2 P 0 
L 2.83866004 4.82966004 2.83866004 4.79736998 2 P 0 
L 2.83866004 4.79736998 2.85311004 4.78291998 2 P 0 
P 2.85311004 4.78291998 8 P 0 0;4=12,6=1
P 2.84491998 4.85788002 36 P 0 0;2,4=1,6=0
P 0.64808996 1.655 9 P 0 0;4=13,6=1
P 5.76 2.66 9 P 0 0;4=0,6=1
L 10.66161004 2.64115 10.63661004 2.61615 5 P 0 
P 10.66161004 2.64115 10 P 0 0;2,4=11,6=0
P 10.63661004 2.61615 8 P 0 0;4=12,6=1
L 2.09606004 3.81615 2.07106004 3.79115 5 P 0 
P 2.07106004 3.79115 10 P 0 0;2,4=11,6=0
P 2.09606004 3.81615 8 P 0 0;4=12,6=1
P 3.09656998 5.0535 8 P 0 0;4=12,6=1
L 3.10476998 4.97913996 3.10476998 5.00178002 2 P 0 
L 3.10476998 5.00178002 3.11101998 5.00803002 2 P 0 
L 3.11101998 5.00803002 3.11101998 5.03905 2 P 0 
L 3.11101998 5.03905 3.09656998 5.0535 2 P 0 
P 3.10476998 4.97913996 36 P 0 0;2,4=1,6=0
P 2.09606004 3.86615 8 P 0 0;4=12,6=1
P 2.07106004 3.84115 10 P 0 0;2,4=11,6=0
L 2.09606004 3.86615 2.07106004 3.84115 5 P 0 
P 3.13656998 5.0535 8 P 0 0;4=12,6=1
L 3.12838996 4.97913996 3.12838996 5.00261998 2 P 0 
L 3.12838996 5.00261998 3.12211998 5.00888996 2 P 0 
L 3.12211998 5.00888996 3.12211998 5.03905 2 P 0 
L 3.12211998 5.03905 3.13656998 5.0535 2 P 0 
P 3.12838996 4.97913996 36 P 0 0;2,4=1,6=0
P 2.88708002 4.667 8 P 0 0;4=12,6=1
L 2.96303002 4.85788002 2.96303002 4.83498002 2 P 0 
L 2.96303002 4.83498002 2.96928996 4.82871998 2 P 0 
L 2.96928996 4.82871998 2.96928996 4.78998002 2 P 0 
L 2.96928996 4.78998002 2.90153002 4.72221998 2 P 0 
L 2.90153002 4.72221998 2.90153002 4.68145 2 P 0 
L 2.90153002 4.68145 2.88708002 4.667 2 P 0 
P 2.04606004 3.76615 8 P 0 0;4=12,6=1
P 2.02106004 3.74115 10 P 0 0;2,4=11,6=0
L 2.04606004 3.76615 2.02106004 3.74115 5 P 0 
P 2.96303002 4.85788002 36 P 0 0;2,4=1,6=0
L 10.76161004 2.64115 10.73661004 2.61615 5 P 0 
P 10.76161004 2.64115 10 P 0 0;2,4=11,6=0
P 10.73661004 2.61615 8 P 0 0;4=12,6=1
L 2.98666004 4.85788002 2.98666004 4.83566004 2 P 0 
L 2.98666004 4.83566004 2.98038996 4.82938996 2 P 0 
L 2.98038996 4.82938996 2.98038996 4.78538002 2 P 0 
L 2.98038996 4.78538002 2.91263002 4.71761998 2 P 0 
L 2.91263002 4.71761998 2.91263002 4.68145 2 P 0 
L 2.91263002 4.68145 2.92708002 4.667 2 P 0 
P 2.92708002 4.667 8 P 0 0;4=12,6=1
P 2.04606004 3.81615 8 P 0 0;4=12,6=1
P 2.02106004 3.79115 10 P 0 0;2,4=11,6=0
L 2.04606004 3.81615 2.02106004 3.79115 5 P 0 
P 2.98666004 4.85788002 36 P 0 0;2,4=1,6=0
L 10.71161004 2.64115 10.68661004 2.61615 5 P 0 
P 10.71161004 2.64115 10 P 0 0;2,4=11,6=0
P 10.68661004 2.61615 8 P 0 0;4=12,6=1
L 5.00768002 2.44115 5.03268002 2.46615 5 P 0 
P 5.03268002 2.46615 8 P 0 0;4=12,6=1
P 5.00768002 2.44115 10 P 0 0;2,4=11,6=0
L 5.00768002 2.49115 5.03268002 2.51615 5 P 0 
P 5.03268002 2.51615 8 P 0 0;4=12,6=1
P 5.00768002 2.49115 10 P 0 0;2,4=11,6=0
L 11.06161004 2.59115 11.08661004 2.56615 5 P 0 
P 11.06161004 2.59115 10 P 0 0;2,4=11,6=0
P 11.08661004 2.56615 8 P 0 0;4=12,6=1
L 10.71161004 2.59115 10.68661004 2.56615 5 P 0 
P 10.71161004 2.59115 10 P 0 0;2,4=11,6=0
P 10.68661004 2.56615 8 P 0 0;4=12,6=1
L 9.20278996 4.97913996 9.20278996 5.00915 5 P 0 
L 9.20278996 5.00915 9.19991998 5.01201998 5 P 0 
L 9.19991998 5.01201998 9.19991998 5.11793996 5 P 0 
L 9.19991998 5.11793996 9.15853996 5.15931998 5 P 0 
L 9.15853996 5.15931998 9.15853996 5.23853996 5 P 0 
L 9.15853996 5.23853996 9.175 5.255 5 P 0 
P 9.175 5.255 9 P 0 0;4=0,6=1
P 9.20278996 4.97913996 36 P 0 0;2,4=1,6=0
P 4.75768002 2.64115 10 P 0 0;2,4=11,6=0
L 4.75768002 2.64115 4.73268002 2.61615 5 P 0 
P 4.73268002 2.61615 8 P 0 0;4=12,6=1
L 9.17916998 4.97913996 9.17916998 5.00961998 5 P 0 
L 9.17916998 5.00961998 9.18253996 5.01298996 5 P 0 
L 9.18253996 5.01298996 9.18253996 5.09896004 5 P 0 
L 9.18253996 5.09896004 9.18196004 5.09953996 5 P 0 
L 9.18196004 5.09953996 9.18196004 5.09955 5 P 0 
L 9.18196004 5.09955 9.15741998 5.12408996 5 P 0 
L 9.15741998 5.12408996 9.15741004 5.12408996 5 P 0 
L 9.15741004 5.12408996 9.13283996 5.14866004 5 P 0 
L 9.13283996 5.14866004 9.13283996 5.2407 5 P 0 
L 9.13283996 5.2407 9.11853996 5.255 5 P 0 
P 9.11853996 5.255 9 P 0 0;4=0,6=1
P 9.17916998 4.97913996 36 P 0 0;2,4=1,6=0
P 5.08268002 2.41615 8 P 0 0;4=12,6=1
P 5.05768002 2.44115 10 P 0 0;2,4=11,6=0
L 5.08268002 2.41615 5.05768002 2.44115 5 P 0 
L 10.91161004 2.69115 10.93661004 2.66615 5 P 0 
P 10.91161004 2.69115 10 P 0 0;2,4=11,6=0
P 10.93661004 2.66615 8 P 0 0;4=12,6=1
L 10.61161004 2.64115 10.58661004 2.61615 5 P 0 
P 10.61161004 2.64115 10 P 0 0;2,4=11,6=0
P 10.58661004 2.61615 8 P 0 0;4=12,6=1
P 8.15 3.76615 8 P 0 0;4=12,6=1
P 8.125 3.74115 10 P 0 0;2,4=11,6=0
L 8.15 3.76615 8.125 3.74115 5 P 0 
L 9.03743996 4.97913996 9.03743996 5.0019 2 P 0 
L 9.03743996 5.0019 9.0437 5.00816004 2 P 0 
L 9.0437 5.00816004 9.0437 5.15055 2 P 0 
L 9.0437 5.15055 9.02925 5.165 2 P 0 
P 9.02925 5.165 8 P 0 0;4=12,6=1
P 9.03743996 4.97913996 36 P 0 0;2,4=1,6=0
P 4.95768002 2.24115 10 P 0 0;2,4=11,6=0
L 4.95768002 2.24115 4.98268002 2.21615 5 P 0 
P 4.98268002 2.21615 8 P 0 0;4=12,6=1
L 10.61161004 2.59115 10.58661004 2.56615 5 P 0 
P 10.61161004 2.59115 10 P 0 0;2,4=11,6=0
P 10.58661004 2.56615 8 P 0 0;4=12,6=1
P 8.15 3.81615 8 P 0 0;4=12,6=1
P 8.125 3.79115 10 P 0 0;2,4=11,6=0
L 8.15 3.81615 8.125 3.79115 5 P 0 
L 9.06106004 4.97913996 9.06106004 5.00148002 2 P 0 
L 9.06106004 5.00148002 9.0548 5.00773996 2 P 0 
L 9.0548 5.00773996 9.0548 5.15055 2 P 0 
L 9.0548 5.15055 9.06925 5.165 2 P 0 
P 9.06925 5.165 8 P 0 0;4=12,6=1
P 9.06106004 4.97913996 36 P 0 0;2,4=1,6=0
L 11.01161004 2.69115 11.03661004 2.66615 5 P 0 
P 11.01161004 2.69115 10 P 0 0;2,4=11,6=0
P 11.03661004 2.66615 8 P 0 0;4=12,6=1
P 4.95768002 2.29115 10 P 0 0;2,4=11,6=0
L 4.95768002 2.29115 4.98268002 2.26615 5 P 0 
P 4.98268002 2.26615 8 P 0 0;4=12,6=1
L 10.91161004 2.64115 10.93661004 2.61615 5 P 0 
P 10.91161004 2.64115 10 P 0 0;2,4=11,6=0
P 10.93661004 2.61615 8 P 0 0;4=12,6=1
P 5.00768002 2.29115 10 P 0 0;2,4=11,6=0
L 5.00768002 2.29115 5.03268002 2.26615 5 P 0 
P 5.03268002 2.26615 8 P 0 0;4=12,6=1
L 11.06161004 2.64115 11.08661004 2.61615 5 P 0 
P 11.06161004 2.64115 10 P 0 0;2,4=11,6=0
P 11.08661004 2.61615 8 P 0 0;4=12,6=1
P 5.00768002 2.34115 10 P 0 0;2,4=11,6=0
L 5.00768002 2.34115 5.03268002 2.31615 5 P 0 
P 5.03268002 2.31615 8 P 0 0;4=12,6=1
L 10.66161004 2.69115 10.63661004 2.66615 5 P 0 
P 10.66161004 2.69115 10 P 0 0;2,4=11,6=0
P 10.63661004 2.66615 8 P 0 0;4=12,6=1
L 3.8399 4.82898996 3.8399 4.8699 5 P 0 
L 3.8399 4.8699 3.84 4.87 5 P 0 
P 3.8399 4.82898996 28 P 0 0;2,4=4,6=0
P 3.88313002 4.96076998 38 P 0 0;2,4=20,6=0
P 3.84 4.87 11 P 0 0;3,4=6,6=1
L 3.84 4.87 3.84 4.89501004 5 P 0 
L 3.84 4.89501004 3.88313002 4.93813996 5 P 0 
L 3.88313002 4.93813996 3.88313002 4.96076998 5 P 0 
L 3.775 5.295 3.83898996 5.35898996 5 P 0 
L 3.83898996 5.35898996 3.8599 5.35898996 5 P 0 
P 3.8599 5.35898996 28 P 0 0;2,4=4,6=0
P 3.775 5.295 9 P 0 0;4=0,6=1
L 0.73 5.78 0.72933002 5.77933002 5 P 0 
L 0.72933002 5.77933002 0.72933002 5.70373996 5 P 0 
L 0.73 5.823 0.73 5.78 5 P 0 
P 0.73 5.823 28 P 0 0;2,4=4,6=0
P 0.72933002 5.70373996 48 P 0 0;2,4=16,6=0
P 0.73 5.78 9 P 0 0;4=13,6=1
L 8.03818996 4.97913996 8.03818996 5.00915 5 P 0 
L 8.03818996 5.00915 8.03531998 5.01201998 5 P 0 
L 8.03531998 5.01201998 8.03531998 5.11821998 5 P 0 
L 8.03531998 5.11821998 8.015 5.13853996 5 P 0 
L 8.015 5.13853996 8.015 5.235 5 P 0 
L 8.015 5.235 8.07 5.29 5 P 0 
P 8.07 5.29 9 P 0 0;4=0,6=1
P 8.03818996 4.97913996 36 P 0 0;2,4=1,6=0
L 3.8399 4.79498996 3.8399 4.765 5 P 0 
P 3.8399 4.765 9 P 0 0;4=0,6=1
L 0.81 5.78 0.81 5.823 5 P 0 
L 0.80806998 5.70373996 0.80806998 5.77806998 5 P 0 
L 0.80806998 5.77806998 0.81 5.78 5 P 0 
P 0.81 5.823 28 P 0 0;2,4=4,6=0
P 0.80806998 5.70373996 48 P 0 0;2,4=16,6=0
P 0.81 5.78 9 P 0 0;4=13,6=1
P 3.8399 4.79498996 28 P 0 0;2,4=4,6=0
L 8.01456998 4.97913996 8.01456998 5.00913996 5 P 0 
L 8.01456998 5.00913996 8.01745 5.01201998 5 P 0 
L 8.01745 5.01201998 8.01745 5.03398002 5 P 0 
L 8.01745 5.03398002 8.01736004 5.03406998 5 P 0 
L 8.01736004 5.03406998 8.01736004 5.09983002 5 P 0 
L 8.01736004 5.09983002 7.98853996 5.12865 5 P 0 
L 7.98853996 5.12865 7.98853996 5.27353996 5 P 0 
L 7.98853996 5.27353996 8.005 5.29 5 P 0 
P 8.005 5.29 9 P 0 0;4=0,6=1
P 8.01456998 4.97913996 36 P 0 0;2,4=1,6=0
L 3.8599 5.2751 3.90871998 5.22628002 5 P 0 
L 3.90871998 5.22628002 3.90871998 5.18321004 5 P 0 
P 3.90871998 5.18321004 38 P 0 0;2,4=20,6=0
L 3.8599 5.32498996 3.8599 5.2751 5 P 0 
P 3.8599 5.32498996 28 P 0 0;2,4=4,6=0
P 3.8599 5.2751 11 P 0 0;3,4=6,6=1
L 11.06161004 1.94115 11.08661004 1.91615 5 P 0 
P 11.08661004 1.91615 8 P 0 0;4=12,6=1
P 11.06161004 1.94115 10 P 0 0;2,4=11,6=0
P 4.95768002 1.94115 10 P 0 0;2,4=11,6=0
L 4.95768002 1.94115 4.98268002 1.91615 5 P 0 
P 4.98268002 1.91615 8 P 0 0;4=12,6=1
P 4.95768002 1.99115 10 P 0 0;2,4=11,6=0
L 4.95768002 1.99115 4.98268002 1.96615 5 P 0 
P 4.98268002 1.96615 8 P 0 0;4=12,6=1
P 4.90768002 1.89115 10 P 0 0;2,4=11,6=0
L 4.90768002 1.89115 4.93268002 1.86615 5 P 0 
P 4.93268002 1.86615 8 P 0 0;4=12,6=1
P 4.90768002 1.94115 10 P 0 0;2,4=11,6=0
L 4.90768002 1.94115 4.93268002 1.91615 5 P 0 
P 4.93268002 1.91615 8 P 0 0;4=12,6=1
L 3.89 4.87 3.89 4.89128002 5 P 0 
L 3.89 4.89128002 3.90871998 4.91 5 P 0 
L 3.90871998 4.91 3.90871998 4.96076998 5 P 0 
L 3.8899 4.82898996 3.8899 4.8699 5 P 0 
L 3.8899 4.8699 3.89 4.87 5 P 0 
P 3.8899 4.82898996 28 P 0 0;2,4=4,6=0
P 3.90871998 4.96076998 38 P 0 0;2,4=20,6=0
P 3.89 4.87 11 P 0 0;3,4=6,6=1
P 5.00768002 1.89115 10 P 0 0;2,4=11,6=0
L 5.03268002 1.86615 5.00768002 1.89115 5 P 0 
P 5.03268002 1.86615 8 P 0 0;4=12,6=1
L 3.9099 5.2751 3.9099 5.32498996 5 P 0 
L 3.93431004 5.18321004 3.93431004 5.25068996 5 P 0 
L 3.93431004 5.25068996 3.9099 5.2751 5 P 0 
P 3.9099 5.32498996 28 P 0 0;2,4=4,6=0
P 3.93431004 5.18321004 38 P 0 0;2,4=20,6=0
P 3.9099 5.2751 11 P 0 0;3,4=6,6=1
P 5.05768002 1.94115 10 P 0 0;2,4=11,6=0
L 5.08268002 1.91615 5.05768002 1.94115 5 P 0 
P 5.08268002 1.91615 8 P 0 0;4=12,6=1
L 5.05768002 2.59115 5.08268002 2.56615 5 P 0 
P 5.05768002 2.59115 10 P 0 0;2,4=11,6=0
P 5.08268002 2.56615 8 P 0 0;4=12,6=1
L 8.125 2.49115 8.15 2.51615 5 P 0 
P 8.15 2.51615 8 P 0 0;4=12,6=1
P 8.125 2.49115 10 P 0 0;2,4=11,6=0
L 4.95768002 2.64115 4.98268002 2.61615 5 P 0 
P 4.95768002 2.64115 10 P 0 0;2,4=11,6=0
P 4.98268002 2.61615 8 P 0 0;4=12,6=1
P 10.71161004 2.74115 10 P 0 0;2,4=11,6=0
L 10.71161004 2.74115 10.68661004 2.71615 5 P 0 
P 10.68661004 2.71615 8 P 0 0;4=12,6=1
P 10.96161004 2.74115 10 P 0 0;2,4=11,6=0
L 10.96161004 2.74115 10.98661004 2.71615 5 P 0 
P 10.98661004 2.71615 8 P 0 0;4=12,6=1
P 10.81161004 2.74115 10 P 0 0;2,4=11,6=0
L 10.81161004 2.74115 10.78661004 2.71615 5 P 0 
P 10.78661004 2.71615 8 P 0 0;4=12,6=1
L 4.90768002 2.69115 4.93268002 2.66615 5 P 0 
P 4.90768002 2.69115 10 P 0 0;2,4=11,6=0
P 4.93268002 2.66615 8 P 0 0;4=12,6=1
P 10.86161004 2.74115 10 P 0 0;2,4=11,6=0
L 10.86161004 2.74115 10.88661004 2.71615 5 P 0 
P 10.88661004 2.71615 8 P 0 0;4=12,6=1
L 9.64 0.71 9.64 0.70836998 5 P 0 
L 9.64 0.70836998 9.60795 0.67631998 5 P 0 
L 9.60795 0.67631998 9.60795 0.65065 5 P 0 
L 9.61795 0.76243002 9.64 0.74038002 5 P 0 
L 9.64 0.74038002 9.64 0.71 5 P 0 
P 10.71161004 2.79115 10 P 0 0;2,4=11,6=0
L 10.71161004 2.79115 10.68661004 2.76615 5 P 0 
P 10.68661004 2.76615 8 P 0 0;4=12,6=1
P 9.60795 0.65065 43 P 0 0;2,4=28,6=0
P 9.64 0.71 9 P 0 0;4=0,6=1
P 9.61795 0.76243002 28 P 0 0;2,4=4,6=0
P 10.61161004 2.84115 10 P 0 0;2,4=11,6=0
L 10.61161004 2.84115 10.58661004 2.81615 5 P 0 
P 10.58661004 2.81615 8 P 0 0;4=12,6=1
L 9.43296004 0.49133002 9.40795 0.46631998 5 P 0 
L 9.40795 0.46631998 9.40795 0.42821004 5 P 0 
L 9.40795 0.42821004 9.40795 0.32643002 5 P 0 
P 9.40795 0.42821004 43 P 0 0;2,4=28,6=0
P 9.43296004 0.49133002 9 P 0 0;4=0,6=1
P 9.40795 0.32643002 28 P 0 0;2,4=4,6=0
P 10.66161004 2.84115 10 P 0 0;2,4=11,6=0
L 10.66161004 2.84115 10.63661004 2.81615 5 P 0 
L 9.43296004 0.73633002 9.43296004 0.73741998 5 P 0 
L 9.43296004 0.73741998 9.40795 0.76243002 5 P 0 
L 9.40795 0.65065 9.40795 0.71131998 5 P 0 
L 9.40795 0.71131998 9.43296004 0.73633002 5 P 0 
P 9.40795 0.65065 43 P 0 0;2,4=28,6=0
P 9.43296004 0.73633002 9 P 0 0;4=0,6=1
P 9.40795 0.76243002 28 P 0 0;2,4=4,6=0
P 10.63661004 2.81615 8 P 0 0;4=12,6=1
P 4.70768002 2.59115 10 P 0 0;2,4=11,6=0
L 4.70768002 2.59115 4.68268002 2.56615 5 P 0 
P 4.68268002 2.56615 8 P 0 0;4=12,6=1
P 10.71161004 2.84115 10 P 0 0;2,4=11,6=0
L 10.71161004 2.84115 10.68661004 2.81615 5 P 0 
P 10.68661004 2.81615 8 P 0 0;4=12,6=1
L 9.55795 0.36633002 9.55795 0.32643002 5 P 0 
L 9.55795 0.42821004 9.55795 0.36633002 5 P 0 
P 9.55795 0.32643002 28 P 0 0;2,4=4,6=0
P 9.55795 0.42821004 43 P 0 0;2,4=28,6=0
P 9.55795 0.36633002 9 P 0 0;4=0,6=1
P 10.76161004 2.84115 10 P 0 0;2,4=11,6=0
L 10.76161004 2.84115 10.73661004 2.81615 5 P 0 
P 10.73661004 2.81615 8 P 0 0;4=12,6=1
L 9.35796004 0.49133002 9.42796004 0.56133002 5 P 0 
L 9.42796004 0.56133002 9.53796004 0.56133002 5 P 0 
L 9.53796004 0.56133002 9.55795 0.58131998 5 P 0 
L 9.55795 0.58131998 9.55795 0.65065 5 P 0 
P 9.55795 0.65065 43 P 0 0;2,4=28,6=0
P 9.35796004 0.49133002 9 P 0 0;4=0,6=1
L 5.00768002 2.69115 5.03268002 2.66615 5 P 0 
P 5.00768002 2.69115 10 P 0 0;2,4=11,6=0
P 5.03268002 2.66615 8 P 0 0;4=12,6=1
P 10.81161004 2.84115 10 P 0 0;2,4=11,6=0
L 10.81161004 2.84115 10.78661004 2.81615 5 P 0 
P 10.78661004 2.81615 8 P 0 0;4=12,6=1
L 9.46795 0.76243002 9.46795 0.71295 5 P 0 
L 9.46795 0.71295 9.45795 0.70295 5 P 0 
L 9.45795 0.70295 9.45795 0.65065 5 P 0 
L 9.58296004 0.71133002 9.58296004 0.72633002 5 P 0 
L 9.58296004 0.72633002 9.54686004 0.76243002 5 P 0 
L 9.54686004 0.76243002 9.46795 0.76243002 5 P 0 
P 9.58296004 0.71133002 9 P 0 0;4=0,6=1
P 9.45795 0.65065 43 P 0 0;2,4=28,6=0
P 9.46795 0.76243002 28 P 0 0;2,4=4,6=0
L 5.05768002 2.64115 5.08268002 2.61615 5 P 0 
P 5.05768002 2.64115 10 P 0 0;2,4=11,6=0
P 5.08268002 2.61615 8 P 0 0;4=12,6=1
L 11.06161004 1.99115 11.08661004 1.96615 5 P 0 
P 11.08661004 1.96615 8 P 0 0;4=12,6=1
P 11.06161004 1.99115 10 P 0 0;2,4=11,6=0
L 11.01161004 1.89115 11.03661004 1.86615 5 P 0 
P 11.03661004 1.86615 8 P 0 0;4=12,6=1
P 11.01161004 1.89115 10 P 0 0;2,4=11,6=0
L 11.01161004 1.94115 11.03661004 1.91615 5 P 0 
P 11.03661004 1.91615 8 P 0 0;4=12,6=1
P 11.01161004 1.94115 10 P 0 0;2,4=11,6=0
L 10.91161004 1.89115 10.93661004 1.86615 5 P 0 
P 10.93661004 1.86615 8 P 0 0;4=12,6=1
P 10.91161004 1.89115 10 P 0 0;2,4=11,6=0
L 10.91161004 1.94115 10.93661004 1.91615 5 P 0 
P 10.93661004 1.91615 8 P 0 0;4=12,6=1
P 10.91161004 1.94115 10 P 0 0;2,4=11,6=0
L 10.96161004 1.94115 10.98661004 1.91615 5 P 0 
P 10.98661004 1.91615 8 P 0 0;4=12,6=1
P 10.96161004 1.94115 10 P 0 0;2,4=11,6=0
L 10.96161004 1.99115 10.98661004 1.96615 5 P 0 
P 10.98661004 1.96615 8 P 0 0;4=12,6=1
P 10.96161004 1.99115 10 P 0 0;2,4=11,6=0
L 4.90768002 2.64115 4.93268002 2.61615 5 P 0 
P 4.90768002 2.64115 10 P 0 0;2,4=11,6=0
P 4.93268002 2.61615 8 P 0 0;4=12,6=1
L 11.01161004 2.04115 11.03661004 2.01615 5 P 0 
P 11.03661004 2.01615 8 P 0 0;4=12,6=1
P 11.01161004 2.04115 10 P 0 0;2,4=11,6=0
L 11.01161004 2.09115 11.03661004 2.06615 5 P 0 
P 11.03661004 2.06615 8 P 0 0;4=12,6=1
P 11.01161004 2.09115 10 P 0 0;2,4=11,6=0
L 10.91161004 2.04115 10.93661004 2.01615 5 P 0 
P 10.93661004 2.01615 8 P 0 0;4=12,6=1
P 10.91161004 2.04115 10 P 0 0;2,4=11,6=0
L 10.91161004 2.09115 10.93661004 2.06615 5 P 0 
P 10.93661004 2.06615 8 P 0 0;4=12,6=1
P 10.91161004 2.09115 10 P 0 0;2,4=11,6=0
L 10.96161004 2.09115 10.98661004 2.06615 5 P 0 
P 10.98661004 2.06615 8 P 0 0;4=12,6=1
P 10.96161004 2.09115 10 P 0 0;2,4=11,6=0
L 10.96161004 2.14115 10.98661004 2.11615 5 P 0 
P 10.98661004 2.11615 8 P 0 0;4=12,6=1
P 10.96161004 2.14115 10 P 0 0;2,4=11,6=0
L 11.06161004 2.09115 11.08661004 2.06615 5 P 0 
P 11.08661004 2.06615 8 P 0 0;4=12,6=1
P 11.06161004 2.09115 10 P 0 0;2,4=11,6=0
L 11.06161004 2.14115 11.08661004 2.11615 5 P 0 
P 11.08661004 2.11615 8 P 0 0;4=12,6=1
P 11.06161004 2.14115 10 P 0 0;2,4=11,6=0
P 3.115 5.255 9 P 0 0;4=0,6=1
L 3.17563002 4.97913996 3.17563002 5.00961998 5 P 0 
L 3.17563002 5.00961998 3.179 5.01298996 5 P 0 
L 3.179 5.01298996 3.179 5.09896004 5 P 0 
L 3.179 5.09896004 3.17841998 5.09953996 5 P 0 
L 3.17841998 5.09953996 3.17841998 5.09955 5 P 0 
L 3.17841998 5.09955 3.15388002 5.12408996 5 P 0 
L 3.15388002 5.12408996 3.15386998 5.12408996 5 P 0 
L 3.15386998 5.12408996 3.1293 5.14866004 5 P 0 
L 3.1293 5.14866004 3.1293 5.2407 5 P 0 
L 3.1293 5.2407 3.115 5.255 5 P 0 
P 3.17563002 4.97913996 36 P 0 0;2,4=1,6=0
P 4.65768002 2.69115 10 P 0 0;2,4=11,6=0
L 4.65768002 2.69115 4.63268002 2.66615 5 P 0 
P 4.63268002 2.66615 8 P 0 0;4=12,6=1
L 11.06161004 2.24115 11.08661004 2.21615 5 P 0 
P 11.08661004 2.21615 8 P 0 0;4=12,6=1
P 11.06161004 2.24115 10 P 0 0;2,4=11,6=0
L 4.95768002 2.59115 4.98268002 2.56615 5 P 0 
P 4.95768002 2.59115 10 P 0 0;2,4=11,6=0
P 4.98268002 2.56615 8 P 0 0;4=12,6=1
L 11.06161004 2.29115 11.08661004 2.26615 5 P 0 
P 11.08661004 2.26615 8 P 0 0;4=12,6=1
P 11.06161004 2.29115 10 P 0 0;2,4=11,6=0
L 11.01161004 2.29115 11.03661004 2.26615 5 P 0 
P 11.03661004 2.26615 8 P 0 0;4=12,6=1
P 11.01161004 2.29115 10 P 0 0;2,4=11,6=0
L 3.0339 4.97913996 3.0339 5.0019 2 P 0 
L 3.0339 5.0019 3.04016004 5.00816004 2 P 0 
L 3.04016004 5.00816004 3.04016004 5.15055 2 P 0 
L 3.04016004 5.15055 3.02571004 5.165 2 P 0 
P 2.14606004 3.76615 8 P 0 0;4=12,6=1
P 2.12106004 3.74115 10 P 0 0;2,4=11,6=0
L 2.14606004 3.76615 2.12106004 3.74115 5 P 0 
P 3.02571004 5.165 8 P 0 0;4=12,6=1
P 3.0339 4.97913996 36 P 0 0;2,4=1,6=0
L 11.01161004 2.34115 11.03661004 2.31615 5 P 0 
P 11.03661004 2.31615 8 P 0 0;4=12,6=1
P 11.01161004 2.34115 10 P 0 0;2,4=11,6=0
L 10.96161004 2.24115 10.98661004 2.21615 5 P 0 
P 10.98661004 2.21615 8 P 0 0;4=12,6=1
P 10.96161004 2.24115 10 P 0 0;2,4=11,6=0
L 10.96161004 2.29115 10.98661004 2.26615 5 P 0 
P 10.98661004 2.26615 8 P 0 0;4=12,6=1
P 10.96161004 2.29115 10 P 0 0;2,4=11,6=0
L 3.19925 4.97913996 3.19925 5.00915 5 P 0 
L 3.19925 5.00915 3.19638002 5.01201998 5 P 0 
L 3.19638002 5.01201998 3.19638002 5.11793996 5 P 0 
L 3.19638002 5.11793996 3.155 5.15931998 5 P 0 
L 3.155 5.15931998 3.155 5.23853996 5 P 0 
L 3.155 5.23853996 3.17146004 5.255 5 P 0 
P 3.17146004 5.255 9 P 0 0;4=0,6=1
P 3.19925 4.97913996 36 P 0 0;2,4=1,6=0
P 4.70768002 2.64115 10 P 0 0;2,4=11,6=0
L 4.70768002 2.64115 4.68268002 2.61615 5 P 0 
P 4.68268002 2.61615 8 P 0 0;4=12,6=1
L 10.91161004 2.29115 10.93661004 2.26615 5 P 0 
P 10.93661004 2.26615 8 P 0 0;4=12,6=1
P 10.91161004 2.29115 10 P 0 0;2,4=11,6=0
P 10.58661004 2.76615 8 P 0 0;4=12,6=1
L 10.61161004 2.79115 10.58661004 2.76615 5 P 0 
P 10.61161004 2.79115 10 P 0 0;2,4=11,6=0
L 4 5.29 4 5.245 5 P 0 
L 4 5.245 3.98548996 5.23048996 5 P 0 
L 3.98548996 5.23048996 3.98548996 5.18321004 5 P 0 
L 4.0099 5.32498996 4 5.31508996 5 P 0 
L 4 5.31508996 4 5.29 5 P 0 
P 3.98548996 5.18321004 38 P 0 0;2,4=20,6=0
P 4.0099 5.32498996 28 P 0 0;2,4=4,6=0
P 4 5.29 9 P 0 0;4=0,6=1
L 10.91161004 2.34115 10.93661004 2.31615 5 P 0 
P 10.93661004 2.31615 8 P 0 0;4=12,6=1
P 10.91161004 2.34115 10 P 0 0;2,4=11,6=0
P 10.86161004 2.19115 10 P 0 0;2,4=11,6=0
L 10.86161004 2.19115 10.88661004 2.16615 5 P 0 
P 10.88661004 2.16615 8 P 0 0;4=12,6=1
L 3.93431004 4.96076998 3.93431004 4.9107 5 P 0 
L 3.93431004 4.9107 3.9399 4.90511004 5 P 0 
L 3.9399 4.90511004 3.9399 4.8701 5 P 0 
L 3.9399 4.8701 3.94 4.87 5 P 0 
L 3.9399 4.82898996 3.9399 4.8699 5 P 0 
L 3.9399 4.8699 3.94 4.87 5 P 0 
P 3.93431004 4.96076998 38 P 0 0;2,4=20,6=0
L 3.98548996 4.96076998 3.98548996 5.01451004 5 P 0 
L 3.98548996 5.01451004 3.98 5.02 5 P 0 
L 3.98 5.02 3.945 5.02 5 P 0 
L 3.945 5.02 3.93431004 5.00931004 5 P 0 
L 3.93431004 5.00931004 3.93431004 4.96076998 5 P 0 
P 3.98548996 4.96076998 38 P 0 0;2,4=20,6=0
P 3.9399 4.82898996 28 P 0 0;2,4=4,6=0
P 3.94 4.87 11 P 0 0;3,4=6,6=1
P 10.76161004 1.94115 10 P 0 0;2,4=11,6=0
L 10.76161004 1.94115 10.73661004 1.91615 5 P 0 
P 10.73661004 1.91615 8 P 0 0;4=12,6=1
P 10.395 1.28555 8 P 0 0;4=12,6=1
P 12.81495 1.96456998 14 P 0 0;4=2,6=0
L 9.41538996 4.97913996 9.41538996 5.00216004 2 P 0 
L 9.41538996 5.00216004 9.40986998 5.00768002 2 P 0 
L 9.40986998 5.00768002 9.40986998 5.20631004 2 P 0 
L 9.40986998 5.20631004 9.42358002 5.22001998 2 P 0 
P 9.42358002 5.22001998 8 P 0 0;4=12,6=1
P 8.98115 2.825 8 P 0 0;4=12,6=1
P 9.41538996 4.97913996 36 P 0 0;2,4=1,6=0
L 3.9599 5.275 3.9599 5.32498996 5 P 0 
L 3.9599 5.18321004 3.9599 5.275 5 P 0 
L 4.01108002 5.18321004 4.01108002 5.13428002 5 P 0 
L 4.01108002 5.13428002 4.00288002 5.12608002 5 P 0 
L 4.00288002 5.12608002 3.9681 5.12608002 5 P 0 
L 3.9681 5.12608002 3.9599 5.13428002 5 P 0 
L 3.9599 5.13428002 3.9599 5.18321004 5 P 0 
P 3.9599 5.18321004 38 P 0 0;2,4=20,6=0
P 4.01108002 5.18321004 38 P 0 0;2,4=20,6=0
P 3.9599 5.32498996 28 P 0 0;2,4=4,6=0
P 3.9599 5.275 11 P 0 0;3,4=6,6=1
P 4.60768002 2.64115 10 P 0 0;2,4=11,6=0
L 4.60768002 2.64115 4.58268002 2.61615 5 P 0 
P 4.58268002 2.61615 8 P 0 0;4=12,6=1
L 9.39176998 4.97913996 9.39176998 5.00221998 2 P 0 
L 9.39176998 5.00221998 9.39876998 5.00921998 2 P 0 
L 9.39876998 5.00921998 9.39876998 5.20483002 2 P 0 
L 9.39876998 5.20483002 9.38358002 5.22001998 2 P 0 
P 9.38358002 5.22001998 8 P 0 0;4=12,6=1
P 8.98115 2.865 8 P 0 0;4=12,6=1
P 9.39176998 4.97913996 36 P 0 0;2,4=1,6=0
P 2.14606004 3.81615 8 P 0 0;4=12,6=1
P 2.12106004 3.79115 10 P 0 0;2,4=11,6=0
L 2.14606004 3.81615 2.12106004 3.79115 5 P 0 
L 3.05751998 4.97913996 3.05751998 5.00148002 2 P 0 
L 3.05751998 5.00148002 3.05126004 5.00773996 2 P 0 
L 3.05126004 5.00773996 3.05126004 5.15055 2 P 0 
L 3.05126004 5.15055 3.06571004 5.165 2 P 0 
P 3.06571004 5.165 8 P 0 0;4=12,6=1
P 3.05751998 4.97913996 36 P 0 0;2,4=1,6=0
P 11.08661004 2.71615 8 P 0 0;4=12,6=1
L 11.06161004 2.74115 11.08661004 2.71615 5 P 0 
P 11.06161004 2.74115 10 P 0 0;2,4=11,6=0
L 3.9899 4.82898996 3.9899 4.88508996 5 P 0 
L 3.9899 4.88508996 3.985 4.88998996 5 P 0 
L 3.985 4.88998996 3.9599 4.91508996 5 P 0 
L 3.9599 4.91508996 3.9599 4.96076998 5 P 0 
P 3.9599 4.96076998 38 P 0 0;2,4=20,6=0
P 3.9899 4.82898996 28 P 0 0;2,4=4,6=0
P 3.985 4.88998996 9 P 0 0;4=0,6=1
P 11.73316004 2.652 8 P 0 0;4=12,6=1
P 12.55905 4.40551004 14 P 0 0;4=2,6=0
P 11.73316004 2.612 8 P 0 0;4=12,6=1
P 12.63778996 4.44488002 14 P 0 0;4=2,6=0
P 8.3 2.86615 8 P 0 0;4=12,6=1
L 8.3 2.86615 8.275 2.84115 2 P 0 
P 8.275 2.84115 10 P 0 0;2,4=11,6=0
L 4.80768002 2.19115 4.83268002 2.16615 5 P 0 
P 4.80768002 2.19115 10 P 0 0;2,4=11,6=0
P 4.83268002 2.16615 8 P 0 0;4=12,6=1
P 0.69348996 1.90611998 8 P 0 0;4=12,6=1
P 11.73316004 2.492 8 P 0 0;4=12,6=1
P 12.55905 4.24803002 14 P 0 0;4=2,6=0
P 4.85768002 2.19115 10 P 0 0;2,4=11,6=0
L 4.85768002 2.19115 4.88268002 2.16615 5 P 0 
P 4.88268002 2.16615 8 P 0 0;4=12,6=1
P 0.69348996 1.86611998 8 P 0 0;4=12,6=1
P 11.73316004 2.452 8 P 0 0;4=12,6=1
P 12.63778996 4.2874 14 P 0 0;4=2,6=0
P 8.25 2.86615 8 P 0 0;4=12,6=1
L 8.25 2.86615 8.225 2.84115 2 P 0 
P 8.225 2.84115 10 P 0 0;2,4=11,6=0
P 12.55905 3.93306998 14 P 0 0;4=2,6=0
P 11.73316004 2.332 8 P 0 0;4=12,6=1
P 12.63778996 3.97243996 14 P 0 0;4=2,6=0
P 11.73316004 2.292 8 P 0 0;4=12,6=1
P 10.81161004 2.19115 10 P 0 0;2,4=11,6=0
L 10.81161004 2.19115 10.83661004 2.16615 5 P 0 
P 10.83661004 2.16615 8 P 0 0;4=12,6=1
P 11.53316004 2.092 8 P 0 0;4=12,6=1
P 12.55905 3.77558996 14 P 0 0;4=2,6=0
P 11.53316004 2.052 8 P 0 0;4=12,6=1
P 12.63778996 3.81496004 14 P 0 0;4=2,6=0
P 12.81495 3.53936998 14 P 0 0;4=2,6=0
P 10.71161004 2.29115 10 P 0 0;2,4=11,6=0
L 10.71161004 2.29115 10.68661004 2.26615 5 P 0 
P 10.68661004 2.26615 8 P 0 0;4=12,6=1
P 9.975 2.3758 8 P 0 0;4=12,6=1
P 12.81495 3.38188996 14 P 0 0;4=2,6=0
P 10.76161004 2.34115 10 P 0 0;2,4=11,6=0
L 10.76161004 2.34115 10.73661004 2.31615 5 P 0 
P 10.73661004 2.31615 8 P 0 0;4=12,6=1
P 9.975 2.23955 8 P 0 0;4=12,6=1
P 12.81495 2.20078996 14 P 0 0;4=2,6=0
P 10.71161004 1.94115 10 P 0 0;2,4=11,6=0
L 10.71161004 1.94115 10.68661004 1.91615 5 P 0 
P 10.68661004 1.91615 8 P 0 0;4=12,6=1
P 10.42445 1.395 8 P 0 0;4=12,6=1
P 12.81495 2.75196998 14 P 0 0;4=2,6=0
P 10.76161004 2.04115 10 P 0 0;2,4=11,6=0
L 10.76161004 2.04115 10.73661004 2.01615 5 P 0 
P 10.73661004 2.01615 8 P 0 0;4=12,6=1
P 10.26025 1.82845 8 P 0 0;4=12,6=1
P 12.73621004 3.73621998 14 P 0 0;4=2,6=0
P 10.61161004 2.24115 10 P 0 0;2,4=11,6=0
L 10.61161004 2.24115 10.58661004 2.21615 5 P 0 
P 10.58661004 2.21615 8 P 0 0;4=12,6=1
P 10.09 2.26825 8 P 0 0;4=12,6=1
P 10.76161004 2.44115 10 P 0 0;2,4=11,6=0
L 10.76161004 2.44115 10.73661004 2.41615 5 P 0 
P 10.73661004 2.41615 8 P 0 0;4=12,6=1
P 10.09 2.69655 8 P 0 0;4=12,6=1
P 12.73621004 4.52361998 14 P 0 0;4=2,6=0
L 7.3054 4.79681998 7.3054 4.75071004 5 P 0 
L 7.3054 4.75071004 7.3426 4.71351004 5 P 0 
L 7.3426 4.71351004 7.3426 4.69351004 5 P 0 
L 7.3426 4.66551004 7.3426 4.69351004 5 P 0 
P 7.3426 4.66551004 28 P 0 0;2,4=4,6=0
P 7.3054 4.79681998 38 P 0 0;2,4=20,6=0
P 7.3426 4.69351004 9 P 0 0;4=0,6=1
P 11.73316004 1.532 8 P 0 0;4=12,6=1
P 12.55905 2.27953002 14 P 0 0;4=2,6=0
L 7.2926 4.69351004 7.2926 4.72351004 5 P 0 
L 7.2926 4.72351004 7.2798 4.73631004 5 P 0 
L 7.2798 4.73631004 7.2798 4.79681998 5 P 0 
L 7.2926 4.66551004 7.2926 4.69351004 5 P 0 
P 7.2926 4.66551004 28 P 0 0;2,4=4,6=0
P 7.2798 4.79681998 38 P 0 0;2,4=20,6=0
P 7.2926 4.69351004 9 P 0 0;4=0,6=1
P 12.73621004 3.57873996 14 P 0 0;4=2,6=0
P 10.71161004 2.24115 10 P 0 0;2,4=11,6=0
L 10.71161004 2.24115 10.68661004 2.21615 5 P 0 
P 10.68661004 2.21615 8 P 0 0;4=12,6=1
P 9.975 2.3358 8 P 0 0;4=12,6=1
L 7.33098996 4.9602 7.33098996 4.9869 5 P 0 
L 7.33098996 4.9869 7.3926 5.04851004 5 P 0 
L 7.3926 5.04851004 7.3926 5.09151004 5 P 0 
P 7.33098996 4.9602 38 P 0 0;2,4=20,6=0
P 7.3926 5.09151004 28 P 0 0;2,4=4,6=0
P 7.3926 5.04851004 11 P 0 0;3,4=6,6=1
P 12.73621004 3.42126004 14 P 0 0;4=2,6=0
P 10.76161004 2.29115 10 P 0 0;2,4=11,6=0
L 10.76161004 2.29115 10.73661004 2.26615 5 P 0 
P 10.73661004 2.26615 8 P 0 0;4=12,6=1
P 9.975 2.19955 8 P 0 0;4=12,6=1
P 11.73316004 2.172 8 P 0 0;4=12,6=1
P 12.55905 3.46063002 14 P 0 0;4=2,6=0
P 4.95768002 2.39115 10 P 0 0;2,4=11,6=0
L 4.95768002 2.39115 4.98268002 2.36615 5 P 0 
P 4.98268002 2.36615 8 P 0 0;4=12,6=1
P 10.76161004 1.89115 10 P 0 0;2,4=11,6=0
L 10.76161004 1.89115 10.73661004 1.86615 5 P 0 
P 10.73661004 1.86615 8 P 0 0;4=12,6=1
P 10.395 1.32555 8 P 0 0;4=12,6=1
P 12.73621004 2.00393996 14 P 0 0;4=2,6=0
P 11.73316004 2.132 8 P 0 0;4=12,6=1
P 12.63778996 3.5 14 P 0 0;4=2,6=0
L 3.38823002 4.97913996 3.38823002 5.00221998 2 P 0 
L 3.38823002 5.00221998 3.39523002 5.00921998 2 P 0 
L 3.39523002 5.00921998 3.39523002 5.20483002 2 P 0 
L 3.39523002 5.20483002 3.38003996 5.22001998 2 P 0 
P 3.38003996 5.22001998 8 P 0 0;4=12,6=1
P 2.97721004 2.865 8 P 0 0;4=12,6=1
P 3.38823002 4.97913996 36 P 0 0;2,4=1,6=0
P 4.95768002 2.44115 10 P 0 0;2,4=11,6=0
L 4.95768002 2.44115 4.98268002 2.41615 5 P 0 
P 4.98268002 2.41615 8 P 0 0;4=12,6=1
P 12.63778996 1.76771998 14 P 0 0;4=2,6=0
L 3.41185 4.97913996 3.41185 5.00216004 2 P 0 
L 3.41185 5.00216004 3.40633002 5.00768002 2 P 0 
L 3.40633002 5.00768002 3.40633002 5.20631004 2 P 0 
L 3.40633002 5.20631004 3.42003996 5.22001998 2 P 0 
P 3.42003996 5.22001998 8 P 0 0;4=12,6=1
P 2.97721004 2.825 8 P 0 0;4=12,6=1
P 3.41185 4.97913996 36 P 0 0;2,4=1,6=0
P 4.85768002 2.84115 10 P 0 0;2,4=11,6=0
L 4.85768002 2.84115 4.88268002 2.81615 9 P 0 
P 4.88268002 2.81615 8 P 0 0;4=12,6=1
P 4.90768002 2.84115 10 P 0 0;2,4=11,6=0
L 4.90768002 2.84115 4.93268002 2.81615 9 P 0 
P 4.93268002 2.81615 8 P 0 0;4=12,6=1
P 4.95768002 2.84115 10 P 0 0;2,4=11,6=0
L 4.95768002 2.84115 4.98268002 2.81615 9 P 0 
P 4.98268002 2.81615 8 P 0 0;4=12,6=1
P 5.00768002 2.84115 10 P 0 0;2,4=11,6=0
L 5.00768002 2.84115 5.03268002 2.81615 9 P 0 
P 5.03268002 2.81615 8 P 0 0;4=12,6=1
P 5.05768002 2.84115 10 P 0 0;2,4=11,6=0
L 5.05768002 2.84115 5.08268002 2.81615 9 P 0 
P 5.08268002 2.81615 8 P 0 0;4=12,6=1
P 11.03661004 2.81615 8 P 0 0;4=12,6=1
L 11.01161004 2.84115 11.03661004 2.81615 9 P 0 
P 11.01161004 2.84115 10 P 0 0;2,4=11,6=0
P 11.08661004 2.81615 8 P 0 0;4=12,6=1
L 11.06161004 2.84115 11.08661004 2.81615 9 P 0 
P 11.06161004 2.84115 10 P 0 0;2,4=11,6=0
P 10.98661004 2.81615 8 P 0 0;4=12,6=1
L 10.96161004 2.84115 10.98661004 2.81615 9 P 0 
P 10.96161004 2.84115 10 P 0 0;2,4=11,6=0
P 10.93661004 2.81615 8 P 0 0;4=12,6=1
L 10.91161004 2.84115 10.93661004 2.81615 9 P 0 
P 10.91161004 2.84115 10 P 0 0;2,4=11,6=0
P 10.88661004 2.81615 8 P 0 0;4=12,6=1
L 10.86161004 2.84115 10.88661004 2.81615 9 P 0 
P 10.86161004 2.84115 10 P 0 0;2,4=11,6=0
P 5.27886004 3.0214 9 P 0 0;4=13,6=1
P 5.27886004 3.0564 9 P 0 0;4=13,6=1
P 5.27886004 3.1014 9 P 0 0;4=13,6=1
P 5.27886004 3.1364 9 P 0 0;4=13,6=1
P 5.27886004 2.9764 9 P 0 0;4=13,6=1
P 5.27886004 2.9414 9 P 0 0;4=13,6=1
P 5.27886004 3.2614 9 P 0 0;4=13,6=1
P 5.27886004 3.2964 9 P 0 0;4=13,6=1
P 5.27886004 3.2164 9 P 0 0;4=13,6=1
P 5.27886004 3.1814 9 P 0 0;4=13,6=1
P 11.28278996 3.1814 9 P 0 0;4=13,6=1
P 11.28278996 3.2164 9 P 0 0;4=13,6=1
P 11.28278996 3.2964 9 P 0 0;4=13,6=1
P 11.28278996 3.2614 9 P 0 0;4=13,6=1
P 11.28278996 2.9414 9 P 0 0;4=13,6=1
P 11.28278996 2.9764 9 P 0 0;4=13,6=1
P 11.28278996 3.1364 9 P 0 0;4=13,6=1
P 11.28278996 3.1014 9 P 0 0;4=13,6=1
P 11.28278996 3.0564 9 P 0 0;4=13,6=1
P 11.28278996 3.0214 9 P 0 0;4=13,6=1
L 6.42418996 5.09705 6.41623996 5.105 7 P 0 
L 6.41623996 5.105 6.195 5.105 7 P 0 
L 6.195 5.105 6.13708996 5.04708996 7 P 0 
L 6.13708996 5.04708996 6.13708996 4.9252 7 P 0 
P 6.42418996 5.09705 28 P 0 0;2,4=4,6=0
P 5.59708996 4.7302 9 P 0 0;4=13,6=1
P 5.57708996 4.6802 9 P 0 0;4=13,6=1
P 5.75708996 4.7302 9 P 0 0;4=13,6=1
P 5.83708996 4.7302 9 P 0 0;4=13,6=1
P 5.69708996 4.6802 9 P 0 0;4=13,6=1
P 5.73708996 4.6802 9 P 0 0;4=13,6=1
P 5.77708996 4.6802 9 P 0 0;4=13,6=1
P 5.81708996 4.6802 9 P 0 0;4=13,6=1
P 5.85708996 4.6802 9 P 0 0;4=13,6=1
P 5.67708996 4.7302 9 P 0 0;4=13,6=1
P 5.65708996 4.6802 9 P 0 0;4=13,6=1
P 5.61708996 4.6802 9 P 0 0;4=13,6=1
P 6.13708996 4.7602 9 P 0 0;4=13,6=1
P 6.09708996 4.6802 9 P 0 0;4=13,6=1
P 6.13708996 4.6402 9 P 0 0;4=13,6=1
P 6.13708996 4.6802 9 P 0 0;4=13,6=1
P 6.13708996 4.7202 9 P 0 0;4=13,6=1
P 5.91708996 4.7302 9 P 0 0;4=13,6=1
P 5.99708996 4.7302 9 P 0 0;4=13,6=1
P 6.07708996 4.7302 9 P 0 0;4=13,6=1
P 5.89708996 4.6802 9 P 0 0;4=13,6=1
P 5.93708996 4.6802 9 P 0 0;4=13,6=1
P 5.97708996 4.6802 9 P 0 0;4=13,6=1
P 6.01708996 4.6802 9 P 0 0;4=13,6=1
P 6.05708996 4.6802 9 P 0 0;4=13,6=1
P 5.59708996 4.7702 9 P 0 0;4=13,6=1
P 5.59708996 4.8102 9 P 0 0;4=13,6=1
P 5.75708996 4.8102 9 P 0 0;4=13,6=1
P 5.83708996 4.8102 9 P 0 0;4=13,6=1
P 5.75708996 4.7702 9 P 0 0;4=13,6=1
P 5.83708996 4.7702 9 P 0 0;4=13,6=1
P 5.67708996 4.8102 9 P 0 0;4=13,6=1
P 5.67708996 4.7702 9 P 0 0;4=13,6=1
P 6.13708996 4.9252 9 P 0 0;4=13,6=1
P 6.13708996 4.8402 9 P 0 0;4=13,6=1
P 6.13708996 4.8002 9 P 0 0;4=13,6=1
P 6.13708996 4.8852 9 P 0 0;4=13,6=1
P 5.91708996 4.8102 9 P 0 0;4=13,6=1
P 5.99708996 4.8102 9 P 0 0;4=13,6=1
P 5.91708996 4.7702 9 P 0 0;4=13,6=1
P 5.99708996 4.7702 9 P 0 0;4=13,6=1
P 6.07708996 4.8102 9 P 0 0;4=13,6=1
P 6.07708996 4.7702 9 P 0 0;4=13,6=1
P 5.53593996 4.6201 28 P 0 0;2,4=4,6=0
P 5.59778996 4.6352 31 P 0 0;2,4=21,6=0
P 5.49093996 4.6201 28 P 0 0;2,4=4,6=0
P 5.67708996 4.6352 31 P 0 0;2,4=21,6=0
P 5.83708996 4.6352 31 P 0 0;2,4=21,6=0
P 5.75708996 4.6352 31 P 0 0;2,4=21,6=0
P 6.07708996 4.6352 31 P 0 0;2,4=21,6=0
P 5.91708996 4.6352 31 P 0 0;2,4=21,6=0
P 5.99708996 4.6352 31 P 0 0;2,4=21,6=0
P 6.21193996 4.77205 51 P 0 0;2,4=24,6=0
S P 0
OB 6.25208996063 4.6652 I
OS 6.19708996063 4.6102
OS 5.47968996063 4.6102
OS 5.47348996063 4.6164
OS 5.47348996063 4.8376
OS 5.58108996063 4.9452
OS 6.16708996063 4.9452
OS 6.25208996063 4.8602
OS 6.25208996063 4.6652
OE
SE
P 4.90768002 2.29115 10 P 0 0;2,4=11,6=0
L 4.93268002 2.26615 4.90768002 2.29115 5 P 0 
P 4.93268002 2.26615 8 P 0 0;4=12,6=1
P 4.90768002 2.34115 10 P 0 0;2,4=11,6=0
L 4.93268002 2.31615 4.90768002 2.34115 5 P 0 
P 4.93268002 2.31615 8 P 0 0;4=12,6=1
P 5.05768002 2.39115 10 P 0 0;2,4=11,6=0
L 5.08268002 2.36615 5.05768002 2.39115 5 P 0 
P 5.08268002 2.36615 8 P 0 0;4=12,6=1
P 12.81495 3.22441004 14 P 0 0;4=2,6=0
P 10.71161004 2.09115 10 P 0 0;2,4=11,6=0
L 10.71161004 2.09115 10.68661004 2.06615 5 P 0 
P 10.68661004 2.06615 8 P 0 0;4=12,6=1
P 10.09 2.13095 8 P 0 0;4=12,6=1
P 10.66161004 2.34115 10 P 0 0;2,4=11,6=0
L 10.66161004 2.34115 10.63661004 2.31615 5 P 0 
P 10.63661004 2.31615 8 P 0 0;4=12,6=1
P 10.09 2.40335 8 P 0 0;4=12,6=1
P 12.81495 3.85433002 14 P 0 0;4=2,6=0
P 11.73316004 2.012 8 P 0 0;4=12,6=1
P 12.63778996 3.1063 14 P 0 0;4=2,6=0
P 11.73316004 1.972 8 P 0 0;4=12,6=1
P 12.55905 3.14566998 14 P 0 0;4=2,6=0
P 11.53316004 1.732 8 P 0 0;4=12,6=1
P 12.55905 2.98818996 14 P 0 0;4=2,6=0
P 12.81495 3.69685 14 P 0 0;4=2,6=0
P 10.61161004 2.29115 10 P 0 0;2,4=11,6=0
L 10.61161004 2.29115 10.58661004 2.26615 5 P 0 
P 10.58661004 2.26615 8 P 0 0;4=12,6=1
P 10.09 2.30825 8 P 0 0;4=12,6=1
P 11.53316004 1.772 8 P 0 0;4=12,6=1
P 12.63778996 2.94881998 14 P 0 0;4=2,6=0
P 12.81495 4.32676998 14 P 0 0;4=2,6=0
P 10.66161004 2.49115 10 P 0 0;2,4=11,6=0
L 10.66161004 2.49115 10.63661004 2.46615 5 P 0 
P 10.63661004 2.46615 8 P 0 0;4=12,6=1
P 9.975 2.62445 8 P 0 0;4=12,6=1
P 12.63778996 2.79133996 14 P 0 0;4=2,6=0
P 11.73316004 1.852 8 P 0 0;4=12,6=1
P 12.55905 2.83071004 14 P 0 0;4=2,6=0
P 11.73316004 1.812 8 P 0 0;4=12,6=1
P 10.76161004 2.49115 10 P 0 0;2,4=11,6=0
L 10.76161004 2.49115 10.73661004 2.46615 5 P 0 
P 10.73661004 2.46615 8 P 0 0;4=12,6=1
P 10.09 2.73655 8 P 0 0;4=12,6=1
P 12.81495 4.48425 14 P 0 0;4=2,6=0
P 10.66161004 2.29115 10 P 0 0;2,4=11,6=0
L 10.66161004 2.29115 10.63661004 2.26615 5 P 0 
P 10.63661004 2.26615 8 P 0 0;4=12,6=1
P 10.09 2.44335 8 P 0 0;4=12,6=1
P 12.73621004 3.8937 14 P 0 0;4=2,6=0
P 10.58661004 2.41615 8 P 0 0;4=12,6=1
L 10.61161004 2.44115 10.58661004 2.41615 5 P 0 
P 10.61161004 2.44115 10 P 0 0;2,4=11,6=0
P 9.975 2.5109 8 P 0 0;4=12,6=1
P 12.81495 4.16928996 14 P 0 0;4=2,6=0
P 1.025 -0.35 30 P 0 0;4=17,6=0
P 1.325 -0.35 30 P 0 0;4=17,6=0
P 1.175 -0.35 30 P 0 0;4=17,6=0
P 0.725 -0.35 30 P 0 0;4=17,6=0
P 0.875 -0.35 30 P 0 0;4=17,6=0
P 12.73621004 4.05118002 14 P 0 0;4=2,6=0
P 10.71161004 2.39115 10 P 0 0;2,4=11,6=0
L 10.71161004 2.39115 10.68661004 2.36615 5 P 0 
P 10.68661004 2.36615 8 P 0 0;4=12,6=1
P 10.09 2.53845 8 P 0 0;4=12,6=1
P 12.81495 2.35826998 14 P 0 0;4=2,6=0
P 10.66161004 1.89115 10 P 0 0;2,4=11,6=0
L 10.66161004 1.89115 10.63661004 1.86615 5 P 0 
P 10.63661004 1.86615 8 P 0 0;4=12,6=1
P 10.35543002 1.52156998 8 P 0 0;4=12,6=1
P 5.00768002 2.04115 10 P 0 0;2,4=11,6=0
L 5.00768002 2.04115 5.03268002 2.01615 5 P 0 
P 5.03268002 2.01615 8 P 0 0;4=12,6=1
P 5.05768002 2.24115 10 P 0 0;2,4=11,6=0
L 5.05768002 2.24115 5.08268002 2.21615 5 P 0 
P 5.08268002 2.21615 8 P 0 0;4=12,6=1
P 12.73621004 2.16141998 14 P 0 0;4=2,6=0
P 10.71161004 1.99115 10 P 0 0;2,4=11,6=0
L 10.71161004 1.99115 10.68661004 1.96615 5 P 0 
P 10.68661004 1.96615 8 P 0 0;4=12,6=1
P 10.46445 1.395 8 P 0 0;4=12,6=1
P 0.82983996 5.1239 35 P 0 0;2,4=10
P 9.50795 0.42821004 43 P 0 0;2,4=28
P 9.60795 0.42821004 43 P 0 0;2,4=28
P 3.70998996 0.40688002 43 P 0 0;2,4=28
P 3.80998996 0.40688002 43 P 0 0;2,4=28
P 0.2 -0.293 21 P 0 0;4=38
P 12.27 0.29 21 P 0 0;4=38
P 0.66 0.29 21 P 0 0;4=38
P 0.2 5.82361998 21 P 0 0;4=38
P 0.5836 5.36731998 13 P 0 0;2,4=39
P 0.9211 0.2854 13 P 0 0;2,4=39
P 11.99518996 0.29 13 P 0 0;2,4=39
P 0.5 -0.293 13 P 0 0;2,4=39
P 12.4252 -0.293 13 P 0 0;2,4=39
P 0.5 6.31661998 13 P 0 0;2,4=39
P 12.4252 6.31661998 13 P 0 0;2,4=39
P 6.55228996 4.91705 45 P 0 0;2,4=19
P 6.69008996 4.9013 46 P 0 0;2,4=19
P 6.62118996 5.00563002 50 P 0 0;2,4=19
P 12.81495 1.57086998 14 P 0 0;4=2
P 12.73621004 1.5315 14 P 0 0;4=2
P 12.63778996 2.7126 14 P 0 0;4=2
P 12.55905 2.67323002 14 P 0 0;4=2
P 12.55905 1.64961004 14 P 0 0;4=2
P 12.63778996 1.61023996 14 P 0 0;4=2
P 12.55905 1.57086998 14 P 0 0;4=2
P 12.63778996 1.5315 14 P 0 0;4=2
P 12.73621004 1.68898002 14 P 0 0;4=2
P 12.81495 1.64961004 14 P 0 0;4=2
P 12.63778996 1.68898002 14 P 0 0;4=2
P 12.55905 1.72835 14 P 0 0;4=2
P 12.81495 1.72835 14 P 0 0;4=2
P 12.73621004 1.45276004 14 P 0 0;4=2
P 12.81495 1.41338996 14 P 0 0;4=2
P 12.73621004 1.37401998 30 P 0 0;4=18
P 12.63778996 1.45276004 14 P 0 0;4=2
P 12.55905 1.41338996 14 P 0 0;4=2
P 0.35038996 1.5315 14 P 0 0;4=2
P 0.27165 1.49213002 14 P 0 0;4=2
P 0.17323002 2.67323002 14 P 0 0;4=2
P 0.09448996 2.63386004 14 P 0 0;4=2
P 0.09448996 1.61023996 14 P 0 0;4=2
P 0.17323002 1.57086998 14 P 0 0;4=2
P 0.09448996 1.5315 14 P 0 0;4=2
P 0.17323002 1.49213002 14 P 0 0;4=2
P 0.27165 1.64961004 14 P 0 0;4=2
P 0.35038996 1.61023996 14 P 0 0;4=2
P 0.17323002 1.64961004 14 P 0 0;4=2
P 0.09448996 1.68898002 14 P 0 0;4=2
P 0.35038996 1.68898002 14 P 0 0;4=2
P 0.27165 1.41338996 14 P 0 0;4=2
P 0.35038996 1.37401998 14 P 0 0;4=2
P 0.27165 1.33465 30 P 0 0;4=18
P 0.17323002 1.41338996 14 P 0 0;4=2
P 0.09448996 1.37401998 14 P 0 0;4=2
P 10.02558996 4.73035 37 P 0 0;2,4=8
P 3.69558996 4.67035 37 P 0 0;2,4=8
P 10.20866004 5.4441 26 P 0 0;4=40
P 5.78346004 5.4441 26 P 0 0;4=40
P 12.7252 6.31661998 21 P 0 0;4=38
P 0.2 6.31661998 21 P 0 0;4=38
P 12.7252 -0.293 21 P 0 0;4=38
P 0.22245 4.87401004 19 P 0 0;4=14
P 5.09558996 5.64035 37 P 0 0;2,4=8
P 12.68701004 0.46063002 22 P 0 0;4=41
P 12.68701998 5.4252 22 P 0 0;4=41
P 0.22245 0.42126004 22 P 0 0;4=41
P 0.22255 5.38583002 22 P 0 0;4=41
L 1.88908002 -1.91246004 1.89293002 -1.91246004 0 P 0 ;0
L 1.89126998 -1.91146004 1.89656998 -1.91146004 0 P 0 ;0
L 1.89393996 -1.91046004 1.9155 -1.91046004 0 P 0 ;0
L 1.91593996 -1.91246004 1.92048996 -1.91246004 0 P 0 ;0
L 1.9126 -1.91146004 1.9184 -1.91146004 0 P 0 ;0
L 1.89763002 -1.90946004 1.91016998 -1.90946004 0 P 0 ;0
L 1.89053002 -1.96001004 1.8974 -1.96001004 0 P 0 ;0
L 1.89053002 -1.95901004 1.8974 -1.95901004 0 P 0 ;0
L 1.89053002 -1.95801004 1.8974 -1.95801004 0 P 0 ;0
L 1.89053002 -1.95701004 1.8974 -1.95701004 0 P 0 ;0
L 1.89053002 -1.95601004 1.8974 -1.95601004 0 P 0 ;0
L 1.89053002 -1.95501004 1.8974 -1.95501004 0 P 0 ;0
L 1.89053002 -1.95401004 1.8974 -1.95401004 0 P 0 ;0
L 1.89053002 -1.95301004 1.89741004 -1.95301004 0 P 0 ;0
L 1.89053002 -1.95201004 1.89741998 -1.95201004 0 P 0 ;0
L 1.89053002 -1.95101004 1.89743996 -1.95101004 0 P 0 ;0
L 1.89053002 -1.95001004 1.89745 -1.95001004 0 P 0 ;0
L 1.89053002 -1.94901004 1.89746004 -1.94901004 0 P 0 ;0
L 1.89053002 -1.94801004 1.89753002 -1.94801004 0 P 0 ;0
L 1.89053002 -1.94701004 1.8977 -1.94701004 0 P 0 ;0
L 1.89053002 -1.94601004 1.89798002 -1.94601004 0 P 0 ;0
L 1.89053002 -1.94501004 1.89861004 -1.94501004 0 P 0 ;0
L 1.89053002 -1.94401004 1.90005 -1.94401004 0 P 0 ;0
L 1.89053002 -1.94301004 1.9113 -1.94301004 0 P 0 ;0
L 1.89053002 -1.94201004 1.91168002 -1.94201004 0 P 0 ;0
L 1.89053002 -1.94101004 1.91246998 -1.94101004 0 P 0 ;0
L 1.89053002 -1.94001004 1.90093996 -1.94001004 0 P 0 ;0
L 1.89053002 -1.93901004 1.89856004 -1.93901004 0 P 0 ;0
L 1.89053002 -1.93801004 1.89786998 -1.93801004 0 P 0 ;0
L 1.89053002 -1.93701004 1.89753996 -1.93701004 0 P 0 ;0
L 1.89053002 -1.93601004 1.89746998 -1.93601004 0 P 0 ;0
L 1.89053002 -1.93501004 1.89743996 -1.93501004 0 P 0 ;0
L 1.89053002 -1.93401004 1.89741998 -1.93401004 0 P 0 ;0
L 1.89053002 -1.93301004 1.8974 -1.93301004 0 P 0 ;0
L 1.89053002 -1.93201004 1.8974 -1.93201004 0 P 0 ;0
L 1.89053002 -1.93101004 1.8974 -1.93101004 0 P 0 ;0
L 1.89053002 -1.93001004 1.8974 -1.93001004 0 P 0 ;0
L 1.89053002 -1.92901004 1.8974 -1.92901004 0 P 0 ;0
L 1.89053002 -1.92801004 1.89753002 -1.92801004 0 P 0 ;0
L 1.89053002 -1.92701004 1.89793996 -1.92701004 0 P 0 ;0
L 1.89053002 -1.92601004 1.91713002 -1.92601004 0 P 0 ;0
L 1.89053002 -1.92501004 1.91628996 -1.92501004 0 P 0 ;0
L 1.89053002 -1.92401004 1.91513996 -1.92401004 0 P 0 ;0
L 1.89053002 -1.92301004 1.91321998 -1.92301004 0 P 0 ;0
L 1.89053002 -1.92201004 1.90551004 -1.92201004 0 P 0 ;0
L 1.89438996 -1.97246004 1.91331004 -1.97246004 0 P 0 ;0
L 1.89106998 -1.97146004 1.89973002 -1.97146004 0 P 0 ;0
L 1.88878002 -1.97046004 1.8949 -1.97046004 0 P 0 ;0
L 1.88698002 -1.96946004 1.89206998 -1.96946004 0 P 0 ;0
L 1.88546004 -1.96846004 1.88986998 -1.96846004 0 P 0 ;0
L 1.88416998 -1.96746004 1.88808996 -1.96746004 0 P 0 ;0
L 1.88288002 -1.96646004 1.88655 -1.96646004 0 P 0 ;0
L 1.88176998 -1.96546004 1.88518002 -1.96546004 0 P 0 ;0
L 1.88068996 -1.96446004 1.88393996 -1.96446004 0 P 0 ;0
L 1.87968996 -1.96346004 1.88286004 -1.96346004 0 P 0 ;0
L 1.87878002 -1.96246004 1.88186004 -1.96246004 0 P 0 ;0
L 1.8786 -1.92046004 1.88126998 -1.92046004 0 P 0 ;0
L 1.87946998 -1.91946004 1.88223002 -1.91946004 0 P 0 ;0
L 1.88048002 -1.91846004 1.88321004 -1.91846004 0 P 0 ;0
L 1.88153996 -1.91746004 1.88436998 -1.91746004 0 P 0 ;0
L 1.88273002 -1.91646004 1.88558996 -1.91646004 0 P 0 ;0
L 1.88406004 -1.91546004 1.88696998 -1.91546004 0 P 0 ;0
L 1.88548996 -1.91446004 1.88853002 -1.91446004 0 P 0 ;0
L 1.88718002 -1.91346004 1.89041998 -1.91346004 0 P 0 ;0
L 1.90896004 -1.92963996 1.90921998 -1.92991998 0 P 0 ;0
L 1.90921998 -1.92991998 1.90945 -1.93021998 0 P 0 ;0
L 1.90945 -1.93021998 1.90966004 -1.93053002 0 P 0 ;0
L 1.90966004 -1.93053002 1.90983002 -1.93086004 0 P 0 ;0
L 1.90983002 -1.93086004 1.90998002 -1.93121004 0 P 0 ;0
L 1.90998002 -1.93121004 1.9101 -1.93156998 0 P 0 ;0
L 1.9101 -1.93156998 1.91018996 -1.93193996 0 P 0 ;0
L 1.91018996 -1.93193996 1.91023996 -1.93231004 0 P 0 ;0
L 1.91023996 -1.93231004 1.91026998 -1.93265 0 P 0 ;0
L 1.91026998 -1.93265 1.91026004 -1.93298002 0 P 0 ;0
L 1.91026004 -1.93298002 1.91023002 -1.93331004 0 P 0 ;0
L 1.91023002 -1.93331004 1.91016998 -1.93363996 0 P 0 ;0
L 1.91016998 -1.93363996 1.91008996 -1.93396004 0 P 0 ;0
L 1.91008996 -1.93396004 1.90998002 -1.93428002 0 P 0 ;0
L 1.90998002 -1.93428002 1.90983996 -1.93458002 0 P 0 ;0
L 1.90983996 -1.93458002 1.90968996 -1.93486998 0 P 0 ;0
L 1.90968996 -1.93486998 1.90951004 -1.93516004 0 P 0 ;0
L 1.90951004 -1.93516004 1.90921004 -1.93556004 0 P 0 ;0
L 1.90921004 -1.93556004 1.90888002 -1.93593002 0 P 0 ;0
L 1.90888002 -1.93593002 1.90853002 -1.93626998 0 P 0 ;0
L 1.90853002 -1.93626998 1.90815 -1.93658996 0 P 0 ;0
L 1.90815 -1.93658996 1.90773996 -1.93686998 0 P 0 ;0
L 1.90773996 -1.93686998 1.90731998 -1.93711998 0 P 0 ;0
L 1.90731998 -1.93711998 1.90686998 -1.93733996 0 P 0 ;0
L 1.90686998 -1.93733996 1.90615 -1.93761004 0 P 0 ;0
L 1.90615 -1.93761004 1.90541998 -1.93783002 0 P 0 ;0
L 1.90541998 -1.93783002 1.90466004 -1.93798002 0 P 0 ;0
L 1.90466004 -1.93798002 1.9039 -1.93808002 0 P 0 ;0
L 1.9039 -1.93808002 1.90311998 -1.9381 0 P 0 ;0
L 1.90311998 -1.9381 1.90196004 -1.93808002 0 P 0 ;0
L 1.90196004 -1.93808002 1.90078996 -1.93798996 0 P 0 ;0
L 1.90078996 -1.93798996 1.90068002 -1.93798002 0 P 0 ;0
L 1.90068002 -1.93798002 1.90058002 -1.93795 0 P 0 ;0
L 1.90058002 -1.93795 1.90046998 -1.93791998 0 P 0 ;0
L 1.90046998 -1.93791998 1.90038002 -1.93788002 0 P 0 ;0
L 1.90038002 -1.93788002 1.90028002 -1.93783002 0 P 0 ;0
L 1.90028002 -1.93783002 1.90018996 -1.93778002 0 P 0 ;0
L 1.90018996 -1.93778002 1.9001 -1.93771004 0 P 0 ;0
L 1.9001 -1.93771004 1.90001998 -1.93763996 0 P 0 ;0
L 1.90001998 -1.93763996 1.89988002 -1.93748002 0 P 0 ;0
L 1.89988002 -1.93748002 1.89978002 -1.93733996 0 P 0 ;0
L 1.89978002 -1.93733996 1.89961998 -1.93703996 0 P 0 ;0
L 1.89961998 -1.93703996 1.89956998 -1.93688002 0 P 0 ;0
L 1.89956998 -1.93688002 1.89951998 -1.93671004 0 P 0 ;0
L 1.89951998 -1.93671004 1.89948996 -1.93655 0 P 0 ;0
L 1.89948996 -1.93655 1.89946998 -1.93636998 0 P 0 ;0
L 1.89946998 -1.93636998 1.8994 -1.93323002 0 P 0 ;0
L 1.8994 -1.93323002 1.8994 -1.92833002 0 P 0 ;0
L 1.8994 -1.92833002 1.90353996 -1.92833002 0 P 0 ;0
L 1.90353996 -1.92833002 1.90436998 -1.92835 0 P 0 ;0
L 1.90436998 -1.92835 1.9052 -1.92843002 0 P 0 ;0
L 1.9052 -1.92843002 1.90603002 -1.92853996 0 P 0 ;0
L 1.90603002 -1.92853996 1.90683996 -1.92871004 0 P 0 ;0
L 1.90683996 -1.92871004 1.90751004 -1.9289 0 P 0 ;0
L 1.90751004 -1.9289 1.90818002 -1.92913002 0 P 0 ;0
L 1.90818002 -1.92913002 1.90851998 -1.92928996 0 P 0 ;0
L 1.90851998 -1.92928996 1.90868002 -1.92938996 0 P 0 ;0
L 1.90868002 -1.92938996 1.90883002 -1.92951004 0 P 0 ;0
L 1.90883002 -1.92951004 1.90896004 -1.92963996 0 P 0 ;0
L 1.91188996 -1.96001004 1.91638996 -1.96001004 0 P 0 ;0
L 1.91156998 -1.95901004 1.91926998 -1.95901004 0 P 0 ;0
L 1.91125 -1.95801004 1.91891998 -1.95801004 0 P 0 ;0
L 1.91091998 -1.95701004 1.91853002 -1.95701004 0 P 0 ;0
L 1.9106 -1.95601004 1.91811004 -1.95601004 0 P 0 ;0
L 1.91025 -1.95501004 1.91765 -1.95501004 0 P 0 ;0
L 1.90988996 -1.95401004 1.91718996 -1.95401004 0 P 0 ;0
L 1.90953002 -1.95301004 1.91673002 -1.95301004 0 P 0 ;0
L 1.90918002 -1.95201004 1.91626998 -1.95201004 0 P 0 ;0
L 1.90881998 -1.95101004 1.91576004 -1.95101004 0 P 0 ;0
L 1.90841004 -1.95001004 1.91523996 -1.95001004 0 P 0 ;0
L 1.90793996 -1.94901004 1.91471004 -1.94901004 0 P 0 ;0
L 1.90738996 -1.94801004 1.91418002 -1.94801004 0 P 0 ;0
L 1.90676998 -1.94701004 1.9136 -1.94701004 0 P 0 ;0
L 1.90598996 -1.94601004 1.91261004 -1.94601004 0 P 0 ;0
L 1.90495 -1.94501004 1.91175 -1.94501004 0 P 0 ;0
L 1.90325 -1.94401004 1.91133002 -1.94401004 0 P 0 ;0
L 1.90456004 -1.94001004 1.91383002 -1.94001004 0 P 0 ;0
L 1.90801004 -1.93901004 1.91523002 -1.93901004 0 P 0 ;0
L 1.90956998 -1.93801004 1.91635 -1.93801004 0 P 0 ;0
L 1.9106 -1.93701004 1.91718002 -1.93701004 0 P 0 ;0
L 1.91133996 -1.93601004 1.91781004 -1.93601004 0 P 0 ;0
L 1.91183996 -1.93501004 1.91826004 -1.93501004 0 P 0 ;0
L 1.91213002 -1.93401004 1.9186 -1.93401004 0 P 0 ;0
L 1.91226004 -1.93301004 1.9188 -1.93301004 0 P 0 ;0
L 1.91221998 -1.93201004 1.9189 -1.93201004 0 P 0 ;0
L 1.91201998 -1.93101004 1.9189 -1.93101004 0 P 0 ;0
L 1.91163996 -1.93001004 1.91878996 -1.93001004 0 P 0 ;0
L 1.91105 -1.92901004 1.91856998 -1.92901004 0 P 0 ;0
L 1.91013996 -1.92801004 1.91823002 -1.92801004 0 P 0 ;0
L 1.90816998 -1.92701004 1.91776004 -1.92701004 0 P 0 ;0
L 1.90313996 -1.94011004 1.90316998 -1.9401 0 P 0 ;0
L 1.90316998 -1.9401 1.9032 -1.9401 0 P 0 ;0
L 1.9032 -1.9401 1.90398002 -1.94006998 0 P 0 ;0
L 1.90398002 -1.94006998 1.90406004 -1.94006998 0 P 0 ;0
L 1.90406004 -1.94006998 1.90413996 -1.94006004 0 P 0 ;0
L 1.90413996 -1.94006004 1.9049 -1.93996998 0 P 0 ;0
L 1.9049 -1.93996998 1.90493996 -1.93996004 0 P 0 ;0
L 1.90493996 -1.93996004 1.90498996 -1.93996004 0 P 0 ;0
L 1.90498996 -1.93996004 1.90506998 -1.93993996 0 P 0 ;0
L 1.90506998 -1.93993996 1.90581998 -1.93978002 0 P 0 ;0
L 1.90581998 -1.93978002 1.90586004 -1.93978002 0 P 0 ;0
L 1.90586004 -1.93978002 1.90593996 -1.93976004 0 P 0 ;0
L 1.90593996 -1.93976004 1.90596998 -1.93973996 0 P 0 ;0
L 1.90596998 -1.93973996 1.90671004 -1.93953002 0 P 0 ;0
L 1.90671004 -1.93953002 1.90678996 -1.93951004 0 P 0 ;0
L 1.90678996 -1.93951004 1.90758996 -1.93921004 0 P 0 ;0
L 1.90758996 -1.93921004 1.90766004 -1.93916998 0 P 0 ;0
L 1.90766004 -1.93916998 1.9077 -1.93915 0 P 0 ;0
L 1.9077 -1.93915 1.90773996 -1.93913996 0 P 0 ;0
L 1.90773996 -1.93913996 1.90818996 -1.93891998 0 P 0 ;0
L 1.90818996 -1.93891998 1.90821998 -1.9389 0 P 0 ;0
L 1.90821998 -1.9389 1.90826004 -1.93888996 0 P 0 ;0
L 1.90826004 -1.93888996 1.90828996 -1.93886998 0 P 0 ;0
L 1.90828996 -1.93886998 1.90833002 -1.93885 0 P 0 ;0
L 1.90833002 -1.93885 1.90875 -1.9386 0 P 0 ;0
L 1.90875 -1.9386 1.90883002 -1.93856004 0 P 0 ;0
L 1.90883002 -1.93856004 1.90888996 -1.93851004 0 P 0 ;0
L 1.90888996 -1.93851004 1.90928996 -1.93823002 0 P 0 ;0
L 1.90928996 -1.93823002 1.90933002 -1.9382 0 P 0 ;0
L 1.90933002 -1.9382 1.90936004 -1.93818002 0 P 0 ;0
L 1.90936004 -1.93818002 1.90938996 -1.93815 0 P 0 ;0
L 1.90938996 -1.93815 1.90941998 -1.93813002 0 P 0 ;0
L 1.90941998 -1.93813002 1.9098 -1.93781998 0 P 0 ;0
L 1.9098 -1.93781998 1.90986004 -1.93776004 0 P 0 ;0
L 1.90986004 -1.93776004 1.90988996 -1.93773996 0 P 0 ;0
L 1.90988996 -1.93773996 1.90991998 -1.93771004 0 P 0 ;0
L 1.90991998 -1.93771004 1.91028002 -1.93736004 0 P 0 ;0
L 1.91028002 -1.93736004 1.91038996 -1.93725 0 P 0 ;0
L 1.91038996 -1.93725 1.91071004 -1.93688002 0 P 0 ;0
L 1.91071004 -1.93688002 1.91073996 -1.93685 0 P 0 ;0
L 1.91073996 -1.93685 1.91116004 -1.9363 0 P 0 ;0
L 1.91116004 -1.9363 1.9112 -1.93623002 0 P 0 ;0
L 1.9112 -1.93623002 1.91138002 -1.93595 0 P 0 ;0
L 1.91138002 -1.93595 1.9114 -1.93591004 0 P 0 ;0
L 1.9114 -1.93591004 1.91143996 -1.93585 0 P 0 ;0
L 1.91143996 -1.93585 1.91146004 -1.93581004 0 P 0 ;0
L 1.91146004 -1.93581004 1.91161004 -1.93551998 0 P 0 ;0
L 1.91161004 -1.93551998 1.91163002 -1.93548996 0 P 0 ;0
L 1.91163002 -1.93548996 1.91165 -1.93545 0 P 0 ;0
L 1.91165 -1.93545 1.91166004 -1.93541004 0 P 0 ;0
L 1.91166004 -1.93541004 1.91168002 -1.93538002 0 P 0 ;0
L 1.91168002 -1.93538002 1.91181004 -1.93506998 0 P 0 ;0
L 1.91181004 -1.93506998 1.91183996 -1.935 0 P 0 ;0
L 1.91183996 -1.935 1.91186004 -1.93496004 0 P 0 ;0
L 1.91186004 -1.93496004 1.91186998 -1.93493002 0 P 0 ;0
L 1.91186998 -1.93493002 1.91198002 -1.93461004 0 P 0 ;0
L 1.91198002 -1.93461004 1.91198996 -1.93456998 0 P 0 ;0
L 1.91198996 -1.93456998 1.912 -1.93453996 0 P 0 ;0
L 1.912 -1.93453996 1.9121 -1.93413996 0 P 0 ;0
L 1.9121 -1.93413996 1.91211998 -1.9341 0 P 0 ;0
L 1.91211998 -1.9341 1.91211998 -1.93406004 0 P 0 ;0
L 1.91211998 -1.93406004 1.91213002 -1.93401998 0 P 0 ;0
L 1.91213002 -1.93401998 1.91213996 -1.93398996 0 P 0 ;0
L 1.91213996 -1.93398996 1.9122 -1.93366004 0 P 0 ;0
L 1.9122 -1.93366004 1.91221004 -1.93358002 0 P 0 ;0
L 1.91221004 -1.93358002 1.91221004 -1.93353996 0 P 0 ;0
L 1.91221004 -1.93353996 1.91221998 -1.9335 0 P 0 ;0
L 1.91221998 -1.9335 1.91225 -1.93316998 0 P 0 ;0
L 1.91225 -1.93316998 1.91226004 -1.93308996 0 P 0 ;0
L 1.91226004 -1.93308996 1.91226004 -1.93268002 0 P 0 ;0
L 1.91226004 -1.93268002 1.91226998 -1.93263996 0 P 0 ;0
L 1.91226998 -1.93263996 1.91226998 -1.9326 0 P 0 ;0
L 1.91226998 -1.9326 1.91226004 -1.93251998 0 P 0 ;0
L 1.91226004 -1.93251998 1.91223996 -1.93218996 0 P 0 ;0
L 1.91223996 -1.93218996 1.91223996 -1.93215 0 P 0 ;0
L 1.91223996 -1.93215 1.91223002 -1.9321 0 P 0 ;0
L 1.91223002 -1.9321 1.91223002 -1.93206004 0 P 0 ;0
L 1.91223002 -1.93206004 1.91221998 -1.93201998 0 P 0 ;0
L 1.91221998 -1.93201998 1.91216998 -1.93163996 0 P 0 ;0
L 1.91216998 -1.93163996 1.91216004 -1.9316 0 P 0 ;0
L 1.91216004 -1.9316 1.91213996 -1.93151004 0 P 0 ;0
L 1.91213996 -1.93151004 1.91213002 -1.93146998 0 P 0 ;0
L 1.91213002 -1.93146998 1.91205 -1.93111004 0 P 0 ;0
L 1.91205 -1.93111004 1.91203996 -1.93106004 0 P 0 ;0
L 1.91203996 -1.93106004 1.91203002 -1.93101998 0 P 0 ;0
L 1.91203002 -1.93101998 1.91201004 -1.93098002 0 P 0 ;0
L 1.91201004 -1.93098002 1.912 -1.93093996 0 P 0 ;0
L 1.912 -1.93093996 1.91188002 -1.93058002 0 P 0 ;0
L 1.91188002 -1.93058002 1.91186998 -1.93053996 0 P 0 ;0
L 1.91186998 -1.93053996 1.91185 -1.9305 0 P 0 ;0
L 1.91185 -1.9305 1.91183996 -1.93046004 0 P 0 ;0
L 1.91183996 -1.93046004 1.91181998 -1.93043002 0 P 0 ;0
L 1.91181998 -1.93043002 1.91166998 -1.93008002 0 P 0 ;0
L 1.91166998 -1.93008002 1.91166004 -1.93003996 0 P 0 ;0
L 1.91166004 -1.93003996 1.9116 -1.92991998 0 P 0 ;0
L 1.9116 -1.92991998 1.91141998 -1.92958996 0 P 0 ;0
L 1.91141998 -1.92958996 1.9114 -1.92955 0 P 0 ;0
L 1.9114 -1.92955 1.91138002 -1.92951998 0 P 0 ;0
L 1.91138002 -1.92951998 1.91133002 -1.92945 0 P 0 ;0
L 1.91133002 -1.92945 1.91113002 -1.92913002 0 P 0 ;0
L 1.91113002 -1.92913002 1.91111004 -1.92908996 0 P 0 ;0
L 1.91111004 -1.92908996 1.91108996 -1.92906004 0 P 0 ;0
L 1.91108996 -1.92906004 1.91106004 -1.92901998 0 P 0 ;0
L 1.91106004 -1.92901998 1.91103002 -1.92898996 0 P 0 ;0
L 1.91103002 -1.92898996 1.9108 -1.92868996 0 P 0 ;0
L 1.9108 -1.92868996 1.91076998 -1.92866004 0 P 0 ;0
L 1.91076998 -1.92866004 1.91075 -1.92861998 0 P 0 ;0
L 1.91075 -1.92861998 1.91068996 -1.92856004 0 P 0 ;0
L 1.91068996 -1.92856004 1.91043002 -1.92828002 0 P 0 ;0
L 1.91043002 -1.92828002 1.91035 -1.9282 0 P 0 ;0
L 1.91035 -1.9282 1.91033002 -1.92816998 0 P 0 ;0
L 1.91033002 -1.92816998 1.91018996 -1.92803996 0 P 0 ;0
L 1.91018996 -1.92803996 1.91018002 -1.92803996 0 P 0 ;0
L 1.91018002 -1.92803996 1.91016004 -1.92801998 0 P 0 ;0
L 1.91016004 -1.92801998 1.91011998 -1.92798996 0 P 0 ;0
L 1.91011998 -1.92798996 1.91006004 -1.92793002 0 P 0 ;0
L 1.91006004 -1.92793002 1.90991004 -1.92781998 0 P 0 ;0
L 1.90991004 -1.92781998 1.90988002 -1.9278 0 P 0 ;0
L 1.90988002 -1.9278 1.90983996 -1.92776998 0 P 0 ;0
L 1.90983996 -1.92776998 1.90976998 -1.92771998 0 P 0 ;0
L 1.90976998 -1.92771998 1.90961004 -1.92761998 0 P 0 ;0
L 1.90961004 -1.92761998 1.90953996 -1.92756998 0 P 0 ;0
L 1.90953996 -1.92756998 1.9095 -1.92755 0 P 0 ;0
L 1.9095 -1.92755 1.90946998 -1.92753002 0 P 0 ;0
L 1.90946998 -1.92753002 1.9093 -1.92743996 0 P 0 ;0
L 1.9093 -1.92743996 1.90926004 -1.92741998 0 P 0 ;0
L 1.90926004 -1.92741998 1.90923002 -1.9274 0 P 0 ;0
L 1.90923002 -1.9274 1.90915 -1.92736998 0 P 0 ;0
L 1.90915 -1.92736998 1.90896998 -1.92728996 0 P 0 ;0
L 1.90896998 -1.92728996 1.90893996 -1.92728002 0 P 0 ;0
L 1.90893996 -1.92728002 1.9089 -1.92726004 0 P 0 ;0
L 1.9089 -1.92726004 1.90886998 -1.92725 0 P 0 ;0
L 1.90886998 -1.92725 1.90883002 -1.92723996 0 P 0 ;0
L 1.90883002 -1.92723996 1.90816004 -1.92701004 0 P 0 ;0
L 1.90816004 -1.92701004 1.90813996 -1.927 0 P 0 ;0
L 1.90813996 -1.927 1.9081 -1.92698996 0 P 0 ;0
L 1.9081 -1.92698996 1.90803996 -1.92696998 0 P 0 ;0
L 1.90803996 -1.92696998 1.90736998 -1.92678002 0 P 0 ;0
L 1.90736998 -1.92678002 1.90723996 -1.92675 0 P 0 ;0
L 1.90723996 -1.92675 1.90643002 -1.92658996 0 P 0 ;0
L 1.90643002 -1.92658996 1.90636998 -1.92656998 0 P 0 ;0
L 1.90636998 -1.92656998 1.90633996 -1.92656998 0 P 0 ;0
L 1.90633996 -1.92656998 1.90631004 -1.92656004 0 P 0 ;0
L 1.90631004 -1.92656004 1.90548996 -1.92645 0 P 0 ;0
L 1.90548996 -1.92645 1.90543996 -1.92643996 0 P 0 ;0
L 1.90543996 -1.92643996 1.9054 -1.92643002 0 P 0 ;0
L 1.9054 -1.92643002 1.90538002 -1.92643002 0 P 0 ;0
L 1.90538002 -1.92643002 1.90455 -1.92636004 0 P 0 ;0
L 1.90455 -1.92636004 1.90443002 -1.92636004 0 P 0 ;0
L 1.90443002 -1.92636004 1.9036 -1.92633002 0 P 0 ;0
L 1.9036 -1.92633002 1.8994 -1.92633002 0 P 0 ;0
L 1.8994 -1.92633002 1.89798002 -1.92691004 0 P 0 ;0
L 1.89798002 -1.92691004 1.8974 -1.92833002 0 P 0 ;0
L 1.8974 -1.92833002 1.8974 -1.93328002 0 P 0 ;0
L 1.8974 -1.93328002 1.89748002 -1.93643002 0 P 0 ;0
L 1.89748002 -1.93643002 1.89748002 -1.93656004 0 P 0 ;0
L 1.89748002 -1.93656004 1.8975 -1.93673002 0 P 0 ;0
L 1.8975 -1.93673002 1.89751004 -1.93681004 0 P 0 ;0
L 1.89751004 -1.93681004 1.89751998 -1.9369 0 P 0 ;0
L 1.89751998 -1.9369 1.89755 -1.93706004 0 P 0 ;0
L 1.89755 -1.93706004 1.89758002 -1.93718996 0 P 0 ;0
L 1.89758002 -1.93718996 1.89758996 -1.93723002 0 P 0 ;0
L 1.89758996 -1.93723002 1.89763002 -1.9374 0 P 0 ;0
L 1.89763002 -1.9374 1.89763996 -1.93743996 0 P 0 ;0
L 1.89763996 -1.93743996 1.89766004 -1.93748002 0 P 0 ;0
L 1.89766004 -1.93748002 1.89768002 -1.93756004 0 P 0 ;0
L 1.89768002 -1.93756004 1.89773996 -1.93771998 0 P 0 ;0
L 1.89773996 -1.93771998 1.89776004 -1.93776004 0 P 0 ;0
L 1.89776004 -1.93776004 1.89776998 -1.9378 0 P 0 ;0
L 1.89776998 -1.9378 1.89781004 -1.93788002 0 P 0 ;0
L 1.89781004 -1.93788002 1.89788002 -1.93803996 0 P 0 ;0
L 1.89788002 -1.93803996 1.8979 -1.93808002 0 P 0 ;0
L 1.8979 -1.93808002 1.89791998 -1.93811004 0 P 0 ;0
L 1.89791998 -1.93811004 1.89796004 -1.93818996 0 P 0 ;0
L 1.89796004 -1.93818996 1.89803996 -1.93833996 0 P 0 ;0
L 1.89803996 -1.93833996 1.89813996 -1.93848002 0 P 0 ;0
L 1.89813996 -1.93848002 1.89823002 -1.93861998 0 P 0 ;0
L 1.89823002 -1.93861998 1.89828002 -1.93868996 0 P 0 ;0
L 1.89828002 -1.93868996 1.89831004 -1.93873002 0 P 0 ;0
L 1.89831004 -1.93873002 1.89833996 -1.93876004 0 P 0 ;0
L 1.89833996 -1.93876004 1.8984 -1.93883996 0 P 0 ;0
L 1.8984 -1.93883996 1.89848996 -1.93893002 0 P 0 ;0
L 1.89848996 -1.93893002 1.89851004 -1.93896004 0 P 0 ;0
L 1.89851004 -1.93896004 1.89868002 -1.93913002 0 P 0 ;0
L 1.89868002 -1.93913002 1.89871004 -1.93915 0 P 0 ;0
L 1.89871004 -1.93915 1.89878996 -1.93921998 0 P 0 ;0
L 1.89878996 -1.93921998 1.89885 -1.93928002 0 P 0 ;0
L 1.89885 -1.93928002 1.89888002 -1.9393 0 P 0 ;0
L 1.89888002 -1.9393 1.89891998 -1.93931998 0 P 0 ;0
L 1.89891998 -1.93931998 1.89901004 -1.93938996 0 P 0 ;0
L 1.89901004 -1.93938996 1.89903996 -1.93941004 0 P 0 ;0
L 1.89903996 -1.93941004 1.89906998 -1.93943996 0 P 0 ;0
L 1.89906998 -1.93943996 1.8991 -1.93946004 0 P 0 ;0
L 1.8991 -1.93946004 1.89913996 -1.93948002 0 P 0 ;0
L 1.89913996 -1.93948002 1.89923002 -1.93953996 0 P 0 ;0
L 1.89923002 -1.93953996 1.89926998 -1.93956004 0 P 0 ;0
L 1.89926998 -1.93956004 1.8993 -1.93958002 0 P 0 ;0
L 1.8993 -1.93958002 1.89933996 -1.9396 0 P 0 ;0
L 1.89933996 -1.9396 1.89936998 -1.93961004 0 P 0 ;0
L 1.89936998 -1.93961004 1.89938002 -1.93961004 0 P 0 ;0
L 1.89938002 -1.93961004 1.89946998 -1.93966004 0 P 0 ;0
L 1.89946998 -1.93966004 1.89953996 -1.9397 0 P 0 ;0
L 1.89953996 -1.9397 1.89971998 -1.93976998 0 P 0 ;0
L 1.89971998 -1.93976998 1.89975 -1.93978996 0 P 0 ;0
L 1.89975 -1.93978996 1.89978996 -1.9398 0 P 0 ;0
L 1.89978996 -1.9398 1.89986998 -1.93983002 0 P 0 ;0
L 1.89986998 -1.93983002 1.89996998 -1.93986004 0 P 0 ;0
L 1.89996998 -1.93986004 1.90001004 -1.93986998 0 P 0 ;0
L 1.90001004 -1.93986998 1.90005 -1.93988996 0 P 0 ;0
L 1.90005 -1.93988996 1.90013002 -1.9399 0 P 0 ;0
L 1.90013002 -1.9399 1.90023002 -1.93993002 0 P 0 ;0
L 1.90023002 -1.93993002 1.90023996 -1.93993002 0 P 0 ;0
L 1.90023996 -1.93993002 1.90028002 -1.93993996 0 P 0 ;0
L 1.90028002 -1.93993996 1.90031004 -1.93995 0 P 0 ;0
L 1.90031004 -1.93995 1.90036004 -1.93995 0 P 0 ;0
L 1.90036004 -1.93995 1.9004 -1.93996004 0 P 0 ;0
L 1.9004 -1.93996004 1.9005 -1.93996998 0 P 0 ;0
L 1.9005 -1.93996998 1.90061004 -1.93998996 0 P 0 ;0
L 1.90061004 -1.93998996 1.90063996 -1.93998996 0 P 0 ;0
L 1.90063996 -1.93998996 1.90181004 -1.94006998 0 P 0 ;0
L 1.90181004 -1.94006998 1.90183996 -1.94008002 0 P 0 ;0
L 1.90183996 -1.94008002 1.90191004 -1.94008002 0 P 0 ;0
L 1.90191004 -1.94008002 1.90308002 -1.9401 0 P 0 ;0
L 1.90308002 -1.9401 1.90311004 -1.9401 0 P 0 ;0
L 1.90311004 -1.9401 1.90313996 -1.94011004 0 P 0 ;0
L 1.90841004 -1.97146004 1.91683996 -1.97146004 0 P 0 ;0
L 1.9135 -1.97046004 1.91931004 -1.97046004 0 P 0 ;0
L 1.91655 -1.96946004 1.92131004 -1.96946004 0 P 0 ;0
L 1.91891998 -1.96846004 1.92301004 -1.96846004 0 P 0 ;0
L 1.92088996 -1.96746004 1.9245 -1.96746004 0 P 0 ;0
L 1.92251004 -1.96646004 1.9258 -1.96646004 0 P 0 ;0
L 1.92391004 -1.96546004 1.92696004 -1.96546004 0 P 0 ;0
L 1.92513002 -1.96446004 1.92803002 -1.96446004 0 P 0 ;0
L 1.9262 -1.96346004 1.92898996 -1.96346004 0 P 0 ;0
L 1.92713996 -1.96246004 1.92986004 -1.96246004 0 P 0 ;0
L 1.928 -1.96146004 1.93068996 -1.96146004 0 P 0 ;0
L 1.92878002 -1.96046004 1.93143002 -1.96046004 0 P 0 ;0
L 1.92951004 -1.95946004 1.93216004 -1.95946004 0 P 0 ;0
L 1.93016998 -1.95846004 1.93278996 -1.95846004 0 P 0 ;0
L 1.93078002 -1.95746004 1.93341004 -1.95746004 0 P 0 ;0
L 1.93133002 -1.95646004 1.93396004 -1.95646004 0 P 0 ;0
L 1.93185 -1.95546004 1.93448996 -1.95546004 0 P 0 ;0
L 1.93231004 -1.95446004 1.93495 -1.95446004 0 P 0 ;0
L 1.93275 -1.95346004 1.93541004 -1.95346004 0 P 0 ;0
L 1.93311998 -1.95246004 1.93586004 -1.95246004 0 P 0 ;0
L 1.93348002 -1.95146004 1.93628996 -1.95146004 0 P 0 ;0
L 1.93376998 -1.95046004 1.93666004 -1.95046004 0 P 0 ;0
L 1.93405 -1.94946004 1.93693002 -1.94946004 0 P 0 ;0
L 1.93428002 -1.94846004 1.93715 -1.94846004 0 P 0 ;0
L 1.93446998 -1.94746004 1.93733002 -1.94746004 0 P 0 ;0
L 1.93466004 -1.94646004 1.93743002 -1.94646004 0 P 0 ;0
L 1.93478996 -1.94546004 1.93748996 -1.94546004 0 P 0 ;0
L 1.9349 -1.94446998 1.93751998 -1.94446998 0 P 0 ;0
L 1.93496998 -1.94346004 1.93755 -1.94346004 0 P 0 ;0
L 1.93501998 -1.94246004 1.93758002 -1.94246004 0 P 0 ;0
L 1.93505 -1.94146998 1.93758996 -1.94146998 0 P 0 ;0
L 1.93503002 -1.94046004 1.93755 -1.94046004 0 P 0 ;0
L 1.935 -1.93946004 1.93751998 -1.93946004 0 P 0 ;0
L 1.93491998 -1.93846004 1.93748002 -1.93846004 0 P 0 ;0
L 1.93481004 -1.93746004 1.93738996 -1.93746004 0 P 0 ;0
L 1.93468996 -1.93646004 1.93726998 -1.93646004 0 P 0 ;0
L 1.93451004 -1.93546004 1.93716004 -1.93546004 0 P 0 ;0
L 1.93433002 -1.93446004 1.93703996 -1.93446004 0 P 0 ;0
L 1.93408996 -1.93346004 1.93685 -1.93346004 0 P 0 ;0
L 1.93383002 -1.93246004 1.93666004 -1.93246004 0 P 0 ;0
L 1.93353002 -1.93146004 1.93638996 -1.93146004 0 P 0 ;0
L 1.9332 -1.93046004 1.93611998 -1.93046004 0 P 0 ;0
L 1.93283996 -1.92946004 1.93576998 -1.92946004 0 P 0 ;0
L 1.93241004 -1.92846004 1.93541004 -1.92846004 0 P 0 ;0
L 1.93198996 -1.92746004 1.93498002 -1.92746004 0 P 0 ;0
L 1.93146998 -1.92646004 1.93451004 -1.92646004 0 P 0 ;0
L 1.93096004 -1.92546004 1.93398002 -1.92546004 0 P 0 ;0
L 1.93035 -1.92446998 1.93338002 -1.92446998 0 P 0 ;0
L 1.92973002 -1.92346004 1.93275 -1.92346004 0 P 0 ;0
L 1.92903002 -1.92246004 1.93201004 -1.92246004 0 P 0 ;0
L 1.92831004 -1.92146004 1.93125 -1.92146004 0 P 0 ;0
L 1.92746998 -1.92046004 1.93041004 -1.92046004 0 P 0 ;0
L 1.92661004 -1.91946004 1.92948996 -1.91946004 0 P 0 ;0
L 1.92558996 -1.91846004 1.92851004 -1.91846004 0 P 0 ;0
L 1.9245 -1.91746004 1.92741998 -1.91746004 0 P 0 ;0
L 1.92328996 -1.91646004 1.92621998 -1.91646004 0 P 0 ;0
L 1.92188002 -1.91546004 1.92491998 -1.91546004 0 P 0 ;0
L 1.92026004 -1.91446004 1.92358996 -1.91446004 0 P 0 ;0
L 1.91835 -1.91346004 1.92208002 -1.91346004 0 P 0 ;0
L 1.82446998 -2.08323996 1.87608002 -2.08323996 0 P 0 ;0
L 1.82403002 -2.08223996 1.87601004 -2.08223996 0 P 0 ;0
L 1.8234 -2.08123996 1.87591004 -2.08123996 0 P 0 ;0
L 1.82256004 -2.08023996 1.87578002 -2.08023996 0 P 0 ;0
L 1.82166004 -2.07923996 1.87558996 -2.07923996 0 P 0 ;0
L 1.82061998 -2.07823996 1.87533002 -2.07823996 0 P 0 ;0
L 1.81946004 -2.07723996 1.87498996 -2.07723996 0 P 0 ;0
L 1.81818002 -2.07623996 1.8746 -2.07623996 0 P 0 ;0
L 1.8168 -2.07523996 1.87416998 -2.07523996 0 P 0 ;0
L 1.81541998 -2.07423996 1.87371004 -2.07423996 0 P 0 ;0
L 1.81403002 -2.07323996 1.87316998 -2.07323996 0 P 0 ;0
L 1.81265 -2.07223996 1.87261004 -2.07223996 0 P 0 ;0
L 1.81126998 -2.07123996 1.87196004 -2.07123996 0 P 0 ;0
L 1.80986004 -2.07023996 1.87128002 -2.07023996 0 P 0 ;0
L 1.80843996 -2.06923996 1.87051998 -2.06923996 0 P 0 ;0
L 1.80703002 -2.06823996 1.8697 -2.06823996 0 P 0 ;0
L 1.80561004 -2.06723996 1.86883002 -2.06723996 0 P 0 ;0
L 1.8042 -2.06623996 1.86796004 -2.06623996 0 P 0 ;0
L 1.80278002 -2.06523996 1.86705 -2.06523996 0 P 0 ;0
L 1.80136004 -2.06423996 1.86608002 -2.06423996 0 P 0 ;0
L 1.79995 -2.06323996 1.8651 -2.06323996 0 P 0 ;0
L 1.79865 -2.06223996 1.86411004 -2.06223996 0 P 0 ;0
L 1.79735 -2.06123996 1.86301998 -2.06123996 0 P 0 ;0
L 1.79605 -2.06023996 1.86193002 -2.06023996 0 P 0 ;0
L 1.79475 -2.05923996 1.86083996 -2.05923996 0 P 0 ;0
L 1.79345 -2.05823996 1.85966998 -2.05823996 0 P 0 ;0
L 1.79215 -2.05723996 1.85846004 -2.05723996 0 P 0 ;0
L 1.79088002 -2.05623996 1.85726004 -2.05623996 0 P 0 ;0
L 1.78971998 -2.05523996 1.85598996 -2.05523996 0 P 0 ;0
L 1.78856004 -2.05423996 1.85461998 -2.05423996 0 P 0 ;0
L 1.7874 -2.05323996 1.85326004 -2.05323996 0 P 0 ;0
L 1.78623002 -2.05223996 1.8519 -2.05223996 0 P 0 ;0
L 1.78506998 -2.05123996 1.85053996 -2.05123996 0 P 0 ;0
L 1.78398002 -2.05023996 1.84918002 -2.05023996 0 P 0 ;0
L 1.783 -2.04923996 1.84781004 -2.04923996 0 P 0 ;0
L 1.87086004 -2.03023996 1.87535 -2.03023996 0 P 0 ;0
L 1.91633002 -1.91473002 1.9183 -1.91565 0 P 0 ;0
L 1.9183 -1.91565 1.92018996 -1.91673002 0 P 0 ;0
L 1.92018996 -1.91673002 1.92196998 -1.91796998 0 P 0 ;0
L 1.92196998 -1.91796998 1.92365 -1.91936004 0 P 0 ;0
L 1.92365 -1.91936004 1.9252 -1.92088002 0 P 0 ;0
L 1.9252 -1.92088002 1.92661004 -1.92253996 0 P 0 ;0
L 1.92661004 -1.92253996 1.92795 -1.92436998 0 P 0 ;0
L 1.92795 -1.92436998 1.92913996 -1.9263 0 P 0 ;0
L 1.92913996 -1.9263 1.93018002 -1.92831998 0 P 0 ;0
L 1.93018002 -1.92831998 1.93106998 -1.93041004 0 P 0 ;0
L 1.93106998 -1.93041004 1.93178996 -1.93256004 0 P 0 ;0
L 1.93178996 -1.93256004 1.93236004 -1.93476004 0 P 0 ;0
L 1.93236004 -1.93476004 1.93276004 -1.93703996 0 P 0 ;0
L 1.93276004 -1.93703996 1.93298996 -1.93933996 0 P 0 ;0
L 1.93298996 -1.93933996 1.93306004 -1.94165 0 P 0 ;0
L 1.93306004 -1.94165 1.93295 -1.94396998 0 P 0 ;0
L 1.93295 -1.94396998 1.93268002 -1.94626004 0 P 0 ;0
L 1.93268002 -1.94626004 1.93223002 -1.94853996 0 P 0 ;0
L 1.93223002 -1.94853996 1.93161998 -1.95071998 0 P 0 ;0
L 1.93161998 -1.95071998 1.93085 -1.95285 0 P 0 ;0
L 1.93085 -1.95285 1.92991004 -1.95491004 0 P 0 ;0
L 1.92991004 -1.95491004 1.92881004 -1.95688996 0 P 0 ;0
L 1.92881004 -1.95688996 1.92756004 -1.95878002 0 P 0 ;0
L 1.92756004 -1.95878002 1.92616004 -1.96056998 0 P 0 ;0
L 1.92616004 -1.96056998 1.92493996 -1.9619 0 P 0 ;0
L 1.92493996 -1.9619 1.92361998 -1.96313996 0 P 0 ;0
L 1.92361998 -1.96313996 1.9222 -1.96426004 0 P 0 ;0
L 1.9222 -1.96426004 1.9207 -1.96526998 0 P 0 ;0
L 1.9207 -1.96526998 1.91911004 -1.96616998 0 P 0 ;0
L 1.91911004 -1.96616998 1.91686998 -1.96721004 0 P 0 ;0
L 1.91686998 -1.96721004 1.91456004 -1.96806998 0 P 0 ;0
L 1.91456004 -1.96806998 1.91218996 -1.96876004 0 P 0 ;0
L 1.91218996 -1.96876004 1.90975 -1.96926998 0 P 0 ;0
L 1.90975 -1.96926998 1.90725 -1.9696 0 P 0 ;0
L 1.90725 -1.9696 1.90473002 -1.96973996 0 P 0 ;0
L 1.90473002 -1.96973996 1.9022 -1.96968996 0 P 0 ;0
L 1.9022 -1.96968996 1.89966998 -1.96945 0 P 0 ;0
L 1.89966998 -1.96945 1.89778002 -1.96913002 0 P 0 ;0
L 1.89778002 -1.96913002 1.89591998 -1.96868996 0 P 0 ;0
L 1.89591998 -1.96868996 1.8941 -1.96811004 0 P 0 ;0
L 1.8941 -1.96811004 1.89231004 -1.96741004 0 P 0 ;0
L 1.89231004 -1.96741004 1.89058002 -1.96658002 0 P 0 ;0
L 1.89058002 -1.96658002 1.88875 -1.96553996 0 P 0 ;0
L 1.88875 -1.96553996 1.88698996 -1.96435 0 P 0 ;0
L 1.88698996 -1.96435 1.88533996 -1.96303002 0 P 0 ;0
L 1.88533996 -1.96303002 1.88378996 -1.9616 0 P 0 ;0
L 1.88378996 -1.9616 1.88235 -1.96003996 0 P 0 ;0
L 1.88235 -1.96003996 1.88103002 -1.95838996 0 P 0 ;0
L 1.88103002 -1.95838996 1.87983996 -1.95663002 0 P 0 ;0
L 1.87983996 -1.95663002 1.87861998 -1.95446998 0 P 0 ;0
L 1.87861998 -1.95446998 1.87758002 -1.9522 0 P 0 ;0
L 1.87758002 -1.9522 1.87673996 -1.94986004 0 P 0 ;0
L 1.87673996 -1.94986004 1.8761 -1.94745 0 P 0 ;0
L 1.8761 -1.94745 1.87568002 -1.945 0 P 0 ;0
L 1.87568002 -1.945 1.87546004 -1.94248996 0 P 0 ;0
L 1.87546004 -1.94248996 1.87546004 -1.93998996 0 P 0 ;0
L 1.87546004 -1.93998996 1.87566998 -1.93748996 0 P 0 ;0
L 1.87566998 -1.93748996 1.87608996 -1.93501998 0 P 0 ;0
L 1.87608996 -1.93501998 1.87671998 -1.9326 0 P 0 ;0
L 1.87671998 -1.9326 1.87755 -1.93023002 0 P 0 ;0
L 1.87755 -1.93023002 1.8786 -1.92793002 0 P 0 ;0
L 1.8786 -1.92793002 1.87981998 -1.92575 0 P 0 ;0
L 1.87981998 -1.92575 1.88123002 -1.92368002 0 P 0 ;0
L 1.88123002 -1.92368002 1.88281004 -1.92175 0 P 0 ;0
L 1.88281004 -1.92175 1.88455 -1.91996004 0 P 0 ;0
L 1.88455 -1.91996004 1.88643002 -1.91831998 0 P 0 ;0
L 1.88643002 -1.91831998 1.88845 -1.91686004 0 P 0 ;0
L 1.88845 -1.91686004 1.88986998 -1.91598996 0 P 0 ;0
L 1.88986998 -1.91598996 1.89135 -1.91523002 0 P 0 ;0
L 1.89135 -1.91523002 1.89288002 -1.91458996 0 P 0 ;0
L 1.89288002 -1.91458996 1.89446998 -1.91406004 0 P 0 ;0
L 1.89446998 -1.91406004 1.89688996 -1.91343996 0 P 0 ;0
L 1.89688996 -1.91343996 1.89935 -1.91298996 0 P 0 ;0
L 1.89935 -1.91298996 1.90183996 -1.91271004 0 P 0 ;0
L 1.90183996 -1.91271004 1.9044 -1.91261004 0 P 0 ;0
L 1.9044 -1.91261004 1.90695 -1.91268002 0 P 0 ;0
L 1.90695 -1.91268002 1.90948996 -1.91291998 0 P 0 ;0
L 1.90948996 -1.91291998 1.91181998 -1.91331998 0 P 0 ;0
L 1.91181998 -1.91331998 1.91408996 -1.91393002 0 P 0 ;0
L 1.91408996 -1.91393002 1.91633002 -1.91473002 0 P 0 ;0
L 1.89498002 -1.90801998 1.8922 -1.90893002 0 P 0 ;0
L 1.8922 -1.90893002 1.88948002 -1.91003002 0 P 0 ;0
L 1.88948002 -1.91003002 1.88686004 -1.91133002 0 P 0 ;0
L 1.88686004 -1.91133002 1.88431004 -1.91283996 0 P 0 ;0
L 1.88431004 -1.91283996 1.88201004 -1.91446004 0 P 0 ;0
L 1.88201004 -1.91446004 1.87985 -1.91626998 0 P 0 ;0
L 1.87985 -1.91626998 1.87785 -1.91826004 0 P 0 ;0
L 1.87785 -1.91826004 1.87601998 -1.92041004 0 P 0 ;0
L 1.87601998 -1.92041004 1.87441004 -1.92266998 0 P 0 ;0
L 1.87441004 -1.92266998 1.87298996 -1.92505 0 P 0 ;0
L 1.87298996 -1.92505 1.87178002 -1.92756004 0 P 0 ;0
L 1.87178002 -1.92756004 1.87078996 -1.93015 0 P 0 ;0
L 1.87078996 -1.93015 1.87 -1.93286998 0 P 0 ;0
L 1.87 -1.93286998 1.86943996 -1.93563996 0 P 0 ;0
L 1.86943996 -1.93563996 1.86908996 -1.93845 0 P 0 ;0
L 1.86908996 -1.93845 1.86898002 -1.94128996 0 P 0 ;0
L 1.86898002 -1.94128996 1.86911998 -1.94485 0 P 0 ;0
L 1.86911998 -1.94485 1.86953996 -1.94841004 0 P 0 ;0
L 1.86953996 -1.94841004 1.86996004 -1.95048996 0 P 0 ;0
L 1.86996004 -1.95048996 1.87053002 -1.95251998 0 P 0 ;0
L 1.87053002 -1.95251998 1.87125 -1.95451998 0 P 0 ;0
L 1.87125 -1.95451998 1.87211004 -1.95643002 0 P 0 ;0
L 1.87211004 -1.95643002 1.8731 -1.95826004 0 P 0 ;0
L 1.8731 -1.95826004 1.87423996 -1.96001998 0 P 0 ;0
L 1.87423996 -1.96001998 1.87636998 -1.96278996 0 P 0 ;0
L 1.87636998 -1.96278996 1.87871998 -1.96536998 0 P 0 ;0
L 1.87871998 -1.96536998 1.88145 -1.96788002 0 P 0 ;0
L 1.88145 -1.96788002 1.88436998 -1.97015 0 P 0 ;0
L 1.88436998 -1.97015 1.88621004 -1.97135 0 P 0 ;0
L 1.88621004 -1.97135 1.88813002 -1.97238002 0 P 0 ;0
L 1.88813002 -1.97238002 1.89013002 -1.97326004 0 P 0 ;0
L 1.89013002 -1.97326004 1.89228002 -1.97398996 0 P 0 ;0
L 1.89228002 -1.97398996 1.89446998 -1.97455 0 P 0 ;0
L 1.89446998 -1.97455 1.89671004 -1.97493996 0 P 0 ;0
L 1.89671004 -1.97493996 1.90076998 -1.97533996 0 P 0 ;0
L 1.90076998 -1.97533996 1.90485 -1.97546998 0 P 0 ;0
L 1.90485 -1.97546998 1.90821004 -1.97531998 0 P 0 ;0
L 1.90821004 -1.97531998 1.91153996 -1.97488996 0 P 0 ;0
L 1.91153996 -1.97488996 1.91481998 -1.97418996 0 P 0 ;0
L 1.91481998 -1.97418996 1.9171 -1.9735 0 P 0 ;0
L 1.9171 -1.9735 1.91933002 -1.97266004 0 P 0 ;0
L 1.91933002 -1.97266004 1.92148002 -1.97166004 0 P 0 ;0
L 1.92148002 -1.97166004 1.92356998 -1.97048996 0 P 0 ;0
L 1.92356998 -1.97048996 1.92553996 -1.96918996 0 P 0 ;0
L 1.92553996 -1.96918996 1.92741004 -1.96773996 0 P 0 ;0
L 1.92741004 -1.96773996 1.92916004 -1.96616998 0 P 0 ;0
L 1.92916004 -1.96616998 1.93081004 -1.96446004 0 P 0 ;0
L 1.93081004 -1.96446004 1.93236998 -1.96256998 0 P 0 ;0
L 1.93236998 -1.96256998 1.93381004 -1.96058996 0 P 0 ;0
L 1.93381004 -1.96058996 1.93511998 -1.95851004 0 P 0 ;0
L 1.93511998 -1.95851004 1.93628996 -1.95633996 0 P 0 ;0
L 1.93628996 -1.95633996 1.93803996 -1.95251998 0 P 0 ;0
L 1.93803996 -1.95251998 1.93858002 -1.95101998 0 P 0 ;0
L 1.93858002 -1.95101998 1.93898996 -1.94948002 0 P 0 ;0
L 1.93898996 -1.94948002 1.93928996 -1.94786998 0 P 0 ;0
L 1.93928996 -1.94786998 1.93946004 -1.94625 0 P 0 ;0
L 1.93946004 -1.94625 1.9396 -1.94178002 0 P 0 ;0
L 1.9396 -1.94178002 1.93946004 -1.93803996 0 P 0 ;0
L 1.93946004 -1.93803996 1.93905 -1.9343 0 P 0 ;0
L 1.93905 -1.9343 1.93863996 -1.93213996 0 P 0 ;0
L 1.93863996 -1.93213996 1.93808002 -1.93001998 0 P 0 ;0
L 1.93808002 -1.93001998 1.93736004 -1.92795 0 P 0 ;0
L 1.93736004 -1.92795 1.93653002 -1.92601004 0 P 0 ;0
L 1.93653002 -1.92601004 1.93555 -1.92415 0 P 0 ;0
L 1.93555 -1.92415 1.93441998 -1.92236004 0 P 0 ;0
L 1.93441998 -1.92236004 1.9331 -1.92056004 0 P 0 ;0
L 1.9331 -1.92056004 1.93166998 -1.91885 0 P 0 ;0
L 1.93166998 -1.91885 1.93011998 -1.91723002 0 P 0 ;0
L 1.93011998 -1.91723002 1.92896004 -1.91615 0 P 0 ;0
L 1.92896004 -1.91615 1.92775 -1.91511004 0 P 0 ;0
L 1.92775 -1.91511004 1.92493002 -1.91295 0 P 0 ;0
L 1.92493002 -1.91295 1.9221 -1.91108002 0 P 0 ;0
L 1.9221 -1.91108002 1.92095 -1.91043002 0 P 0 ;0
L 1.92095 -1.91043002 1.91975 -1.90985 0 P 0 ;0
L 1.91975 -1.90985 1.91796004 -1.90913996 0 P 0 ;0
L 1.91796004 -1.90913996 1.91613002 -1.90856004 0 P 0 ;0
L 1.91613002 -1.90856004 1.91423996 -1.9081 0 P 0 ;0
L 1.91423996 -1.9081 1.91086004 -1.90751998 0 P 0 ;0
L 1.91086004 -1.90751998 1.90743002 -1.90716004 0 P 0 ;0
L 1.90743002 -1.90716004 1.90401004 -1.90701004 0 P 0 ;0
L 1.90401004 -1.90701004 1.90058002 -1.90708002 0 P 0 ;0
L 1.90058002 -1.90708002 1.8987 -1.90726004 0 P 0 ;0
L 1.8987 -1.90726004 1.89683002 -1.90756998 0 P 0 ;0
L 1.89683002 -1.90756998 1.89498002 -1.90801998 0 P 0 ;0
L 1.86643002 -2.02923996 1.87525 -2.02923996 0 P 0 ;0
L 1.86176998 -2.02823996 1.87515 -2.02823996 0 P 0 ;0
L 1.85588996 -2.02723996 1.87505 -2.02723996 0 P 0 ;0
L 1.78365 -2.00523996 1.87281004 -2.00523996 0 P 0 ;0
L 1.78451004 -2.00423996 1.87271004 -2.00423996 0 P 0 ;0
L 1.78546998 -2.00323996 1.87261004 -2.00323996 0 P 0 ;0
L 1.78655 -2.00223996 1.8725 -2.00223996 0 P 0 ;0
L 1.78776004 -2.00123996 1.8724 -2.00123996 0 P 0 ;0
L 1.78915 -2.00023996 1.8723 -2.00023996 0 P 0 ;0
L 1.79078996 -1.99923996 1.8722 -1.99923996 0 P 0 ;0
L 1.79263996 -1.99823996 1.87208996 -1.99823996 0 P 0 ;0
L 1.79458996 -1.99723996 1.87198996 -1.99723996 0 P 0 ;0
L 1.79686998 -1.99623996 1.87188002 -1.99623996 0 P 0 ;0
L 1.79946004 -1.99523996 1.87178002 -1.99523996 0 P 0 ;0
L 1.80231004 -1.99423996 1.86961998 -1.99423996 0 P 0 ;0
L 1.80596004 -1.99323996 1.86218002 -1.99323996 0 P 0 ;0
L 1.81051004 -1.99223996 1.85398002 -1.99223996 0 P 0 ;0
L 1.81676004 -1.99123996 1.84395 -1.99123996 0 P 0 ;0
L 1.87786998 -1.96146004 1.88093996 -1.96146004 0 P 0 ;0
L 1.8771 -1.96046004 1.88013002 -1.96046004 0 P 0 ;0
L 1.87633996 -1.95946004 1.87933996 -1.95946004 0 P 0 ;0
L 1.87561998 -1.95846004 1.87866998 -1.95846004 0 P 0 ;0
L 1.87496998 -1.95746004 1.87801998 -1.95746004 0 P 0 ;0
L 1.8744 -1.95646004 1.87745 -1.95646004 0 P 0 ;0
L 1.87386998 -1.95546004 1.87688002 -1.95546004 0 P 0 ;0
L 1.87341998 -1.95446004 1.87641998 -1.95446004 0 P 0 ;0
L 1.87298996 -1.95346004 1.87596004 -1.95346004 0 P 0 ;0
L 1.87263002 -1.95246004 1.87555 -1.95246004 0 P 0 ;0
L 1.87231004 -1.95146004 1.87518996 -1.95146004 0 P 0 ;0
L 1.87203002 -1.95046004 1.87483002 -1.95046004 0 P 0 ;0
L 1.87178996 -1.94946004 1.87456998 -1.94946004 0 P 0 ;0
L 1.87158996 -1.94846004 1.87431004 -1.94846004 0 P 0 ;0
L 1.87143996 -1.94746004 1.87408002 -1.94746004 0 P 0 ;0
L 1.87133002 -1.94646004 1.8739 -1.94646004 0 P 0 ;0
L 1.87121004 -1.94546004 1.87373002 -1.94546004 0 P 0 ;0
L 1.8711 -1.94446998 1.87361998 -1.94446998 0 P 0 ;0
L 1.87106998 -1.94346004 1.87353996 -1.94346004 0 P 0 ;0
L 1.87103002 -1.94246004 1.87346004 -1.94246004 0 P 0 ;0
L 1.87098996 -1.94146998 1.87346004 -1.94146998 0 P 0 ;0
L 1.87101004 -1.94046004 1.87346004 -1.94046004 0 P 0 ;0
L 1.87106004 -1.93946004 1.87348996 -1.93946004 0 P 0 ;0
L 1.87111004 -1.93846004 1.87358002 -1.93846004 0 P 0 ;0
L 1.87123002 -1.93746004 1.87366004 -1.93746004 0 P 0 ;0
L 1.87135 -1.93646004 1.87381998 -1.93646004 0 P 0 ;0
L 1.87151004 -1.93546004 1.87398996 -1.93546004 0 P 0 ;0
L 1.87171998 -1.93446004 1.87416998 -1.93446004 0 P 0 ;0
L 1.87191998 -1.93346004 1.87443002 -1.93346004 0 P 0 ;0
L 1.8722 -1.93246004 1.87468996 -1.93246004 0 P 0 ;0
L 1.87248996 -1.93146004 1.875 -1.93146004 0 P 0 ;0
L 1.87281004 -1.93046004 1.87535 -1.93046004 0 P 0 ;0
L 1.87318996 -1.92946004 1.87571004 -1.92946004 0 P 0 ;0
L 1.87356998 -1.92846004 1.87616004 -1.92846004 0 P 0 ;0
L 1.87405 -1.92746004 1.87661004 -1.92746004 0 P 0 ;0
L 1.87453002 -1.92646004 1.87711998 -1.92646004 0 P 0 ;0
L 1.87506998 -1.92546004 1.87768996 -1.92546004 0 P 0 ;0
L 1.87566004 -1.92446998 1.87826998 -1.92446998 0 P 0 ;0
L 1.87628996 -1.92346004 1.87896004 -1.92346004 0 P 0 ;0
L 1.87701004 -1.92246004 1.87963996 -1.92246004 0 P 0 ;0
L 1.87775 -1.92146004 1.88046004 -1.92146004 0 P 0 ;0
L 1.90483996 -1.97346004 1.9009 -1.97333996 0 P 0 ;0
L 1.9009 -1.97333996 1.89698002 -1.97295 0 P 0 ;0
L 1.89698002 -1.97295 1.89488996 -1.97258996 0 P 0 ;0
L 1.89488996 -1.97258996 1.89285 -1.97206998 0 P 0 ;0
L 1.89285 -1.97206998 1.89086004 -1.97138996 0 P 0 ;0
L 1.89086004 -1.97138996 1.889 -1.97058002 0 P 0 ;0
L 1.889 -1.97058002 1.88723002 -1.96961998 0 P 0 ;0
L 1.88723002 -1.96961998 1.88553002 -1.96851998 0 P 0 ;0
L 1.88553002 -1.96851998 1.88273996 -1.96636004 0 P 0 ;0
L 1.88273996 -1.96636004 1.88013996 -1.96396004 0 P 0 ;0
L 1.88013996 -1.96396004 1.8779 -1.9615 0 P 0 ;0
L 1.8779 -1.9615 1.87588002 -1.95886998 0 P 0 ;0
L 1.87588002 -1.95886998 1.87483002 -1.95723996 0 P 0 ;0
L 1.87483002 -1.95723996 1.8739 -1.95553996 0 P 0 ;0
L 1.8739 -1.95553996 1.87311004 -1.95376998 0 P 0 ;0
L 1.87311004 -1.95376998 1.87243002 -1.95191004 0 P 0 ;0
L 1.87243002 -1.95191004 1.8719 -1.95001998 0 P 0 ;0
L 1.8719 -1.95001998 1.87151998 -1.9481 0 P 0 ;0
L 1.87151998 -1.9481 1.87111004 -1.94468996 0 P 0 ;0
L 1.87111004 -1.94468996 1.87098002 -1.94128996 0 P 0 ;0
L 1.87098002 -1.94128996 1.87108996 -1.93861004 0 P 0 ;0
L 1.87108996 -1.93861004 1.87141004 -1.93596998 0 P 0 ;0
L 1.87141004 -1.93596998 1.87195 -1.93335 0 P 0 ;0
L 1.87195 -1.93335 1.87268996 -1.93078996 0 P 0 ;0
L 1.87268996 -1.93078996 1.87361998 -1.92835 0 P 0 ;0
L 1.87361998 -1.92835 1.87475 -1.926 0 P 0 ;0
L 1.87475 -1.926 1.87608996 -1.92376004 0 P 0 ;0
L 1.87608996 -1.92376004 1.8776 -1.92163996 0 P 0 ;0
L 1.8776 -1.92163996 1.87931998 -1.91961998 0 P 0 ;0
L 1.87931998 -1.91961998 1.8812 -1.91775 0 P 0 ;0
L 1.8812 -1.91775 1.88323002 -1.91605 0 P 0 ;0
L 1.88323002 -1.91605 1.8854 -1.91451998 0 P 0 ;0
L 1.8854 -1.91451998 1.88781004 -1.91308996 0 P 0 ;0
L 1.88781004 -1.91308996 1.89031004 -1.91186004 0 P 0 ;0
L 1.89031004 -1.91186004 1.89288002 -1.9108 0 P 0 ;0
L 1.89288002 -1.9108 1.89553002 -1.90995 0 P 0 ;0
L 1.89553002 -1.90995 1.89723002 -1.90953002 0 P 0 ;0
L 1.89723002 -1.90953002 1.89896004 -1.90923996 0 P 0 ;0
L 1.89896004 -1.90923996 1.90068996 -1.90908002 0 P 0 ;0
L 1.90068996 -1.90908002 1.90398996 -1.90901004 0 P 0 ;0
L 1.90398996 -1.90901004 1.90728002 -1.90915 0 P 0 ;0
L 1.90728002 -1.90915 1.91058996 -1.90951004 0 P 0 ;0
L 1.91058996 -1.90951004 1.91383996 -1.91006004 0 P 0 ;0
L 1.91383996 -1.91006004 1.91558996 -1.91048996 0 P 0 ;0
L 1.91558996 -1.91048996 1.91728996 -1.91101998 0 P 0 ;0
L 1.91728996 -1.91101998 1.91895 -1.91168002 0 P 0 ;0
L 1.91895 -1.91168002 1.92001998 -1.9122 0 P 0 ;0
L 1.92001998 -1.9122 1.92105 -1.91278996 0 P 0 ;0
L 1.92105 -1.91278996 1.92376998 -1.91458002 0 P 0 ;0
L 1.92376998 -1.91458002 1.92648996 -1.91666998 0 P 0 ;0
L 1.92648996 -1.91666998 1.92763002 -1.91763996 0 P 0 ;0
L 1.92763002 -1.91763996 1.92871004 -1.91865 0 P 0 ;0
L 1.92871004 -1.91865 1.93018002 -1.92018996 0 P 0 ;0
L 1.93018002 -1.92018996 1.93153002 -1.9218 0 P 0 ;0
L 1.93153002 -1.9218 1.93276998 -1.92348996 0 P 0 ;0
L 1.93276998 -1.92348996 1.93381004 -1.92515 0 P 0 ;0
L 1.93381004 -1.92515 1.93471998 -1.92686998 0 P 0 ;0
L 1.93471998 -1.92686998 1.9355 -1.92866998 0 P 0 ;0
L 1.9355 -1.92866998 1.93616998 -1.93061004 0 P 0 ;0
L 1.93616998 -1.93061004 1.93668996 -1.93258002 0 P 0 ;0
L 1.93668996 -1.93258002 1.93706998 -1.93458996 0 P 0 ;0
L 1.93706998 -1.93458996 1.93746998 -1.93818996 0 P 0 ;0
L 1.93746998 -1.93818996 1.9376 -1.94178996 0 P 0 ;0
L 1.9376 -1.94178996 1.93746004 -1.94611004 0 P 0 ;0
L 1.93746004 -1.94611004 1.93731004 -1.94758996 0 P 0 ;0
L 1.93731004 -1.94758996 1.93705 -1.94903996 0 P 0 ;0
L 1.93705 -1.94903996 1.93666998 -1.95041998 0 P 0 ;0
L 1.93666998 -1.95041998 1.93618002 -1.95176004 0 P 0 ;0
L 1.93618002 -1.95176004 1.9345 -1.95545 0 P 0 ;0
L 1.9345 -1.95545 1.93338996 -1.9575 0 P 0 ;0
L 1.93338996 -1.9575 1.93216004 -1.95946998 0 P 0 ;0
L 1.93216004 -1.95946998 1.93078996 -1.96133996 0 P 0 ;0
L 1.93078996 -1.96133996 1.92931004 -1.96311998 0 P 0 ;0
L 1.92931004 -1.96311998 1.92776998 -1.96473002 0 P 0 ;0
L 1.92776998 -1.96473002 1.92613002 -1.96621004 0 P 0 ;0
L 1.92613002 -1.96621004 1.92438002 -1.96756004 0 P 0 ;0
L 1.92438002 -1.96756004 1.92253002 -1.96878002 0 P 0 ;0
L 1.92253002 -1.96878002 1.92056998 -1.96986998 0 P 0 ;0
L 1.92056998 -1.96986998 1.91855 -1.97081998 0 P 0 ;0
L 1.91855 -1.97081998 1.91646004 -1.97161004 0 P 0 ;0
L 1.91646004 -1.97161004 1.91433002 -1.97223996 0 P 0 ;0
L 1.91433002 -1.97223996 1.9112 -1.97291004 0 P 0 ;0
L 1.9112 -1.97291004 1.90803996 -1.97331998 0 P 0 ;0
L 1.90803996 -1.97331998 1.90483996 -1.97346004 0 P 0 ;0
L 1.90476004 -1.97173996 1.9048 -1.97173996 0 P 0 ;0
L 1.9048 -1.97173996 1.90483996 -1.97173002 0 P 0 ;0
L 1.90483996 -1.97173002 1.90736004 -1.9716 0 P 0 ;0
L 1.90736004 -1.9716 1.9074 -1.97158996 0 P 0 ;0
L 1.9074 -1.97158996 1.90746998 -1.97158996 0 P 0 ;0
L 1.90746998 -1.97158996 1.90751004 -1.97158002 0 P 0 ;0
L 1.90751004 -1.97158002 1.91001004 -1.97126004 0 P 0 ;0
L 1.91001004 -1.97126004 1.91005 -1.97125 0 P 0 ;0
L 1.91005 -1.97125 1.91008002 -1.97123996 0 P 0 ;0
L 1.91008002 -1.97123996 1.91011998 -1.97123996 0 P 0 ;0
L 1.91011998 -1.97123996 1.91016004 -1.97123002 0 P 0 ;0
L 1.91016004 -1.97123002 1.9126 -1.97071998 0 P 0 ;0
L 1.9126 -1.97071998 1.9126 -1.97071004 0 P 0 ;0
L 1.9126 -1.97071004 1.91266998 -1.97071004 0 P 0 ;0
L 1.91266998 -1.97071004 1.91271004 -1.97068996 0 P 0 ;0
L 1.91271004 -1.97068996 1.91275 -1.97068002 0 P 0 ;0
L 1.91275 -1.97068002 1.91511998 -1.96998996 0 P 0 ;0
L 1.91511998 -1.96998996 1.91515 -1.96998996 0 P 0 ;0
L 1.91515 -1.96998996 1.91518996 -1.96996998 0 P 0 ;0
L 1.91518996 -1.96996998 1.91523002 -1.96996004 0 P 0 ;0
L 1.91523002 -1.96996004 1.91526004 -1.96995 0 P 0 ;0
L 1.91526004 -1.96995 1.91756998 -1.96908002 0 P 0 ;0
L 1.91756998 -1.96908002 1.91761004 -1.96906998 0 P 0 ;0
L 1.91761004 -1.96906998 1.91768002 -1.96903996 0 P 0 ;0
L 1.91768002 -1.96903996 1.91771004 -1.96901998 0 P 0 ;0
L 1.91771004 -1.96901998 1.91995 -1.96798002 0 P 0 ;0
L 1.91995 -1.96798002 1.92001998 -1.96795 0 P 0 ;0
L 1.92001998 -1.96795 1.92005 -1.96793002 0 P 0 ;0
L 1.92005 -1.96793002 1.92008996 -1.96791004 0 P 0 ;0
L 1.92008996 -1.96791004 1.92168002 -1.96701998 0 P 0 ;0
L 1.92168002 -1.96701998 1.92171998 -1.967 0 P 0 ;0
L 1.92171998 -1.967 1.92175 -1.96698002 0 P 0 ;0
L 1.92175 -1.96698002 1.92178996 -1.96695 0 P 0 ;0
L 1.92178996 -1.96695 1.92181998 -1.96693002 0 P 0 ;0
L 1.92181998 -1.96693002 1.92331998 -1.96591998 0 P 0 ;0
L 1.92331998 -1.96591998 1.92336004 -1.9659 0 P 0 ;0
L 1.92336004 -1.9659 1.92341998 -1.96586004 0 P 0 ;0
L 1.92341998 -1.96586004 1.92345 -1.96583002 0 P 0 ;0
L 1.92345 -1.96583002 1.92486004 -1.9647 0 P 0 ;0
L 1.92486004 -1.9647 1.92493002 -1.96465 0 P 0 ;0
L 1.92493002 -1.96465 1.92496004 -1.96463002 0 P 0 ;0
L 1.92496004 -1.96463002 1.92498996 -1.9646 0 P 0 ;0
L 1.92498996 -1.9646 1.92631004 -1.96336998 0 P 0 ;0
L 1.92631004 -1.96336998 1.9264 -1.96328002 0 P 0 ;0
L 1.9264 -1.96328002 1.92641998 -1.96325 0 P 0 ;0
L 1.92641998 -1.96325 1.92763996 -1.96191998 0 P 0 ;0
L 1.92763996 -1.96191998 1.92766998 -1.96188996 0 P 0 ;0
L 1.92766998 -1.96188996 1.92768996 -1.96186004 0 P 0 ;0
L 1.92768996 -1.96186004 1.92771998 -1.96183002 0 P 0 ;0
L 1.92771998 -1.96183002 1.92773996 -1.9618 0 P 0 ;0
L 1.92773996 -1.9618 1.92913996 -1.96001004 0 P 0 ;0
L 1.92913996 -1.96001004 1.92918996 -1.95995 0 P 0 ;0
L 1.92918996 -1.95995 1.92921004 -1.95991004 0 P 0 ;0
L 1.92921004 -1.95991004 1.92923002 -1.95988002 0 P 0 ;0
L 1.92923002 -1.95988002 1.93048002 -1.95798996 0 P 0 ;0
L 1.93048002 -1.95798996 1.93051998 -1.95793002 0 P 0 ;0
L 1.93051998 -1.95793002 1.93053996 -1.95788996 0 P 0 ;0
L 1.93053996 -1.95788996 1.93056004 -1.95786004 0 P 0 ;0
L 1.93056004 -1.95786004 1.93166004 -1.95588002 0 P 0 ;0
L 1.93166004 -1.95588002 1.93171004 -1.95576998 0 P 0 ;0
L 1.93171004 -1.95576998 1.93173002 -1.95573996 0 P 0 ;0
L 1.93173002 -1.95573996 1.93266998 -1.95366998 0 P 0 ;0
L 1.93266998 -1.95366998 1.93271004 -1.95356998 0 P 0 ;0
L 1.93271004 -1.95356998 1.93273002 -1.95353002 0 P 0 ;0
L 1.93273002 -1.95353002 1.9335 -1.9514 0 P 0 ;0
L 1.9335 -1.9514 1.93351004 -1.95136998 0 P 0 ;0
L 1.93351004 -1.95136998 1.93353002 -1.95133002 0 P 0 ;0
L 1.93353002 -1.95133002 1.93355 -1.95125 0 P 0 ;0
L 1.93355 -1.95125 1.93416004 -1.94906998 0 P 0 ;0
L 1.93416004 -1.94906998 1.93416998 -1.94903002 0 P 0 ;0
L 1.93416998 -1.94903002 1.93418002 -1.949 0 P 0 ;0
L 1.93418002 -1.949 1.93418002 -1.94896004 0 P 0 ;0
L 1.93418002 -1.94896004 1.93418996 -1.94891998 0 P 0 ;0
L 1.93418996 -1.94891998 1.93463996 -1.94665 0 P 0 ;0
L 1.93463996 -1.94665 1.93463996 -1.94661004 0 P 0 ;0
L 1.93463996 -1.94661004 1.93465 -1.94656998 0 P 0 ;0
L 1.93465 -1.94656998 1.93466004 -1.9465 0 P 0 ;0
L 1.93466004 -1.9465 1.93493996 -1.9442 0 P 0 ;0
L 1.93493996 -1.9442 1.93493996 -1.94413002 0 P 0 ;0
L 1.93493996 -1.94413002 1.93495 -1.94408996 0 P 0 ;0
L 1.93495 -1.94408996 1.93495 -1.94406004 0 P 0 ;0
L 1.93495 -1.94406004 1.93505 -1.94173996 0 P 0 ;0
L 1.93505 -1.94173996 1.93506004 -1.94171004 0 P 0 ;0
L 1.93506004 -1.94171004 1.93506004 -1.9416 0 P 0 ;0
L 1.93506004 -1.9416 1.93498996 -1.93928996 0 P 0 ;0
L 1.93498996 -1.93928996 1.93498996 -1.93921004 0 P 0 ;0
L 1.93498996 -1.93921004 1.93498002 -1.93913996 0 P 0 ;0
L 1.93498002 -1.93913996 1.93475 -1.93683996 0 P 0 ;0
L 1.93475 -1.93683996 1.93473996 -1.93676998 0 P 0 ;0
L 1.93473996 -1.93676998 1.93473002 -1.93673002 0 P 0 ;0
L 1.93473002 -1.93673002 1.93473002 -1.93668996 0 P 0 ;0
L 1.93473002 -1.93668996 1.93433002 -1.93441004 0 P 0 ;0
L 1.93433002 -1.93441004 1.93431998 -1.93436998 0 P 0 ;0
L 1.93431998 -1.93436998 1.93431004 -1.93433996 0 P 0 ;0
L 1.93431004 -1.93433996 1.93428996 -1.93426004 0 P 0 ;0
L 1.93428996 -1.93426004 1.93373002 -1.93206004 0 P 0 ;0
L 1.93373002 -1.93206004 1.93368996 -1.93191998 0 P 0 ;0
L 1.93368996 -1.93191998 1.93296004 -1.92976998 0 P 0 ;0
L 1.93296004 -1.92976998 1.93293996 -1.9297 0 P 0 ;0
L 1.93293996 -1.9297 1.93291004 -1.92963002 0 P 0 ;0
L 1.93291004 -1.92963002 1.93201998 -1.92753996 0 P 0 ;0
L 1.93201998 -1.92753996 1.93196998 -1.92743002 0 P 0 ;0
L 1.93196998 -1.92743002 1.93196004 -1.9274 0 P 0 ;0
L 1.93196004 -1.9274 1.93091998 -1.92538996 0 P 0 ;0
L 1.93091998 -1.92538996 1.9309 -1.92536004 0 P 0 ;0
L 1.9309 -1.92536004 1.93088002 -1.92531998 0 P 0 ;0
L 1.93088002 -1.92531998 1.93086004 -1.92528996 0 P 0 ;0
L 1.93086004 -1.92528996 1.93083996 -1.92525 0 P 0 ;0
L 1.93083996 -1.92525 1.92965 -1.92331998 0 P 0 ;0
L 1.92965 -1.92331998 1.92956998 -1.9232 0 P 0 ;0
L 1.92956998 -1.9232 1.92823002 -1.92136004 0 P 0 ;0
L 1.92823002 -1.92136004 1.92818002 -1.9213 0 P 0 ;0
L 1.92818002 -1.9213 1.92816004 -1.92126998 0 P 0 ;0
L 1.92816004 -1.92126998 1.92813002 -1.92123996 0 P 0 ;0
L 1.92813002 -1.92123996 1.92671998 -1.91958002 0 P 0 ;0
L 1.92671998 -1.91958002 1.9266 -1.91946004 0 P 0 ;0
L 1.9266 -1.91946004 1.92505 -1.91793002 0 P 0 ;0
L 1.92505 -1.91793002 1.92498996 -1.91786998 0 P 0 ;0
L 1.92498996 -1.91786998 1.92493002 -1.91781998 0 P 0 ;0
L 1.92493002 -1.91781998 1.92325 -1.91643002 0 P 0 ;0
L 1.92325 -1.91643002 1.92318996 -1.91636998 0 P 0 ;0
L 1.92318996 -1.91636998 1.92311998 -1.91631998 0 P 0 ;0
L 1.92311998 -1.91631998 1.92133002 -1.91508002 0 P 0 ;0
L 1.92133002 -1.91508002 1.92126004 -1.91503996 0 P 0 ;0
L 1.92126004 -1.91503996 1.92121998 -1.91501004 0 P 0 ;0
L 1.92121998 -1.91501004 1.92118002 -1.91498996 0 P 0 ;0
L 1.92118002 -1.91498996 1.91928996 -1.91391004 0 P 0 ;0
L 1.91928996 -1.91391004 1.91926004 -1.91388996 0 P 0 ;0
L 1.91926004 -1.91388996 1.91913996 -1.91383002 0 P 0 ;0
L 1.91913996 -1.91383002 1.91716998 -1.91291004 0 P 0 ;0
L 1.91716998 -1.91291004 1.91711998 -1.91288996 0 P 0 ;0
L 1.91711998 -1.91288996 1.91705 -1.91286004 0 P 0 ;0
L 1.91705 -1.91286004 1.917 -1.91285 0 P 0 ;0
L 1.917 -1.91285 1.91476998 -1.91203996 0 P 0 ;0
L 1.91476998 -1.91203996 1.91468996 -1.91201998 0 P 0 ;0
L 1.91468996 -1.91201998 1.91465 -1.912 0 P 0 ;0
L 1.91465 -1.912 1.9146 -1.91198996 0 P 0 ;0
L 1.9146 -1.91198996 1.91233002 -1.91138996 0 P 0 ;0
L 1.91233002 -1.91138996 1.91228002 -1.91138002 0 P 0 ;0
L 1.91228002 -1.91138002 1.91223996 -1.91136998 0 P 0 ;0
L 1.91223996 -1.91136998 1.91216004 -1.91136004 0 P 0 ;0
L 1.91216004 -1.91136004 1.90983002 -1.91095 0 P 0 ;0
L 1.90983002 -1.91095 1.9098 -1.91093996 0 P 0 ;0
L 1.9098 -1.91093996 1.90976004 -1.91093996 0 P 0 ;0
L 1.90976004 -1.91093996 1.90971998 -1.91093002 0 P 0 ;0
L 1.90971998 -1.91093002 1.90968002 -1.91093002 0 P 0 ;0
L 1.90968002 -1.91093002 1.90713996 -1.91068996 0 P 0 ;0
L 1.90713996 -1.91068996 1.9071 -1.91068002 0 P 0 ;0
L 1.9071 -1.91068002 1.907 -1.91068002 0 P 0 ;0
L 1.907 -1.91068002 1.90445 -1.91061004 0 P 0 ;0
L 1.90445 -1.91061004 1.90431004 -1.91061004 0 P 0 ;0
L 1.90431004 -1.91061004 1.90176004 -1.91071004 0 P 0 ;0
L 1.90176004 -1.91071004 1.90173002 -1.91071998 0 P 0 ;0
L 1.90173002 -1.91071998 1.90166004 -1.91071998 0 P 0 ;0
L 1.90166004 -1.91071998 1.90161998 -1.91073002 0 P 0 ;0
L 1.90161998 -1.91073002 1.89913002 -1.911 0 P 0 ;0
L 1.89913002 -1.911 1.89906004 -1.91101004 0 P 0 ;0
L 1.89906004 -1.91101004 1.89901998 -1.91101998 0 P 0 ;0
L 1.89901998 -1.91101998 1.89898996 -1.91101998 0 P 0 ;0
L 1.89898996 -1.91101998 1.89653002 -1.91146998 0 P 0 ;0
L 1.89653002 -1.91146998 1.8965 -1.91148002 0 P 0 ;0
L 1.8965 -1.91148002 1.89646004 -1.91148002 0 P 0 ;0
L 1.89646004 -1.91148002 1.8964 -1.9115 0 P 0 ;0
L 1.8964 -1.9115 1.89396998 -1.91211998 0 P 0 ;0
L 1.89396998 -1.91211998 1.89393996 -1.91213002 0 P 0 ;0
L 1.89393996 -1.91213002 1.89383002 -1.91216004 0 P 0 ;0
L 1.89383002 -1.91216004 1.89225 -1.91268996 0 P 0 ;0
L 1.89225 -1.91268996 1.89218002 -1.91271998 0 P 0 ;0
L 1.89218002 -1.91271998 1.89211004 -1.91273996 0 P 0 ;0
L 1.89211004 -1.91273996 1.8921 -1.91273996 0 P 0 ;0
L 1.8921 -1.91273996 1.89058002 -1.91338996 0 P 0 ;0
L 1.89058002 -1.91338996 1.89043996 -1.91345 0 P 0 ;0
L 1.89043996 -1.91345 1.88896004 -1.91421004 0 P 0 ;0
L 1.88896004 -1.91421004 1.88893002 -1.91423002 0 P 0 ;0
L 1.88893002 -1.91423002 1.8889 -1.91423996 0 P 0 ;0
L 1.8889 -1.91423996 1.88886004 -1.91426004 0 P 0 ;0
L 1.88886004 -1.91426004 1.88883002 -1.91428002 0 P 0 ;0
L 1.88883002 -1.91428002 1.88741004 -1.91515 0 P 0 ;0
L 1.88741004 -1.91515 1.88733996 -1.91518996 0 P 0 ;0
L 1.88733996 -1.91518996 1.88728002 -1.91523996 0 P 0 ;0
L 1.88728002 -1.91523996 1.88526004 -1.9167 0 P 0 ;0
L 1.88526004 -1.9167 1.88521998 -1.91673002 0 P 0 ;0
L 1.88521998 -1.91673002 1.88518996 -1.91675 0 P 0 ;0
L 1.88518996 -1.91675 1.88516004 -1.91678002 0 P 0 ;0
L 1.88516004 -1.91678002 1.88511998 -1.91681004 0 P 0 ;0
L 1.88511998 -1.91681004 1.88323002 -1.91845 0 P 0 ;0
L 1.88323002 -1.91845 1.8832 -1.91846998 0 P 0 ;0
L 1.8832 -1.91846998 1.88311004 -1.91856004 0 P 0 ;0
L 1.88311004 -1.91856004 1.88136998 -1.92036004 0 P 0 ;0
L 1.88136998 -1.92036004 1.88128002 -1.92045 0 P 0 ;0
L 1.88128002 -1.92045 1.88125 -1.92048996 0 P 0 ;0
L 1.88125 -1.92048996 1.87968002 -1.92241998 0 P 0 ;0
L 1.87968002 -1.92241998 1.87965 -1.92245 0 P 0 ;0
L 1.87965 -1.92245 1.87961998 -1.92248996 0 P 0 ;0
L 1.87961998 -1.92248996 1.87956998 -1.92256004 0 P 0 ;0
L 1.87956998 -1.92256004 1.87816998 -1.92461998 0 P 0 ;0
L 1.87816998 -1.92461998 1.8781 -1.92473002 0 P 0 ;0
L 1.8781 -1.92473002 1.87808002 -1.92476998 0 P 0 ;0
L 1.87808002 -1.92476998 1.87685 -1.92695 0 P 0 ;0
L 1.87685 -1.92695 1.87683002 -1.92698996 0 P 0 ;0
L 1.87683002 -1.92698996 1.87681004 -1.92701998 0 P 0 ;0
L 1.87681004 -1.92701998 1.87678996 -1.92706998 0 P 0 ;0
L 1.87678996 -1.92706998 1.87676998 -1.92711004 0 P 0 ;0
L 1.87676998 -1.92711004 1.87573002 -1.92941004 0 P 0 ;0
L 1.87573002 -1.92941004 1.87571004 -1.92945 0 P 0 ;0
L 1.87571004 -1.92945 1.8757 -1.92948996 0 P 0 ;0
L 1.8757 -1.92948996 1.87568002 -1.92951998 0 P 0 ;0
L 1.87568002 -1.92951998 1.87566998 -1.92956998 0 P 0 ;0
L 1.87566998 -1.92956998 1.87483996 -1.93193002 0 P 0 ;0
L 1.87483996 -1.93193002 1.87481004 -1.93201004 0 P 0 ;0
L 1.87481004 -1.93201004 1.87478996 -1.93208996 0 P 0 ;0
L 1.87478996 -1.93208996 1.87416004 -1.93451998 0 P 0 ;0
L 1.87416004 -1.93451998 1.87413996 -1.93456004 0 P 0 ;0
L 1.87413996 -1.93456004 1.87413002 -1.9346 0 P 0 ;0
L 1.87413002 -1.9346 1.87413002 -1.93463996 0 P 0 ;0
L 1.87413002 -1.93463996 1.87411998 -1.93468002 0 P 0 ;0
L 1.87411998 -1.93468002 1.8737 -1.93715 0 P 0 ;0
L 1.8737 -1.93715 1.87368996 -1.93718996 0 P 0 ;0
L 1.87368996 -1.93718996 1.87368002 -1.93723996 0 P 0 ;0
L 1.87368002 -1.93723996 1.87368002 -1.93731998 0 P 0 ;0
L 1.87368002 -1.93731998 1.87346998 -1.93981998 0 P 0 ;0
L 1.87346998 -1.93981998 1.87346004 -1.93986004 0 P 0 ;0
L 1.87346004 -1.93986004 1.87346004 -1.94258002 0 P 0 ;0
L 1.87346004 -1.94258002 1.87346998 -1.94266004 0 P 0 ;0
L 1.87346998 -1.94266004 1.87368002 -1.94516998 0 P 0 ;0
L 1.87368002 -1.94516998 1.87368996 -1.94521004 0 P 0 ;0
L 1.87368996 -1.94521004 1.87368996 -1.94525 0 P 0 ;0
L 1.87368996 -1.94525 1.87371004 -1.94533996 0 P 0 ;0
L 1.87371004 -1.94533996 1.87413996 -1.94778996 0 P 0 ;0
L 1.87413996 -1.94778996 1.87413996 -1.94783996 0 P 0 ;0
L 1.87413996 -1.94783996 1.87416998 -1.94796004 0 P 0 ;0
L 1.87416998 -1.94796004 1.87481004 -1.95036998 0 P 0 ;0
L 1.87481004 -1.95036998 1.87483996 -1.95048996 0 P 0 ;0
L 1.87483996 -1.95048996 1.87486004 -1.95053002 0 P 0 ;0
L 1.87486004 -1.95053002 1.8757 -1.95288002 0 P 0 ;0
L 1.8757 -1.95288002 1.87571004 -1.95291998 0 P 0 ;0
L 1.87571004 -1.95291998 1.87575 -1.953 0 P 0 ;0
L 1.87575 -1.953 1.87576004 -1.95303996 0 P 0 ;0
L 1.87576004 -1.95303996 1.8768 -1.9553 0 P 0 ;0
L 1.8768 -1.9553 1.87686004 -1.95541998 0 P 0 ;0
L 1.87686004 -1.95541998 1.87688002 -1.95545 0 P 0 ;0
L 1.87688002 -1.95545 1.8781 -1.95761004 0 P 0 ;0
L 1.8781 -1.95761004 1.87811998 -1.95761004 0 P 0 ;0
L 1.87811998 -1.95761004 1.8781 -1.95761998 0 P 0 ;0
L 1.8781 -1.95761998 1.87813996 -1.95768996 0 P 0 ;0
L 1.87813996 -1.95768996 1.87816998 -1.95771998 0 P 0 ;0
L 1.87816998 -1.95771998 1.87818996 -1.95775 0 P 0 ;0
L 1.87818996 -1.95775 1.87938002 -1.95951004 0 P 0 ;0
L 1.87938002 -1.95951004 1.87943996 -1.9596 0 P 0 ;0
L 1.87943996 -1.9596 1.87946998 -1.95963002 0 P 0 ;0
L 1.87946998 -1.95963002 1.88078002 -1.96128996 0 P 0 ;0
L 1.88078002 -1.96128996 1.88081004 -1.96131998 0 P 0 ;0
L 1.88081004 -1.96131998 1.88083002 -1.96135 0 P 0 ;0
L 1.88083002 -1.96135 1.88086004 -1.96136998 0 P 0 ;0
L 1.88086004 -1.96136998 1.88088002 -1.9614 0 P 0 ;0
L 1.88088002 -1.9614 1.88231998 -1.96295 0 P 0 ;0
L 1.88231998 -1.96295 1.88233996 -1.96298002 0 P 0 ;0
L 1.88233996 -1.96298002 1.8824 -1.96303996 0 P 0 ;0
L 1.8824 -1.96303996 1.88243002 -1.96306004 0 P 0 ;0
L 1.88243002 -1.96306004 1.88398002 -1.9645 0 P 0 ;0
L 1.88398002 -1.9645 1.88401004 -1.96451998 0 P 0 ;0
L 1.88401004 -1.96451998 1.88403002 -1.96455 0 P 0 ;0
L 1.88403002 -1.96455 1.88406998 -1.96458002 0 P 0 ;0
L 1.88406998 -1.96458002 1.88408996 -1.9646 0 P 0 ;0
L 1.88408996 -1.9646 1.88575 -1.96591004 0 P 0 ;0
L 1.88575 -1.96591004 1.88578002 -1.96593996 0 P 0 ;0
L 1.88578002 -1.96593996 1.88586998 -1.966 0 P 0 ;0
L 1.88586998 -1.966 1.88761998 -1.96718996 0 P 0 ;0
L 1.88761998 -1.96718996 1.88766004 -1.96721004 0 P 0 ;0
L 1.88766004 -1.96721004 1.88775 -1.96726998 0 P 0 ;0
L 1.88775 -1.96726998 1.88958996 -1.96831998 0 P 0 ;0
L 1.88958996 -1.96831998 1.88965 -1.96836004 0 P 0 ;0
L 1.88965 -1.96836004 1.88968002 -1.96836998 0 P 0 ;0
L 1.88968002 -1.96836998 1.88971998 -1.96838996 0 P 0 ;0
L 1.88971998 -1.96838996 1.89145 -1.96921998 0 P 0 ;0
L 1.89145 -1.96921998 1.89151004 -1.96925 0 P 0 ;0
L 1.89151004 -1.96925 1.89155 -1.96926004 0 P 0 ;0
L 1.89155 -1.96926004 1.89158002 -1.96926998 0 P 0 ;0
L 1.89158002 -1.96926998 1.89336004 -1.96996998 0 P 0 ;0
L 1.89336004 -1.96996998 1.89336004 -1.96998002 0 P 0 ;0
L 1.89336004 -1.96998002 1.89346004 -1.97001004 0 P 0 ;0
L 1.89346004 -1.97001004 1.89348996 -1.97001998 0 P 0 ;0
L 1.89348996 -1.97001998 1.89531998 -1.9706 0 P 0 ;0
L 1.89531998 -1.9706 1.89536004 -1.97061004 0 P 0 ;0
L 1.89536004 -1.97061004 1.89541998 -1.97063002 0 P 0 ;0
L 1.89541998 -1.97063002 1.89546004 -1.97063002 0 P 0 ;0
L 1.89546004 -1.97063002 1.89731998 -1.97108002 0 P 0 ;0
L 1.89731998 -1.97108002 1.89741998 -1.9711 0 P 0 ;0
L 1.89741998 -1.9711 1.89746004 -1.9711 0 P 0 ;0
L 1.89746004 -1.9711 1.89746004 -1.97111004 0 P 0 ;0
L 1.89746004 -1.97111004 1.89933996 -1.97141998 0 P 0 ;0
L 1.89933996 -1.97141998 1.89936998 -1.97143002 0 P 0 ;0
L 1.89936998 -1.97143002 1.89941004 -1.97143002 0 P 0 ;0
L 1.89941004 -1.97143002 1.89945 -1.97143996 0 P 0 ;0
L 1.89945 -1.97143996 1.89948002 -1.97143996 0 P 0 ;0
L 1.89948002 -1.97143996 1.90201004 -1.97168002 0 P 0 ;0
L 1.90201004 -1.97168002 1.90205 -1.97168002 0 P 0 ;0
L 1.90205 -1.97168002 1.90208996 -1.97168996 0 P 0 ;0
L 1.90208996 -1.97168996 1.90216004 -1.97168996 0 P 0 ;0
L 1.90216004 -1.97168996 1.90468996 -1.97173996 0 P 0 ;0
L 1.90468996 -1.97173996 1.90476004 -1.97173996 0 P 0 ;0
L 1.80616004 -2.12823996 1.83348996 -2.12823996 0 P 0 ;0
L 1.79591998 -2.12723996 1.8396 -2.12723996 0 P 0 ;0
L 1.78818002 -2.12623996 1.84465 -2.12623996 0 P 0 ;0
L 1.82003996 -2.09123996 1.87618996 -2.09123996 0 P 0 ;0
L 1.82198996 -2.09023996 1.8762 -2.09023996 0 P 0 ;0
L 1.82325 -2.08923996 1.8762 -2.08923996 0 P 0 ;0
L 1.82411998 -2.08823996 1.87618996 -2.08823996 0 P 0 ;0
L 1.82463002 -2.08723996 1.87616998 -2.08723996 0 P 0 ;0
L 1.82488002 -2.08623996 1.87615 -2.08623996 0 P 0 ;0
L 1.82493002 -2.08523996 1.87613002 -2.08523996 0 P 0 ;0
L 1.82476998 -2.08423996 1.87611004 -2.08423996 0 P 0 ;0
L 1.64846004 -2.08295 1.73316998 -2.08295 0 P 0 ;0
L 1.64811998 -2.08195 1.73356998 -2.08195 0 P 0 ;0
L 1.64776998 -2.08095 1.73398002 -2.08095 0 P 0 ;0
L 1.64743002 -2.07995 1.73438002 -2.07995 0 P 0 ;0
L 1.64708996 -2.07895 1.73478996 -2.07895 0 P 0 ;0
L 1.64673996 -2.07795 1.7352 -2.07795 0 P 0 ;0
L 1.6464 -2.07695 1.7356 -2.07695 0 P 0 ;0
L 1.64605 -2.07595 1.73601004 -2.07595 0 P 0 ;0
L 1.64571004 -2.07495 1.73641004 -2.07495 0 P 0 ;0
L 1.64536004 -2.07395 1.73681004 -2.07395 0 P 0 ;0
L 1.64501998 -2.07295 1.73721998 -2.07295 0 P 0 ;0
L 1.64466998 -2.07195 1.73761998 -2.07195 0 P 0 ;0
L 1.64433002 -2.07095 1.73803002 -2.07095 0 P 0 ;0
L 1.64398002 -2.06995 1.69251004 -2.06995 0 P 0 ;0
L 1.69583002 -2.06995 1.73843996 -2.06995 0 P 0 ;0
L 1.64363002 -2.06895 1.69168002 -2.06895 0 P 0 ;0
L 1.69671998 -2.06895 1.73883996 -2.06895 0 P 0 ;0
L 1.64328996 -2.06795 1.69136004 -2.06795 0 P 0 ;0
L 1.69708996 -2.06795 1.73925 -2.06795 0 P 0 ;0
L 1.64293996 -2.06695 1.69108002 -2.06695 0 P 0 ;0
L 1.69738002 -2.06695 1.73965 -2.06695 0 P 0 ;0
L 1.64258996 -2.06595 1.6908 -2.06595 0 P 0 ;0
L 1.69768002 -2.06595 1.74006004 -2.06595 0 P 0 ;0
L 1.64223996 -2.06495 1.69051998 -2.06495 0 P 0 ;0
L 1.69796998 -2.06495 1.74046004 -2.06495 0 P 0 ;0
L 1.6419 -2.06395 1.69023002 -2.06395 0 P 0 ;0
L 1.69826998 -2.06395 1.74086004 -2.06395 0 P 0 ;0
L 1.64155 -2.06295 1.68996004 -2.06295 0 P 0 ;0
L 1.69856004 -2.06295 1.74126998 -2.06295 0 P 0 ;0
L 1.6412 -2.06195 1.68966998 -2.06195 0 P 0 ;0
L 1.69886004 -2.06195 1.74168002 -2.06195 0 P 0 ;0
L 1.64085 -2.06095 1.68938996 -2.06095 0 P 0 ;0
L 1.69915 -2.06095 1.74208002 -2.06095 0 P 0 ;0
L 1.6405 -2.05995 1.68911004 -2.05995 0 P 0 ;0
L 1.69945 -2.05995 1.74248002 -2.05995 0 P 0 ;0
L 1.64016004 -2.05895 1.68883002 -2.05895 0 P 0 ;0
L 1.69973996 -2.05895 1.74288996 -2.05895 0 P 0 ;0
L 1.63981004 -2.05795 1.68855 -2.05795 0 P 0 ;0
L 1.70003996 -2.05795 1.74328996 -2.05795 0 P 0 ;0
L 1.63946004 -2.05695 1.68826998 -2.05695 0 P 0 ;0
L 1.70033002 -2.05695 1.7437 -2.05695 0 P 0 ;0
L 1.63911004 -2.05595 1.68798996 -2.05595 0 P 0 ;0
L 1.70063002 -2.05595 1.7441 -2.05595 0 P 0 ;0
L 1.63876998 -2.05495 1.68771004 -2.05495 0 P 0 ;0
L 1.70091998 -2.05495 1.74451004 -2.05495 0 P 0 ;0
L 1.63841998 -2.05395 1.68741998 -2.05395 0 P 0 ;0
L 1.70121998 -2.05395 1.74491004 -2.05395 0 P 0 ;0
L 1.63806998 -2.05295 1.68713996 -2.05295 0 P 0 ;0
L 1.70151004 -2.05295 1.74531004 -2.05295 0 P 0 ;0
L 1.63771998 -2.05195 1.68686004 -2.05195 0 P 0 ;0
L 1.70181004 -2.05195 1.74571998 -2.05195 0 P 0 ;0
L 1.63738002 -2.05095 1.68658002 -2.05095 0 P 0 ;0
L 1.7021 -2.05095 1.74611998 -2.05095 0 P 0 ;0
L 1.63703002 -2.04995 1.6863 -2.04995 0 P 0 ;0
L 1.7024 -2.04995 1.74653002 -2.04995 0 P 0 ;0
L 1.63668002 -2.04895 1.68601998 -2.04895 0 P 0 ;0
L 1.70268996 -2.04895 1.74693002 -2.04895 0 P 0 ;0
L 1.63633002 -2.04795 1.68573996 -2.04795 0 P 0 ;0
L 1.70298996 -2.04795 1.74733002 -2.04795 0 P 0 ;0
L 1.63598002 -2.04695 1.68546004 -2.04695 0 P 0 ;0
L 1.70328002 -2.04695 1.74773996 -2.04695 0 P 0 ;0
L 1.63563996 -2.04595 1.68518002 -2.04595 0 P 0 ;0
L 1.70358002 -2.04595 1.74813996 -2.04595 0 P 0 ;0
L 1.63528996 -2.04495 1.6849 -2.04495 0 P 0 ;0
L 1.70386998 -2.04495 1.74855 -2.04495 0 P 0 ;0
L 1.63493996 -2.04395 1.68461004 -2.04395 0 P 0 ;0
L 1.70416998 -2.04395 1.74895 -2.04395 0 P 0 ;0
L 1.63458996 -2.04295 1.68433002 -2.04295 0 P 0 ;0
L 1.70446004 -2.04295 1.74936004 -2.04295 0 P 0 ;0
L 1.63425 -2.04195 1.68405 -2.04195 0 P 0 ;0
L 1.70475 -2.04195 1.74976004 -2.04195 0 P 0 ;0
L 1.6339 -2.04095 1.68376998 -2.04095 0 P 0 ;0
L 1.70503002 -2.04095 1.75016004 -2.04095 0 P 0 ;0
L 1.63355 -2.03995 1.68348996 -2.03995 0 P 0 ;0
L 1.70531998 -2.03995 1.75056998 -2.03995 0 P 0 ;0
L 1.6332 -2.03895 1.68321004 -2.03895 0 P 0 ;0
L 1.7056 -2.03895 1.75096998 -2.03895 0 P 0 ;0
L 1.63286004 -2.03795 1.68293002 -2.03795 0 P 0 ;0
L 1.70588996 -2.03795 1.75138002 -2.03795 0 P 0 ;0
L 1.63251004 -2.03695 1.68266004 -2.03695 0 P 0 ;0
L 1.70618002 -2.03695 1.75178002 -2.03695 0 P 0 ;0
L 1.63216004 -2.03595 1.68238002 -2.03595 0 P 0 ;0
L 1.70646998 -2.03595 1.75218996 -2.03595 0 P 0 ;0
L 1.63181004 -2.03495 1.6821 -2.03495 0 P 0 ;0
L 1.70675 -2.03495 1.75258996 -2.03495 0 P 0 ;0
L 1.63146998 -2.03395 1.68183002 -2.03395 0 P 0 ;0
L 1.70703996 -2.03395 1.75298996 -2.03395 0 P 0 ;0
L 1.63111998 -2.03295 1.68155 -2.03295 0 P 0 ;0
L 1.70733002 -2.03295 1.7534 -2.03295 0 P 0 ;0
L 1.63076998 -2.03195 1.68126998 -2.03195 0 P 0 ;0
L 1.70761004 -2.03195 1.75381004 -2.03195 0 P 0 ;0
L 1.63041998 -2.03095 1.68098996 -2.03095 0 P 0 ;0
L 1.7079 -2.03095 1.75421004 -2.03095 0 P 0 ;0
L 1.63006998 -2.02995 1.68071004 -2.02995 0 P 0 ;0
L 1.70818996 -2.02995 1.75461004 -2.02995 0 P 0 ;0
L 1.62973002 -2.02895 1.68043996 -2.02895 0 P 0 ;0
L 1.70846998 -2.02895 1.75501998 -2.02895 0 P 0 ;0
L 1.62938002 -2.02795 1.68016004 -2.02795 0 P 0 ;0
L 1.70876004 -2.02795 1.75541998 -2.02795 0 P 0 ;0
L 1.62903002 -2.02695 1.67988002 -2.02695 0 P 0 ;0
L 1.70905 -2.02695 1.75583002 -2.02695 0 P 0 ;0
L 1.62868002 -2.02595 1.6796 -2.02595 0 P 0 ;0
L 1.70933996 -2.02595 1.75623002 -2.02595 0 P 0 ;0
L 1.62831004 -2.02495 1.67933002 -2.02495 0 P 0 ;0
L 1.70961998 -2.02495 1.75663996 -2.02495 0 P 0 ;0
L 1.62793996 -2.02395 1.67905 -2.02395 0 P 0 ;0
L 1.70991004 -2.02395 1.75703996 -2.02395 0 P 0 ;0
L 1.62756998 -2.02295 1.67876998 -2.02295 0 P 0 ;0
L 1.7102 -2.02295 1.75743996 -2.02295 0 P 0 ;0
L 1.6272 -2.02195 1.6785 -2.02195 0 P 0 ;0
L 1.71048002 -2.02195 1.75785 -2.02195 0 P 0 ;0
L 1.62683002 -2.02095 1.67821998 -2.02095 0 P 0 ;0
L 1.71076004 -2.02095 1.75825 -2.02095 0 P 0 ;0
L 1.62646998 -2.01995 1.67793996 -2.01995 0 P 0 ;0
L 1.71101004 -2.01995 1.75866004 -2.01995 0 P 0 ;0
L 1.6261 -2.01895 1.67766004 -2.01895 0 P 0 ;0
L 1.71126998 -2.01895 1.75906004 -2.01895 0 P 0 ;0
L 1.62573002 -2.01795 1.67738996 -2.01795 0 P 0 ;0
L 1.71151998 -2.01795 1.75946998 -2.01795 0 P 0 ;0
L 1.62536004 -2.01695 1.67711004 -2.01695 0 P 0 ;0
L 1.71176998 -2.01695 1.75986998 -2.01695 0 P 0 ;0
L 1.62498996 -2.01595 1.67683002 -2.01595 0 P 0 ;0
L 1.71203002 -2.01595 1.76026998 -2.01595 0 P 0 ;0
L 1.62461998 -2.01495 1.67656004 -2.01495 0 P 0 ;0
L 1.71228002 -2.01495 1.76068002 -2.01495 0 P 0 ;0
L 1.62425 -2.01395 1.67628002 -2.01395 0 P 0 ;0
L 1.71253996 -2.01395 1.76108002 -2.01395 0 P 0 ;0
L 1.62388002 -2.01295 1.67601998 -2.01295 0 P 0 ;0
L 1.71278996 -2.01295 1.76148996 -2.01295 0 P 0 ;0
L 1.62351004 -2.01195 1.67576998 -2.01195 0 P 0 ;0
L 1.71305 -2.01195 1.76188996 -2.01195 0 P 0 ;0
L 1.62313996 -2.01095 1.67551998 -2.01095 0 P 0 ;0
L 1.7133 -2.01095 1.76228996 -2.01095 0 P 0 ;0
L 1.62276998 -2.00995 1.67528002 -2.00995 0 P 0 ;0
L 1.71355 -2.00995 1.7627 -2.00995 0 P 0 ;0
L 1.6224 -2.00895 1.67503002 -2.00895 0 P 0 ;0
L 1.71381004 -2.00895 1.7631 -2.00895 0 P 0 ;0
L 1.62203002 -2.00795 1.67478996 -2.00795 0 P 0 ;0
L 1.71406004 -2.00795 1.76351004 -2.00795 0 P 0 ;0
L 1.62166004 -2.00695 1.67453996 -2.00695 0 P 0 ;0
L 1.71431004 -2.00695 1.76391004 -2.00695 0 P 0 ;0
L 1.62128996 -2.00595 1.67428996 -2.00595 0 P 0 ;0
L 1.71453996 -2.00595 1.76431998 -2.00595 0 P 0 ;0
L 1.62091004 -2.00495 1.67405 -2.00495 0 P 0 ;0
L 1.71476998 -2.00495 1.76471998 -2.00495 0 P 0 ;0
L 1.62051998 -2.00395 1.6738 -2.00395 0 P 0 ;0
L 1.715 -2.00395 1.76511998 -2.00395 0 P 0 ;0
L 1.62013002 -2.00295 1.67355 -2.00295 0 P 0 ;0
L 1.71523002 -2.00295 1.76553002 -2.00295 0 P 0 ;0
L 1.61973996 -2.00195 1.67331004 -2.00195 0 P 0 ;0
L 1.71546004 -2.00195 1.76593996 -2.00195 0 P 0 ;0
L 1.61935 -2.00095 1.67306004 -2.00095 0 P 0 ;0
L 1.71568996 -2.00095 1.76633996 -2.00095 0 P 0 ;0
L 1.61896004 -1.99995 1.67283996 -1.99995 0 P 0 ;0
L 1.71591998 -1.99995 1.76673996 -1.99995 0 P 0 ;0
L 1.61856998 -1.99895 1.67261998 -1.99895 0 P 0 ;0
L 1.71613996 -1.99895 1.76715 -1.99895 0 P 0 ;0
L 1.71638002 -1.99795 1.76755 -1.99795 0 P 0 ;0
L 1.7166 -1.99695 1.76796004 -1.99695 0 P 0 ;0
L 1.71683002 -1.99595 1.76836004 -1.99595 0 P 0 ;0
L 1.71866998 -1.99495 1.76876998 -1.99495 0 P 0 ;0
L 1.78213996 -2.04823996 1.84641998 -2.04823996 0 P 0 ;0
L 1.78138002 -2.04723996 1.84498996 -2.04723996 0 P 0 ;0
L 1.78071004 -2.04623996 1.84356004 -2.04623996 0 P 0 ;0
L 1.7801 -2.04523996 1.84213996 -2.04523996 0 P 0 ;0
L 1.77956004 -2.04423996 1.84071004 -2.04423996 0 P 0 ;0
L 1.77908996 -2.04323996 1.83928002 -2.04323996 0 P 0 ;0
L 1.77866004 -2.04223996 1.83786004 -2.04223996 0 P 0 ;0
L 1.77831004 -2.04123996 1.83658996 -2.04123996 0 P 0 ;0
L 1.77796004 -2.04023996 1.83536004 -2.04023996 0 P 0 ;0
L 1.77761004 -2.03923996 1.83428002 -2.03923996 0 P 0 ;0
L 1.77733996 -2.03823996 1.83321998 -2.03823996 0 P 0 ;0
L 1.77706998 -2.03723996 1.83236998 -2.03723996 0 P 0 ;0
L 1.7768 -2.03623996 1.83171004 -2.03623996 0 P 0 ;0
L 1.7766 -2.03523996 1.83121004 -2.03523996 0 P 0 ;0
L 1.77641004 -2.03423996 1.83085 -2.03423996 0 P 0 ;0
L 1.77621004 -2.03323996 1.83071004 -2.03323996 0 P 0 ;0
L 1.77608002 -2.03223996 1.83076998 -2.03223996 0 P 0 ;0
L 1.77596004 -2.03123996 1.83106004 -2.03123996 0 P 0 ;0
L 1.77583996 -2.03023996 1.83158996 -2.03023996 0 P 0 ;0
L 1.77576004 -2.02923996 1.83238002 -2.02923996 0 P 0 ;0
L 1.7757 -2.02823996 1.83356998 -2.02823996 0 P 0 ;0
L 1.7757 -2.02723996 1.83591998 -2.02723996 0 P 0 ;0
L 1.77571998 -2.02623996 1.87495 -2.02623996 0 P 0 ;0
L 1.7758 -2.02523996 1.87485 -2.02523996 0 P 0 ;0
L 1.77588996 -2.02423996 1.87475 -2.02423996 0 P 0 ;0
L 1.77605 -2.02323996 1.87465 -2.02323996 0 P 0 ;0
L 1.77621004 -2.02223996 1.87455 -2.02223996 0 P 0 ;0
L 1.7764 -2.02123996 1.87445 -2.02123996 0 P 0 ;0
L 1.77665 -2.02023996 1.87433996 -2.02023996 0 P 0 ;0
L 1.7769 -2.01923996 1.87425 -2.01923996 0 P 0 ;0
L 1.7772 -2.01823996 1.87413996 -2.01823996 0 P 0 ;0
L 1.77753002 -2.01723996 1.87405 -2.01723996 0 P 0 ;0
L 1.77786004 -2.01623996 1.87393996 -2.01623996 0 P 0 ;0
L 1.77823002 -2.01523996 1.87383996 -2.01523996 0 P 0 ;0
L 1.77863996 -2.01423996 1.87373996 -2.01423996 0 P 0 ;0
L 1.77903996 -2.01323996 1.87363996 -2.01323996 0 P 0 ;0
L 1.7795 -2.01223996 1.87353996 -2.01223996 0 P 0 ;0
L 1.77998996 -2.01123996 1.87343996 -2.01123996 0 P 0 ;0
L 1.78046998 -2.01023996 1.87333002 -2.01023996 0 P 0 ;0
L 1.78103996 -2.00923996 1.87323002 -2.00923996 0 P 0 ;0
L 1.78161004 -2.00823996 1.87311998 -2.00823996 0 P 0 ;0
L 1.78221004 -2.00723996 1.87301998 -2.00723996 0 P 0 ;0
L 1.78288002 -2.00623996 1.87291998 -2.00623996 0 P 0 ;0
L 1.64213996 -2.14795 1.70566004 -2.14795 0 P 0 ;0
L 1.64518996 -2.14695 1.7062 -2.14695 0 P 0 ;0
L 1.64728996 -2.14595 1.70673996 -2.14595 0 P 0 ;0
L 1.64906998 -2.14495 1.70728002 -2.14495 0 P 0 ;0
L 1.65058002 -2.14395 1.70783002 -2.14395 0 P 0 ;0
L 1.6519 -2.14295 1.70836998 -2.14295 0 P 0 ;0
L 1.65311998 -2.14195 1.70881998 -2.14195 0 P 0 ;0
L 1.65416998 -2.14095 1.70926998 -2.14095 0 P 0 ;0
L 1.65508996 -2.13995 1.70973002 -2.13995 0 P 0 ;0
L 1.65588002 -2.13895 1.71018002 -2.13895 0 P 0 ;0
L 1.65658002 -2.13795 1.71063002 -2.13795 0 P 0 ;0
L 1.65726998 -2.13695 1.71108996 -2.13695 0 P 0 ;0
L 1.65791998 -2.13595 1.71153996 -2.13595 0 P 0 ;0
L 1.65853002 -2.13495 1.71198996 -2.13495 0 P 0 ;0
L 1.65913002 -2.13395 1.71245 -2.13395 0 P 0 ;0
L 1.65968002 -2.13295 1.7129 -2.13295 0 P 0 ;0
L 1.66021998 -2.13195 1.71331004 -2.13195 0 P 0 ;0
L 1.66071998 -2.13095 1.71371998 -2.13095 0 P 0 ;0
L 1.66121004 -2.12995 1.71411998 -2.12995 0 P 0 ;0
L 1.66166998 -2.12895 1.71453002 -2.12895 0 P 0 ;0
L 1.66201004 -2.12795 1.71493996 -2.12795 0 P 0 ;0
L 1.66223996 -2.12695 1.71533996 -2.12695 0 P 0 ;0
L 1.66235 -2.12595 1.71575 -2.12595 0 P 0 ;0
L 1.66236004 -2.12495 1.71615 -2.12495 0 P 0 ;0
L 1.66228002 -2.12395 1.71656004 -2.12395 0 P 0 ;0
L 1.66211998 -2.12295 1.71696004 -2.12295 0 P 0 ;0
L 1.66188002 -2.12195 1.71736004 -2.12195 0 P 0 ;0
L 1.66156004 -2.12095 1.71776998 -2.12095 0 P 0 ;0
L 1.66121004 -2.11995 1.71818002 -2.11995 0 P 0 ;0
L 1.66086998 -2.11895 1.71858002 -2.11895 0 P 0 ;0
L 1.66053002 -2.11795 1.71898996 -2.11795 0 P 0 ;0
L 1.66018002 -2.11695 1.71938996 -2.11695 0 P 0 ;0
L 1.65983996 -2.11595 1.7198 -2.11595 0 P 0 ;0
L 1.65948996 -2.11495 1.7202 -2.11495 0 P 0 ;0
L 1.65913996 -2.11395 1.72061004 -2.11395 0 P 0 ;0
L 1.6588 -2.11295 1.72101004 -2.11295 0 P 0 ;0
L 1.65846004 -2.11195 1.72141998 -2.11195 0 P 0 ;0
L 1.65811004 -2.11095 1.72181998 -2.11095 0 P 0 ;0
L 1.65776998 -2.10995 1.72223002 -2.10995 0 P 0 ;0
L 1.65741998 -2.10895 1.72263002 -2.10895 0 P 0 ;0
L 1.65708002 -2.10795 1.72303996 -2.10795 0 P 0 ;0
L 1.65673002 -2.10695 1.72343996 -2.10695 0 P 0 ;0
L 1.65638996 -2.10595 1.72385 -2.10595 0 P 0 ;0
L 1.65605 -2.10495 1.72425 -2.10495 0 P 0 ;0
L 1.6557 -2.10395 1.72466004 -2.10395 0 P 0 ;0
L 1.65536004 -2.10295 1.72506998 -2.10295 0 P 0 ;0
L 1.65501004 -2.10195 1.72546998 -2.10195 0 P 0 ;0
L 1.65466998 -2.10095 1.72588002 -2.10095 0 P 0 ;0
L 1.65431998 -2.09995 1.72628002 -2.09995 0 P 0 ;0
L 1.65398002 -2.09895 1.72668996 -2.09895 0 P 0 ;0
L 1.65363002 -2.09795 1.72708996 -2.09795 0 P 0 ;0
L 1.65328996 -2.09695 1.72748996 -2.09695 0 P 0 ;0
L 1.65293996 -2.09595 1.7279 -2.09595 0 P 0 ;0
L 1.6526 -2.09495 1.72831004 -2.09495 0 P 0 ;0
L 1.65225 -2.09395 1.72871004 -2.09395 0 P 0 ;0
L 1.65191004 -2.09295 1.72911998 -2.09295 0 P 0 ;0
L 1.65156998 -2.09195 1.72951998 -2.09195 0 P 0 ;0
L 1.65121998 -2.09095 1.72993002 -2.09095 0 P 0 ;0
L 1.65088002 -2.08995 1.73033002 -2.08995 0 P 0 ;0
L 1.65053002 -2.08895 1.73073996 -2.08895 0 P 0 ;0
L 1.65018996 -2.08795 1.73113996 -2.08795 0 P 0 ;0
L 1.64983996 -2.08695 1.73155 -2.08695 0 P 0 ;0
L 1.6495 -2.08595 1.73195 -2.08595 0 P 0 ;0
L 1.64915 -2.08495 1.73236004 -2.08495 0 P 0 ;0
L 1.64881004 -2.08395 1.73276004 -2.08395 0 P 0 ;0
L 1.81726998 -1.98915 1.81196004 -1.9899 0 P 0 ;0
L 1.81196004 -1.9899 1.80668996 -1.99096998 0 P 0 ;0
L 1.80668996 -1.99096998 1.8019 -1.99226004 0 P 0 ;0
L 1.8019 -1.99226004 1.79718996 -1.99391004 0 P 0 ;0
L 1.79718996 -1.99391004 1.79316004 -1.99568002 0 P 0 ;0
L 1.79316004 -1.99568002 1.78926998 -1.99778002 0 P 0 ;0
L 1.78926998 -1.99778002 1.78771004 -1.99878002 0 P 0 ;0
L 1.78771004 -1.99878002 1.78623002 -1.99988002 0 P 0 ;0
L 1.78623002 -1.99988002 1.78481004 -2.00108002 0 P 0 ;0
L 1.78481004 -2.00108002 1.78346998 -2.00238996 0 P 0 ;0
L 1.78346998 -2.00238996 1.78228996 -2.00371998 0 P 0 ;0
L 1.78228996 -2.00371998 1.78121004 -2.00513002 0 P 0 ;0
L 1.78121004 -2.00513002 1.78023002 -2.00661004 0 P 0 ;0
L 1.78023002 -2.00661004 1.77868002 -2.00933996 0 P 0 ;0
L 1.77868002 -2.00933996 1.77731998 -2.01216998 0 P 0 ;0
L 1.77731998 -2.01216998 1.77611004 -2.01516004 0 P 0 ;0
L 1.77611004 -2.01516004 1.77508996 -2.01823002 0 P 0 ;0
L 1.77508996 -2.01823002 1.77436998 -2.02111004 0 P 0 ;0
L 1.77436998 -2.02111004 1.77388996 -2.02406004 0 P 0 ;0
L 1.77388996 -2.02406004 1.77371998 -2.02603996 0 P 0 ;0
L 1.77371998 -2.02603996 1.77368996 -2.02801998 0 P 0 ;0
L 1.77368996 -2.02801998 1.7738 -2.03001998 0 P 0 ;0
L 1.7738 -2.03001998 1.7742 -2.03338996 0 P 0 ;0
L 1.7742 -2.03338996 1.77485 -2.03671004 0 P 0 ;0
L 1.77485 -2.03671004 1.77573002 -2.03993996 0 P 0 ;0
L 1.77573002 -2.03993996 1.77683996 -2.04308002 0 P 0 ;0
L 1.77683996 -2.04308002 1.7776 -2.04481998 0 P 0 ;0
L 1.7776 -2.04481998 1.7785 -2.04648996 0 P 0 ;0
L 1.7785 -2.04648996 1.77953002 -2.04808996 0 P 0 ;0
L 1.77953002 -2.04808996 1.78061004 -2.04953996 0 P 0 ;0
L 1.78061004 -2.04953996 1.78181004 -2.05091004 0 P 0 ;0
L 1.78181004 -2.05091004 1.78311004 -2.05218996 0 P 0 ;0
L 1.78311004 -2.05218996 1.78988996 -2.05801998 0 P 0 ;0
L 1.78988996 -2.05801998 1.79883996 -2.06491004 0 P 0 ;0
L 1.79883996 -2.06491004 1.80976998 -2.07261004 0 P 0 ;0
L 1.80976998 -2.07261004 1.81753002 -2.07823002 0 P 0 ;0
L 1.81753002 -2.07823002 1.81896998 -2.07943002 0 P 0 ;0
L 1.81896998 -2.07943002 1.82033002 -2.08073002 0 P 0 ;0
L 1.82033002 -2.08073002 1.82156998 -2.08213996 0 P 0 ;0
L 1.82156998 -2.08213996 1.82186004 -2.08251004 0 P 0 ;0
L 1.82186004 -2.08251004 1.82211004 -2.0829 0 P 0 ;0
L 1.82211004 -2.0829 1.82233002 -2.08331004 0 P 0 ;0
L 1.82233002 -2.08331004 1.82253002 -2.08373996 0 P 0 ;0
L 1.82253002 -2.08373996 1.82268002 -2.08418002 0 P 0 ;0
L 1.82268002 -2.08418002 1.82281004 -2.08463002 0 P 0 ;0
L 1.82281004 -2.08463002 1.8229 -2.0851 0 P 0 ;0
L 1.8229 -2.0851 1.82293002 -2.08533996 0 P 0 ;0
L 1.82293002 -2.08533996 1.82293996 -2.08558996 0 P 0 ;0
L 1.82293996 -2.08558996 1.82291998 -2.08583996 0 P 0 ;0
L 1.82291998 -2.08583996 1.82288002 -2.08608002 0 P 0 ;0
L 1.82288002 -2.08608002 1.82283002 -2.08631998 0 P 0 ;0
L 1.82283002 -2.08631998 1.82275 -2.08656004 0 P 0 ;0
L 1.82275 -2.08656004 1.82265 -2.08678996 0 P 0 ;0
L 1.82265 -2.08678996 1.82253996 -2.087 0 P 0 ;0
L 1.82253996 -2.087 1.8224 -2.08721004 0 P 0 ;0
L 1.8224 -2.08721004 1.82225 -2.08741004 0 P 0 ;0
L 1.82225 -2.08741004 1.82208996 -2.08758996 0 P 0 ;0
L 1.82208996 -2.08758996 1.8216 -2.08803996 0 P 0 ;0
L 1.8216 -2.08803996 1.82106998 -2.08845 0 P 0 ;0
L 1.82106998 -2.08845 1.82051004 -2.08881004 0 P 0 ;0
L 1.82051004 -2.08881004 1.81991998 -2.08911998 0 P 0 ;0
L 1.81991998 -2.08911998 1.81931004 -2.08936998 0 P 0 ;0
L 1.81931004 -2.08936998 1.81868002 -2.08958002 0 P 0 ;0
L 1.81868002 -2.08958002 1.81803002 -2.08973002 0 P 0 ;0
L 1.81803002 -2.08973002 1.81736004 -2.08981998 0 P 0 ;0
L 1.81736004 -2.08981998 1.81293002 -2.09001998 0 P 0 ;0
L 1.81293002 -2.09001998 1.80846998 -2.08986004 0 P 0 ;0
L 1.80846998 -2.08986004 1.80256998 -2.08923002 0 P 0 ;0
L 1.80256998 -2.08923002 1.79668002 -2.08818996 0 P 0 ;0
L 1.79668002 -2.08818996 1.78223002 -2.08458002 0 P 0 ;0
L 1.78223002 -2.08458002 1.77788996 -2.08338002 0 P 0 ;0
L 1.77788996 -2.08338002 1.77415 -2.08246004 0 P 0 ;0
L 1.77415 -2.08246004 1.77095 -2.08175 0 P 0 ;0
L 1.77095 -2.08175 1.7709 -2.08173996 0 P 0 ;0
L 1.7709 -2.08173996 1.77076998 -2.08173996 0 P 0 ;0
L 1.77076998 -2.08173996 1.77068996 -2.08176004 0 P 0 ;0
L 1.77068996 -2.08176004 1.77053002 -2.08183996 0 P 0 ;0
L 1.77053002 -2.08183996 1.77043002 -2.08193996 0 P 0 ;0
L 1.77043002 -2.08193996 1.77036998 -2.08201998 0 P 0 ;0
L 1.77036998 -2.08201998 1.77031998 -2.08211998 0 P 0 ;0
L 1.77031998 -2.08211998 1.7703 -2.08216998 0 P 0 ;0
L 1.7703 -2.08216998 1.77028996 -2.08223002 0 P 0 ;0
L 1.77028996 -2.08223002 1.77028002 -2.08228002 0 P 0 ;0
L 1.77028002 -2.08228002 1.77028002 -2.08238996 0 P 0 ;0
L 1.77028002 -2.08238996 1.77056998 -2.08838996 0 P 0 ;0
L 1.77056998 -2.08838996 1.77096004 -2.09526004 0 P 0 ;0
L 1.77096004 -2.09526004 1.77153996 -2.1033 0 P 0 ;0
L 1.77153996 -2.1033 1.77236004 -2.11291004 0 P 0 ;0
L 1.77236004 -2.11291004 1.77311004 -2.1194 0 P 0 ;0
L 1.77311004 -2.1194 1.77383002 -2.12398002 0 P 0 ;0
L 1.77383002 -2.12398002 1.77386004 -2.12411004 0 P 0 ;0
L 1.77386004 -2.12411004 1.7739 -2.12423002 0 P 0 ;0
L 1.7739 -2.12423002 1.77395 -2.12436004 0 P 0 ;0
L 1.77395 -2.12436004 1.77401004 -2.12448002 0 P 0 ;0
L 1.77401004 -2.12448002 1.77408002 -2.12458996 0 P 0 ;0
L 1.77408002 -2.12458996 1.77416004 -2.1247 0 P 0 ;0
L 1.77416004 -2.1247 1.77425 -2.1248 0 P 0 ;0
L 1.77425 -2.1248 1.77435 -2.12488996 0 P 0 ;0
L 1.77435 -2.12488996 1.77445 -2.12496998 0 P 0 ;0
L 1.77445 -2.12496998 1.77456998 -2.12505 0 P 0 ;0
L 1.77456998 -2.12505 1.77571004 -2.12568996 0 P 0 ;0
L 1.77571004 -2.12568996 1.7769 -2.12623996 0 P 0 ;0
L 1.7769 -2.12623996 1.77813002 -2.12668996 0 P 0 ;0
L 1.77813002 -2.12668996 1.7794 -2.12703996 0 P 0 ;0
L 1.7794 -2.12703996 1.78068996 -2.12728996 0 P 0 ;0
L 1.78068996 -2.12728996 1.79791998 -2.12951004 0 P 0 ;0
L 1.79791998 -2.12951004 1.81536004 -2.13106004 0 P 0 ;0
L 1.81536004 -2.13106004 1.82125 -2.13123996 0 P 0 ;0
L 1.82125 -2.13123996 1.82716004 -2.13098996 0 P 0 ;0
L 1.82716004 -2.13098996 1.83583996 -2.12998002 0 P 0 ;0
L 1.83583996 -2.12998002 1.84445 -2.12836004 0 P 0 ;0
L 1.84445 -2.12836004 1.84911998 -2.12711004 0 P 0 ;0
L 1.84911998 -2.12711004 1.85366004 -2.12548002 0 P 0 ;0
L 1.85366004 -2.12548002 1.85806998 -2.12348002 0 P 0 ;0
L 1.85806998 -2.12348002 1.86078996 -2.12196998 0 P 0 ;0
L 1.86078996 -2.12196998 1.8634 -2.12026998 0 P 0 ;0
L 1.8634 -2.12026998 1.86586998 -2.11836998 0 P 0 ;0
L 1.86586998 -2.11836998 1.86821004 -2.11628002 0 P 0 ;0
L 1.86821004 -2.11628002 1.87026004 -2.11413002 0 P 0 ;0
L 1.87026004 -2.11413002 1.8721 -2.11181998 0 P 0 ;0
L 1.8721 -2.11181998 1.87375 -2.10936004 0 P 0 ;0
L 1.87375 -2.10936004 1.87516998 -2.10673996 0 P 0 ;0
L 1.87516998 -2.10673996 1.87605 -2.10483996 0 P 0 ;0
L 1.87605 -2.10483996 1.87683996 -2.10291004 0 P 0 ;0
L 1.87683996 -2.10291004 1.8772 -2.10188002 0 P 0 ;0
L 1.8772 -2.10188002 1.87748996 -2.10083002 0 P 0 ;0
L 1.87748996 -2.10083002 1.87771004 -2.09976998 0 P 0 ;0
L 1.87771004 -2.09976998 1.87798002 -2.09788996 0 P 0 ;0
L 1.87798002 -2.09788996 1.87811998 -2.09601004 0 P 0 ;0
L 1.87811998 -2.09601004 1.87821004 -2.08966998 0 P 0 ;0
L 1.87821004 -2.08966998 1.8781 -2.08353996 0 P 0 ;0
L 1.8781 -2.08353996 1.87798002 -2.08166004 0 P 0 ;0
L 1.87798002 -2.08166004 1.87773002 -2.07976998 0 P 0 ;0
L 1.87773002 -2.07976998 1.87753002 -2.07873996 0 P 0 ;0
L 1.87753002 -2.07873996 1.87726998 -2.07773996 0 P 0 ;0
L 1.87726998 -2.07773996 1.87695 -2.07673996 0 P 0 ;0
L 1.87695 -2.07673996 1.87628996 -2.07505 0 P 0 ;0
L 1.87628996 -2.07505 1.87553002 -2.07338002 0 P 0 ;0
L 1.87553002 -2.07338002 1.87441004 -2.07133996 0 P 0 ;0
L 1.87441004 -2.07133996 1.87313996 -2.06938002 0 P 0 ;0
L 1.87313996 -2.06938002 1.87171004 -2.06751004 0 P 0 ;0
L 1.87171004 -2.06751004 1.8688 -2.06416004 0 P 0 ;0
L 1.8688 -2.06416004 1.86566998 -2.06095 0 P 0 ;0
L 1.86566998 -2.06095 1.86181998 -2.05741998 0 P 0 ;0
L 1.86181998 -2.05741998 1.85778002 -2.05406998 0 P 0 ;0
L 1.85778002 -2.05406998 1.84833996 -2.04715 0 P 0 ;0
L 1.84833996 -2.04715 1.83913996 -2.0407 0 P 0 ;0
L 1.83913996 -2.0407 1.83686004 -2.0389 0 P 0 ;0
L 1.83686004 -2.0389 1.83471998 -2.03691998 0 P 0 ;0
L 1.83471998 -2.03691998 1.83428002 -2.03643002 0 P 0 ;0
L 1.83428002 -2.03643002 1.83386998 -2.0359 0 P 0 ;0
L 1.83386998 -2.0359 1.83351004 -2.03535 0 P 0 ;0
L 1.83351004 -2.03535 1.83318996 -2.03476004 0 P 0 ;0
L 1.83318996 -2.03476004 1.83291998 -2.03415 0 P 0 ;0
L 1.83291998 -2.03415 1.83283996 -2.03393996 0 P 0 ;0
L 1.83283996 -2.03393996 1.83278002 -2.03371004 0 P 0 ;0
L 1.83278002 -2.03371004 1.83273002 -2.03348996 0 P 0 ;0
L 1.83273002 -2.03348996 1.83271004 -2.03326004 0 P 0 ;0
L 1.83271004 -2.03326004 1.8327 -2.03303002 0 P 0 ;0
L 1.8327 -2.03303002 1.83271004 -2.0328 0 P 0 ;0
L 1.83271004 -2.0328 1.83275 -2.03258002 0 P 0 ;0
L 1.83275 -2.03258002 1.83278996 -2.03235 0 P 0 ;0
L 1.83278996 -2.03235 1.83286004 -2.03213002 0 P 0 ;0
L 1.83286004 -2.03213002 1.83293996 -2.03191998 0 P 0 ;0
L 1.83293996 -2.03191998 1.83305 -2.03171004 0 P 0 ;0
L 1.83305 -2.03171004 1.83325 -2.03135 0 P 0 ;0
L 1.83325 -2.03135 1.83348996 -2.03101998 0 P 0 ;0
L 1.83348996 -2.03101998 1.83375 -2.03071004 0 P 0 ;0
L 1.83375 -2.03071004 1.83403002 -2.03041004 0 P 0 ;0
L 1.83403002 -2.03041004 1.83433996 -2.03015 0 P 0 ;0
L 1.83433996 -2.03015 1.83466998 -2.02991004 0 P 0 ;0
L 1.83466998 -2.02991004 1.83501998 -2.02968996 0 P 0 ;0
L 1.83501998 -2.02968996 1.83538002 -2.02951004 0 P 0 ;0
L 1.83538002 -2.02951004 1.83576004 -2.02936004 0 P 0 ;0
L 1.83576004 -2.02936004 1.83615 -2.02923996 0 P 0 ;0
L 1.83615 -2.02923996 1.83655 -2.02915 0 P 0 ;0
L 1.83655 -2.02915 1.8392 -2.02873996 0 P 0 ;0
L 1.8392 -2.02873996 1.84188002 -2.0285 0 P 0 ;0
L 1.84188002 -2.0285 1.84458002 -2.02841004 0 P 0 ;0
L 1.84458002 -2.02841004 1.84993996 -2.02858002 0 P 0 ;0
L 1.84993996 -2.02858002 1.85526998 -2.02916004 0 P 0 ;0
L 1.85526998 -2.02916004 1.86155 -2.03023002 0 P 0 ;0
L 1.86155 -2.03023002 1.86778002 -2.03158002 0 P 0 ;0
L 1.86778002 -2.03158002 1.8713 -2.03238996 0 P 0 ;0
L 1.8713 -2.03238996 1.87428996 -2.03303002 0 P 0 ;0
L 1.87428996 -2.03303002 1.8769 -2.03356004 0 P 0 ;0
L 1.8769 -2.03356004 1.87691998 -2.03356998 0 P 0 ;0
L 1.87691998 -2.03356998 1.87696004 -2.03356998 0 P 0 ;0
L 1.87696004 -2.03356998 1.87696998 -2.03356004 0 P 0 ;0
L 1.87696998 -2.03356004 1.87701004 -2.03356004 0 P 0 ;0
L 1.87701004 -2.03356004 1.87703996 -2.03353996 0 P 0 ;0
L 1.87703996 -2.03353996 1.87706004 -2.03353002 0 P 0 ;0
L 1.87706004 -2.03353002 1.87706998 -2.03351998 0 P 0 ;0
L 1.87706998 -2.03351998 1.87708996 -2.03351004 0 P 0 ;0
L 1.87708996 -2.03351004 1.8771 -2.03348996 0 P 0 ;0
L 1.8771 -2.03348996 1.87711004 -2.03348002 0 P 0 ;0
L 1.87711004 -2.03348002 1.87721998 -2.0333 0 P 0 ;0
L 1.87721998 -2.0333 1.87731998 -2.0331 0 P 0 ;0
L 1.87731998 -2.0331 1.8774 -2.0329 0 P 0 ;0
L 1.8774 -2.0329 1.87746004 -2.03268996 0 P 0 ;0
L 1.87746004 -2.03268996 1.87751004 -2.03248002 0 P 0 ;0
L 1.87751004 -2.03248002 1.87753002 -2.03226998 0 P 0 ;0
L 1.87753002 -2.03226998 1.87753996 -2.03205 0 P 0 ;0
L 1.87753996 -2.03205 1.87753002 -2.03183002 0 P 0 ;0
L 1.87753002 -2.03183002 1.87565 -2.01323996 0 P 0 ;0
L 1.87565 -2.01323996 1.87371004 -1.99451998 0 P 0 ;0
L 1.87371004 -1.99451998 1.8737 -1.99438996 0 P 0 ;0
L 1.8737 -1.99438996 1.87366998 -1.99426998 0 P 0 ;0
L 1.87366998 -1.99426998 1.87363002 -1.99415 0 P 0 ;0
L 1.87363002 -1.99415 1.87358002 -1.99403002 0 P 0 ;0
L 1.87358002 -1.99403002 1.87351998 -1.99391004 0 P 0 ;0
L 1.87351998 -1.99391004 1.87346004 -1.9938 0 P 0 ;0
L 1.87346004 -1.9938 1.87338002 -1.9937 0 P 0 ;0
L 1.87338002 -1.9937 1.87328996 -1.9936 0 P 0 ;0
L 1.87328996 -1.9936 1.8732 -1.99351004 0 P 0 ;0
L 1.8732 -1.99351004 1.8731 -1.99343002 0 P 0 ;0
L 1.8731 -1.99343002 1.87298996 -1.99335 0 P 0 ;0
L 1.87298996 -1.99335 1.87248002 -1.99305 0 P 0 ;0
L 1.87248002 -1.99305 1.87193996 -1.99278002 0 P 0 ;0
L 1.87193996 -1.99278002 1.87136998 -1.99256998 0 P 0 ;0
L 1.87136998 -1.99256998 1.87078996 -1.99241004 0 P 0 ;0
L 1.87078996 -1.99241004 1.8702 -1.9923 0 P 0 ;0
L 1.8702 -1.9923 1.85876004 -1.99076004 0 P 0 ;0
L 1.85876004 -1.99076004 1.84691998 -1.98943002 0 P 0 ;0
L 1.84691998 -1.98943002 1.83693002 -1.98876004 0 P 0 ;0
L 1.83693002 -1.98876004 1.8318 -1.98863002 0 P 0 ;0
L 1.8318 -1.98863002 1.82623002 -1.98866998 0 P 0 ;0
L 1.82623002 -1.98866998 1.82106004 -1.98883996 0 P 0 ;0
L 1.82106004 -1.98883996 1.81726998 -1.98915 0 P 0 ;0
L 1.78061004 -2.12523996 1.84838002 -2.12523996 0 P 0 ;0
L 1.77733002 -2.12423996 1.85121004 -2.12423996 0 P 0 ;0
L 1.77573996 -2.12323996 1.85376998 -2.12323996 0 P 0 ;0
L 1.77558002 -2.12223996 1.85596998 -2.12223996 0 P 0 ;0
L 1.77541998 -2.12123996 1.85798996 -2.12123996 0 P 0 ;0
L 1.77526998 -2.12023996 1.85978996 -2.12023996 0 P 0 ;0
L 1.77511004 -2.11923996 1.86131998 -2.11923996 0 P 0 ;0
L 1.77498996 -2.11823996 1.86276004 -2.11823996 0 P 0 ;0
L 1.77486998 -2.11723996 1.86406998 -2.11723996 0 P 0 ;0
L 1.77475 -2.11623996 1.86526004 -2.11623996 0 P 0 ;0
L 1.77463996 -2.11523996 1.86638002 -2.11523996 0 P 0 ;0
L 1.77451998 -2.11423996 1.8674 -2.11423996 0 P 0 ;0
L 1.77441004 -2.11323996 1.86835 -2.11323996 0 P 0 ;0
L 1.77431004 -2.11223996 1.86921004 -2.11223996 0 P 0 ;0
L 1.77421998 -2.11123996 1.87001004 -2.11123996 0 P 0 ;0
L 1.77413996 -2.11023996 1.87075 -2.11023996 0 P 0 ;0
L 1.77405 -2.10923996 1.87141998 -2.10923996 0 P 0 ;0
L 1.77396998 -2.10823996 1.87208002 -2.10823996 0 P 0 ;0
L 1.77388002 -2.10723996 1.87261998 -2.10723996 0 P 0 ;0
L 1.7738 -2.10623996 1.87316998 -2.10623996 0 P 0 ;0
L 1.77371004 -2.10523996 1.87366004 -2.10523996 0 P 0 ;0
L 1.77363002 -2.10423996 1.87411998 -2.10423996 0 P 0 ;0
L 1.77353996 -2.10323996 1.87453996 -2.10323996 0 P 0 ;0
L 1.77346998 -2.10223996 1.87495 -2.10223996 0 P 0 ;0
L 1.7734 -2.10123996 1.8753 -2.10123996 0 P 0 ;0
L 1.77333002 -2.10023996 1.87556998 -2.10023996 0 P 0 ;0
L 1.77325 -2.09923996 1.87576998 -2.09923996 0 P 0 ;0
L 1.77318002 -2.09823996 1.87591998 -2.09823996 0 P 0 ;0
L 1.77311004 -2.09723996 1.87603002 -2.09723996 0 P 0 ;0
L 1.77303996 -2.09623996 1.8761 -2.09623996 0 P 0 ;0
L 1.77296998 -2.09523996 1.87613002 -2.09523996 0 P 0 ;0
L 1.77291004 -2.09423996 1.87613996 -2.09423996 0 P 0 ;0
L 1.77285 -2.09323996 1.87616004 -2.09323996 0 P 0 ;0
L 1.77278996 -2.09223996 1.87616998 -2.09223996 0 P 0 ;0
L 1.77273002 -2.09123996 1.80256998 -2.09123996 0 P 0 ;0
L 1.77268002 -2.09023996 1.7968 -2.09023996 0 P 0 ;0
L 1.77261998 -2.08923996 1.79263002 -2.08923996 0 P 0 ;0
L 1.77256004 -2.08823996 1.78861998 -2.08823996 0 P 0 ;0
L 1.77251004 -2.08723996 1.7846 -2.08723996 0 P 0 ;0
L 1.77246004 -2.08623996 1.7807 -2.08623996 0 P 0 ;0
L 1.77241998 -2.08523996 1.77705 -2.08523996 0 P 0 ;0
L 1.77236998 -2.08423996 1.77293996 -2.08423996 0 P 0 ;0
L 1.62463996 -2.18195 1.65948996 -2.18195 0 P 0 ;0
L 1.61963996 -2.18095 1.66483002 -2.18095 0 P 0 ;0
L 1.61818002 -1.99795 1.6724 -1.99795 0 P 0 ;0
L 1.61778996 -1.99695 1.67218002 -1.99695 0 P 0 ;0
L 1.6174 -1.99595 1.67196004 -1.99595 0 P 0 ;0
L 1.61701004 -1.99495 1.67173996 -1.99495 0 P 0 ;0
L 1.61391998 -2.15695 1.70026004 -2.15695 0 P 0 ;0
L 1.61386004 -2.15595 1.70088002 -2.15595 0 P 0 ;0
L 1.61381004 -2.15495 1.70151004 -2.15495 0 P 0 ;0
L 1.61375 -2.15395 1.70213996 -2.15395 0 P 0 ;0
L 1.6137 -2.15295 1.70276004 -2.15295 0 P 0 ;0
L 1.61365 -2.15195 1.70338996 -2.15195 0 P 0 ;0
L 1.6136 -2.15095 1.70401004 -2.15095 0 P 0 ;0
L 1.61355 -2.14995 1.70456998 -2.14995 0 P 0 ;0
L 1.61348996 -2.14895 1.70511998 -2.14895 0 P 0 ;0
L 1.61343996 -2.14795 1.61738002 -2.14795 0 P 0 ;0
L 1.55341004 -2.08286998 1.60538002 -2.08286998 0 P 0 ;0
L 1.55286004 -2.08186998 1.60526998 -2.08186998 0 P 0 ;0
L 1.5521 -2.08086998 1.6051 -2.08086998 0 P 0 ;0
L 1.55126998 -2.07986998 1.6049 -2.07986998 0 P 0 ;0
L 1.55033996 -2.07886998 1.60463996 -2.07886998 0 P 0 ;0
L 1.54928996 -2.07786998 1.60433002 -2.07786998 0 P 0 ;0
L 1.54806998 -2.07686998 1.60398996 -2.07686998 0 P 0 ;0
L 1.5467 -2.07586998 1.60356998 -2.07586998 0 P 0 ;0
L 1.54531004 -2.07486998 1.6031 -2.07486998 0 P 0 ;0
L 1.54391004 -2.07386998 1.60258996 -2.07386998 0 P 0 ;0
L 1.54251004 -2.07286998 1.60201004 -2.07286998 0 P 0 ;0
L 1.54111998 -2.07186998 1.60138002 -2.07186998 0 P 0 ;0
L 1.53971998 -2.07086998 1.60068002 -2.07086998 0 P 0 ;0
L 1.53833002 -2.06986998 1.59993002 -2.06986998 0 P 0 ;0
L 1.53693002 -2.06886998 1.59908002 -2.06886998 0 P 0 ;0
L 1.53556004 -2.06786998 1.59821004 -2.06786998 0 P 0 ;0
L 1.53418996 -2.06686998 1.59733996 -2.06686998 0 P 0 ;0
L 1.53281998 -2.06586998 1.59646998 -2.06586998 0 P 0 ;0
L 1.53145 -2.06486998 1.5955 -2.06486998 0 P 0 ;0
L 1.53008002 -2.06386998 1.59453002 -2.06386998 0 P 0 ;0
L 1.52871004 -2.06286998 1.59356004 -2.06286998 0 P 0 ;0
L 1.52733996 -2.06186998 1.59253002 -2.06186998 0 P 0 ;0
L 1.52596998 -2.06086998 1.59145 -2.06086998 0 P 0 ;0
L 1.5246 -2.05986998 1.59038002 -2.05986998 0 P 0 ;0
L 1.52323002 -2.05886998 1.5893 -2.05886998 0 P 0 ;0
L 1.52186004 -2.05786998 1.58813996 -2.05786998 0 P 0 ;0
L 1.52053996 -2.05686998 1.58696004 -2.05686998 0 P 0 ;0
L 1.51935 -2.05586998 1.58576998 -2.05586998 0 P 0 ;0
L 1.51816004 -2.05486998 1.58456998 -2.05486998 0 P 0 ;0
L 1.51706998 -2.05386998 1.58321004 -2.05386998 0 P 0 ;0
L 1.51603996 -2.05286998 1.58185 -2.05286998 0 P 0 ;0
L 1.51501998 -2.05186998 1.58048996 -2.05186998 0 P 0 ;0
L 1.51408996 -2.05086998 1.57913002 -2.05086998 0 P 0 ;0
L 1.5132 -2.04986998 1.57776998 -2.04986998 0 P 0 ;0
L 1.51231998 -2.04886998 1.57641998 -2.04886998 0 P 0 ;0
L 1.51151004 -2.04786998 1.57505 -2.04786998 0 P 0 ;0
L 1.51075 -2.04686998 1.57365 -2.04686998 0 P 0 ;0
L 1.51008002 -2.04586998 1.57223002 -2.04586998 0 P 0 ;0
L 1.50945 -2.04486998 1.57081004 -2.04486998 0 P 0 ;0
L 1.50888002 -2.04386998 1.56938996 -2.04386998 0 P 0 ;0
L 1.50836004 -2.04286998 1.56796998 -2.04286998 0 P 0 ;0
L 1.5079 -2.04186998 1.56655 -2.04186998 0 P 0 ;0
L 1.50748002 -2.04086998 1.56518996 -2.04086998 0 P 0 ;0
L 1.50708996 -2.03986998 1.564 -2.03986998 0 P 0 ;0
L 1.50676004 -2.03886998 1.56296998 -2.03886998 0 P 0 ;0
L 1.50641998 -2.03786998 1.56206004 -2.03786998 0 P 0 ;0
L 1.50616998 -2.03686998 1.56125 -2.03686998 0 P 0 ;0
L 1.50591004 -2.03586998 1.56066998 -2.03586998 0 P 0 ;0
L 1.5057 -2.03486998 1.56031998 -2.03486998 0 P 0 ;0
L 1.50551998 -2.03386998 1.56016004 -2.03386998 0 P 0 ;0
L 1.50533996 -2.03286998 1.56016998 -2.03286998 0 P 0 ;0
L 1.50523996 -2.03186998 1.56036004 -2.03186998 0 P 0 ;0
L 1.50513002 -2.03086998 1.56071998 -2.03086998 0 P 0 ;0
L 1.50506998 -2.02986998 1.56131004 -2.02986998 0 P 0 ;0
L 1.50503996 -2.02886998 1.5622 -2.02886998 0 P 0 ;0
L 1.50501004 -2.02786998 1.56355 -2.02786998 0 P 0 ;0
L 1.50501998 -2.02686998 1.5657 -2.02686998 0 P 0 ;0
L 1.50506998 -2.02586998 1.60378996 -2.02586998 0 P 0 ;0
L 1.50511998 -2.02486998 1.60371004 -2.02486998 0 P 0 ;0
L 1.50521004 -2.02386998 1.60363996 -2.02386998 0 P 0 ;0
L 1.50533996 -2.02286998 1.60356998 -2.02286998 0 P 0 ;0
L 1.50546998 -2.02186998 1.6035 -2.02186998 0 P 0 ;0
L 1.50563996 -2.02086998 1.60343002 -2.02086998 0 P 0 ;0
L 1.50585 -2.01986998 1.60336004 -2.01986998 0 P 0 ;0
L 1.50606004 -2.01886998 1.60328996 -2.01886998 0 P 0 ;0
L 1.50633002 -2.01786998 1.60321998 -2.01786998 0 P 0 ;0
L 1.50661998 -2.01686998 1.60315 -2.01686998 0 P 0 ;0
L 1.50691004 -2.01586998 1.60308002 -2.01586998 0 P 0 ;0
L 1.50726998 -2.01486998 1.603 -2.01486998 0 P 0 ;0
L 1.50766004 -2.01386998 1.60293002 -2.01386998 0 P 0 ;0
L 1.50808996 -2.01286998 1.60285 -2.01286998 0 P 0 ;0
L 1.50856998 -2.01186998 1.60278002 -2.01186998 0 P 0 ;0
L 1.50908996 -2.01086998 1.6027 -2.01086998 0 P 0 ;0
L 1.50966004 -2.00986998 1.60261998 -2.00986998 0 P 0 ;0
L 1.51028996 -2.00886998 1.60255 -2.00886998 0 P 0 ;0
L 1.51096998 -2.00786998 1.60246998 -2.00786998 0 P 0 ;0
L 1.51171998 -2.00686998 1.6024 -2.00686998 0 P 0 ;0
L 1.51253996 -2.00586998 1.60233002 -2.00586998 0 P 0 ;0
L 1.51343996 -2.00486998 1.60225 -2.00486998 0 P 0 ;0
L 1.5144 -2.00386998 1.60218002 -2.00386998 0 P 0 ;0
L 1.51551998 -2.00286998 1.6021 -2.00286998 0 P 0 ;0
L 1.51663996 -2.00186998 1.60203002 -2.00186998 0 P 0 ;0
L 1.51795 -2.00086998 1.60195 -2.00086998 0 P 0 ;0
L 1.51928996 -1.99986998 1.60183996 -1.99986998 0 P 0 ;0
L 1.52086998 -1.99886998 1.60173002 -1.99886998 0 P 0 ;0
L 1.52258996 -1.99786998 1.60156998 -1.99786998 0 P 0 ;0
L 1.52451004 -1.99686998 1.60138996 -1.99686998 0 P 0 ;0
L 1.52686998 -1.99586998 1.60106998 -1.99586998 0 P 0 ;0
L 1.52976004 -1.99486998 1.59943996 -1.99486998 0 P 0 ;0
L 1.53283002 -1.99386998 1.59543002 -1.99386998 0 P 0 ;0
L 1.53678996 -1.99286998 1.59003996 -1.99286998 0 P 0 ;0
L 1.54173996 -1.99186998 1.58073996 -1.99186998 0 P 0 ;0
L 1.55036998 -1.99086998 1.56493002 -1.99086998 0 P 0 ;0
L 1.6036 -2.03086998 1.60413996 -2.03086998 0 P 0 ;0
L 1.59891004 -2.02986998 1.60406998 -2.02986998 0 P 0 ;0
L 1.59435 -2.02886998 1.604 -2.02886998 0 P 0 ;0
L 1.58838996 -2.02786998 1.60393002 -2.02786998 0 P 0 ;0
L 1.57981004 -2.02686998 1.60386004 -2.02686998 0 P 0 ;0
L 1.54575 -1.98923996 1.53931998 -1.99021998 0 P 0 ;0
L 1.53931998 -1.99021998 1.53298996 -1.99171998 0 P 0 ;0
L 1.53298996 -1.99171998 1.52678996 -1.99373996 0 P 0 ;0
L 1.52678996 -1.99373996 1.52376998 -1.995 0 P 0 ;0
L 1.52376998 -1.995 1.52086998 -1.99651004 0 P 0 ;0
L 1.52086998 -1.99651004 1.5181 -1.99826004 0 P 0 ;0
L 1.5181 -1.99826004 1.51548002 -2.00023002 0 P 0 ;0
L 1.51548002 -2.00023002 1.51301004 -2.00243002 0 P 0 ;0
L 1.51301004 -2.00243002 1.51128996 -2.00423002 0 P 0 ;0
L 1.51128996 -2.00423002 1.50971998 -2.00616004 0 P 0 ;0
L 1.50971998 -2.00616004 1.50831004 -2.00821004 0 P 0 ;0
L 1.50831004 -2.00821004 1.50706998 -2.01036998 0 P 0 ;0
L 1.50706998 -2.01036998 1.50598996 -2.01261998 0 P 0 ;0
L 1.50598996 -2.01261998 1.50508996 -2.01496998 0 P 0 ;0
L 1.50508996 -2.01496998 1.5042 -2.01801004 0 P 0 ;0
L 1.5042 -2.01801004 1.50355 -2.02111004 0 P 0 ;0
L 1.50355 -2.02111004 1.50313996 -2.02426004 0 P 0 ;0
L 1.50313996 -2.02426004 1.50298996 -2.02743002 0 P 0 ;0
L 1.50298996 -2.02743002 1.50308996 -2.03063002 0 P 0 ;0
L 1.50308996 -2.03063002 1.50338002 -2.03326998 0 P 0 ;0
L 1.50338002 -2.03326998 1.50385 -2.03588002 0 P 0 ;0
L 1.50385 -2.03588002 1.50451004 -2.03845 0 P 0 ;0
L 1.50451004 -2.03845 1.50535 -2.04096998 0 P 0 ;0
L 1.50535 -2.04096998 1.50633002 -2.0433 0 P 0 ;0
L 1.50633002 -2.0433 1.5075 -2.04553002 0 P 0 ;0
L 1.5075 -2.04553002 1.50883996 -2.04766998 0 P 0 ;0
L 1.50883996 -2.04766998 1.51036998 -2.04968996 0 P 0 ;0
L 1.51036998 -2.04968996 1.51323002 -2.05291998 0 P 0 ;0
L 1.51323002 -2.05291998 1.51631998 -2.05593996 0 P 0 ;0
L 1.51631998 -2.05593996 1.51961998 -2.05871004 0 P 0 ;0
L 1.51961998 -2.05871004 1.53591004 -2.0706 0 P 0 ;0
L 1.53591004 -2.0706 1.54668002 -2.07831004 0 P 0 ;0
L 1.54668002 -2.07831004 1.54793996 -2.07933996 0 P 0 ;0
L 1.54793996 -2.07933996 1.54911998 -2.08046998 0 P 0 ;0
L 1.54911998 -2.08046998 1.55021004 -2.08168002 0 P 0 ;0
L 1.55021004 -2.08168002 1.5512 -2.08298996 0 P 0 ;0
L 1.5512 -2.08298996 1.55136004 -2.08323002 0 P 0 ;0
L 1.55136004 -2.08323002 1.5515 -2.08348002 0 P 0 ;0
L 1.5515 -2.08348002 1.55161004 -2.08373996 0 P 0 ;0
L 1.55161004 -2.08373996 1.5517 -2.08401998 0 P 0 ;0
L 1.5517 -2.08401998 1.55176998 -2.0843 0 P 0 ;0
L 1.55176998 -2.0843 1.55181004 -2.08458002 0 P 0 ;0
L 1.55181004 -2.08458002 1.55183002 -2.08486998 0 P 0 ;0
L 1.55183002 -2.08486998 1.55181998 -2.08516004 0 P 0 ;0
L 1.55181998 -2.08516004 1.55178996 -2.08545 0 P 0 ;0
L 1.55178996 -2.08545 1.55173996 -2.08573002 0 P 0 ;0
L 1.55173996 -2.08573002 1.55166004 -2.086 0 P 0 ;0
L 1.55166004 -2.086 1.55156004 -2.08628002 0 P 0 ;0
L 1.55156004 -2.08628002 1.55136998 -2.08666998 0 P 0 ;0
L 1.55136998 -2.08666998 1.55115 -2.08703996 0 P 0 ;0
L 1.55115 -2.08703996 1.5509 -2.08738996 0 P 0 ;0
L 1.5509 -2.08738996 1.55063002 -2.08771998 0 P 0 ;0
L 1.55063002 -2.08771998 1.55033002 -2.08803002 0 P 0 ;0
L 1.55033002 -2.08803002 1.55 -2.08831004 0 P 0 ;0
L 1.55 -2.08831004 1.54966004 -2.08856004 0 P 0 ;0
L 1.54966004 -2.08856004 1.54928996 -2.08878996 0 P 0 ;0
L 1.54928996 -2.08878996 1.5489 -2.08898996 0 P 0 ;0
L 1.5489 -2.08898996 1.54786004 -2.08941004 0 P 0 ;0
L 1.54786004 -2.08941004 1.54678996 -2.08973996 0 P 0 ;0
L 1.54678996 -2.08973996 1.54568002 -2.08998002 0 P 0 ;0
L 1.54568002 -2.08998002 1.54456998 -2.09011998 0 P 0 ;0
L 1.54456998 -2.09011998 1.54343996 -2.09016998 0 P 0 ;0
L 1.54343996 -2.09016998 1.53906998 -2.09003002 0 P 0 ;0
L 1.53906998 -2.09003002 1.53468002 -2.08961998 0 P 0 ;0
L 1.53468002 -2.08961998 1.52908996 -2.08878996 0 P 0 ;0
L 1.52908996 -2.08878996 1.52351004 -2.08766004 0 P 0 ;0
L 1.52351004 -2.08766004 1.51005 -2.08418996 0 P 0 ;0
L 1.51005 -2.08418996 1.50631004 -2.08318002 0 P 0 ;0
L 1.50631004 -2.08318002 1.50308002 -2.08238996 0 P 0 ;0
L 1.50308002 -2.08238996 1.50033996 -2.08183002 0 P 0 ;0
L 1.50033996 -2.08183002 1.5003 -2.08181998 0 P 0 ;0
L 1.5003 -2.08181998 1.50016004 -2.08181998 0 P 0 ;0
L 1.50016004 -2.08181998 1.50011998 -2.08183002 0 P 0 ;0
L 1.50011998 -2.08183002 1.50006998 -2.08183996 0 P 0 ;0
L 1.50006998 -2.08183996 1.50003002 -2.08186004 0 P 0 ;0
L 1.50003002 -2.08186004 1.49998996 -2.08186998 0 P 0 ;0
L 1.49998996 -2.08186998 1.49995 -2.08188996 0 P 0 ;0
L 1.49995 -2.08188996 1.49991004 -2.08191998 0 P 0 ;0
L 1.49991004 -2.08191998 1.49988002 -2.08195 0 P 0 ;0
L 1.49988002 -2.08195 1.49983996 -2.08198002 0 P 0 ;0
L 1.49983996 -2.08198002 1.4997 -2.08213996 0 P 0 ;0
L 1.4997 -2.08213996 1.49956004 -2.08231998 0 P 0 ;0
L 1.49956004 -2.08231998 1.49943996 -2.0825 0 P 0 ;0
L 1.49943996 -2.0825 1.49933996 -2.0827 0 P 0 ;0
L 1.49933996 -2.0827 1.49925 -2.0829 0 P 0 ;0
L 1.49925 -2.0829 1.49918996 -2.08311004 0 P 0 ;0
L 1.49918996 -2.08311004 1.49913996 -2.08333002 0 P 0 ;0
L 1.49913996 -2.08333002 1.49911004 -2.08355 0 P 0 ;0
L 1.49911004 -2.08355 1.4991 -2.08376998 0 P 0 ;0
L 1.4991 -2.08376998 1.49911004 -2.08398996 0 P 0 ;0
L 1.49911004 -2.08398996 1.50071004 -2.10395 0 P 0 ;0
L 1.50071004 -2.10395 1.5024 -2.12403996 0 P 0 ;0
L 1.5024 -2.12403996 1.50241998 -2.12418002 0 P 0 ;0
L 1.50241998 -2.12418002 1.50246004 -2.12431004 0 P 0 ;0
L 1.50246004 -2.12431004 1.50248996 -2.12445 0 P 0 ;0
L 1.50248996 -2.12445 1.50255 -2.12456998 0 P 0 ;0
L 1.50255 -2.12456998 1.50261004 -2.1247 0 P 0 ;0
L 1.50261004 -2.1247 1.50276998 -2.12491998 0 P 0 ;0
L 1.50276998 -2.12491998 1.50286004 -2.12501998 0 P 0 ;0
L 1.50286004 -2.12501998 1.50296998 -2.12511998 0 P 0 ;0
L 1.50296998 -2.12511998 1.50308002 -2.12521004 0 P 0 ;0
L 1.50308002 -2.12521004 1.50318996 -2.12528002 0 P 0 ;0
L 1.50318996 -2.12528002 1.50331998 -2.12535 0 P 0 ;0
L 1.50331998 -2.12535 1.50343996 -2.1254 0 P 0 ;0
L 1.50343996 -2.1254 1.50391998 -2.12556004 0 P 0 ;0
L 1.50391998 -2.12556004 1.5044 -2.12568996 0 P 0 ;0
L 1.5044 -2.12568996 1.50848002 -2.12648996 0 P 0 ;0
L 1.50848002 -2.12648996 1.51328996 -2.12738002 0 P 0 ;0
L 1.51328996 -2.12738002 1.51873996 -2.12833996 0 P 0 ;0
L 1.51873996 -2.12833996 1.52606004 -2.12945 0 P 0 ;0
L 1.52606004 -2.12945 1.53343996 -2.13023002 0 P 0 ;0
L 1.53343996 -2.13023002 1.54886998 -2.13086998 0 P 0 ;0
L 1.54886998 -2.13086998 1.56305 -2.1303 0 P 0 ;0
L 1.56305 -2.1303 1.56666004 -2.12988996 0 P 0 ;0
L 1.56666004 -2.12988996 1.57023002 -2.12926998 0 P 0 ;0
L 1.57023002 -2.12926998 1.5738 -2.12843002 0 P 0 ;0
L 1.5738 -2.12843002 1.57945 -2.12668996 0 P 0 ;0
L 1.57945 -2.12668996 1.58498002 -2.12456998 0 P 0 ;0
L 1.58498002 -2.12456998 1.58793996 -2.12318002 0 P 0 ;0
L 1.58793996 -2.12318002 1.59078996 -2.12156004 0 P 0 ;0
L 1.59078996 -2.12156004 1.59348996 -2.11971998 0 P 0 ;0
L 1.59348996 -2.11971998 1.59525 -2.11833002 0 P 0 ;0
L 1.59525 -2.11833002 1.5969 -2.11681998 0 P 0 ;0
L 1.5969 -2.11681998 1.59846004 -2.11521004 0 P 0 ;0
L 1.59846004 -2.11521004 1.59991004 -2.11348002 0 P 0 ;0
L 1.59991004 -2.11348002 1.60175 -2.11093996 0 P 0 ;0
L 1.60175 -2.11093996 1.60338002 -2.10826998 0 P 0 ;0
L 1.60338002 -2.10826998 1.60481004 -2.10548002 0 P 0 ;0
L 1.60481004 -2.10548002 1.60573002 -2.10321004 0 P 0 ;0
L 1.60573002 -2.10321004 1.60646004 -2.10088002 0 P 0 ;0
L 1.60646004 -2.10088002 1.60698002 -2.09848996 0 P 0 ;0
L 1.60698002 -2.09848996 1.60756004 -2.09421998 0 P 0 ;0
L 1.60756004 -2.09421998 1.6078 -2.08991004 0 P 0 ;0
L 1.6078 -2.08991004 1.60768996 -2.08565 0 P 0 ;0
L 1.60768996 -2.08565 1.60723002 -2.08141998 0 P 0 ;0
L 1.60723002 -2.08141998 1.60691998 -2.07968002 0 P 0 ;0
L 1.60691998 -2.07968002 1.60646998 -2.07796998 0 P 0 ;0
L 1.60646998 -2.07796998 1.60591998 -2.0763 0 P 0 ;0
L 1.60591998 -2.0763 1.60523002 -2.07466998 0 P 0 ;0
L 1.60523002 -2.07466998 1.60411998 -2.07246998 0 P 0 ;0
L 1.60411998 -2.07246998 1.60281004 -2.07038002 0 P 0 ;0
L 1.60281004 -2.07038002 1.60131998 -2.06838996 0 P 0 ;0
L 1.60131998 -2.06838996 1.59803996 -2.06461998 0 P 0 ;0
L 1.59803996 -2.06461998 1.59455 -2.06101998 0 P 0 ;0
L 1.59455 -2.06101998 1.59031998 -2.05708996 0 P 0 ;0
L 1.59031998 -2.05708996 1.58586004 -2.05333996 0 P 0 ;0
L 1.58586004 -2.05333996 1.57588002 -2.04598996 0 P 0 ;0
L 1.57588002 -2.04598996 1.56685 -2.03963996 0 P 0 ;0
L 1.56685 -2.03963996 1.56578002 -2.03878996 0 P 0 ;0
L 1.56578002 -2.03878996 1.56476998 -2.03786004 0 P 0 ;0
L 1.56476998 -2.03786004 1.56383002 -2.03686998 0 P 0 ;0
L 1.56383002 -2.03686998 1.56295 -2.0358 0 P 0 ;0
L 1.56295 -2.0358 1.56276998 -2.03555 0 P 0 ;0
L 1.56276998 -2.03555 1.56261004 -2.03528002 0 P 0 ;0
L 1.56261004 -2.03528002 1.56246998 -2.035 0 P 0 ;0
L 1.56246998 -2.035 1.56236004 -2.03471998 0 P 0 ;0
L 1.56236004 -2.03471998 1.56226998 -2.03441998 0 P 0 ;0
L 1.56226998 -2.03441998 1.5622 -2.03411998 0 P 0 ;0
L 1.5622 -2.03411998 1.56216004 -2.03381998 0 P 0 ;0
L 1.56216004 -2.03381998 1.56213996 -2.03351004 0 P 0 ;0
L 1.56213996 -2.03351004 1.56215 -2.0332 0 P 0 ;0
L 1.56215 -2.0332 1.56218002 -2.03288996 0 P 0 ;0
L 1.56218002 -2.03288996 1.56225 -2.03253996 0 P 0 ;0
L 1.56225 -2.03253996 1.56233996 -2.03221004 0 P 0 ;0
L 1.56233996 -2.03221004 1.56246004 -2.03186998 0 P 0 ;0
L 1.56246004 -2.03186998 1.56261004 -2.03156004 0 P 0 ;0
L 1.56261004 -2.03156004 1.56278996 -2.03125 0 P 0 ;0
L 1.56278996 -2.03125 1.56298002 -2.03096004 0 P 0 ;0
L 1.56298002 -2.03096004 1.56321004 -2.03068996 0 P 0 ;0
L 1.56321004 -2.03068996 1.56345 -2.03043996 0 P 0 ;0
L 1.56345 -2.03043996 1.56371004 -2.0302 0 P 0 ;0
L 1.56371004 -2.0302 1.56416004 -2.02986004 0 P 0 ;0
L 1.56416004 -2.02986004 1.56463002 -2.02955 0 P 0 ;0
L 1.56463002 -2.02955 1.56511998 -2.02928002 0 P 0 ;0
L 1.56511998 -2.02928002 1.56561998 -2.02903002 0 P 0 ;0
L 1.56561998 -2.02903002 1.56611998 -2.02883996 0 P 0 ;0
L 1.56611998 -2.02883996 1.56663996 -2.02866998 0 P 0 ;0
L 1.56663996 -2.02866998 1.56716004 -2.02855 0 P 0 ;0
L 1.56716004 -2.02855 1.5677 -2.02846998 0 P 0 ;0
L 1.5677 -2.02846998 1.56926998 -2.02835 0 P 0 ;0
L 1.56926998 -2.02835 1.57085 -2.02833996 0 P 0 ;0
L 1.57085 -2.02833996 1.57725 -2.02866998 0 P 0 ;0
L 1.57725 -2.02866998 1.58205 -2.02906004 0 P 0 ;0
L 1.58205 -2.02906004 1.58746998 -2.02975 0 P 0 ;0
L 1.58746998 -2.02975 1.59271004 -2.03056998 0 P 0 ;0
L 1.59271004 -2.03056998 1.59681004 -2.03143002 0 P 0 ;0
L 1.59681004 -2.03143002 1.60016004 -2.03221998 0 P 0 ;0
L 1.60016004 -2.03221998 1.60308002 -2.03281004 0 P 0 ;0
L 1.60308002 -2.03281004 1.60553996 -2.03323996 0 P 0 ;0
L 1.60553996 -2.03323996 1.60568996 -2.03323996 0 P 0 ;0
L 1.60568996 -2.03323996 1.60576998 -2.03321998 0 P 0 ;0
L 1.60576998 -2.03321998 1.60586004 -2.03316004 0 P 0 ;0
L 1.60586004 -2.03316004 1.6059 -2.03313996 0 P 0 ;0
L 1.6059 -2.03313996 1.60591998 -2.03311004 0 P 0 ;0
L 1.60591998 -2.03311004 1.60598996 -2.03303996 0 P 0 ;0
L 1.60598996 -2.03303996 1.60605 -2.03296998 0 P 0 ;0
L 1.60605 -2.03296998 1.6061 -2.03288996 0 P 0 ;0
L 1.6061 -2.03288996 1.60618002 -2.03273002 0 P 0 ;0
L 1.60618002 -2.03273002 1.60621004 -2.03263002 0 P 0 ;0
L 1.60621004 -2.03263002 1.60623002 -2.03253996 0 P 0 ;0
L 1.60623002 -2.03253996 1.60625 -2.03236004 0 P 0 ;0
L 1.60625 -2.03236004 1.60623996 -2.03226004 0 P 0 ;0
L 1.60623996 -2.03226004 1.60508002 -2.01578002 0 P 0 ;0
L 1.60508002 -2.01578002 1.60393996 -2.00068002 0 P 0 ;0
L 1.60393996 -2.00068002 1.60368002 -1.99833996 0 P 0 ;0
L 1.60368002 -1.99833996 1.60326998 -1.99601004 0 P 0 ;0
L 1.60326998 -1.99601004 1.60321004 -1.99576998 0 P 0 ;0
L 1.60321004 -1.99576998 1.60313996 -1.99553002 0 P 0 ;0
L 1.60313996 -1.99553002 1.60303996 -1.9953 0 P 0 ;0
L 1.60303996 -1.9953 1.60293002 -1.99508002 0 P 0 ;0
L 1.60293002 -1.99508002 1.60281004 -1.99486004 0 P 0 ;0
L 1.60281004 -1.99486004 1.60261998 -1.9946 0 P 0 ;0
L 1.60261998 -1.9946 1.60241004 -1.99435 0 P 0 ;0
L 1.60241004 -1.99435 1.60218002 -1.99411998 0 P 0 ;0
L 1.60218002 -1.99411998 1.60191998 -1.99391004 0 P 0 ;0
L 1.60191998 -1.99391004 1.60161004 -1.99368996 0 P 0 ;0
L 1.60161004 -1.99368996 1.60128996 -1.99348996 0 P 0 ;0
L 1.60128996 -1.99348996 1.60095 -1.99331998 0 P 0 ;0
L 1.60095 -1.99331998 1.6006 -1.99316004 0 P 0 ;0
L 1.6006 -1.99316004 1.59966004 -1.99283002 0 P 0 ;0
L 1.59966004 -1.99283002 1.59871004 -1.99255 0 P 0 ;0
L 1.59871004 -1.99255 1.5933 -1.99135 0 P 0 ;0
L 1.5933 -1.99135 1.5878 -1.9905 0 P 0 ;0
L 1.5878 -1.9905 1.57285 -1.98915 0 P 0 ;0
L 1.57285 -1.98915 1.55763996 -1.98861004 0 P 0 ;0
L 1.55763996 -1.98861004 1.55171004 -1.98876004 0 P 0 ;0
L 1.55171004 -1.98876004 1.54575 -1.98923996 0 P 0 ;0
L 1.53011998 -2.12786998 1.5666 -2.12786998 0 P 0 ;0
L 1.52236004 -2.12686998 1.57168002 -2.12686998 0 P 0 ;0
L 1.51621998 -2.12586998 1.5753 -2.12586998 0 P 0 ;0
L 1.51071004 -2.12486998 1.57856004 -2.12486998 0 P 0 ;0
L 1.50553002 -2.12386998 1.58121004 -2.12386998 0 P 0 ;0
L 1.50431004 -2.12286998 1.58381998 -2.12286998 0 P 0 ;0
L 1.50423002 -2.12186998 1.58601998 -2.12186998 0 P 0 ;0
L 1.50413996 -2.12086998 1.58796004 -2.12086998 0 P 0 ;0
L 1.50406004 -2.11986998 1.58971004 -2.11986998 0 P 0 ;0
L 1.50396998 -2.11886998 1.59118002 -2.11886998 0 P 0 ;0
L 1.50388996 -2.11786998 1.5926 -2.11786998 0 P 0 ;0
L 1.50381004 -2.11686998 1.59386004 -2.11686998 0 P 0 ;0
L 1.50371998 -2.11586998 1.59496998 -2.11586998 0 P 0 ;0
L 1.50363996 -2.11486998 1.59601004 -2.11486998 0 P 0 ;0
L 1.50355 -2.11386998 1.59696998 -2.11386998 0 P 0 ;0
L 1.50346998 -2.11286998 1.59781004 -2.11286998 0 P 0 ;0
L 1.50338002 -2.11186998 1.5986 -2.11186998 0 P 0 ;0
L 1.5033 -2.11086998 1.59933002 -2.11086998 0 P 0 ;0
L 1.50321004 -2.10986998 1.60005 -2.10986998 0 P 0 ;0
L 1.50313002 -2.10886998 1.60066998 -2.10886998 0 P 0 ;0
L 1.50305 -2.10786998 1.60128002 -2.10786998 0 P 0 ;0
L 1.50296004 -2.10686998 1.60185 -2.10686998 0 P 0 ;0
L 1.50288002 -2.10586998 1.60236004 -2.10586998 0 P 0 ;0
L 1.50278996 -2.10486998 1.60286998 -2.10486998 0 P 0 ;0
L 1.50271004 -2.10386998 1.6033 -2.10386998 0 P 0 ;0
L 1.50263002 -2.10286998 1.60371004 -2.10286998 0 P 0 ;0
L 1.50255 -2.10186998 1.60405 -2.10186998 0 P 0 ;0
L 1.50246998 -2.10086998 1.60436004 -2.10086998 0 P 0 ;0
L 1.50238996 -2.09986998 1.60463002 -2.09986998 0 P 0 ;0
L 1.50231004 -2.09886998 1.60485 -2.09886998 0 P 0 ;0
L 1.50223002 -2.09786998 1.60505 -2.09786998 0 P 0 ;0
L 1.50215 -2.09686998 1.60518002 -2.09686998 0 P 0 ;0
L 1.50206998 -2.09586998 1.60531998 -2.09586998 0 P 0 ;0
L 1.50198996 -2.09486998 1.60545 -2.09486998 0 P 0 ;0
L 1.50191004 -2.09386998 1.60558002 -2.09386998 0 P 0 ;0
L 1.50183002 -2.09286998 1.60563002 -2.09286998 0 P 0 ;0
L 1.50175 -2.09186998 1.53725 -2.09186998 0 P 0 ;0
L 1.54638996 -2.09186998 1.60568996 -2.09186998 0 P 0 ;0
L 1.50166998 -2.09086998 1.5295 -2.09086998 0 P 0 ;0
L 1.54956998 -2.09086998 1.60573996 -2.09086998 0 P 0 ;0
L 1.50158996 -2.08986998 1.52436004 -2.08986998 0 P 0 ;0
L 1.55125 -2.08986998 1.60578996 -2.08986998 0 P 0 ;0
L 1.50151004 -2.08886998 1.52021004 -2.08886998 0 P 0 ;0
L 1.55226998 -2.08886998 1.60576998 -2.08886998 0 P 0 ;0
L 1.50143002 -2.08786998 1.51633002 -2.08786998 0 P 0 ;0
L 1.55298002 -2.08786998 1.60573996 -2.08786998 0 P 0 ;0
L 1.50133996 -2.08686998 1.51246004 -2.08686998 0 P 0 ;0
L 1.55346998 -2.08686998 1.60571998 -2.08686998 0 P 0 ;0
L 1.50126998 -2.08586998 1.50861998 -2.08586998 0 P 0 ;0
L 1.55375 -2.08586998 1.60568996 -2.08586998 0 P 0 ;0
L 1.50118002 -2.08486998 1.50481004 -2.08486998 0 P 0 ;0
L 1.55383002 -2.08486998 1.60558996 -2.08486998 0 P 0 ;0
L 1.55371998 -2.08386998 1.60548996 -2.08386998 0 P 0 ;0
L 1.54886998 -2.12886998 1.53358996 -2.12823996 0 P 0 ;0
L 1.53358996 -2.12823996 1.52631998 -2.12746998 0 P 0 ;0
L 1.52631998 -2.12746998 1.51906004 -2.12636998 0 P 0 ;0
L 1.51906004 -2.12636998 1.51363002 -2.12541004 0 P 0 ;0
L 1.51363002 -2.12541004 1.50886998 -2.12451998 0 P 0 ;0
L 1.50886998 -2.12451998 1.50483996 -2.12373996 0 P 0 ;0
L 1.50483996 -2.12373996 1.50448996 -2.12365 0 P 0 ;0
L 1.50448996 -2.12365 1.50438002 -2.12361004 0 P 0 ;0
L 1.50438002 -2.12361004 1.5027 -2.10378002 0 P 0 ;0
L 1.5027 -2.10378002 1.50111998 -2.08403002 0 P 0 ;0
L 1.50111998 -2.08403002 1.50263996 -2.08433996 0 P 0 ;0
L 1.50263996 -2.08433996 1.50581004 -2.08511004 0 P 0 ;0
L 1.50581004 -2.08511004 1.50955 -2.08611998 0 P 0 ;0
L 1.50955 -2.08611998 1.52306004 -2.08961004 0 P 0 ;0
L 1.52306004 -2.08961004 1.52311004 -2.08961998 0 P 0 ;0
L 1.52311004 -2.08961998 1.52875 -2.09076004 0 P 0 ;0
L 1.52875 -2.09076004 1.5288 -2.09076004 0 P 0 ;0
L 1.5288 -2.09076004 1.53443996 -2.09161004 0 P 0 ;0
L 1.53443996 -2.09161004 1.53893996 -2.09203002 0 P 0 ;0
L 1.53893996 -2.09203002 1.54346004 -2.09216998 0 P 0 ;0
L 1.54346004 -2.09216998 1.54473996 -2.09211004 0 P 0 ;0
L 1.54473996 -2.09211004 1.54603002 -2.09195 0 P 0 ;0
L 1.54603002 -2.09195 1.54728996 -2.09166998 0 P 0 ;0
L 1.54728996 -2.09166998 1.54853002 -2.09128996 0 P 0 ;0
L 1.54853002 -2.09128996 1.54973002 -2.09081004 0 P 0 ;0
L 1.54973002 -2.09081004 1.55026998 -2.09053996 0 P 0 ;0
L 1.55026998 -2.09053996 1.55076998 -2.09023002 0 P 0 ;0
L 1.55076998 -2.09023002 1.55118002 -2.08991998 0 P 0 ;0
L 1.55118002 -2.08991998 1.55118002 -2.08991004 0 P 0 ;0
L 1.55118002 -2.08991004 1.5512 -2.08991004 0 P 0 ;0
L 1.5512 -2.08991004 1.55125 -2.08986998 0 P 0 ;0
L 1.55125 -2.08986998 1.55131004 -2.08981998 0 P 0 ;0
L 1.55131004 -2.08981998 1.55126998 -2.08978002 0 P 0 ;0
L 1.55126998 -2.08978002 1.55136004 -2.08978002 0 P 0 ;0
L 1.55136004 -2.08978002 1.5517 -2.08948996 0 P 0 ;0
L 1.5517 -2.08948996 1.55206004 -2.08911998 0 P 0 ;0
L 1.55206004 -2.08911998 1.55205 -2.08911004 0 P 0 ;0
L 1.55205 -2.08911004 1.55206004 -2.08911004 0 P 0 ;0
L 1.55206004 -2.08911004 1.55211998 -2.08906004 0 P 0 ;0
L 1.55211998 -2.08906004 1.55248996 -2.08861004 0 P 0 ;0
L 1.55248996 -2.08861004 1.55283996 -2.08811998 0 P 0 ;0
L 1.55283996 -2.08811998 1.55313996 -2.08761004 0 P 0 ;0
L 1.55313996 -2.08761004 1.5534 -2.08706998 0 P 0 ;0
L 1.5534 -2.08706998 1.55356004 -2.08663002 0 P 0 ;0
L 1.55356004 -2.08663002 1.55368996 -2.08618996 0 P 0 ;0
L 1.55368996 -2.08618996 1.55376998 -2.08573996 0 P 0 ;0
L 1.55376998 -2.08573996 1.55378002 -2.08565 0 P 0 ;0
L 1.55378002 -2.08565 1.55381998 -2.08528002 0 P 0 ;0
L 1.55381998 -2.08528002 1.55383002 -2.08481998 0 P 0 ;0
L 1.55383002 -2.08481998 1.5538 -2.08436998 0 P 0 ;0
L 1.5538 -2.08436998 1.55373002 -2.08391998 0 P 0 ;0
L 1.55373002 -2.08391998 1.55361998 -2.08346998 0 P 0 ;0
L 1.55361998 -2.08346998 1.55348002 -2.08303996 0 P 0 ;0
L 1.55348002 -2.08303996 1.5533 -2.08261004 0 P 0 ;0
L 1.5533 -2.08261004 1.55308996 -2.08221004 0 P 0 ;0
L 1.55308996 -2.08221004 1.55283996 -2.08183002 0 P 0 ;0
L 1.55283996 -2.08183002 1.55175 -2.0804 0 P 0 ;0
L 1.55175 -2.0804 1.55055 -2.07908002 0 P 0 ;0
L 1.55055 -2.07908002 1.54926004 -2.07783996 0 P 0 ;0
L 1.54926004 -2.07783996 1.54788996 -2.07671998 0 P 0 ;0
L 1.54788996 -2.07671998 1.53706998 -2.06898002 0 P 0 ;0
L 1.53706998 -2.06898002 1.52085 -2.05713996 0 P 0 ;0
L 1.52085 -2.05713996 1.51766004 -2.05445 0 P 0 ;0
L 1.51766004 -2.05445 1.51468002 -2.05153996 0 P 0 ;0
L 1.51468002 -2.05153996 1.51191998 -2.04841998 0 P 0 ;0
L 1.51191998 -2.04841998 1.51048996 -2.04651998 0 P 0 ;0
L 1.51048996 -2.04651998 1.50923002 -2.04453002 0 P 0 ;0
L 1.50923002 -2.04453002 1.50813996 -2.04245 0 P 0 ;0
L 1.50813996 -2.04245 1.50721998 -2.04026004 0 P 0 ;0
L 1.50721998 -2.04026004 1.50643002 -2.03788002 0 P 0 ;0
L 1.50643002 -2.03788002 1.50581004 -2.03545 0 P 0 ;0
L 1.50581004 -2.03545 1.50536004 -2.03298996 0 P 0 ;0
L 1.50536004 -2.03298996 1.50508996 -2.0305 0 P 0 ;0
L 1.50508996 -2.0305 1.50498996 -2.02745 0 P 0 ;0
L 1.50498996 -2.02745 1.50513996 -2.02443996 0 P 0 ;0
L 1.50513996 -2.02443996 1.50551998 -2.02145 0 P 0 ;0
L 1.50551998 -2.02145 1.50613996 -2.0185 0 P 0 ;0
L 1.50613996 -2.0185 1.50698996 -2.01561004 0 P 0 ;0
L 1.50698996 -2.01561004 1.50783002 -2.01341004 0 P 0 ;0
L 1.50783002 -2.01341004 1.50883002 -2.0113 0 P 0 ;0
L 1.50883002 -2.0113 1.51 -2.00928002 0 P 0 ;0
L 1.51 -2.00928002 1.51133002 -2.00736004 0 P 0 ;0
L 1.51133002 -2.00736004 1.5128 -2.00555 0 P 0 ;0
L 1.5128 -2.00555 1.5144 -2.00386004 0 P 0 ;0
L 1.5144 -2.00386004 1.51675 -2.00176998 0 P 0 ;0
L 1.51675 -2.00176998 1.51923002 -1.9999 0 P 0 ;0
L 1.51923002 -1.9999 1.52186004 -1.99823996 0 P 0 ;0
L 1.52186004 -1.99823996 1.52461998 -1.99681004 0 P 0 ;0
L 1.52461998 -1.99681004 1.52748996 -1.99561004 0 P 0 ;0
L 1.52748996 -1.99561004 1.53353002 -1.99363996 0 P 0 ;0
L 1.53353002 -1.99363996 1.5397 -1.99218002 0 P 0 ;0
L 1.5397 -1.99218002 1.54598002 -1.99123002 0 P 0 ;0
L 1.54598002 -1.99123002 1.55181004 -1.99075 0 P 0 ;0
L 1.55181004 -1.99075 1.55763002 -1.99061998 0 P 0 ;0
L 1.55763002 -1.99061998 1.57273002 -1.99113996 0 P 0 ;0
L 1.57273002 -1.99113996 1.58755 -1.99248996 0 P 0 ;0
L 1.58755 -1.99248996 1.59293002 -1.99331998 0 P 0 ;0
L 1.59293002 -1.99331998 1.59821004 -1.99448996 0 P 0 ;0
L 1.59821004 -1.99448996 1.59905 -1.99473002 0 P 0 ;0
L 1.59905 -1.99473002 1.59986004 -1.99501998 0 P 0 ;0
L 1.59986004 -1.99501998 1.60008002 -1.99511998 0 P 0 ;0
L 1.60008002 -1.99511998 1.6003 -1.99523002 0 P 0 ;0
L 1.6003 -1.99523002 1.60051004 -1.99536004 0 P 0 ;0
L 1.60051004 -1.99536004 1.60071004 -1.9955 0 P 0 ;0
L 1.60071004 -1.9955 1.60083002 -1.99561004 0 P 0 ;0
L 1.60083002 -1.99561004 1.60093996 -1.99571004 0 P 0 ;0
L 1.60093996 -1.99571004 1.60103996 -1.99583002 0 P 0 ;0
L 1.60103996 -1.99583002 1.60111998 -1.99595 0 P 0 ;0
L 1.60111998 -1.99595 1.60116998 -1.99601998 0 P 0 ;0
L 1.60116998 -1.99601998 1.60121004 -1.99611004 0 P 0 ;0
L 1.60121004 -1.99611004 1.60125 -1.99621004 0 P 0 ;0
L 1.60125 -1.99621004 1.60128002 -1.9963 0 P 0 ;0
L 1.60128002 -1.9963 1.60131004 -1.99641004 0 P 0 ;0
L 1.60131004 -1.99641004 1.6017 -1.99861998 0 P 0 ;0
L 1.6017 -1.99861998 1.60195 -2.00086998 0 P 0 ;0
L 1.60195 -2.00086998 1.60308002 -2.01593002 0 P 0 ;0
L 1.60308002 -2.01593002 1.60415 -2.03096998 0 P 0 ;0
L 1.60415 -2.03096998 1.60345 -2.03083996 0 P 0 ;0
L 1.60345 -2.03083996 1.60058996 -2.03026004 0 P 0 ;0
L 1.60058996 -2.03026004 1.59723002 -2.02948002 0 P 0 ;0
L 1.59723002 -2.02948002 1.59721998 -2.02948002 0 P 0 ;0
L 1.59721998 -2.02948002 1.59306998 -2.0286 0 P 0 ;0
L 1.59306998 -2.0286 1.58776004 -2.02776998 0 P 0 ;0
L 1.58776004 -2.02776998 1.58226004 -2.02708002 0 P 0 ;0
L 1.58226004 -2.02708002 1.57738002 -2.02666998 0 P 0 ;0
L 1.57738002 -2.02666998 1.5709 -2.02633996 0 P 0 ;0
L 1.5709 -2.02633996 1.56918996 -2.02635 0 P 0 ;0
L 1.56918996 -2.02635 1.56746998 -2.02648996 0 P 0 ;0
L 1.56746998 -2.02648996 1.56678996 -2.02658996 0 P 0 ;0
L 1.56678996 -2.02658996 1.56611998 -2.02673996 0 P 0 ;0
L 1.56611998 -2.02673996 1.56546004 -2.02695 0 P 0 ;0
L 1.56546004 -2.02695 1.56481998 -2.0272 0 P 0 ;0
L 1.56481998 -2.0272 1.56418996 -2.0275 0 P 0 ;0
L 1.56418996 -2.0275 1.56358002 -2.02785 0 P 0 ;0
L 1.56358002 -2.02785 1.563 -2.02823002 0 P 0 ;0
L 1.563 -2.02823002 1.56245 -2.02865 0 P 0 ;0
L 1.56245 -2.02865 1.56206998 -2.02898996 0 P 0 ;0
L 1.56206998 -2.02898996 1.56171004 -2.02936004 0 P 0 ;0
L 1.56171004 -2.02936004 1.56138002 -2.02976004 0 P 0 ;0
L 1.56138002 -2.02976004 1.56108996 -2.03018996 0 P 0 ;0
L 1.56108996 -2.03018996 1.56083002 -2.03063996 0 P 0 ;0
L 1.56083002 -2.03063996 1.56061998 -2.0311 0 P 0 ;0
L 1.56061998 -2.0311 1.56043996 -2.03158996 0 P 0 ;0
L 1.56043996 -2.03158996 1.5603 -2.03208002 0 P 0 ;0
L 1.5603 -2.03208002 1.5602 -2.0326 0 P 0 ;0
L 1.5602 -2.0326 1.56015 -2.03308002 0 P 0 ;0
L 1.56015 -2.03308002 1.56013996 -2.03353996 0 P 0 ;0
L 1.56013996 -2.03353996 1.56016004 -2.03391004 0 P 0 ;0
L 1.56016004 -2.03391004 1.56048002 -2.03391004 0 P 0 ;0
L 1.56048002 -2.03391004 1.56016004 -2.03393002 0 P 0 ;0
L 1.56016004 -2.03393002 1.56016998 -2.03401004 0 P 0 ;0
L 1.56016998 -2.03401004 1.56023002 -2.03448002 0 P 0 ;0
L 1.56023002 -2.03448002 1.56025 -2.03456004 0 P 0 ;0
L 1.56025 -2.03456004 1.56033002 -2.03493002 0 P 0 ;0
L 1.56033002 -2.03493002 1.56046998 -2.03538002 0 P 0 ;0
L 1.56046998 -2.03538002 1.56063996 -2.03581998 0 P 0 ;0
L 1.56063996 -2.03581998 1.56085 -2.03623996 0 P 0 ;0
L 1.56085 -2.03623996 1.56108996 -2.03663996 0 P 0 ;0
L 1.56108996 -2.03663996 1.56136004 -2.03701998 0 P 0 ;0
L 1.56136004 -2.03701998 1.56233002 -2.03818996 0 P 0 ;0
L 1.56233002 -2.03818996 1.56336998 -2.03928996 0 P 0 ;0
L 1.56336998 -2.03928996 1.56448002 -2.04031004 0 P 0 ;0
L 1.56448002 -2.04031004 1.56566004 -2.04123996 0 P 0 ;0
L 1.56566004 -2.04123996 1.57471004 -2.04761998 0 P 0 ;0
L 1.57471004 -2.04761998 1.58461998 -2.05491004 0 P 0 ;0
L 1.58461998 -2.05491004 1.58898996 -2.05858996 0 P 0 ;0
L 1.58898996 -2.05858996 1.59315 -2.06245 0 P 0 ;0
L 1.59315 -2.06245 1.59656998 -2.06596998 0 P 0 ;0
L 1.59656998 -2.06596998 1.59976004 -2.06965 0 P 0 ;0
L 1.59976004 -2.06965 1.60116004 -2.07151004 0 P 0 ;0
L 1.60116004 -2.07151004 1.60238002 -2.07346004 0 P 0 ;0
L 1.60238002 -2.07346004 1.60341998 -2.0755 0 P 0 ;0
L 1.60341998 -2.0755 1.60403996 -2.077 0 P 0 ;0
L 1.60403996 -2.077 1.60456004 -2.07853996 0 P 0 ;0
L 1.60456004 -2.07853996 1.60496004 -2.08011004 0 P 0 ;0
L 1.60496004 -2.08011004 1.60525 -2.0817 0 P 0 ;0
L 1.60525 -2.0817 1.60568996 -2.08578002 0 P 0 ;0
L 1.60568996 -2.08578002 1.60578996 -2.08988002 0 P 0 ;0
L 1.60578996 -2.08988002 1.60556998 -2.09403002 0 P 0 ;0
L 1.60556998 -2.09403002 1.60501004 -2.09813996 0 P 0 ;0
L 1.60501004 -2.09813996 1.60451998 -2.10036998 0 P 0 ;0
L 1.60451998 -2.10036998 1.60383996 -2.10253996 0 P 0 ;0
L 1.60383996 -2.10253996 1.60298996 -2.10465 0 P 0 ;0
L 1.60298996 -2.10465 1.60163996 -2.1073 0 P 0 ;0
L 1.60163996 -2.1073 1.60008002 -2.10983002 0 P 0 ;0
L 1.60008002 -2.10983002 1.59833002 -2.11225 0 P 0 ;0
L 1.59833002 -2.11225 1.59696998 -2.11386998 0 P 0 ;0
L 1.59696998 -2.11386998 1.59551004 -2.11538996 0 P 0 ;0
L 1.59551004 -2.11538996 1.59395 -2.1168 0 P 0 ;0
L 1.59395 -2.1168 1.59231004 -2.11811004 0 P 0 ;0
L 1.59231004 -2.11811004 1.58973002 -2.11986004 0 P 0 ;0
L 1.58973002 -2.11986004 1.58701998 -2.1214 0 P 0 ;0
L 1.58701998 -2.1214 1.5842 -2.12273002 0 P 0 ;0
L 1.5842 -2.12273002 1.5788 -2.1248 0 P 0 ;0
L 1.5788 -2.1248 1.57326998 -2.12648996 0 P 0 ;0
L 1.57326998 -2.12648996 1.56983002 -2.12731004 0 P 0 ;0
L 1.56983002 -2.12731004 1.56638002 -2.12791004 0 P 0 ;0
L 1.56638002 -2.12791004 1.56288996 -2.1283 0 P 0 ;0
L 1.56288996 -2.1283 1.54886998 -2.12886998 0 P 0 ;0
L 1.35851998 -2.06545 1.47866004 -2.06545 0 P 0 ;0
L 1.35936004 -2.06445 1.47871004 -2.06445 0 P 0 ;0
L 1.36041004 -2.06345 1.47875 -2.06345 0 P 0 ;0
L 1.36163996 -2.06245 1.4788 -2.06245 0 P 0 ;0
L 1.36293996 -2.06145 1.47883996 -2.06145 0 P 0 ;0
L 1.36436004 -2.06045 1.47888996 -2.06045 0 P 0 ;0
L 1.36598002 -2.05945 1.47893996 -2.05945 0 P 0 ;0
L 1.36776004 -2.05845 1.47898996 -2.05845 0 P 0 ;0
L 1.36971004 -2.05745 1.47903002 -2.05745 0 P 0 ;0
L 1.37166004 -2.05645 1.47908002 -2.05645 0 P 0 ;0
L 1.37391004 -2.05545 1.47911998 -2.05545 0 P 0 ;0
L 1.37616998 -2.05445 1.47916998 -2.05445 0 P 0 ;0
L 1.37873002 -2.05345 1.47921004 -2.05345 0 P 0 ;0
L 1.38136004 -2.05245 1.47926004 -2.05245 0 P 0 ;0
L 1.36875 -2.03345 1.37108996 -2.03345 0 P 0 ;0
L 1.36886004 -2.03245 1.37385 -2.03245 0 P 0 ;0
L 1.36896998 -2.03145 1.37678002 -2.03145 0 P 0 ;0
L 1.36908996 -2.03045 1.3797 -2.03045 0 P 0 ;0
L 1.36921004 -2.02945 1.38261998 -2.02945 0 P 0 ;0
L 1.36933002 -2.02845 1.38638996 -2.02845 0 P 0 ;0
L 1.36946004 -2.02745 1.39023996 -2.02745 0 P 0 ;0
L 1.36958002 -2.02645 1.39503002 -2.02645 0 P 0 ;0
L 1.3697 -2.02545 1.40068002 -2.02545 0 P 0 ;0
L 1.36981998 -2.02445 1.41053996 -2.02445 0 P 0 ;0
L 1.36993996 -2.02345 1.47993996 -2.02345 0 P 0 ;0
L 1.37008002 -2.02245 1.47988002 -2.02245 0 P 0 ;0
L 1.37021004 -2.02145 1.47978002 -2.02145 0 P 0 ;0
L 1.37033996 -2.02045 1.47968002 -2.02045 0 P 0 ;0
L 1.37046998 -2.01945 1.47953002 -2.01945 0 P 0 ;0
L 1.3706 -2.01845 1.47936004 -2.01845 0 P 0 ;0
L 1.37073002 -2.01745 1.47918002 -2.01745 0 P 0 ;0
L 1.37086004 -2.01645 1.47893002 -2.01645 0 P 0 ;0
L 1.37098996 -2.01545 1.47868002 -2.01545 0 P 0 ;0
L 1.37113002 -2.01445 1.4784 -2.01445 0 P 0 ;0
L 1.37126998 -2.01345 1.47806004 -2.01345 0 P 0 ;0
L 1.3714 -2.01245 1.47773002 -2.01245 0 P 0 ;0
L 1.37153996 -2.01145 1.47733002 -2.01145 0 P 0 ;0
L 1.37168002 -2.01045 1.47691004 -2.01045 0 P 0 ;0
L 1.37181004 -2.00945 1.47641004 -2.00945 0 P 0 ;0
L 1.37195 -2.00845 1.47588996 -2.00845 0 P 0 ;0
L 1.37208002 -2.00745 1.47528002 -2.00745 0 P 0 ;0
L 1.37221004 -2.00645 1.47463996 -2.00645 0 P 0 ;0
L 1.37235 -2.00545 1.47391998 -2.00545 0 P 0 ;0
L 1.37248996 -2.00445 1.47311004 -2.00445 0 P 0 ;0
L 1.37261998 -2.00345 1.47225 -2.00345 0 P 0 ;0
L 1.37276004 -2.00245 1.47126998 -2.00245 0 P 0 ;0
L 1.3729 -2.00145 1.4702 -2.00145 0 P 0 ;0
L 1.37303002 -2.00045 1.46903996 -2.00045 0 P 0 ;0
L 1.37316998 -1.99945 1.46775 -1.99945 0 P 0 ;0
L 1.3733 -1.99845 1.46625 -1.99845 0 P 0 ;0
L 1.37343996 -1.99745 1.46455 -1.99745 0 P 0 ;0
L 1.37356998 -1.99645 1.46253996 -1.99645 0 P 0 ;0
L 1.37753002 -1.99545 1.46041004 -1.99545 0 P 0 ;0
L 1.38218996 -1.99445 1.45781004 -1.99445 0 P 0 ;0
L 1.42925 -2.08345 1.47785 -2.08345 0 P 0 ;0
L 1.42931998 -2.08245 1.47788996 -2.08245 0 P 0 ;0
L 1.42938002 -2.08145 1.47793002 -2.08145 0 P 0 ;0
L 1.42945 -2.08045 1.47796998 -2.08045 0 P 0 ;0
L 1.42951004 -2.07945 1.47801004 -2.07945 0 P 0 ;0
L 1.42958002 -2.07845 1.47806004 -2.07845 0 P 0 ;0
L 1.42963996 -2.07745 1.4781 -2.07745 0 P 0 ;0
L 1.4297 -2.07645 1.47815 -2.07645 0 P 0 ;0
L 1.42976998 -2.07545 1.4782 -2.07545 0 P 0 ;0
L 1.42983002 -2.07445 1.47825 -2.07445 0 P 0 ;0
L 1.4299 -2.07345 1.47828996 -2.07345 0 P 0 ;0
L 1.42963996 -2.07245 1.47833996 -2.07245 0 P 0 ;0
L 1.42918996 -2.07145 1.47838002 -2.07145 0 P 0 ;0
L 1.38425 -2.05145 1.47931004 -2.05145 0 P 0 ;0
L 1.38731998 -2.05045 1.47933996 -2.05045 0 P 0 ;0
L 1.39088002 -2.04945 1.47938002 -2.04945 0 P 0 ;0
L 1.3947 -2.04845 1.47941004 -2.04845 0 P 0 ;0
L 1.39851004 -2.04745 1.47945 -2.04745 0 P 0 ;0
L 1.40233002 -2.04645 1.47948002 -2.04645 0 P 0 ;0
L 1.40608002 -2.04545 1.47951004 -2.04545 0 P 0 ;0
L 1.40983002 -2.04445 1.47955 -2.04445 0 P 0 ;0
L 1.41306998 -2.04345 1.47958996 -2.04345 0 P 0 ;0
L 1.41591998 -2.04245 1.47961998 -2.04245 0 P 0 ;0
L 1.41876998 -2.04145 1.47965 -2.04145 0 P 0 ;0
L 1.42133996 -2.04045 1.47968996 -2.04045 0 P 0 ;0
L 1.42361998 -2.03945 1.47971998 -2.03945 0 P 0 ;0
L 1.42591004 -2.03845 1.47975 -2.03845 0 P 0 ;0
L 1.42805 -2.03745 1.47978002 -2.03745 0 P 0 ;0
L 1.42936004 -2.03645 1.47981004 -2.03645 0 P 0 ;0
L 1.43003002 -2.03545 1.47983002 -2.03545 0 P 0 ;0
L 1.43081998 -2.03445 1.47986004 -2.03445 0 P 0 ;0
L 1.43121004 -2.03345 1.47988002 -2.03345 0 P 0 ;0
L 1.43141998 -2.03245 1.4799 -2.03245 0 P 0 ;0
L 1.43146998 -2.03145 1.47993002 -2.03145 0 P 0 ;0
L 1.43136004 -2.03045 1.47996004 -2.03045 0 P 0 ;0
L 1.43108002 -2.02945 1.47998002 -2.02945 0 P 0 ;0
L 1.4306 -2.02845 1.48001004 -2.02845 0 P 0 ;0
L 1.42986998 -2.02745 1.48001004 -2.02745 0 P 0 ;0
L 1.42875 -2.02645 1.47998996 -2.02645 0 P 0 ;0
L 1.42658996 -2.02545 1.47996998 -2.02545 0 P 0 ;0
L 1.42203996 -2.02445 1.47996004 -2.02445 0 P 0 ;0
L 1.38748002 -1.99345 1.45483002 -1.99345 0 P 0 ;0
L 1.39331998 -1.99245 1.45108996 -1.99245 0 P 0 ;0
L 1.40051004 -1.99145 1.44503002 -1.99145 0 P 0 ;0
L 1.38096998 -2.12745 1.4051 -2.12745 0 P 0 ;0
L 1.37671004 -2.12645 1.41113996 -2.12645 0 P 0 ;0
L 1.3736 -2.12545 1.41238996 -2.12545 0 P 0 ;0
L 1.37096998 -2.12445 1.41268002 -2.12445 0 P 0 ;0
L 1.36876998 -2.12345 1.41296998 -2.12345 0 P 0 ;0
L 1.36685 -2.12245 1.41326998 -2.12245 0 P 0 ;0
L 1.36516004 -2.12145 1.41356004 -2.12145 0 P 0 ;0
L 1.36366004 -2.12045 1.41385 -2.12045 0 P 0 ;0
L 1.36225 -2.11945 1.41413996 -2.11945 0 P 0 ;0
L 1.361 -2.11845 1.41443002 -2.11845 0 P 0 ;0
L 1.35983002 -2.11745 1.41471998 -2.11745 0 P 0 ;0
L 1.35876004 -2.11645 1.41501004 -2.11645 0 P 0 ;0
L 1.42661998 -2.12445 1.47693002 -2.12445 0 P 0 ;0
L 1.42665 -2.12345 1.47693002 -2.12345 0 P 0 ;0
L 1.4267 -2.12245 1.47693002 -2.12245 0 P 0 ;0
L 1.42675 -2.12145 1.47693002 -2.12145 0 P 0 ;0
L 1.42681004 -2.12045 1.47693002 -2.12045 0 P 0 ;0
L 1.42686998 -2.11945 1.47693002 -2.11945 0 P 0 ;0
L 1.42691998 -2.11845 1.47693002 -2.11845 0 P 0 ;0
L 1.42698996 -2.11745 1.47693002 -2.11745 0 P 0 ;0
L 1.42705 -2.11645 1.47693002 -2.11645 0 P 0 ;0
L 1.42711004 -2.11545 1.47693002 -2.11545 0 P 0 ;0
L 1.42716998 -2.11445 1.47693002 -2.11445 0 P 0 ;0
L 1.42723002 -2.11345 1.47693996 -2.11345 0 P 0 ;0
L 1.4273 -2.11245 1.47695 -2.11245 0 P 0 ;0
L 1.42736998 -2.11145 1.47696004 -2.11145 0 P 0 ;0
L 1.42743996 -2.11045 1.47698002 -2.11045 0 P 0 ;0
L 1.42751004 -2.10945 1.47698996 -2.10945 0 P 0 ;0
L 1.42758002 -2.10845 1.47701004 -2.10845 0 P 0 ;0
L 1.42765 -2.10745 1.47703002 -2.10745 0 P 0 ;0
L 1.42771004 -2.10645 1.47703996 -2.10645 0 P 0 ;0
L 1.42778002 -2.10545 1.47706998 -2.10545 0 P 0 ;0
L 1.42783996 -2.10445 1.4771 -2.10445 0 P 0 ;0
L 1.42791004 -2.10345 1.47713002 -2.10345 0 P 0 ;0
L 1.42798002 -2.10245 1.47716004 -2.10245 0 P 0 ;0
L 1.42805 -2.10145 1.4772 -2.10145 0 P 0 ;0
L 1.42811004 -2.10045 1.47723002 -2.10045 0 P 0 ;0
L 1.40953002 -2.09945 1.41973002 -2.09945 0 P 0 ;0
L 1.42818002 -2.09945 1.47726004 -2.09945 0 P 0 ;0
L 1.41618002 -2.09845 1.41996998 -2.09845 0 P 0 ;0
L 1.42825 -2.09845 1.47728996 -2.09845 0 P 0 ;0
L 1.42831998 -2.09745 1.47733002 -2.09745 0 P 0 ;0
L 1.42838996 -2.09645 1.47736004 -2.09645 0 P 0 ;0
L 1.42846004 -2.09545 1.47738996 -2.09545 0 P 0 ;0
L 1.42851998 -2.09445 1.47741998 -2.09445 0 P 0 ;0
L 1.42858996 -2.09345 1.47746004 -2.09345 0 P 0 ;0
L 1.42866004 -2.09245 1.4775 -2.09245 0 P 0 ;0
L 1.42873002 -2.09145 1.47753996 -2.09145 0 P 0 ;0
L 1.42878996 -2.09045 1.47758002 -2.09045 0 P 0 ;0
L 1.42886004 -2.08945 1.47761998 -2.08945 0 P 0 ;0
L 1.42893002 -2.08845 1.47766004 -2.08845 0 P 0 ;0
L 1.42898996 -2.08745 1.4777 -2.08745 0 P 0 ;0
L 1.42906004 -2.08645 1.47773002 -2.08645 0 P 0 ;0
L 1.42911998 -2.08545 1.47776998 -2.08545 0 P 0 ;0
L 1.42918996 -2.08445 1.47781004 -2.08445 0 P 0 ;0
L 1.61686004 -2.17995 1.66846004 -2.17995 0 P 0 ;0
L 1.61591004 -2.17895 1.67158996 -2.17895 0 P 0 ;0
L 1.61553996 -2.17795 1.67431998 -2.17795 0 P 0 ;0
L 1.61526998 -2.17695 1.67675 -2.17695 0 P 0 ;0
L 1.61508002 -2.17595 1.67903996 -2.17595 0 P 0 ;0
L 1.61496998 -2.17495 1.68108002 -2.17495 0 P 0 ;0
L 1.61491004 -2.17395 1.68295 -2.17395 0 P 0 ;0
L 1.61485 -2.17295 1.68458996 -2.17295 0 P 0 ;0
L 1.61478996 -2.17195 1.6861 -2.17195 0 P 0 ;0
L 1.61473002 -2.17095 1.6875 -2.17095 0 P 0 ;0
L 1.61466998 -2.16995 1.68876998 -2.16995 0 P 0 ;0
L 1.61461004 -2.16895 1.68998002 -2.16895 0 P 0 ;0
L 1.61455 -2.16795 1.69108002 -2.16795 0 P 0 ;0
L 1.61448996 -2.16695 1.69211998 -2.16695 0 P 0 ;0
L 1.61443002 -2.16595 1.69316004 -2.16595 0 P 0 ;0
L 1.61436998 -2.16495 1.69411998 -2.16495 0 P 0 ;0
L 1.61431004 -2.16395 1.69498996 -2.16395 0 P 0 ;0
L 1.61425 -2.16295 1.69586004 -2.16295 0 P 0 ;0
L 1.61418996 -2.16195 1.69673002 -2.16195 0 P 0 ;0
L 1.61413002 -2.16095 1.69746998 -2.16095 0 P 0 ;0
L 1.61406998 -2.15995 1.6982 -2.15995 0 P 0 ;0
L 1.61401998 -2.15895 1.69893996 -2.15895 0 P 0 ;0
L 1.61396998 -2.15795 1.69963002 -2.15795 0 P 0 ;0
L 1.64433002 -2.18295 1.63151004 -2.18271004 0 P 0 ;0
L 1.63151004 -2.18271004 1.62658002 -2.18226998 0 P 0 ;0
L 1.62658002 -2.18226998 1.62168996 -2.18146998 0 P 0 ;0
L 1.62168996 -2.18146998 1.6201 -2.1811 0 P 0 ;0
L 1.6201 -2.1811 1.61853996 -2.18061004 0 P 0 ;0
L 1.61853996 -2.18061004 1.61701004 -2.18001998 0 P 0 ;0
L 1.61701004 -2.18001998 1.61686004 -2.17995 0 P 0 ;0
L 1.61686004 -2.17995 1.61671004 -2.17986998 0 P 0 ;0
L 1.61671004 -2.17986998 1.61656998 -2.17976998 0 P 0 ;0
L 1.61656998 -2.17976998 1.61643996 -2.17966998 0 P 0 ;0
L 1.61643996 -2.17966998 1.61631998 -2.17955 0 P 0 ;0
L 1.61631998 -2.17955 1.61621004 -2.17943002 0 P 0 ;0
L 1.61621004 -2.17943002 1.6161 -2.1793 0 P 0 ;0
L 1.6161 -2.1793 1.61601004 -2.17915 0 P 0 ;0
L 1.61601004 -2.17915 1.61593002 -2.179 0 P 0 ;0
L 1.61593002 -2.179 1.61586004 -2.17885 0 P 0 ;0
L 1.61586004 -2.17885 1.61553002 -2.17791004 0 P 0 ;0
L 1.61553002 -2.17791004 1.61526998 -2.17696004 0 P 0 ;0
L 1.61526998 -2.17696004 1.61508996 -2.17598996 0 P 0 ;0
L 1.61508996 -2.17598996 1.61496998 -2.17496998 0 P 0 ;0
L 1.61496998 -2.17496998 1.61408002 -2.16011004 0 P 0 ;0
L 1.61408002 -2.16011004 1.61341998 -2.14758996 0 P 0 ;0
L 1.61341998 -2.14758996 1.6202 -2.14821004 0 P 0 ;0
L 1.6202 -2.14821004 1.62023002 -2.14821004 0 P 0 ;0
L 1.62023002 -2.14821004 1.63216998 -2.14893996 0 P 0 ;0
L 1.63216998 -2.14893996 1.6349 -2.14893002 0 P 0 ;0
L 1.6349 -2.14893002 1.63761998 -2.14873002 0 P 0 ;0
L 1.63761998 -2.14873002 1.64031998 -2.14835 0 P 0 ;0
L 1.64031998 -2.14835 1.64198996 -2.14798996 0 P 0 ;0
L 1.64198996 -2.14798996 1.64363002 -2.14751998 0 P 0 ;0
L 1.64363002 -2.14751998 1.64523002 -2.14693002 0 P 0 ;0
L 1.64523002 -2.14693002 1.64678996 -2.14623002 0 P 0 ;0
L 1.64678996 -2.14623002 1.64888002 -2.14506998 0 P 0 ;0
L 1.64888002 -2.14506998 1.65086998 -2.14376004 0 P 0 ;0
L 1.65086998 -2.14376004 1.65093996 -2.14371004 0 P 0 ;0
L 1.65093996 -2.14371004 1.65275 -2.14228996 0 P 0 ;0
L 1.65275 -2.14228996 1.6539 -2.14123996 0 P 0 ;0
L 1.6539 -2.14123996 1.65496004 -2.14011004 0 P 0 ;0
L 1.65496004 -2.14011004 1.65591998 -2.13891004 0 P 0 ;0
L 1.65591998 -2.13891004 1.65755 -2.13653996 0 P 0 ;0
L 1.65755 -2.13653996 1.65901998 -2.13415 0 P 0 ;0
L 1.65901998 -2.13415 1.65903002 -2.13413002 0 P 0 ;0
L 1.65903002 -2.13413002 1.66035 -2.13171998 0 P 0 ;0
L 1.66035 -2.13171998 1.66155 -2.12925 0 P 0 ;0
L 1.66155 -2.12925 1.66183996 -2.12851998 0 P 0 ;0
L 1.66183996 -2.12851998 1.66206998 -2.12776004 0 P 0 ;0
L 1.66206998 -2.12776004 1.66223996 -2.12696998 0 P 0 ;0
L 1.66223996 -2.12696998 1.66233996 -2.12618002 0 P 0 ;0
L 1.66233996 -2.12618002 1.66236998 -2.12538996 0 P 0 ;0
L 1.66236998 -2.12538996 1.66233002 -2.12436004 0 P 0 ;0
L 1.66233002 -2.12436004 1.66221004 -2.12335 0 P 0 ;0
L 1.66221004 -2.12335 1.662 -2.12235 0 P 0 ;0
L 1.662 -2.12235 1.66171004 -2.12141004 0 P 0 ;0
L 1.66171004 -2.12141004 1.64438996 -2.07113002 0 P 0 ;0
L 1.64438996 -2.07113002 1.62871998 -2.02606004 0 P 0 ;0
L 1.62871998 -2.02606004 1.62116004 -2.00558996 0 P 0 ;0
L 1.62116004 -2.00558996 1.62116004 -2.00556998 0 P 0 ;0
L 1.62116004 -2.00556998 1.61681004 -1.99443996 0 P 0 ;0
L 1.61681004 -1.99443996 1.67163002 -1.99443996 0 P 0 ;0
L 1.67163002 -1.99443996 1.67301004 -2.00076004 0 P 0 ;0
L 1.67301004 -2.00076004 1.67613002 -2.01341998 0 P 0 ;0
L 1.67613002 -2.01341998 1.68331004 -2.03931998 0 P 0 ;0
L 1.68331004 -2.03931998 1.69153002 -2.06856998 0 P 0 ;0
L 1.69153002 -2.06856998 1.6916 -2.06876004 0 P 0 ;0
L 1.6916 -2.06876004 1.69168996 -2.06896998 0 P 0 ;0
L 1.69168996 -2.06896998 1.69181004 -2.06918002 0 P 0 ;0
L 1.69181004 -2.06918002 1.69193002 -2.06936998 0 P 0 ;0
L 1.69193002 -2.06936998 1.69208002 -2.06956004 0 P 0 ;0
L 1.69208002 -2.06956004 1.69223996 -2.06973002 0 P 0 ;0
L 1.69223996 -2.06973002 1.69241998 -2.06988002 0 P 0 ;0
L 1.69241998 -2.06988002 1.6926 -2.07001998 0 P 0 ;0
L 1.6926 -2.07001998 1.6928 -2.07015 0 P 0 ;0
L 1.6928 -2.07015 1.69301004 -2.07025 0 P 0 ;0
L 1.69301004 -2.07025 1.69323002 -2.07033996 0 P 0 ;0
L 1.69323002 -2.07033996 1.69346004 -2.07041004 0 P 0 ;0
L 1.69346004 -2.07041004 1.69368002 -2.07045 0 P 0 ;0
L 1.69368002 -2.07045 1.69391998 -2.07048002 0 P 0 ;0
L 1.69391998 -2.07048002 1.69413996 -2.07048996 0 P 0 ;0
L 1.69413996 -2.07048996 1.6944 -2.07048002 0 P 0 ;0
L 1.6944 -2.07048002 1.69465 -2.07045 0 P 0 ;0
L 1.69465 -2.07045 1.69488996 -2.07038996 0 P 0 ;0
L 1.69488996 -2.07038996 1.69513996 -2.07031998 0 P 0 ;0
L 1.69513996 -2.07031998 1.69536998 -2.07021998 0 P 0 ;0
L 1.69536998 -2.07021998 1.69558996 -2.0701 0 P 0 ;0
L 1.69558996 -2.0701 1.69581004 -2.06996998 0 P 0 ;0
L 1.69581004 -2.06996998 1.69601004 -2.06981998 0 P 0 ;0
L 1.69601004 -2.06981998 1.6962 -2.06965 0 P 0 ;0
L 1.6962 -2.06965 1.69636998 -2.06946004 0 P 0 ;0
L 1.69636998 -2.06946004 1.69653002 -2.06926004 0 P 0 ;0
L 1.69653002 -2.06926004 1.69666004 -2.06905 0 P 0 ;0
L 1.69666004 -2.06905 1.69678996 -2.06883002 0 P 0 ;0
L 1.69678996 -2.06883002 1.69688002 -2.0686 0 P 0 ;0
L 1.69688002 -2.0686 1.69695 -2.0684 0 P 0 ;0
L 1.69695 -2.0684 1.70426004 -2.04365 0 P 0 ;0
L 1.70426004 -2.04365 1.70426004 -2.04363002 0 P 0 ;0
L 1.70426004 -2.04363002 1.71066998 -2.0213 0 P 0 ;0
L 1.71066998 -2.0213 1.71068002 -2.02126004 0 P 0 ;0
L 1.71068002 -2.02126004 1.71431998 -2.00693996 0 P 0 ;0
L 1.71431998 -2.00693996 1.71706004 -1.99496998 0 P 0 ;0
L 1.71706004 -1.99496998 1.74335 -1.9947 0 P 0 ;0
L 1.74335 -1.9947 1.75403002 -1.99461004 0 P 0 ;0
L 1.75403002 -1.99461004 1.76301004 -1.99465 0 P 0 ;0
L 1.76301004 -1.99465 1.76886004 -1.99471004 0 P 0 ;0
L 1.76886004 -1.99471004 1.76883996 -1.99476004 0 P 0 ;0
L 1.76883996 -1.99476004 1.74021004 -2.06556004 0 P 0 ;0
L 1.74021004 -2.06556004 1.71298002 -2.13276998 0 P 0 ;0
L 1.71298002 -2.13276998 1.70836998 -2.14293996 0 P 0 ;0
L 1.70836998 -2.14293996 1.70413996 -2.15076004 0 P 0 ;0
L 1.70413996 -2.15076004 1.69941998 -2.15828996 0 P 0 ;0
L 1.69941998 -2.15828996 1.6967 -2.16198996 0 P 0 ;0
L 1.6967 -2.16198996 1.6937 -2.16541998 0 P 0 ;0
L 1.6937 -2.16541998 1.69041998 -2.1686 0 P 0 ;0
L 1.69041998 -2.1686 1.68793996 -2.17063002 0 P 0 ;0
L 1.68793996 -2.17063002 1.68535 -2.17248002 0 P 0 ;0
L 1.68535 -2.17248002 1.68263996 -2.17413996 0 P 0 ;0
L 1.68263996 -2.17413996 1.67981004 -2.17561004 0 P 0 ;0
L 1.67981004 -2.17561004 1.67525 -2.17761004 0 P 0 ;0
L 1.67525 -2.17761004 1.6706 -2.17931998 0 P 0 ;0
L 1.6706 -2.17931998 1.66586004 -2.18073002 0 P 0 ;0
L 1.66586004 -2.18073002 1.66141998 -2.1817 0 P 0 ;0
L 1.66141998 -2.1817 1.65691998 -2.18228996 0 P 0 ;0
L 1.65691998 -2.18228996 1.64433002 -2.18295 0 P 0 ;0
L 1.61928996 -2.00628002 1.62683996 -2.02673002 0 P 0 ;0
L 1.62683996 -2.02673002 1.6425 -2.07178002 0 P 0 ;0
L 1.6425 -2.07178002 1.65981004 -2.12201998 0 P 0 ;0
L 1.65981004 -2.12201998 1.66006004 -2.12283996 0 P 0 ;0
L 1.66006004 -2.12283996 1.66023002 -2.12368002 0 P 0 ;0
L 1.66023002 -2.12368002 1.66033996 -2.12451998 0 P 0 ;0
L 1.66033996 -2.12451998 1.66036998 -2.12538002 0 P 0 ;0
L 1.66036998 -2.12538002 1.66033996 -2.12601004 0 P 0 ;0
L 1.66033996 -2.12601004 1.66026998 -2.12663996 0 P 0 ;0
L 1.66026998 -2.12663996 1.66013996 -2.12725 0 P 0 ;0
L 1.66013996 -2.12725 1.65995 -2.12786004 0 P 0 ;0
L 1.65995 -2.12786004 1.65971004 -2.12843996 0 P 0 ;0
L 1.65971004 -2.12843996 1.65856998 -2.1308 0 P 0 ;0
L 1.65856998 -2.1308 1.6573 -2.13313002 0 P 0 ;0
L 1.6573 -2.13313002 1.65586998 -2.13545 0 P 0 ;0
L 1.65586998 -2.13545 1.65431004 -2.13771998 0 P 0 ;0
L 1.65431004 -2.13771998 1.65343996 -2.1388 0 P 0 ;0
L 1.65343996 -2.1388 1.65248996 -2.13981998 0 P 0 ;0
L 1.65248996 -2.13981998 1.65146004 -2.14076004 0 P 0 ;0
L 1.65146004 -2.14076004 1.64971004 -2.14213002 0 P 0 ;0
L 1.64971004 -2.14213002 1.64785 -2.14336004 0 P 0 ;0
L 1.64785 -2.14336004 1.64588996 -2.14443996 0 P 0 ;0
L 1.64588996 -2.14443996 1.64446998 -2.14508002 0 P 0 ;0
L 1.64446998 -2.14508002 1.64301004 -2.14561998 0 P 0 ;0
L 1.64301004 -2.14561998 1.64151004 -2.14605 0 P 0 ;0
L 1.64151004 -2.14605 1.63996998 -2.14636998 0 P 0 ;0
L 1.63996998 -2.14636998 1.63741004 -2.14673996 0 P 0 ;0
L 1.63741004 -2.14673996 1.63483002 -2.14693002 0 P 0 ;0
L 1.63483002 -2.14693002 1.63223002 -2.14693996 0 P 0 ;0
L 1.63223002 -2.14693996 1.62036004 -2.14621998 0 P 0 ;0
L 1.62036004 -2.14621998 1.6113 -2.14538002 0 P 0 ;0
L 1.6113 -2.14538002 1.61208996 -2.16023002 0 P 0 ;0
L 1.61208996 -2.16023002 1.61298002 -2.17515 0 P 0 ;0
L 1.61298002 -2.17515 1.6131 -2.17628002 0 P 0 ;0
L 1.6131 -2.17628002 1.61331998 -2.17741004 0 P 0 ;0
L 1.61331998 -2.17741004 1.61361998 -2.17851004 0 P 0 ;0
L 1.61361998 -2.17851004 1.614 -2.17958996 0 P 0 ;0
L 1.614 -2.17958996 1.61413996 -2.17988996 0 P 0 ;0
L 1.61413996 -2.17988996 1.61428996 -2.18018002 0 P 0 ;0
L 1.61428996 -2.18018002 1.61446998 -2.18045 0 P 0 ;0
L 1.61446998 -2.18045 1.61466998 -2.18071004 0 P 0 ;0
L 1.61466998 -2.18071004 1.61488996 -2.18095 0 P 0 ;0
L 1.61488996 -2.18095 1.61511998 -2.18116998 0 P 0 ;0
L 1.61511998 -2.18116998 1.61538002 -2.18138002 0 P 0 ;0
L 1.61538002 -2.18138002 1.61565 -2.18156004 0 P 0 ;0
L 1.61565 -2.18156004 1.61593002 -2.18173002 0 P 0 ;0
L 1.61593002 -2.18173002 1.61623002 -2.18186004 0 P 0 ;0
L 1.61623002 -2.18186004 1.61788002 -2.1825 0 P 0 ;0
L 1.61788002 -2.1825 1.61956998 -2.18301998 0 P 0 ;0
L 1.61956998 -2.18301998 1.6213 -2.18343002 0 P 0 ;0
L 1.6213 -2.18343002 1.62633002 -2.18426004 0 P 0 ;0
L 1.62633002 -2.18426004 1.6314 -2.18471004 0 P 0 ;0
L 1.6314 -2.18471004 1.64436004 -2.18495 0 P 0 ;0
L 1.64436004 -2.18495 1.65711004 -2.18428002 0 P 0 ;0
L 1.65711004 -2.18428002 1.66176998 -2.18366998 0 P 0 ;0
L 1.66176998 -2.18366998 1.66636004 -2.18266998 0 P 0 ;0
L 1.66636004 -2.18266998 1.67123002 -2.18121004 0 P 0 ;0
L 1.67123002 -2.18121004 1.676 -2.17946998 0 P 0 ;0
L 1.676 -2.17946998 1.68068002 -2.17741998 0 P 0 ;0
L 1.68068002 -2.17741998 1.68361998 -2.17588002 0 P 0 ;0
L 1.68361998 -2.17588002 1.68646004 -2.17415 0 P 0 ;0
L 1.68646004 -2.17415 1.68916004 -2.17221998 0 P 0 ;0
L 1.68916004 -2.17221998 1.69175 -2.17008996 0 P 0 ;0
L 1.69175 -2.17008996 1.69515 -2.1668 0 P 0 ;0
L 1.69515 -2.1668 1.69826004 -2.16323996 0 P 0 ;0
L 1.69826004 -2.16323996 1.70108002 -2.15941998 0 P 0 ;0
L 1.70108002 -2.15941998 1.70586004 -2.15176998 0 P 0 ;0
L 1.70586004 -2.15176998 1.71016004 -2.14383002 0 P 0 ;0
L 1.71016004 -2.14383002 1.71481998 -2.13356004 0 P 0 ;0
L 1.71481998 -2.13356004 1.74206998 -2.06631004 0 P 0 ;0
L 1.74206998 -2.06631004 1.77071004 -1.99548002 0 P 0 ;0
L 1.77071004 -1.99548002 1.77088002 -1.99498996 0 P 0 ;0
L 1.77088002 -1.99498996 1.77101998 -1.99448996 0 P 0 ;0
L 1.77101998 -1.99448996 1.77111998 -1.99398996 0 P 0 ;0
L 1.77111998 -1.99398996 1.77118002 -1.99346998 0 P 0 ;0
L 1.77118002 -1.99346998 1.7712 -1.99295 0 P 0 ;0
L 1.7712 -1.99295 1.7712 -1.99293002 0 P 0 ;0
L 1.7712 -1.99293002 1.77118996 -1.99286998 0 P 0 ;0
L 1.77118996 -1.99286998 1.77118002 -1.99286004 0 P 0 ;0
L 1.77118002 -1.99286004 1.77118002 -1.99283996 0 P 0 ;0
L 1.77118002 -1.99283996 1.77111004 -1.99276998 0 P 0 ;0
L 1.77111004 -1.99276998 1.77106998 -1.99275 0 P 0 ;0
L 1.77106998 -1.99275 1.77106004 -1.99273996 0 P 0 ;0
L 1.77106004 -1.99273996 1.771 -1.99273002 0 P 0 ;0
L 1.771 -1.99273002 1.77098002 -1.99273002 0 P 0 ;0
L 1.77098002 -1.99273002 1.76301004 -1.99265 0 P 0 ;0
L 1.76301004 -1.99265 1.75401998 -1.99261004 0 P 0 ;0
L 1.75401998 -1.99261004 1.74333002 -1.9927 0 P 0 ;0
L 1.74333002 -1.9927 1.71546004 -1.99298996 0 P 0 ;0
L 1.71546004 -1.99298996 1.71236998 -2.00646998 0 P 0 ;0
L 1.71236998 -2.00646998 1.70873996 -2.02078002 0 P 0 ;0
L 1.70873996 -2.02078002 1.70233996 -2.04308002 0 P 0 ;0
L 1.70233996 -2.04308002 1.69505 -2.0678 0 P 0 ;0
L 1.69505 -2.0678 1.69501998 -2.06788002 0 P 0 ;0
L 1.69501998 -2.06788002 1.69498996 -2.06795 0 P 0 ;0
L 1.69498996 -2.06795 1.69495 -2.06801998 0 P 0 ;0
L 1.69495 -2.06801998 1.69485 -2.06816004 0 P 0 ;0
L 1.69485 -2.06816004 1.69478996 -2.06821998 0 P 0 ;0
L 1.69478996 -2.06821998 1.69466998 -2.06831998 0 P 0 ;0
L 1.69466998 -2.06831998 1.69453002 -2.0684 0 P 0 ;0
L 1.69453002 -2.0684 1.69445 -2.06843002 0 P 0 ;0
L 1.69445 -2.06843002 1.69438002 -2.06846004 0 P 0 ;0
L 1.69438002 -2.06846004 1.69428996 -2.06846998 0 P 0 ;0
L 1.69428996 -2.06846998 1.69421004 -2.06848996 0 P 0 ;0
L 1.69421004 -2.06848996 1.69406998 -2.06848996 0 P 0 ;0
L 1.69406998 -2.06848996 1.69395 -2.06846998 0 P 0 ;0
L 1.69395 -2.06846998 1.69383002 -2.06843002 0 P 0 ;0
L 1.69383002 -2.06843002 1.69373002 -2.06836998 0 P 0 ;0
L 1.69373002 -2.06836998 1.69363002 -2.06828996 0 P 0 ;0
L 1.69363002 -2.06828996 1.69358996 -2.06823996 0 P 0 ;0
L 1.69358996 -2.06823996 1.69355 -2.0682 0 P 0 ;0
L 1.69355 -2.0682 1.69351998 -2.06815 0 P 0 ;0
L 1.69351998 -2.06815 1.69346004 -2.06803996 0 P 0 ;0
L 1.69346004 -2.06803996 1.69343996 -2.06798002 0 P 0 ;0
L 1.69343996 -2.06798002 1.68523002 -2.03878002 0 P 0 ;0
L 1.68523002 -2.03878002 1.67806998 -2.01291998 0 P 0 ;0
L 1.67806998 -2.01291998 1.67496004 -2.00031004 0 P 0 ;0
L 1.67496004 -2.00031004 1.67323002 -1.99243996 0 P 0 ;0
L 1.67323002 -1.99243996 1.61388002 -1.99243996 0 P 0 ;0
L 1.61388002 -1.99243996 1.61928996 -2.00628002 0 P 0 ;0
L 1.35018002 -2.08345 1.39488996 -2.08345 0 P 0 ;0
L 1.35026004 -2.08245 1.39586004 -2.08245 0 P 0 ;0
L 1.35041004 -2.08145 1.39708996 -2.08145 0 P 0 ;0
L 1.35058996 -2.08045 1.39853002 -2.08045 0 P 0 ;0
L 1.35083996 -2.07945 1.40031998 -2.07945 0 P 0 ;0
L 1.35116998 -2.07845 1.40271004 -2.07845 0 P 0 ;0
L 1.35158002 -2.07745 1.40561998 -2.07745 0 P 0 ;0
L 1.35203002 -2.07645 1.4092 -2.07645 0 P 0 ;0
L 1.35248002 -2.07545 1.41288996 -2.07545 0 P 0 ;0
L 1.35293002 -2.07445 1.4164 -2.07445 0 P 0 ;0
L 1.35338996 -2.07345 1.41975 -2.07345 0 P 0 ;0
L 1.35393996 -2.07245 1.42293996 -2.07245 0 P 0 ;0
L 1.35448996 -2.07145 1.42606998 -2.07145 0 P 0 ;0
L 1.35505 -2.07045 1.47843002 -2.07045 0 P 0 ;0
L 1.3557 -2.06945 1.47846998 -2.06945 0 P 0 ;0
L 1.35635 -2.06845 1.47851998 -2.06845 0 P 0 ;0
L 1.35701998 -2.06745 1.47856998 -2.06745 0 P 0 ;0
L 1.35776998 -2.06645 1.47861004 -2.06645 0 P 0 ;0
L 1.29346998 -2.00516004 1.33388996 -2.00516004 0 P 0 ;0
L 1.29448996 -2.00416004 1.33385 -2.00416004 0 P 0 ;0
L 1.29551004 -2.00316004 1.33381004 -2.00316004 0 P 0 ;0
L 1.29653996 -2.00216004 1.33376004 -2.00216004 0 P 0 ;0
L 1.29756004 -2.00116004 1.33371004 -2.00116004 0 P 0 ;0
L 1.29861998 -2.00016004 1.33366004 -2.00016004 0 P 0 ;0
L 1.29973002 -1.99916004 1.3336 -1.99916004 0 P 0 ;0
L 1.30101004 -1.99816004 1.33355 -1.99816004 0 P 0 ;0
L 1.30238996 -1.99716004 1.3335 -1.99716004 0 P 0 ;0
L 1.30393996 -1.99616004 1.33345 -1.99616004 0 P 0 ;0
L 1.30571004 -1.99516004 1.33338996 -1.99516004 0 P 0 ;0
L 1.3077 -1.99416004 1.33333002 -1.99416004 0 P 0 ;0
L 1.31001004 -1.99316004 1.33328002 -1.99316004 0 P 0 ;0
L 1.31288002 -1.99216004 1.33321998 -1.99216004 0 P 0 ;0
L 1.31688996 -1.99116004 1.33316004 -1.99116004 0 P 0 ;0
L 1.39798996 -1.98971998 1.39326998 -1.99043002 0 P 0 ;0
L 1.39326998 -1.99043002 1.38806998 -1.9913 0 P 0 ;0
L 1.38806998 -1.9913 1.38316004 -1.9922 0 P 0 ;0
L 1.38316004 -1.9922 1.37946004 -1.99296998 0 P 0 ;0
L 1.37946004 -1.99296998 1.3718 -1.99466998 0 P 0 ;0
L 1.3718 -1.99466998 1.36896004 -2.01553996 0 P 0 ;0
L 1.36896004 -2.01553996 1.36791004 -2.02358996 0 P 0 ;0
L 1.36791004 -2.02358996 1.36708002 -2.03043002 0 P 0 ;0
L 1.36708002 -2.03043002 1.36638996 -2.03646004 0 P 0 ;0
L 1.36638996 -2.03646004 1.36638002 -2.03648996 0 P 0 ;0
L 1.36638002 -2.03648996 1.36638996 -2.03653002 0 P 0 ;0
L 1.36638996 -2.03653002 1.36638996 -2.03656998 0 P 0 ;0
L 1.36638996 -2.03656998 1.3664 -2.03663996 0 P 0 ;0
L 1.3664 -2.03663996 1.36641998 -2.03666998 0 P 0 ;0
L 1.36641998 -2.03666998 1.36643002 -2.03671004 0 P 0 ;0
L 1.36643002 -2.03671004 1.36648996 -2.0368 0 P 0 ;0
L 1.36648996 -2.0368 1.36656004 -2.03686004 0 P 0 ;0
L 1.36656004 -2.03686004 1.3666 -2.03688996 0 P 0 ;0
L 1.3666 -2.03688996 1.36663002 -2.03691004 0 P 0 ;0
L 1.36663002 -2.03691004 1.36666004 -2.03691004 0 P 0 ;0
L 1.36666004 -2.03691004 1.36671004 -2.03693002 0 P 0 ;0
L 1.36671004 -2.03693002 1.36676998 -2.03693002 0 P 0 ;0
L 1.36676998 -2.03693002 1.36685 -2.03691998 0 P 0 ;0
L 1.36685 -2.03691998 1.36895 -2.03628002 0 P 0 ;0
L 1.36895 -2.03628002 1.37143002 -2.03545 0 P 0 ;0
L 1.37143002 -2.03545 1.37428996 -2.03441004 0 P 0 ;0
L 1.37428996 -2.03441004 1.38346004 -2.03126998 0 P 0 ;0
L 1.38346004 -2.03126998 1.39251998 -2.02891998 0 P 0 ;0
L 1.39251998 -2.02891998 1.40156004 -2.02731998 0 P 0 ;0
L 1.40156004 -2.02731998 1.41068002 -2.02643996 0 P 0 ;0
L 1.41068002 -2.02643996 1.41566998 -2.02628002 0 P 0 ;0
L 1.41566998 -2.02628002 1.42066004 -2.02633996 0 P 0 ;0
L 1.42066004 -2.02633996 1.42221004 -2.02646998 0 P 0 ;0
L 1.42221004 -2.02646998 1.42375 -2.02671998 0 P 0 ;0
L 1.42375 -2.02671998 1.42525 -2.0271 0 P 0 ;0
L 1.42525 -2.0271 1.42671998 -2.02761004 0 P 0 ;0
L 1.42671998 -2.02761004 1.42706004 -2.02776004 0 P 0 ;0
L 1.42706004 -2.02776004 1.42738002 -2.02793002 0 P 0 ;0
L 1.42738002 -2.02793002 1.42768002 -2.02813996 0 P 0 ;0
L 1.42768002 -2.02813996 1.42796998 -2.02836004 0 P 0 ;0
L 1.42796998 -2.02836004 1.42823002 -2.02861004 0 P 0 ;0
L 1.42823002 -2.02861004 1.42848002 -2.02888996 0 P 0 ;0
L 1.42848002 -2.02888996 1.4287 -2.02918002 0 P 0 ;0
L 1.4287 -2.02918002 1.42888996 -2.02948996 0 P 0 ;0
L 1.42888996 -2.02948996 1.42906004 -2.02981004 0 P 0 ;0
L 1.42906004 -2.02981004 1.4292 -2.03015 0 P 0 ;0
L 1.4292 -2.03015 1.42931998 -2.0305 0 P 0 ;0
L 1.42931998 -2.0305 1.4294 -2.03086004 0 P 0 ;0
L 1.4294 -2.03086004 1.42945 -2.03121998 0 P 0 ;0
L 1.42945 -2.03121998 1.42946998 -2.03158002 0 P 0 ;0
L 1.42946998 -2.03158002 1.42946004 -2.03195 0 P 0 ;0
L 1.42946004 -2.03195 1.42941998 -2.03231004 0 P 0 ;0
L 1.42941998 -2.03231004 1.42935 -2.03266998 0 P 0 ;0
L 1.42935 -2.03266998 1.42925 -2.03301998 0 P 0 ;0
L 1.42925 -2.03301998 1.42911998 -2.03336004 0 P 0 ;0
L 1.42911998 -2.03336004 1.42896004 -2.03368996 0 P 0 ;0
L 1.42896004 -2.03368996 1.42875 -2.03405 0 P 0 ;0
L 1.42875 -2.03405 1.42851004 -2.03438996 0 P 0 ;0
L 1.42851004 -2.03438996 1.42825 -2.03471004 0 P 0 ;0
L 1.42825 -2.03471004 1.42796004 -2.03501004 0 P 0 ;0
L 1.42796004 -2.03501004 1.42765 -2.03528996 0 P 0 ;0
L 1.42765 -2.03528996 1.42731998 -2.03553996 0 P 0 ;0
L 1.42731998 -2.03553996 1.42696998 -2.03576004 0 P 0 ;0
L 1.42696998 -2.03576004 1.4266 -2.03596004 0 P 0 ;0
L 1.4266 -2.03596004 1.41951004 -2.03906004 0 P 0 ;0
L 1.41951004 -2.03906004 1.4109 -2.04208996 0 P 0 ;0
L 1.4109 -2.04208996 1.40178002 -2.04451998 0 P 0 ;0
L 1.40178002 -2.04451998 1.3878 -2.04818996 0 P 0 ;0
L 1.3878 -2.04818996 1.38176998 -2.05015 0 P 0 ;0
L 1.38176998 -2.05015 1.3758 -2.05243002 0 P 0 ;0
L 1.3758 -2.05243002 1.37086998 -2.0546 0 P 0 ;0
L 1.37086998 -2.0546 1.36603996 -2.05708002 0 P 0 ;0
L 1.36603996 -2.05708002 1.36356004 -2.05856004 0 P 0 ;0
L 1.36356004 -2.05856004 1.36118996 -2.06023002 0 P 0 ;0
L 1.36118996 -2.06023002 1.35895 -2.06206004 0 P 0 ;0
L 1.35895 -2.06206004 1.35805 -2.06291004 0 P 0 ;0
L 1.35805 -2.06291004 1.35721998 -2.06385 0 P 0 ;0
L 1.35721998 -2.06385 1.35518996 -2.06655 0 P 0 ;0
L 1.35518996 -2.06655 1.3532 -2.06961998 0 P 0 ;0
L 1.3532 -2.06961998 1.35156004 -2.07263002 0 P 0 ;0
L 1.35156004 -2.07263002 1.34951004 -2.07718002 0 P 0 ;0
L 1.34951004 -2.07718002 1.34911004 -2.07825 0 P 0 ;0
L 1.34911004 -2.07825 1.34878996 -2.07935 0 P 0 ;0
L 1.34878996 -2.07935 1.34853002 -2.08046998 0 P 0 ;0
L 1.34853002 -2.08046998 1.34825 -2.08238002 0 P 0 ;0
L 1.34825 -2.08238002 1.34811998 -2.08431004 0 P 0 ;0
L 1.34811998 -2.08431004 1.348 -2.09128996 0 P 0 ;0
L 1.348 -2.09128996 1.3481 -2.09761004 0 P 0 ;0
L 1.3481 -2.09761004 1.34823002 -2.09961004 0 P 0 ;0
L 1.34823002 -2.09961004 1.34846998 -2.10161004 0 P 0 ;0
L 1.34846998 -2.10161004 1.34876998 -2.10321998 0 P 0 ;0
L 1.34876998 -2.10321998 1.3492 -2.10478996 0 P 0 ;0
L 1.3492 -2.10478996 1.3498 -2.10648996 0 P 0 ;0
L 1.3498 -2.10648996 1.3505 -2.10815 0 P 0 ;0
L 1.3505 -2.10815 1.35178996 -2.11066004 0 P 0 ;0
L 1.35178996 -2.11066004 1.35328002 -2.11305 0 P 0 ;0
L 1.35328002 -2.11305 1.35496998 -2.1153 0 P 0 ;0
L 1.35496998 -2.1153 1.35685 -2.1174 0 P 0 ;0
L 1.35685 -2.1174 1.35891998 -2.11933996 0 P 0 ;0
L 1.35891998 -2.11933996 1.36126998 -2.12121998 0 P 0 ;0
L 1.36126998 -2.12121998 1.36373996 -2.12293002 0 P 0 ;0
L 1.36373996 -2.12293002 1.36633002 -2.12446004 0 P 0 ;0
L 1.36633002 -2.12446004 1.36901004 -2.1258 0 P 0 ;0
L 1.36901004 -2.1258 1.3718 -2.12695 0 P 0 ;0
L 1.3718 -2.12695 1.37578996 -2.12828002 0 P 0 ;0
L 1.37578996 -2.12828002 1.37986998 -2.12928996 0 P 0 ;0
L 1.37986998 -2.12928996 1.38401998 -2.12998996 0 P 0 ;0
L 1.38401998 -2.12998996 1.3882 -2.13036004 0 P 0 ;0
L 1.3882 -2.13036004 1.39443002 -2.13045 0 P 0 ;0
L 1.39443002 -2.13045 1.40066004 -2.13006998 0 P 0 ;0
L 1.40066004 -2.13006998 1.40685 -2.12923002 0 P 0 ;0
L 1.40685 -2.12923002 1.41371004 -2.12801998 0 P 0 ;0
L 1.41371004 -2.12801998 1.41583002 -2.12081004 0 P 0 ;0
L 1.41583002 -2.12081004 1.41953996 -2.10798996 0 P 0 ;0
L 1.41953996 -2.10798996 1.42135 -2.10126998 0 P 0 ;0
L 1.42135 -2.10126998 1.42236998 -2.097 0 P 0 ;0
L 1.42236998 -2.097 1.42238996 -2.09691004 0 P 0 ;0
L 1.42238996 -2.09691004 1.4224 -2.09681998 0 P 0 ;0
L 1.4224 -2.09681998 1.4224 -2.09673996 0 P 0 ;0
L 1.4224 -2.09673996 1.42238002 -2.09656004 0 P 0 ;0
L 1.42238002 -2.09656004 1.42235 -2.09648002 0 P 0 ;0
L 1.42235 -2.09648002 1.42233002 -2.09638996 0 P 0 ;0
L 1.42233002 -2.09638996 1.42225 -2.09623002 0 P 0 ;0
L 1.42225 -2.09623002 1.4222 -2.09616004 0 P 0 ;0
L 1.4222 -2.09616004 1.42213996 -2.09608996 0 P 0 ;0
L 1.42213996 -2.09608996 1.42208996 -2.09601998 0 P 0 ;0
L 1.42208996 -2.09601998 1.42203996 -2.09598996 0 P 0 ;0
L 1.42203996 -2.09598996 1.42198996 -2.09595 0 P 0 ;0
L 1.42198996 -2.09595 1.42188996 -2.09588996 0 P 0 ;0
L 1.42188996 -2.09588996 1.42183002 -2.09586004 0 P 0 ;0
L 1.42183002 -2.09586004 1.42178002 -2.09585 0 P 0 ;0
L 1.42178002 -2.09585 1.42171998 -2.09583002 0 P 0 ;0
L 1.42171998 -2.09583002 1.42166004 -2.09581998 0 P 0 ;0
L 1.42166004 -2.09581998 1.42153996 -2.09581998 0 P 0 ;0
L 1.42153996 -2.09581998 1.41978002 -2.09591004 0 P 0 ;0
L 1.41978002 -2.09591004 1.41763996 -2.09615 0 P 0 ;0
L 1.41763996 -2.09615 1.41521998 -2.09658002 0 P 0 ;0
L 1.41521998 -2.09658002 1.4107 -2.09733002 0 P 0 ;0
L 1.4107 -2.09733002 1.40613002 -2.09775 0 P 0 ;0
L 1.40613002 -2.09775 1.40481004 -2.09778002 0 P 0 ;0
L 1.40481004 -2.09778002 1.40348996 -2.09771998 0 P 0 ;0
L 1.40348996 -2.09771998 1.40216998 -2.09756004 0 P 0 ;0
L 1.40216998 -2.09756004 1.40086998 -2.0973 0 P 0 ;0
L 1.40086998 -2.0973 1.39958996 -2.09695 0 P 0 ;0
L 1.39958996 -2.09695 1.39895 -2.09671998 0 P 0 ;0
L 1.39895 -2.09671998 1.39831998 -2.09643002 0 P 0 ;0
L 1.39831998 -2.09643002 1.39773002 -2.0961 0 P 0 ;0
L 1.39773002 -2.0961 1.39716004 -2.09571004 0 P 0 ;0
L 1.39716004 -2.09571004 1.39663002 -2.09528002 0 P 0 ;0
L 1.39663002 -2.09528002 1.39613996 -2.0948 0 P 0 ;0
L 1.39613996 -2.0948 1.39568002 -2.09428002 0 P 0 ;0
L 1.39568002 -2.09428002 1.39533996 -2.09381998 0 P 0 ;0
L 1.39533996 -2.09381998 1.39505 -2.09333996 0 P 0 ;0
L 1.39505 -2.09333996 1.39478996 -2.09281998 0 P 0 ;0
L 1.39478996 -2.09281998 1.39456998 -2.09228996 0 P 0 ;0
L 1.39456998 -2.09228996 1.3944 -2.09173996 0 P 0 ;0
L 1.3944 -2.09173996 1.39428002 -2.09118996 0 P 0 ;0
L 1.39428002 -2.09118996 1.39421004 -2.09061998 0 P 0 ;0
L 1.39421004 -2.09061998 1.39418002 -2.09003996 0 P 0 ;0
L 1.39418002 -2.09003996 1.39421004 -2.08943002 0 P 0 ;0
L 1.39421004 -2.08943002 1.39428002 -2.08883002 0 P 0 ;0
L 1.39428002 -2.08883002 1.39441004 -2.08823002 0 P 0 ;0
L 1.39441004 -2.08823002 1.3946 -2.08765 0 P 0 ;0
L 1.3946 -2.08765 1.39483002 -2.08708002 0 P 0 ;0
L 1.39483002 -2.08708002 1.39511004 -2.08653996 0 P 0 ;0
L 1.39511004 -2.08653996 1.39555 -2.08583996 0 P 0 ;0
L 1.39555 -2.08583996 1.39603996 -2.08518002 0 P 0 ;0
L 1.39603996 -2.08518002 1.39658002 -2.08456004 0 P 0 ;0
L 1.39658002 -2.08456004 1.39716004 -2.08396998 0 P 0 ;0
L 1.39716004 -2.08396998 1.39778002 -2.08343002 0 P 0 ;0
L 1.39778002 -2.08343002 1.39878996 -2.08266998 0 P 0 ;0
L 1.39878996 -2.08266998 1.39985 -2.08196998 0 P 0 ;0
L 1.39985 -2.08196998 1.40096004 -2.08135 0 P 0 ;0
L 1.40096004 -2.08135 1.40211998 -2.08081004 0 P 0 ;0
L 1.40211998 -2.08081004 1.40503002 -2.07971004 0 P 0 ;0
L 1.40503002 -2.07971004 1.40801998 -2.07881998 0 P 0 ;0
L 1.40801998 -2.07881998 1.41128996 -2.07796004 0 P 0 ;0
L 1.41128996 -2.07796004 1.41506004 -2.07691998 0 P 0 ;0
L 1.41506004 -2.07691998 1.41871998 -2.07585 0 P 0 ;0
L 1.41871998 -2.07585 1.42165 -2.07495 0 P 0 ;0
L 1.42165 -2.07495 1.42791998 -2.07295 0 P 0 ;0
L 1.42791998 -2.07295 1.42731998 -2.08241004 0 P 0 ;0
L 1.42731998 -2.08241004 1.42701004 -2.08708002 0 P 0 ;0
L 1.42701004 -2.08708002 1.42658002 -2.09353996 0 P 0 ;0
L 1.42658002 -2.09353996 1.4261 -2.10055 0 P 0 ;0
L 1.4261 -2.10055 1.42566998 -2.10706004 0 P 0 ;0
L 1.42566998 -2.10706004 1.42525 -2.11306004 0 P 0 ;0
L 1.42525 -2.11306004 1.42491998 -2.11851998 0 P 0 ;0
L 1.42491998 -2.11851998 1.42466004 -2.1231 0 P 0 ;0
L 1.42466004 -2.1231 1.42461004 -2.12471004 0 P 0 ;0
L 1.42461004 -2.12471004 1.4246 -2.12716004 0 P 0 ;0
L 1.4246 -2.12716004 1.47893002 -2.12716004 0 P 0 ;0
L 1.47893002 -2.12716004 1.47893002 -2.11358002 0 P 0 ;0
L 1.47893002 -2.11358002 1.47905 -2.10616998 0 P 0 ;0
L 1.47905 -2.10616998 1.47943996 -2.09385 0 P 0 ;0
L 1.47943996 -2.09385 1.48 -2.07968996 0 P 0 ;0
L 1.48 -2.07968996 1.48066004 -2.0655 0 P 0 ;0
L 1.48066004 -2.0655 1.4813 -2.05168996 0 P 0 ;0
L 1.4813 -2.05168996 1.48175 -2.03873996 0 P 0 ;0
L 1.48175 -2.03873996 1.48201998 -2.02785 0 P 0 ;0
L 1.48201998 -2.02785 1.48191998 -2.02286004 0 P 0 ;0
L 1.48191998 -2.02286004 1.48165 -2.01995 0 P 0 ;0
L 1.48165 -2.01995 1.48115 -2.01708002 0 P 0 ;0
L 1.48115 -2.01708002 1.48043996 -2.01425 0 P 0 ;0
L 1.48043996 -2.01425 1.47951004 -2.01146998 0 P 0 ;0
L 1.47951004 -2.01146998 1.47866998 -2.00946998 0 P 0 ;0
L 1.47866998 -2.00946998 1.47768002 -2.00753996 0 P 0 ;0
L 1.47768002 -2.00753996 1.47655 -2.00568002 0 P 0 ;0
L 1.47655 -2.00568002 1.47528002 -2.00391998 0 P 0 ;0
L 1.47528002 -2.00391998 1.47388002 -2.00225 0 P 0 ;0
L 1.47388002 -2.00225 1.47228996 -2.00063002 0 P 0 ;0
L 1.47228996 -2.00063002 1.4706 -1.99911998 0 P 0 ;0
L 1.4706 -1.99911998 1.4688 -1.99773002 0 P 0 ;0
L 1.4688 -1.99773002 1.46691004 -1.99648002 0 P 0 ;0
L 1.46691004 -1.99648002 1.46491998 -1.99535 0 P 0 ;0
L 1.46491998 -1.99535 1.46098996 -1.99351004 0 P 0 ;0
L 1.46098996 -1.99351004 1.45693002 -1.99196998 0 P 0 ;0
L 1.45693002 -1.99196998 1.45276004 -1.99076004 0 P 0 ;0
L 1.45276004 -1.99076004 1.44953996 -1.99006004 0 P 0 ;0
L 1.44953996 -1.99006004 1.44628996 -1.98956004 0 P 0 ;0
L 1.44628996 -1.98956004 1.44298002 -1.98923996 0 P 0 ;0
L 1.44298002 -1.98923996 1.42695 -1.98856998 0 P 0 ;0
L 1.42695 -1.98856998 1.41038996 -1.98865 0 P 0 ;0
L 1.41038996 -1.98865 1.4042 -1.98901004 0 P 0 ;0
L 1.4042 -1.98901004 1.39798996 -1.98971998 0 P 0 ;0
L 1.35778996 -2.11545 1.4153 -2.11545 0 P 0 ;0
L 1.35688996 -2.11445 1.41558996 -2.11445 0 P 0 ;0
L 1.35608002 -2.11345 1.41588002 -2.11345 0 P 0 ;0
L 1.35533002 -2.11245 1.41616998 -2.11245 0 P 0 ;0
L 1.35463996 -2.11145 1.41646004 -2.11145 0 P 0 ;0
L 1.35401004 -2.11045 1.41675 -2.11045 0 P 0 ;0
L 1.35341004 -2.10945 1.41703996 -2.10945 0 P 0 ;0
L 1.3529 -2.10845 1.41733002 -2.10845 0 P 0 ;0
L 1.35238002 -2.10745 1.41761998 -2.10745 0 P 0 ;0
L 1.35195 -2.10645 1.41788002 -2.10645 0 P 0 ;0
L 1.35155 -2.10545 1.41816004 -2.10545 0 P 0 ;0
L 1.3512 -2.10445 1.41841998 -2.10445 0 P 0 ;0
L 1.35091004 -2.10345 1.41868996 -2.10345 0 P 0 ;0
L 1.35066004 -2.10245 1.41896004 -2.10245 0 P 0 ;0
L 1.35046998 -2.10145 1.41923002 -2.10145 0 P 0 ;0
L 1.35033996 -2.10045 1.41948996 -2.10045 0 P 0 ;0
L 1.35021998 -2.09945 1.40141004 -2.09945 0 P 0 ;0
L 1.35016004 -2.09845 1.39791004 -2.09845 0 P 0 ;0
L 1.3501 -2.09745 1.39616004 -2.09745 0 P 0 ;0
L 1.35008002 -2.09645 1.39496004 -2.09645 0 P 0 ;0
L 1.35006998 -2.09545 1.39406004 -2.09545 0 P 0 ;0
L 1.35005 -2.09445 1.39338002 -2.09445 0 P 0 ;0
L 1.35003996 -2.09345 1.39288002 -2.09345 0 P 0 ;0
L 1.35001998 -2.09245 1.39253002 -2.09245 0 P 0 ;0
L 1.35001004 -2.09145 1.3923 -2.09145 0 P 0 ;0
L 1.35001998 -2.09045 1.3922 -2.09045 0 P 0 ;0
L 1.35003002 -2.08945 1.3922 -2.08945 0 P 0 ;0
L 1.35005 -2.08845 1.39231998 -2.08845 0 P 0 ;0
L 1.35006998 -2.08745 1.39256004 -2.08745 0 P 0 ;0
L 1.35008002 -2.08645 1.39293002 -2.08645 0 P 0 ;0
L 1.3501 -2.08545 1.39343002 -2.08545 0 P 0 ;0
L 1.35011004 -2.08445 1.39408996 -2.08445 0 P 0 ;0
L 1.39438002 -2.12845 1.3883 -2.12836004 0 P 0 ;0
L 1.3883 -2.12836004 1.38426998 -2.128 0 P 0 ;0
L 1.38426998 -2.128 1.38028002 -2.12733002 0 P 0 ;0
L 1.38028002 -2.12733002 1.37635 -2.12636004 0 P 0 ;0
L 1.37635 -2.12636004 1.37248996 -2.12508002 0 P 0 ;0
L 1.37248996 -2.12508002 1.36983996 -2.12398002 0 P 0 ;0
L 1.36983996 -2.12398002 1.36728996 -2.1227 0 P 0 ;0
L 1.36728996 -2.1227 1.36481998 -2.12123996 0 P 0 ;0
L 1.36481998 -2.12123996 1.36246004 -2.11961004 0 P 0 ;0
L 1.36246004 -2.11961004 1.36023002 -2.11781998 0 P 0 ;0
L 1.36023002 -2.11781998 1.35828996 -2.116 0 P 0 ;0
L 1.35828996 -2.116 1.35651998 -2.11403002 0 P 0 ;0
L 1.35651998 -2.11403002 1.35493002 -2.11191004 0 P 0 ;0
L 1.35493002 -2.11191004 1.35353002 -2.10966998 0 P 0 ;0
L 1.35353002 -2.10966998 1.35231004 -2.10731004 0 P 0 ;0
L 1.35231004 -2.10731004 1.35166998 -2.10576998 0 P 0 ;0
L 1.35166998 -2.10576998 1.35111004 -2.1042 0 P 0 ;0
L 1.35111004 -2.1042 1.35071998 -2.10276004 0 P 0 ;0
L 1.35071998 -2.10276004 1.35045 -2.1013 0 P 0 ;0
L 1.35045 -2.1013 1.35021998 -2.09943002 0 P 0 ;0
L 1.35021998 -2.09943002 1.3501 -2.09753002 0 P 0 ;0
L 1.3501 -2.09753002 1.35001004 -2.09128002 0 P 0 ;0
L 1.35001004 -2.09128002 1.35011998 -2.0844 0 P 0 ;0
L 1.35011998 -2.0844 1.35023996 -2.08258996 0 P 0 ;0
L 1.35023996 -2.08258996 1.3505 -2.08083996 0 P 0 ;0
L 1.3505 -2.08083996 1.35071998 -2.07985 0 P 0 ;0
L 1.35071998 -2.07985 1.35101004 -2.07888002 0 P 0 ;0
L 1.35101004 -2.07888002 1.35136004 -2.07793002 0 P 0 ;0
L 1.35136004 -2.07793002 1.35335 -2.07351998 0 P 0 ;0
L 1.35335 -2.07351998 1.35491998 -2.07065 0 P 0 ;0
L 1.35491998 -2.07065 1.35683002 -2.0677 0 P 0 ;0
L 1.35683002 -2.0677 1.35876998 -2.06511004 0 P 0 ;0
L 1.35876998 -2.06511004 1.35948996 -2.0643 0 P 0 ;0
L 1.35948996 -2.0643 1.36026998 -2.06356004 0 P 0 ;0
L 1.36026998 -2.06356004 1.3624 -2.06181998 0 P 0 ;0
L 1.3624 -2.06181998 1.36465 -2.06023996 0 P 0 ;0
L 1.36465 -2.06023996 1.36701004 -2.05883002 0 P 0 ;0
L 1.36701004 -2.05883002 1.37173002 -2.05641004 0 P 0 ;0
L 1.37173002 -2.05641004 1.37656004 -2.05426998 0 P 0 ;0
L 1.37656004 -2.05426998 1.38243002 -2.05203996 0 P 0 ;0
L 1.38243002 -2.05203996 1.38836004 -2.0501 0 P 0 ;0
L 1.38836004 -2.0501 1.4023 -2.04645 0 P 0 ;0
L 1.4023 -2.04645 1.41148996 -2.044 0 P 0 ;0
L 1.41148996 -2.044 1.42016998 -2.04095 0 P 0 ;0
L 1.42016998 -2.04095 1.42016998 -2.04093996 0 P 0 ;0
L 1.42016998 -2.04093996 1.42021004 -2.04093996 0 P 0 ;0
L 1.42021004 -2.04093996 1.42023996 -2.04093002 0 P 0 ;0
L 1.42023996 -2.04093002 1.42746998 -2.03776004 0 P 0 ;0
L 1.42746998 -2.03776004 1.42753002 -2.03773002 0 P 0 ;0
L 1.42753002 -2.03773002 1.42796998 -2.03748996 0 P 0 ;0
L 1.42796998 -2.03748996 1.42846004 -2.03718996 0 P 0 ;0
L 1.42846004 -2.03718996 1.42891998 -2.03683996 0 P 0 ;0
L 1.42891998 -2.03683996 1.42935 -2.03646004 0 P 0 ;0
L 1.42935 -2.03646004 1.42975 -2.03603996 0 P 0 ;0
L 1.42975 -2.03603996 1.43011004 -2.0356 0 P 0 ;0
L 1.43011004 -2.0356 1.43016004 -2.03553002 0 P 0 ;0
L 1.43016004 -2.03553002 1.4299 -2.03535 0 P 0 ;0
L 1.4299 -2.03535 1.43028002 -2.03535 0 P 0 ;0
L 1.43028002 -2.03535 1.43043996 -2.03513002 0 P 0 ;0
L 1.43043996 -2.03513002 1.43048002 -2.03506004 0 P 0 ;0
L 1.43048002 -2.03506004 1.43041998 -2.03501998 0 P 0 ;0
L 1.43041998 -2.03501998 1.4305 -2.03501998 0 P 0 ;0
L 1.4305 -2.03501998 1.43073002 -2.03463002 0 P 0 ;0
L 1.43073002 -2.03463002 1.43096004 -2.03415 0 P 0 ;0
L 1.43096004 -2.03415 1.43115 -2.03365 0 P 0 ;0
L 1.43115 -2.03365 1.4313 -2.03313002 0 P 0 ;0
L 1.4313 -2.03313002 1.4314 -2.03261004 0 P 0 ;0
L 1.4314 -2.03261004 1.43146004 -2.03208002 0 P 0 ;0
L 1.43146004 -2.03208002 1.43146998 -2.03155 0 P 0 ;0
L 1.43146998 -2.03155 1.43143996 -2.03101004 0 P 0 ;0
L 1.43143996 -2.03101004 1.43143002 -2.03093002 0 P 0 ;0
L 1.43143002 -2.03093002 1.43136004 -2.03048996 0 P 0 ;0
L 1.43136004 -2.03048996 1.43125 -2.02996998 0 P 0 ;0
L 1.43125 -2.02996998 1.43108002 -2.02946004 0 P 0 ;0
L 1.43108002 -2.02946004 1.43086998 -2.02896004 0 P 0 ;0
L 1.43086998 -2.02896004 1.43063002 -2.02848996 0 P 0 ;0
L 1.43063002 -2.02848996 1.43033996 -2.02803996 0 P 0 ;0
L 1.43033996 -2.02803996 1.43001998 -2.02761004 0 P 0 ;0
L 1.43001998 -2.02761004 1.42966004 -2.02721004 0 P 0 ;0
L 1.42966004 -2.02721004 1.42928002 -2.02685 0 P 0 ;0
L 1.42928002 -2.02685 1.42886004 -2.02651998 0 P 0 ;0
L 1.42886004 -2.02651998 1.42841998 -2.02623002 0 P 0 ;0
L 1.42841998 -2.02623002 1.42795 -2.02596998 0 P 0 ;0
L 1.42795 -2.02596998 1.42746004 -2.02575 0 P 0 ;0
L 1.42746004 -2.02575 1.42583002 -2.02518002 0 P 0 ;0
L 1.42583002 -2.02518002 1.42416004 -2.02476004 0 P 0 ;0
L 1.42416004 -2.02476004 1.42245 -2.02448002 0 P 0 ;0
L 1.42245 -2.02448002 1.42075 -2.02435 0 P 0 ;0
L 1.42075 -2.02435 1.41565 -2.02428002 0 P 0 ;0
L 1.41565 -2.02428002 1.4156 -2.02428002 0 P 0 ;0
L 1.4156 -2.02428002 1.41055 -2.02445 0 P 0 ;0
L 1.41055 -2.02445 1.41048002 -2.02445 0 P 0 ;0
L 1.41048002 -2.02445 1.40128996 -2.02533996 0 P 0 ;0
L 1.40128996 -2.02533996 1.39208996 -2.02696998 0 P 0 ;0
L 1.39208996 -2.02696998 1.38288002 -2.02936004 0 P 0 ;0
L 1.38288002 -2.02936004 1.37363002 -2.03251998 0 P 0 ;0
L 1.37363002 -2.03251998 1.37076998 -2.03356004 0 P 0 ;0
L 1.37076998 -2.03356004 1.36865 -2.03426998 0 P 0 ;0
L 1.36865 -2.03426998 1.36906004 -2.03066998 0 P 0 ;0
L 1.36906004 -2.03066998 1.36988996 -2.02383996 0 P 0 ;0
L 1.36988996 -2.02383996 1.37095 -2.01581004 0 P 0 ;0
L 1.37095 -2.01581004 1.37358996 -1.99631998 0 P 0 ;0
L 1.37358996 -1.99631998 1.37988002 -1.99491998 0 P 0 ;0
L 1.37988002 -1.99491998 1.38353996 -1.99416998 0 P 0 ;0
L 1.38353996 -1.99416998 1.38841998 -1.99326998 0 P 0 ;0
L 1.38841998 -1.99326998 1.39358002 -1.9924 0 P 0 ;0
L 1.39358002 -1.9924 1.39825 -1.9917 0 P 0 ;0
L 1.39825 -1.9917 1.40436998 -1.991 0 P 0 ;0
L 1.40436998 -1.991 1.41045 -1.99065 0 P 0 ;0
L 1.41045 -1.99065 1.42691004 -1.99056998 0 P 0 ;0
L 1.42691004 -1.99056998 1.44283996 -1.99123996 0 P 0 ;0
L 1.44283996 -1.99123996 1.44603996 -1.99153996 0 P 0 ;0
L 1.44603996 -1.99153996 1.44918002 -1.99203002 0 P 0 ;0
L 1.44918002 -1.99203002 1.45226004 -1.9927 0 P 0 ;0
L 1.45226004 -1.9927 1.4563 -1.99386998 0 P 0 ;0
L 1.4563 -1.99386998 1.46021004 -1.99535 0 P 0 ;0
L 1.46021004 -1.99535 1.464 -1.99713002 0 P 0 ;0
L 1.464 -1.99713002 1.46586004 -1.99818996 0 P 0 ;0
L 1.46586004 -1.99818996 1.46763996 -1.99936004 0 P 0 ;0
L 1.46763996 -1.99936004 1.46931998 -2.00066004 0 P 0 ;0
L 1.46931998 -2.00066004 1.47091004 -2.00206998 0 P 0 ;0
L 1.47091004 -2.00206998 1.47238996 -2.00358996 0 P 0 ;0
L 1.47238996 -2.00358996 1.4737 -2.00515 0 P 0 ;0
L 1.4737 -2.00515 1.47488002 -2.00678996 0 P 0 ;0
L 1.47488002 -2.00678996 1.47593996 -2.00851004 0 P 0 ;0
L 1.47593996 -2.00851004 1.47686004 -2.01031004 0 P 0 ;0
L 1.47686004 -2.01031004 1.47763996 -2.01216998 0 P 0 ;0
L 1.47763996 -2.01216998 1.47851998 -2.01481004 0 P 0 ;0
L 1.47851998 -2.01481004 1.47918996 -2.01748996 0 P 0 ;0
L 1.47918996 -2.01748996 1.47966004 -2.02021998 0 P 0 ;0
L 1.47966004 -2.02021998 1.47993002 -2.02296998 0 P 0 ;0
L 1.47993002 -2.02296998 1.48001998 -2.02783996 0 P 0 ;0
L 1.48001998 -2.02783996 1.47975 -2.03868996 0 P 0 ;0
L 1.47975 -2.03868996 1.4793 -2.05161004 0 P 0 ;0
L 1.4793 -2.05161004 1.47866004 -2.06543002 0 P 0 ;0
L 1.47866004 -2.06543002 1.47801004 -2.07961004 0 P 0 ;0
L 1.47801004 -2.07961004 1.47743996 -2.09378996 0 P 0 ;0
L 1.47743996 -2.09378996 1.47705 -2.10613002 0 P 0 ;0
L 1.47705 -2.10613002 1.47693002 -2.11356004 0 P 0 ;0
L 1.47693002 -2.11356004 1.47693002 -2.12516004 0 P 0 ;0
L 1.47693002 -2.12516004 1.42661004 -2.12516004 0 P 0 ;0
L 1.42661004 -2.12516004 1.42661004 -2.12473996 0 P 0 ;0
L 1.42661004 -2.12473996 1.42666004 -2.12318002 0 P 0 ;0
L 1.42666004 -2.12318002 1.42691004 -2.11863996 0 P 0 ;0
L 1.42691004 -2.11863996 1.42725 -2.1132 0 P 0 ;0
L 1.42725 -2.1132 1.42766004 -2.1072 0 P 0 ;0
L 1.42766004 -2.1072 1.42766004 -2.10718996 0 P 0 ;0
L 1.42766004 -2.10718996 1.4281 -2.10068996 0 P 0 ;0
L 1.4281 -2.10068996 1.42858002 -2.09368002 0 P 0 ;0
L 1.42858002 -2.09368002 1.42901004 -2.08721004 0 P 0 ;0
L 1.42901004 -2.08721004 1.42901004 -2.0872 0 P 0 ;0
L 1.42901004 -2.0872 1.42931004 -2.08256004 0 P 0 ;0
L 1.42931004 -2.08256004 1.42991998 -2.07308002 0 P 0 ;0
L 1.42991998 -2.07308002 1.42916004 -2.07136998 0 P 0 ;0
L 1.42916004 -2.07136998 1.42731998 -2.07105 0 P 0 ;0
L 1.42731998 -2.07105 1.42105 -2.07303996 0 P 0 ;0
L 1.42105 -2.07303996 1.41815 -2.07393002 0 P 0 ;0
L 1.41815 -2.07393002 1.41451004 -2.075 0 P 0 ;0
L 1.41451004 -2.075 1.41076004 -2.07603002 0 P 0 ;0
L 1.41076004 -2.07603002 1.40748002 -2.0769 0 P 0 ;0
L 1.40748002 -2.0769 1.40438996 -2.07781004 0 P 0 ;0
L 1.40438996 -2.07781004 1.40431998 -2.07783996 0 P 0 ;0
L 1.40431998 -2.07783996 1.40133996 -2.07896998 0 P 0 ;0
L 1.40133996 -2.07896998 1.40005 -2.07956998 0 P 0 ;0
L 1.40005 -2.07956998 1.39881998 -2.08026004 0 P 0 ;0
L 1.39881998 -2.08026004 1.39763996 -2.08103002 0 P 0 ;0
L 1.39763996 -2.08103002 1.39651998 -2.08188002 0 P 0 ;0
L 1.39651998 -2.08188002 1.39578996 -2.08251004 0 P 0 ;0
L 1.39578996 -2.08251004 1.39573996 -2.08256004 0 P 0 ;0
L 1.39573996 -2.08256004 1.3951 -2.08318996 0 P 0 ;0
L 1.3951 -2.08318996 1.39446998 -2.08393002 0 P 0 ;0
L 1.39446998 -2.08393002 1.3939 -2.08471004 0 P 0 ;0
L 1.3939 -2.08471004 1.39336998 -2.08553996 0 P 0 ;0
L 1.39336998 -2.08553996 1.39301004 -2.08623996 0 P 0 ;0
L 1.39301004 -2.08623996 1.39271004 -2.08696998 0 P 0 ;0
L 1.39271004 -2.08696998 1.39248002 -2.08771998 0 P 0 ;0
L 1.39248002 -2.08771998 1.39231004 -2.08848996 0 P 0 ;0
L 1.39231004 -2.08848996 1.39221004 -2.08926004 0 P 0 ;0
L 1.39221004 -2.08926004 1.39218002 -2.09003996 0 P 0 ;0
L 1.39218002 -2.09003996 1.39221004 -2.0908 0 P 0 ;0
L 1.39221004 -2.0908 1.39231004 -2.09153002 0 P 0 ;0
L 1.39231004 -2.09153002 1.39246998 -2.09226004 0 P 0 ;0
L 1.39246998 -2.09226004 1.39268996 -2.09296998 0 P 0 ;0
L 1.39268996 -2.09296998 1.39296004 -2.09365 0 P 0 ;0
L 1.39296004 -2.09365 1.3933 -2.09431004 0 P 0 ;0
L 1.3933 -2.09431004 1.39368996 -2.09493996 0 P 0 ;0
L 1.39368996 -2.09493996 1.39411998 -2.09553996 0 P 0 ;0
L 1.39411998 -2.09553996 1.39468996 -2.09618002 0 P 0 ;0
L 1.39468996 -2.09618002 1.3953 -2.09678002 0 P 0 ;0
L 1.3953 -2.09678002 1.39596004 -2.09731998 0 P 0 ;0
L 1.39596004 -2.09731998 1.39666998 -2.0978 0 P 0 ;0
L 1.39666998 -2.0978 1.39673996 -2.09783996 0 P 0 ;0
L 1.39673996 -2.09783996 1.39741004 -2.09821998 0 P 0 ;0
L 1.39741004 -2.09821998 1.39748996 -2.09825 0 P 0 ;0
L 1.39748996 -2.09825 1.39818996 -2.09856998 0 P 0 ;0
L 1.39818996 -2.09856998 1.39898996 -2.09886004 0 P 0 ;0
L 1.39898996 -2.09886004 1.39906998 -2.09888002 0 P 0 ;0
L 1.39906998 -2.09888002 1.40043996 -2.09888002 0 P 0 ;0
L 1.40043996 -2.09888002 1.40033996 -2.09923002 0 P 0 ;0
L 1.40033996 -2.09923002 1.40041998 -2.09925 0 P 0 ;0
L 1.40041998 -2.09925 1.40186004 -2.09953002 0 P 0 ;0
L 1.40186004 -2.09953002 1.40331004 -2.09971004 0 P 0 ;0
L 1.40331004 -2.09971004 1.40478002 -2.09978002 0 P 0 ;0
L 1.40478002 -2.09978002 1.40625 -2.09975 0 P 0 ;0
L 1.40625 -2.09975 1.41096004 -2.09931004 0 P 0 ;0
L 1.41096004 -2.09931004 1.41556998 -2.09855 0 P 0 ;0
L 1.41556998 -2.09855 1.41791998 -2.09813002 0 P 0 ;0
L 1.41791998 -2.09813002 1.41995 -2.09791004 0 P 0 ;0
L 1.41995 -2.09791004 1.4201 -2.0979 0 P 0 ;0
L 1.4201 -2.0979 1.41941004 -2.10078002 0 P 0 ;0
L 1.41941004 -2.10078002 1.41761004 -2.10745 0 P 0 ;0
L 1.41761004 -2.10745 1.41391004 -2.12025 0 P 0 ;0
L 1.41391004 -2.12025 1.41215 -2.12626998 0 P 0 ;0
L 1.41215 -2.12626998 1.40655 -2.12725 0 P 0 ;0
L 1.40655 -2.12725 1.40046004 -2.12808002 0 P 0 ;0
L 1.40046004 -2.12808002 1.39438002 -2.12845 0 P 0 ;0
L 1.15303002 -2.08283002 1.20788996 -2.08283002 0 P 0 ;0
L 1.15398996 -2.08183002 1.20795 -2.08183002 0 P 0 ;0
L 1.15483002 -2.08083002 1.208 -2.08083002 0 P 0 ;0
L 1.15555 -2.07983002 1.20805 -2.07983002 0 P 0 ;0
L 1.15621998 -2.07883002 1.2081 -2.07883002 0 P 0 ;0
L 1.15681998 -2.07783002 1.20816004 -2.07783002 0 P 0 ;0
L 1.15733002 -2.07683002 1.20821004 -2.07683002 0 P 0 ;0
L 1.15778996 -2.07583002 1.20826004 -2.07583002 0 P 0 ;0
L 1.15818002 -2.07483002 1.20831004 -2.07483002 0 P 0 ;0
L 1.15853996 -2.07383002 1.20836998 -2.07383002 0 P 0 ;0
L 1.15881998 -2.07283002 1.20841998 -2.07283002 0 P 0 ;0
L 1.1591 -2.07183002 1.20846998 -2.07183002 0 P 0 ;0
L 1.15938002 -2.07083002 1.20853002 -2.07083002 0 P 0 ;0
L 1.1596 -2.06983002 1.20858002 -2.06983002 0 P 0 ;0
L 1.15981004 -2.06883002 1.20863996 -2.06883002 0 P 0 ;0
L 1.16001004 -2.06783002 1.20868996 -2.06783002 0 P 0 ;0
L 1.1602 -2.06683002 1.20875 -2.06683002 0 P 0 ;0
L 1.16033996 -2.06583002 1.2088 -2.06583002 0 P 0 ;0
L 1.16048996 -2.06483002 1.20886004 -2.06483002 0 P 0 ;0
L 1.16063996 -2.06383002 1.20891998 -2.06383002 0 P 0 ;0
L 1.16078002 -2.06283002 1.20896998 -2.06283002 0 P 0 ;0
L 1.16088996 -2.06183002 1.20903002 -2.06183002 0 P 0 ;0
L 1.16098996 -2.06083002 1.20908002 -2.06083002 0 P 0 ;0
L 1.16108996 -2.05983002 1.20913996 -2.05983002 0 P 0 ;0
L 1.16118002 -2.05883002 1.20918996 -2.05883002 0 P 0 ;0
L 1.16128002 -2.05783002 1.20925 -2.05783002 0 P 0 ;0
L 1.16133996 -2.05683002 1.2093 -2.05683002 0 P 0 ;0
L 1.1614 -2.05583002 1.20936004 -2.05583002 0 P 0 ;0
L 1.16146004 -2.05483002 1.20941004 -2.05483002 0 P 0 ;0
L 1.16151998 -2.05383002 1.20946998 -2.05383002 0 P 0 ;0
L 1.16158002 -2.05283002 1.20951998 -2.05283002 0 P 0 ;0
L 1.16163996 -2.05183002 1.20958002 -2.05183002 0 P 0 ;0
L 1.1617 -2.05083002 1.20963996 -2.05083002 0 P 0 ;0
L 1.16175 -2.04983002 1.2097 -2.04983002 0 P 0 ;0
L 1.16181004 -2.04883002 1.20975 -2.04883002 0 P 0 ;0
L 1.16186998 -2.04783002 1.20981004 -2.04783002 0 P 0 ;0
L 1.16193002 -2.04683002 1.20986998 -2.04683002 0 P 0 ;0
L 1.16198996 -2.04583002 1.20993002 -2.04583002 0 P 0 ;0
L 1.16205 -2.04483002 1.20998996 -2.04483002 0 P 0 ;0
L 1.16211004 -2.04383002 1.21005 -2.04383002 0 P 0 ;0
L 1.16215 -2.04283002 1.2101 -2.04283002 0 P 0 ;0
L 1.1622 -2.04183002 1.21016004 -2.04183002 0 P 0 ;0
L 1.16225 -2.04083002 1.21021998 -2.04083002 0 P 0 ;0
L 1.16228996 -2.03983002 1.21028002 -2.03983002 0 P 0 ;0
L 1.16233996 -2.03883002 1.21033996 -2.03883002 0 P 0 ;0
L 1.16238002 -2.03783002 1.2104 -2.03783002 0 P 0 ;0
L 1.16243002 -2.03683002 1.21046004 -2.03683002 0 P 0 ;0
L 1.16246998 -2.03583002 1.21051004 -2.03583002 0 P 0 ;0
L 1.16251998 -2.03483002 1.21056998 -2.03483002 0 P 0 ;0
L 1.16256998 -2.03383002 1.21063996 -2.03383002 0 P 0 ;0
L 1.16261004 -2.03283002 1.2107 -2.03283002 0 P 0 ;0
L 1.16266004 -2.03183002 1.21076004 -2.03183002 0 P 0 ;0
L 1.1627 -2.03083002 1.21083002 -2.03083002 0 P 0 ;0
L 1.16015 -1.97631004 1.17066004 -1.97631004 0 P 0 ;0
L 1.15961998 -1.97531004 1.17026004 -1.97531004 0 P 0 ;0
L 1.1591 -1.97431004 1.16986998 -1.97431004 0 P 0 ;0
L 1.15856998 -1.97331004 1.16946998 -1.97331004 0 P 0 ;0
L 1.15803996 -1.97231004 1.16903002 -1.97231004 0 P 0 ;0
L 1.15746998 -1.97131004 1.16858996 -1.97131004 0 P 0 ;0
L 1.1569 -1.97031004 1.16815 -1.97031004 0 P 0 ;0
L 1.15631998 -1.96931004 1.16771004 -1.96931004 0 P 0 ;0
L 1.15573996 -1.96831004 1.16726998 -1.96831004 0 P 0 ;0
L 1.15516004 -1.96731004 1.16681998 -1.96731004 0 P 0 ;0
L 1.15458996 -1.96631004 1.16638002 -1.96631004 0 P 0 ;0
L 1.15398002 -1.96531004 1.16593996 -1.96531004 0 P 0 ;0
L 1.1533 -1.96431004 1.16548996 -1.96431004 0 P 0 ;0
L 1.15261998 -1.96331004 1.16503002 -1.96331004 0 P 0 ;0
L 1.15193996 -1.96231004 1.16448002 -1.96231004 0 P 0 ;0
L 1.15126004 -1.96131004 1.16393002 -1.96131004 0 P 0 ;0
L 1.15058002 -1.96031004 1.16338002 -1.96031004 0 P 0 ;0
L 1.1499 -1.95931004 1.16283002 -1.95931004 0 P 0 ;0
L 1.1491 -1.95831004 1.16228996 -1.95831004 0 P 0 ;0
L 1.14831004 -1.95731004 1.16173996 -1.95731004 0 P 0 ;0
L 1.14751004 -1.95631004 1.16118996 -1.95631004 0 P 0 ;0
L 1.14671004 -1.95531004 1.16063996 -1.95531004 0 P 0 ;0
L 1.14591998 -1.95431004 1.16008996 -1.95431004 0 P 0 ;0
L 1.14511998 -1.95331004 1.15943996 -1.95331004 0 P 0 ;0
L 1.1442 -1.95231004 1.15878002 -1.95231004 0 P 0 ;0
L 1.14326998 -1.95131004 1.15811004 -1.95131004 0 P 0 ;0
L 1.14233996 -1.95031004 1.15745 -1.95031004 0 P 0 ;0
L 1.14141004 -1.94931004 1.15678002 -1.94931004 0 P 0 ;0
L 1.14048996 -1.94831004 1.15611998 -1.94831004 0 P 0 ;0
L 1.1395 -1.94731004 1.15545 -1.94731004 0 P 0 ;0
L 1.13843002 -1.94631004 1.15478996 -1.94631004 0 P 0 ;0
L 1.13736004 -1.94531004 1.15411998 -1.94531004 0 P 0 ;0
L 1.13628996 -1.94431004 1.15333002 -1.94431004 0 P 0 ;0
L 1.13521004 -1.94331004 1.15253002 -1.94331004 0 P 0 ;0
L 1.13413996 -1.94231004 1.15173996 -1.94231004 0 P 0 ;0
L 1.13306998 -1.94131004 1.15093996 -1.94131004 0 P 0 ;0
L 1.132 -1.94031004 1.15013996 -1.94031004 0 P 0 ;0
L 1.13081004 -1.93931004 1.14935 -1.93931004 0 P 0 ;0
L 1.12958002 -1.93831004 1.14855 -1.93831004 0 P 0 ;0
L 1.12833996 -1.93731004 1.14775 -1.93731004 0 P 0 ;0
L 1.1271 -1.93631004 1.14688996 -1.93631004 0 P 0 ;0
L 1.12586004 -1.93531004 1.14593996 -1.93531004 0 P 0 ;0
L 1.12461998 -1.93431004 1.14498996 -1.93431004 0 P 0 ;0
L 1.12338002 -1.93331004 1.14405 -1.93331004 0 P 0 ;0
L 1.12203002 -1.93231004 1.1431 -1.93231004 0 P 0 ;0
L 1.1206 -1.93131004 1.14216004 -1.93131004 0 P 0 ;0
L 1.11916004 -1.93031004 1.14121004 -1.93031004 0 P 0 ;0
L 1.11771998 -1.92931004 1.14026998 -1.92931004 0 P 0 ;0
L 1.11628996 -1.92831004 1.13931998 -1.92831004 0 P 0 ;0
L 1.11483996 -1.92731004 1.13838002 -1.92731004 0 P 0 ;0
L 1.11338996 -1.92631004 1.13743002 -1.92631004 0 P 0 ;0
L 1.11171998 -1.92531004 1.13648996 -1.92531004 0 P 0 ;0
L 1.11005 -1.92431004 1.13538002 -1.92431004 0 P 0 ;0
L 1.10838002 -1.92331004 1.13426998 -1.92331004 0 P 0 ;0
L 1.1067 -1.92231004 1.13315 -1.92231004 0 P 0 ;0
L 1.10503002 -1.92131004 1.13203002 -1.92131004 0 P 0 ;0
L 1.10336004 -1.92031004 1.13091998 -1.92031004 0 P 0 ;0
L 1.1015 -1.91931004 1.1298 -1.91931004 0 P 0 ;0
L 1.09955 -1.91831004 1.12868002 -1.91831004 0 P 0 ;0
L 1.16275 -2.02983002 1.21088996 -2.02983002 0 P 0 ;0
L 1.16278996 -2.02883002 1.21095 -2.02883002 0 P 0 ;0
L 1.16283996 -2.02783002 1.21101004 -2.02783002 0 P 0 ;0
L 1.16226998 -2.02683002 1.21108002 -2.02683002 0 P 0 ;0
L 1.16153996 -2.02583002 1.21113996 -2.02583002 0 P 0 ;0
L 1.15846004 -2.02483002 1.2112 -2.02483002 0 P 0 ;0
L 1.10036004 -2.00383002 1.21255 -2.00383002 0 P 0 ;0
L 1.10226004 -2.00283002 1.2126 -2.00283002 0 P 0 ;0
L 1.10433996 -2.00183002 1.21266998 -2.00183002 0 P 0 ;0
L 1.1065 -2.00083002 1.21273002 -2.00083002 0 P 0 ;0
L 1.10886998 -1.99983002 1.21278996 -1.99983002 0 P 0 ;0
L 1.11138002 -1.99883002 1.21285 -1.99883002 0 P 0 ;0
L 1.11436998 -1.99783002 1.21288002 -1.99783002 0 P 0 ;0
L 1.11748996 -1.99683002 1.21255 -1.99683002 0 P 0 ;0
L 1.12061998 -1.99583002 1.2089 -1.99583002 0 P 0 ;0
L 1.12433996 -1.99483002 1.2036 -1.99483002 0 P 0 ;0
L 1.12863996 -1.99383002 1.19728002 -1.99383002 0 P 0 ;0
L 1.13295 -1.99283002 1.19096998 -1.99283002 0 P 0 ;0
L 1.13985 -1.99183002 1.18111998 -1.99183002 0 P 0 ;0
L 1.14948002 -1.99083002 1.1651 -1.99083002 0 P 0 ;0
L 1.24218002 -2.08316004 1.29143996 -2.08316004 0 P 0 ;0
L 1.24223002 -2.08216004 1.29151004 -2.08216004 0 P 0 ;0
L 1.24228002 -2.08116004 1.29158996 -2.08116004 0 P 0 ;0
L 1.24233996 -2.08016004 1.29166004 -2.08016004 0 P 0 ;0
L 1.24238996 -2.07916004 1.29173002 -2.07916004 0 P 0 ;0
L 1.24245 -2.07816004 1.29181004 -2.07816004 0 P 0 ;0
L 1.2425 -2.07716004 1.29188002 -2.07716004 0 P 0 ;0
L 1.24256004 -2.07616004 1.29195 -2.07616004 0 P 0 ;0
L 1.24261004 -2.07516004 1.29203002 -2.07516004 0 P 0 ;0
L 1.24266998 -2.07416004 1.2921 -2.07416004 0 P 0 ;0
L 1.24271998 -2.07316004 1.29216998 -2.07316004 0 P 0 ;0
L 1.24278002 -2.07216004 1.29223996 -2.07216004 0 P 0 ;0
L 1.24283002 -2.07116004 1.29231998 -2.07116004 0 P 0 ;0
L 1.24288002 -2.07016004 1.29238996 -2.07016004 0 P 0 ;0
L 1.24293002 -2.06916004 1.29246004 -2.06916004 0 P 0 ;0
L 1.24296998 -2.06816004 1.29253002 -2.06816004 0 P 0 ;0
L 1.24301998 -2.06716004 1.29261004 -2.06716004 0 P 0 ;0
L 1.24306004 -2.06616004 1.2927 -2.06616004 0 P 0 ;0
L 1.24311004 -2.06516004 1.29281004 -2.06516004 0 P 0 ;0
L 1.24315 -2.06416004 1.29291998 -2.06416004 0 P 0 ;0
L 1.2432 -2.06316004 1.29303002 -2.06316004 0 P 0 ;0
L 1.24323996 -2.06216004 1.29315 -2.06216004 0 P 0 ;0
L 1.24328996 -2.06116004 1.29331998 -2.06116004 0 P 0 ;0
L 1.24333002 -2.06016004 1.2935 -2.06016004 0 P 0 ;0
L 1.24338002 -2.05916004 1.29366998 -2.05916004 0 P 0 ;0
L 1.24341998 -2.05816004 1.29385 -2.05816004 0 P 0 ;0
L 1.24346998 -2.05716004 1.29408996 -2.05716004 0 P 0 ;0
L 1.24351004 -2.05616004 1.29433996 -2.05616004 0 P 0 ;0
L 1.24355 -2.05516004 1.29458996 -2.05516004 0 P 0 ;0
L 1.2436 -2.05416004 1.29485 -2.05416004 0 P 0 ;0
L 1.24363996 -2.05316004 1.29516998 -2.05316004 0 P 0 ;0
L 1.24368996 -2.05216004 1.29551998 -2.05216004 0 P 0 ;0
L 1.24373002 -2.05116004 1.29586004 -2.05116004 0 P 0 ;0
L 1.24378002 -2.05016004 1.29621004 -2.05016004 0 P 0 ;0
L 1.24383002 -2.04916004 1.29663996 -2.04916004 0 P 0 ;0
L 1.24386998 -2.04816004 1.29708002 -2.04816004 0 P 0 ;0
L 1.24391004 -2.04716004 1.29753002 -2.04716004 0 P 0 ;0
L 1.24396004 -2.04616004 1.29796998 -2.04616004 0 P 0 ;0
L 1.244 -2.04516004 1.29851004 -2.04516004 0 P 0 ;0
L 1.24405 -2.04416004 1.2991 -2.04416004 0 P 0 ;0
L 1.24408996 -2.04316004 1.29975 -2.04316004 0 P 0 ;0
L 1.24413996 -2.04216004 1.3005 -2.04216004 0 P 0 ;0
L 1.24418002 -2.04116004 1.30131998 -2.04116004 0 P 0 ;0
L 1.24423002 -2.04016004 1.30223002 -2.04016004 0 P 0 ;0
L 1.24426998 -2.03916004 1.30326998 -2.03916004 0 P 0 ;0
L 1.24431998 -2.03816004 1.30446004 -2.03816004 0 P 0 ;0
L 1.24436004 -2.03716004 1.30581998 -2.03716004 0 P 0 ;0
L 1.24441004 -2.03616004 1.30738002 -2.03616004 0 P 0 ;0
L 1.24445 -2.03516004 1.30923002 -2.03516004 0 P 0 ;0
L 1.24448996 -2.03416004 1.31156004 -2.03416004 0 P 0 ;0
L 1.24453996 -2.03316004 1.31478996 -2.03316004 0 P 0 ;0
L 1.24458996 -2.03216004 1.32013002 -2.03216004 0 P 0 ;0
L 1.24461998 -2.03116004 1.33481004 -2.03116004 0 P 0 ;0
L 1.24463996 -2.03016004 1.33478002 -2.03016004 0 P 0 ;0
L 1.24466004 -2.02916004 1.33473996 -2.02916004 0 P 0 ;0
L 1.24468002 -2.02816004 1.33471004 -2.02816004 0 P 0 ;0
L 1.2447 -2.02716004 1.33468002 -2.02716004 0 P 0 ;0
L 1.24471998 -2.02616004 1.33463996 -2.02616004 0 P 0 ;0
L 1.24473996 -2.02516004 1.3346 -2.02516004 0 P 0 ;0
L 1.24476004 -2.02416004 1.33456998 -2.02416004 0 P 0 ;0
L 1.24478002 -2.02316004 1.33453002 -2.02316004 0 P 0 ;0
L 1.2448 -2.02216004 1.3345 -2.02216004 0 P 0 ;0
L 1.24481998 -2.02116004 1.33446998 -2.02116004 0 P 0 ;0
L 1.24483996 -2.02016004 1.33443002 -2.02016004 0 P 0 ;0
L 1.24486004 -2.01916004 1.3344 -2.01916004 0 P 0 ;0
L 1.24488002 -2.01816004 1.33436004 -2.01816004 0 P 0 ;0
L 1.2449 -2.01716004 1.33433002 -2.01716004 0 P 0 ;0
L 1.24491998 -2.01616004 1.33428996 -2.01616004 0 P 0 ;0
L 1.24493996 -2.01516004 1.33426004 -2.01516004 0 P 0 ;0
L 1.24496004 -2.01416004 1.33421998 -2.01416004 0 P 0 ;0
L 1.24498002 -2.01316004 1.33418996 -2.01316004 0 P 0 ;0
L 1.245 -2.01216004 1.33415 -2.01216004 0 P 0 ;0
L 1.24501998 -2.01116004 1.33411998 -2.01116004 0 P 0 ;0
L 1.24503996 -2.01016004 1.33408002 -2.01016004 0 P 0 ;0
L 1.24506004 -2.00916004 1.33403996 -2.00916004 0 P 0 ;0
L 1.24508002 -2.00816004 1.334 -2.00816004 0 P 0 ;0
L 1.2451 -2.00716004 1.33396004 -2.00716004 0 P 0 ;0
L 1.24511998 -2.00616004 1.33393002 -2.00616004 0 P 0 ;0
L 1.24513996 -2.00516004 1.29098996 -2.00516004 0 P 0 ;0
L 1.24513996 -2.00416004 1.29033002 -2.00416004 0 P 0 ;0
L 1.24513996 -2.00316004 1.29005 -2.00316004 0 P 0 ;0
L 1.24513996 -2.00216004 1.29005 -2.00216004 0 P 0 ;0
L 1.24513996 -2.00116004 1.29005 -2.00116004 0 P 0 ;0
L 1.24515 -2.00016004 1.29005 -2.00016004 0 P 0 ;0
L 1.24515 -1.99916004 1.29005 -1.99916004 0 P 0 ;0
L 1.24515 -1.99816004 1.29005 -1.99816004 0 P 0 ;0
L 1.24515 -1.99716004 1.29005 -1.99716004 0 P 0 ;0
L 1.24515 -1.99616004 1.29005 -1.99616004 0 P 0 ;0
L 1.24515 -1.99516004 1.29005 -1.99516004 0 P 0 ;0
L 1.16085 -2.02753002 1.1601 -2.04393002 0 P 0 ;0
L 1.1601 -2.04393002 1.15928996 -2.05771998 0 P 0 ;0
L 1.15928996 -2.05771998 1.15883996 -2.06228002 0 P 0 ;0
L 1.15883996 -2.06228002 1.15818002 -2.06681998 0 P 0 ;0
L 1.15818002 -2.06681998 1.15751004 -2.07006998 0 P 0 ;0
L 1.15751004 -2.07006998 1.15661004 -2.07328996 0 P 0 ;0
L 1.15661004 -2.07328996 1.15616004 -2.07453996 0 P 0 ;0
L 1.15616004 -2.07453996 1.15563002 -2.07576998 0 P 0 ;0
L 1.15563002 -2.07576998 1.15501998 -2.07696004 0 P 0 ;0
L 1.15501998 -2.07696004 1.15433002 -2.0781 0 P 0 ;0
L 1.15433002 -2.0781 1.1534 -2.07941998 0 P 0 ;0
L 1.1534 -2.07941998 1.15236004 -2.08066004 0 P 0 ;0
L 1.15236004 -2.08066004 1.15123002 -2.08181998 0 P 0 ;0
L 1.15123002 -2.08181998 1.15001004 -2.08286998 0 P 0 ;0
L 1.15001004 -2.08286998 1.14871004 -2.08383002 0 P 0 ;0
L 1.14871004 -2.08383002 1.14733002 -2.08468002 0 P 0 ;0
L 1.14733002 -2.08468002 1.14591004 -2.0854 0 P 0 ;0
L 1.14591004 -2.0854 1.14443996 -2.086 0 P 0 ;0
L 1.14443996 -2.086 1.14291004 -2.08648002 0 P 0 ;0
L 1.14291004 -2.08648002 1.14136004 -2.08683002 0 P 0 ;0
L 1.14136004 -2.08683002 1.13976998 -2.08703996 0 P 0 ;0
L 1.13976998 -2.08703996 1.13816004 -2.08713002 0 P 0 ;0
L 1.13816004 -2.08713002 1.13656998 -2.08708002 0 P 0 ;0
L 1.13656998 -2.08708002 1.13498996 -2.0869 0 P 0 ;0
L 1.13498996 -2.0869 1.13341998 -2.08658996 0 P 0 ;0
L 1.13341998 -2.08658996 1.13188996 -2.08615 0 P 0 ;0
L 1.13188996 -2.08615 1.1304 -2.08558996 0 P 0 ;0
L 1.1304 -2.08558996 1.12895 -2.08488996 0 P 0 ;0
L 1.12895 -2.08488996 1.12756998 -2.08408002 0 P 0 ;0
L 1.12756998 -2.08408002 1.12625 -2.08315 0 P 0 ;0
L 1.12625 -2.08315 1.12501004 -2.08211998 0 P 0 ;0
L 1.12501004 -2.08211998 1.12386004 -2.081 0 P 0 ;0
L 1.12386004 -2.081 1.12281004 -2.07978002 0 P 0 ;0
L 1.12281004 -2.07978002 1.12183996 -2.07846998 0 P 0 ;0
L 1.12183996 -2.07846998 1.1211 -2.07726004 0 P 0 ;0
L 1.1211 -2.07726004 1.12046998 -2.07598996 0 P 0 ;0
L 1.12046998 -2.07598996 1.11996004 -2.07466998 0 P 0 ;0
L 1.11996004 -2.07466998 1.11955 -2.07331004 0 P 0 ;0
L 1.11955 -2.07331004 1.11926998 -2.07191004 0 P 0 ;0
L 1.11926998 -2.07191004 1.11868002 -2.06693996 0 P 0 ;0
L 1.11868002 -2.06693996 1.11848002 -2.06191004 0 P 0 ;0
L 1.11848002 -2.06191004 1.11871004 -2.05668002 0 P 0 ;0
L 1.11871004 -2.05668002 1.11936004 -2.05148002 0 P 0 ;0
L 1.11936004 -2.05148002 1.11978996 -2.04936998 0 P 0 ;0
L 1.11978996 -2.04936998 1.12036998 -2.0473 0 P 0 ;0
L 1.12036998 -2.0473 1.12108996 -2.04528002 0 P 0 ;0
L 1.12108996 -2.04528002 1.12196004 -2.04331998 0 P 0 ;0
L 1.12196004 -2.04331998 1.1229 -2.04153996 0 P 0 ;0
L 1.1229 -2.04153996 1.12396998 -2.03985 0 P 0 ;0
L 1.12396998 -2.03985 1.12516998 -2.03823002 0 P 0 ;0
L 1.12516998 -2.03823002 1.12735 -2.03573996 0 P 0 ;0
L 1.12735 -2.03573996 1.12973002 -2.03345 0 P 0 ;0
L 1.12973002 -2.03345 1.13223996 -2.03141998 0 P 0 ;0
L 1.13223996 -2.03141998 1.13491998 -2.02961004 0 P 0 ;0
L 1.13491998 -2.02961004 1.13611004 -2.02893002 0 P 0 ;0
L 1.13611004 -2.02893002 1.13735 -2.02833996 0 P 0 ;0
L 1.13735 -2.02833996 1.13861998 -2.02781998 0 P 0 ;0
L 1.13861998 -2.02781998 1.13993996 -2.0274 0 P 0 ;0
L 1.13993996 -2.0274 1.14191004 -2.02693002 0 P 0 ;0
L 1.14191004 -2.02693002 1.14391004 -2.02663002 0 P 0 ;0
L 1.14391004 -2.02663002 1.14935 -2.02626004 0 P 0 ;0
L 1.14935 -2.02626004 1.15471004 -2.0263 0 P 0 ;0
L 1.15471004 -2.0263 1.15591004 -2.02638996 0 P 0 ;0
L 1.15591004 -2.02638996 1.1571 -2.02656998 0 P 0 ;0
L 1.1571 -2.02656998 1.15828002 -2.02683996 0 P 0 ;0
L 1.15828002 -2.02683996 1.16085 -2.02753002 0 P 0 ;0
L 1.13876998 -2.14783002 1.20233002 -2.14783002 0 P 0 ;0
L 1.14236998 -2.14683002 1.20266004 -2.14683002 0 P 0 ;0
L 1.14481004 -2.14583002 1.20296004 -2.14583002 0 P 0 ;0
L 1.1467 -2.14483002 1.20325 -2.14483002 0 P 0 ;0
L 1.14826004 -2.14383002 1.20353002 -2.14383002 0 P 0 ;0
L 1.1496 -2.14283002 1.20373996 -2.14283002 0 P 0 ;0
L 1.15078996 -2.14183002 1.20395 -2.14183002 0 P 0 ;0
L 1.15186004 -2.14083002 1.20415 -2.14083002 0 P 0 ;0
L 1.15278996 -2.13983002 1.20431998 -2.13983002 0 P 0 ;0
L 1.15361998 -2.13883002 1.20446004 -2.13883002 0 P 0 ;0
L 1.15436004 -2.13783002 1.20458002 -2.13783002 0 P 0 ;0
L 1.155 -2.13683002 1.20466998 -2.13683002 0 P 0 ;0
L 1.15556998 -2.13583002 1.20475 -2.13583002 0 P 0 ;0
L 1.15608996 -2.13483002 1.20481998 -2.13483002 0 P 0 ;0
L 1.15653996 -2.13383002 1.20488996 -2.13383002 0 P 0 ;0
L 1.15691004 -2.13283002 1.20496004 -2.13283002 0 P 0 ;0
L 1.15723996 -2.13183002 1.20503002 -2.13183002 0 P 0 ;0
L 1.15751998 -2.13083002 1.2051 -2.13083002 0 P 0 ;0
L 1.15773002 -2.12983002 1.20516004 -2.12983002 0 P 0 ;0
L 1.15793002 -2.12883002 1.20523002 -2.12883002 0 P 0 ;0
L 1.15806004 -2.12783002 1.2053 -2.12783002 0 P 0 ;0
L 1.15816998 -2.12683002 1.20536998 -2.12683002 0 P 0 ;0
L 1.15821004 -2.12583002 1.20543996 -2.12583002 0 P 0 ;0
L 1.11716004 -2.12483002 1.12726004 -2.12483002 0 P 0 ;0
L 1.15823996 -2.12483002 1.20551004 -2.12483002 0 P 0 ;0
L 1.10911998 -2.12383002 1.1352 -2.12383002 0 P 0 ;0
L 1.15821998 -2.12383002 1.20556998 -2.12383002 0 P 0 ;0
L 1.10468996 -2.12283002 1.14018996 -2.12283002 0 P 0 ;0
L 1.1582 -2.12283002 1.20563996 -2.12283002 0 P 0 ;0
L 1.10131004 -2.12183002 1.14366998 -2.12183002 0 P 0 ;0
L 1.15818002 -2.12183002 1.2057 -2.12183002 0 P 0 ;0
L 1.15808996 -2.12083002 1.20576004 -2.12083002 0 P 0 ;0
L 1.15781004 -2.11983002 1.20583002 -2.11983002 0 P 0 ;0
L 1.15721004 -2.11883002 1.20588002 -2.11883002 0 P 0 ;0
L 1.14146004 -2.08883002 1.20758002 -2.08883002 0 P 0 ;0
L 1.14525 -2.08783002 1.20763002 -2.08783002 0 P 0 ;0
L 1.14751004 -2.08683002 1.20768002 -2.08683002 0 P 0 ;0
L 1.14928002 -2.08583002 1.20773002 -2.08583002 0 P 0 ;0
L 1.15073002 -2.08483002 1.20778996 -2.08483002 0 P 0 ;0
L 1.15196004 -2.08383002 1.20783996 -2.08383002 0 P 0 ;0
L 1.13818996 -2.08913002 1.13826998 -2.08913002 0 P 0 ;0
L 1.13826998 -2.08913002 1.13988002 -2.08903996 0 P 0 ;0
L 1.13988002 -2.08903996 1.13996004 -2.08903996 0 P 0 ;0
L 1.13996004 -2.08903996 1.14001004 -2.08903002 0 P 0 ;0
L 1.14001004 -2.08903002 1.14005 -2.08901998 0 P 0 ;0
L 1.14005 -2.08901998 1.14163002 -2.08881004 0 P 0 ;0
L 1.14163002 -2.08881004 1.14166998 -2.0888 0 P 0 ;0
L 1.14166998 -2.0888 1.14171004 -2.0888 0 P 0 ;0
L 1.14171004 -2.0888 1.14178996 -2.08878002 0 P 0 ;0
L 1.14178996 -2.08878002 1.14335 -2.08843002 0 P 0 ;0
L 1.14335 -2.08843002 1.14351004 -2.08838996 0 P 0 ;0
L 1.14351004 -2.08838996 1.14503002 -2.08791004 0 P 0 ;0
L 1.14503002 -2.08791004 1.14511004 -2.08788996 0 P 0 ;0
L 1.14511004 -2.08788996 1.14515 -2.08786998 0 P 0 ;0
L 1.14515 -2.08786998 1.14518996 -2.08786004 0 P 0 ;0
L 1.14518996 -2.08786004 1.14666004 -2.08725 0 P 0 ;0
L 1.14666004 -2.08725 1.14673996 -2.08721998 0 P 0 ;0
L 1.14673996 -2.08721998 1.14678002 -2.0872 0 P 0 ;0
L 1.14678002 -2.0872 1.14681998 -2.08718996 0 P 0 ;0
L 1.14681998 -2.08718996 1.14823996 -2.08646998 0 P 0 ;0
L 1.14823996 -2.08646998 1.14826998 -2.08645 0 P 0 ;0
L 1.14826998 -2.08645 1.14835 -2.08641004 0 P 0 ;0
L 1.14835 -2.08641004 1.14838002 -2.08638002 0 P 0 ;0
L 1.14838002 -2.08638002 1.14976004 -2.08553002 0 P 0 ;0
L 1.14976004 -2.08553002 1.14978996 -2.08551004 0 P 0 ;0
L 1.14978996 -2.08551004 1.14983002 -2.08548996 0 P 0 ;0
L 1.14983002 -2.08548996 1.14988996 -2.08543996 0 P 0 ;0
L 1.14988996 -2.08543996 1.1512 -2.08448996 0 P 0 ;0
L 1.1512 -2.08448996 1.15126004 -2.08443996 0 P 0 ;0
L 1.15126004 -2.08443996 1.15128996 -2.08441004 0 P 0 ;0
L 1.15128996 -2.08441004 1.15131998 -2.08438996 0 P 0 ;0
L 1.15131998 -2.08438996 1.15253996 -2.08333002 0 P 0 ;0
L 1.15253996 -2.08333002 1.15256998 -2.0833 0 P 0 ;0
L 1.15256998 -2.0833 1.1526 -2.08328002 0 P 0 ;0
L 1.1526 -2.08328002 1.15263002 -2.08323996 0 P 0 ;0
L 1.15263002 -2.08323996 1.15266004 -2.08321998 0 P 0 ;0
L 1.15266004 -2.08321998 1.15378996 -2.08206004 0 P 0 ;0
L 1.15378996 -2.08206004 1.15376004 -2.08203996 0 P 0 ;0
L 1.15376004 -2.08203996 1.15381998 -2.08203996 0 P 0 ;0
L 1.15381998 -2.08203996 1.15383996 -2.082 0 P 0 ;0
L 1.15383996 -2.082 1.15386998 -2.08196998 0 P 0 ;0
L 1.15386998 -2.08196998 1.1539 -2.08195 0 P 0 ;0
L 1.1539 -2.08195 1.15493002 -2.08071004 0 P 0 ;0
L 1.15493002 -2.08071004 1.15493002 -2.0807 0 P 0 ;0
L 1.15493002 -2.0807 1.15496004 -2.08066998 0 P 0 ;0
L 1.15496004 -2.08066998 1.15498002 -2.08063996 0 P 0 ;0
L 1.15498002 -2.08063996 1.15501004 -2.08061004 0 P 0 ;0
L 1.15501004 -2.08061004 1.15503002 -2.08058002 0 P 0 ;0
L 1.15503002 -2.08058002 1.15596004 -2.07926004 0 P 0 ;0
L 1.15596004 -2.07926004 1.15603996 -2.07913996 0 P 0 ;0
L 1.15603996 -2.07913996 1.15673002 -2.07798996 0 P 0 ;0
L 1.15673002 -2.07798996 1.15676998 -2.07793002 0 P 0 ;0
L 1.15676998 -2.07793002 1.15678996 -2.07786998 0 P 0 ;0
L 1.15678996 -2.07786998 1.15741004 -2.07668996 0 P 0 ;0
L 1.15741004 -2.07668996 1.15743996 -2.07663002 0 P 0 ;0
L 1.15743996 -2.07663002 1.15746004 -2.07656998 0 P 0 ;0
L 1.15746004 -2.07656998 1.15746998 -2.07656998 0 P 0 ;0
L 1.15746998 -2.07656998 1.158 -2.07533996 0 P 0 ;0
L 1.158 -2.07533996 1.15801004 -2.07531004 0 P 0 ;0
L 1.15801004 -2.07531004 1.15803002 -2.07528002 0 P 0 ;0
L 1.15803002 -2.07528002 1.15805 -2.07521998 0 P 0 ;0
L 1.15805 -2.07521998 1.15848996 -2.07396004 0 P 0 ;0
L 1.15848996 -2.07396004 1.15841004 -2.07393002 0 P 0 ;0
L 1.15841004 -2.07393002 1.15851004 -2.07393002 0 P 0 ;0
L 1.15851004 -2.07393002 1.15851998 -2.0739 0 P 0 ;0
L 1.15851998 -2.0739 1.15853002 -2.07386004 0 P 0 ;0
L 1.15853002 -2.07386004 1.15853996 -2.07383002 0 P 0 ;0
L 1.15853996 -2.07383002 1.15943996 -2.07061004 0 P 0 ;0
L 1.15943996 -2.07061004 1.15945 -2.07058002 0 P 0 ;0
L 1.15945 -2.07058002 1.15946004 -2.07053996 0 P 0 ;0
L 1.15946004 -2.07053996 1.15946998 -2.07051004 0 P 0 ;0
L 1.15946998 -2.07051004 1.15946998 -2.07046998 0 P 0 ;0
L 1.15946998 -2.07046998 1.16013996 -2.06723002 0 P 0 ;0
L 1.16013996 -2.06723002 1.16013996 -2.0672 0 P 0 ;0
L 1.16013996 -2.0672 1.16016004 -2.06713996 0 P 0 ;0
L 1.16016004 -2.06713996 1.16016004 -2.06711004 0 P 0 ;0
L 1.16016004 -2.06711004 1.16081998 -2.06256004 0 P 0 ;0
L 1.16081998 -2.06256004 1.16081998 -2.06253996 0 P 0 ;0
L 1.16081998 -2.06253996 1.16083002 -2.0625 0 P 0 ;0
L 1.16083002 -2.0625 1.16083002 -2.06246998 0 P 0 ;0
L 1.16083002 -2.06246998 1.16126998 -2.05791004 0 P 0 ;0
L 1.16126998 -2.05791004 1.16128002 -2.0579 0 P 0 ;0
L 1.16128002 -2.0579 1.16128002 -2.05783996 0 P 0 ;0
L 1.16128002 -2.05783996 1.1621 -2.04405 0 P 0 ;0
L 1.1621 -2.04405 1.1621 -2.04401998 0 P 0 ;0
L 1.1621 -2.04401998 1.16285 -2.02761998 0 P 0 ;0
L 1.16285 -2.02761998 1.16136998 -2.0256 0 P 0 ;0
L 1.16136998 -2.0256 1.15878996 -2.02491004 0 P 0 ;0
L 1.15878996 -2.02491004 1.15878002 -2.0249 0 P 0 ;0
L 1.15878002 -2.0249 1.15871998 -2.02488996 0 P 0 ;0
L 1.15871998 -2.02488996 1.15755 -2.02461998 0 P 0 ;0
L 1.15755 -2.02461998 1.15746998 -2.0246 0 P 0 ;0
L 1.15746998 -2.0246 1.1574 -2.0246 0 P 0 ;0
L 1.1574 -2.0246 1.15621004 -2.02441004 0 P 0 ;0
L 1.15621004 -2.02441004 1.15616998 -2.02441004 0 P 0 ;0
L 1.15616998 -2.02441004 1.1561 -2.0244 0 P 0 ;0
L 1.1561 -2.0244 1.15606004 -2.02438996 0 P 0 ;0
L 1.15606004 -2.02438996 1.15486004 -2.0243 0 P 0 ;0
L 1.15486004 -2.0243 1.15471998 -2.0243 0 P 0 ;0
L 1.15471998 -2.0243 1.14936004 -2.02426004 0 P 0 ;0
L 1.14936004 -2.02426004 1.14928996 -2.02426004 0 P 0 ;0
L 1.14928996 -2.02426004 1.14925 -2.02426998 0 P 0 ;0
L 1.14925 -2.02426998 1.14921004 -2.02426998 0 P 0 ;0
L 1.14921004 -2.02426998 1.14376998 -2.02463996 0 P 0 ;0
L 1.14376998 -2.02463996 1.1437 -2.02463996 0 P 0 ;0
L 1.1437 -2.02463996 1.14365 -2.02465 0 P 0 ;0
L 1.14365 -2.02465 1.14361004 -2.02465 0 P 0 ;0
L 1.14361004 -2.02465 1.14161998 -2.02495 0 P 0 ;0
L 1.14161998 -2.02495 1.14161004 -2.02495 0 P 0 ;0
L 1.14161004 -2.02495 1.14153002 -2.02496998 0 P 0 ;0
L 1.14153002 -2.02496998 1.14148996 -2.02496998 0 P 0 ;0
L 1.14148996 -2.02496998 1.14143996 -2.02498996 0 P 0 ;0
L 1.14143996 -2.02498996 1.13946998 -2.02545 0 P 0 ;0
L 1.13946998 -2.02545 1.13943996 -2.02546998 0 P 0 ;0
L 1.13943996 -2.02546998 1.1394 -2.02546998 0 P 0 ;0
L 1.1394 -2.02546998 1.13933002 -2.0255 0 P 0 ;0
L 1.13933002 -2.0255 1.13801004 -2.02591998 0 P 0 ;0
L 1.13801004 -2.02591998 1.13798002 -2.02593002 0 P 0 ;0
L 1.13798002 -2.02593002 1.13793996 -2.02593996 0 P 0 ;0
L 1.13793996 -2.02593996 1.13788002 -2.02596998 0 P 0 ;0
L 1.13788002 -2.02596998 1.1366 -2.02648002 0 P 0 ;0
L 1.1366 -2.02648002 1.13653996 -2.0265 0 P 0 ;0
L 1.13653996 -2.0265 1.13648002 -2.02653002 0 P 0 ;0
L 1.13648002 -2.02653002 1.13523996 -2.02713002 0 P 0 ;0
L 1.13523996 -2.02713002 1.13518002 -2.02716004 0 P 0 ;0
L 1.13518002 -2.02716004 1.13515 -2.02716998 0 P 0 ;0
L 1.13515 -2.02716998 1.13511998 -2.02718996 0 P 0 ;0
L 1.13511998 -2.02718996 1.13393002 -2.02786998 0 P 0 ;0
L 1.13393002 -2.02786998 1.13388996 -2.02788996 0 P 0 ;0
L 1.13388996 -2.02788996 1.1338 -2.02795 0 P 0 ;0
L 1.1338 -2.02795 1.13111998 -2.02976004 0 P 0 ;0
L 1.13111998 -2.02976004 1.13105 -2.02981004 0 P 0 ;0
L 1.13105 -2.02981004 1.13101004 -2.02983996 0 P 0 ;0
L 1.13101004 -2.02983996 1.13098002 -2.02986004 0 P 0 ;0
L 1.13098002 -2.02986004 1.12846998 -2.03188996 0 P 0 ;0
L 1.12846998 -2.03188996 1.12838002 -2.03198002 0 P 0 ;0
L 1.12838002 -2.03198002 1.12833996 -2.03201004 0 P 0 ;0
L 1.12833996 -2.03201004 1.12596004 -2.0343 0 P 0 ;0
L 1.12596004 -2.0343 1.12593996 -2.03433002 0 P 0 ;0
L 1.12593996 -2.03433002 1.1259 -2.03436004 0 P 0 ;0
L 1.1259 -2.03436004 1.12588002 -2.03438996 0 P 0 ;0
L 1.12588002 -2.03438996 1.12585 -2.03443002 0 P 0 ;0
L 1.12585 -2.03443002 1.12366998 -2.03691004 0 P 0 ;0
L 1.12366998 -2.03691004 1.12363996 -2.03695 0 P 0 ;0
L 1.12363996 -2.03695 1.12361998 -2.03698002 0 P 0 ;0
L 1.12361998 -2.03698002 1.12358996 -2.03701004 0 P 0 ;0
L 1.12358996 -2.03701004 1.12356998 -2.03703996 0 P 0 ;0
L 1.12356998 -2.03703996 1.12236998 -2.03865 0 P 0 ;0
L 1.12236998 -2.03865 1.12233996 -2.03868996 0 P 0 ;0
L 1.12233996 -2.03868996 1.12233002 -2.03871004 0 P 0 ;0
L 1.12233002 -2.03871004 1.12228996 -2.03878002 0 P 0 ;0
L 1.12228996 -2.03878002 1.12121004 -2.04046998 0 P 0 ;0
L 1.12121004 -2.04046998 1.12118996 -2.0405 0 P 0 ;0
L 1.12118996 -2.0405 1.12116998 -2.04053996 0 P 0 ;0
L 1.12116998 -2.04053996 1.12115 -2.04056998 0 P 0 ;0
L 1.12115 -2.04056998 1.12113996 -2.04061004 0 P 0 ;0
L 1.12113996 -2.04061004 1.12018996 -2.04238002 0 P 0 ;0
L 1.12018996 -2.04238002 1.12016004 -2.04245 0 P 0 ;0
L 1.12016004 -2.04245 1.12013996 -2.04248002 0 P 0 ;0
L 1.12013996 -2.04248002 1.12013002 -2.04251004 0 P 0 ;0
L 1.12013002 -2.04251004 1.11926004 -2.04446998 0 P 0 ;0
L 1.11926004 -2.04446998 1.11925 -2.0445 0 P 0 ;0
L 1.11925 -2.0445 1.11923002 -2.04453996 0 P 0 ;0
L 1.11923002 -2.04453996 1.11921998 -2.04458002 0 P 0 ;0
L 1.11921998 -2.04458002 1.11921004 -2.04461004 0 P 0 ;0
L 1.11921004 -2.04461004 1.11848002 -2.04663002 0 P 0 ;0
L 1.11848002 -2.04663002 1.11846998 -2.04666004 0 P 0 ;0
L 1.11846998 -2.04666004 1.11846004 -2.0467 0 P 0 ;0
L 1.11846004 -2.0467 1.11843996 -2.04676998 0 P 0 ;0
L 1.11843996 -2.04676998 1.11786004 -2.04883996 0 P 0 ;0
L 1.11786004 -2.04883996 1.11785 -2.04886998 0 P 0 ;0
L 1.11785 -2.04886998 1.11783996 -2.04891004 0 P 0 ;0
L 1.11783996 -2.04891004 1.11783996 -2.04893996 0 P 0 ;0
L 1.11783996 -2.04893996 1.11783002 -2.04896998 0 P 0 ;0
L 1.11783002 -2.04896998 1.11783002 -2.04898002 0 P 0 ;0
L 1.11783002 -2.04898002 1.1174 -2.05108002 0 P 0 ;0
L 1.1174 -2.05108002 1.1174 -2.05111998 0 P 0 ;0
L 1.1174 -2.05111998 1.11738996 -2.05116004 0 P 0 ;0
L 1.11738996 -2.05116004 1.11738002 -2.05118996 0 P 0 ;0
L 1.11738002 -2.05118996 1.11738002 -2.05123002 0 P 0 ;0
L 1.11738002 -2.05123002 1.11673002 -2.05643002 0 P 0 ;0
L 1.11673002 -2.05643002 1.11671998 -2.05646998 0 P 0 ;0
L 1.11671998 -2.05646998 1.11671998 -2.05655 0 P 0 ;0
L 1.11671998 -2.05655 1.11671004 -2.05658996 0 P 0 ;0
L 1.11671004 -2.05658996 1.11648996 -2.06181998 0 P 0 ;0
L 1.11648996 -2.06181998 1.11648002 -2.06186998 0 P 0 ;0
L 1.11648002 -2.06186998 1.11648002 -2.06195 0 P 0 ;0
L 1.11648002 -2.06195 1.11648996 -2.06198996 0 P 0 ;0
L 1.11648996 -2.06198996 1.11668002 -2.06696998 0 P 0 ;0
L 1.11668002 -2.06696998 1.11768002 -2.06696998 0 P 0 ;0
L 1.11768002 -2.06696998 1.11668002 -2.06701004 0 P 0 ;0
L 1.11668002 -2.06701004 1.11668002 -2.06713002 0 P 0 ;0
L 1.11668002 -2.06713002 1.11668996 -2.06716998 0 P 0 ;0
L 1.11668996 -2.06716998 1.11728002 -2.07215 0 P 0 ;0
L 1.11728002 -2.07215 1.11728996 -2.07218996 0 P 0 ;0
L 1.11728996 -2.07218996 1.11728996 -2.07223002 0 P 0 ;0
L 1.11728996 -2.07223002 1.11731004 -2.07231004 0 P 0 ;0
L 1.11731004 -2.07231004 1.11758996 -2.07371004 0 P 0 ;0
L 1.11758996 -2.07371004 1.1176 -2.07375 0 P 0 ;0
L 1.1176 -2.07375 1.11761004 -2.0738 0 P 0 ;0
L 1.11761004 -2.0738 1.11761998 -2.07383996 0 P 0 ;0
L 1.11761998 -2.07383996 1.11763996 -2.07388002 0 P 0 ;0
L 1.11763996 -2.07388002 1.11803996 -2.07523996 0 P 0 ;0
L 1.11803996 -2.07523996 1.11806004 -2.07531998 0 P 0 ;0
L 1.11806004 -2.07531998 1.11808002 -2.07536004 0 P 0 ;0
L 1.11808002 -2.07536004 1.11808996 -2.07541004 0 P 0 ;0
L 1.11808996 -2.07541004 1.11861004 -2.07673002 0 P 0 ;0
L 1.11861004 -2.07673002 1.11863996 -2.07681004 0 P 0 ;0
L 1.11863996 -2.07681004 1.11866004 -2.07683996 0 P 0 ;0
L 1.11866004 -2.07683996 1.11868002 -2.07688002 0 P 0 ;0
L 1.11868002 -2.07688002 1.11931004 -2.07815 0 P 0 ;0
L 1.11931004 -2.07815 1.11935 -2.07823002 0 P 0 ;0
L 1.11935 -2.07823002 1.1194 -2.0783 0 P 0 ;0
L 1.1194 -2.0783 1.12013996 -2.07951998 0 P 0 ;0
L 1.12013996 -2.07951998 1.12021004 -2.07961998 0 P 0 ;0
L 1.12021004 -2.07961998 1.12023002 -2.07965 0 P 0 ;0
L 1.12023002 -2.07965 1.12023002 -2.07966004 0 P 0 ;0
L 1.12023002 -2.07966004 1.1212 -2.08096998 0 P 0 ;0
L 1.1212 -2.08096998 1.12123996 -2.08103002 0 P 0 ;0
L 1.12123996 -2.08103002 1.12126998 -2.08106004 0 P 0 ;0
L 1.12126998 -2.08106004 1.12128996 -2.08108996 0 P 0 ;0
L 1.12128996 -2.08108996 1.12235 -2.08231004 0 P 0 ;0
L 1.12235 -2.08231004 1.12238002 -2.08233996 0 P 0 ;0
L 1.12238002 -2.08233996 1.1224 -2.08236998 0 P 0 ;0
L 1.1224 -2.08236998 1.12246004 -2.08243002 0 P 0 ;0
L 1.12246004 -2.08243002 1.12361004 -2.08355 0 P 0 ;0
L 1.12361004 -2.08355 1.12366998 -2.08361004 0 P 0 ;0
L 1.12366998 -2.08361004 1.1237 -2.08363002 0 P 0 ;0
L 1.1237 -2.08363002 1.12373002 -2.08366004 0 P 0 ;0
L 1.12373002 -2.08366004 1.12496998 -2.08468996 0 P 0 ;0
L 1.12496998 -2.08468996 1.125 -2.08471004 0 P 0 ;0
L 1.125 -2.08471004 1.12503002 -2.08473996 0 P 0 ;0
L 1.12503002 -2.08473996 1.12506998 -2.08476004 0 P 0 ;0
L 1.12506998 -2.08476004 1.1251 -2.08478996 0 P 0 ;0
L 1.1251 -2.08478996 1.12641998 -2.08571004 0 P 0 ;0
L 1.12641998 -2.08571004 1.12645 -2.08573002 0 P 0 ;0
L 1.12645 -2.08573002 1.12648002 -2.08576004 0 P 0 ;0
L 1.12648002 -2.08576004 1.12651004 -2.08578002 0 P 0 ;0
L 1.12651004 -2.08578002 1.12655 -2.0858 0 P 0 ;0
L 1.12655 -2.0858 1.12793996 -2.08661004 0 P 0 ;0
L 1.12793996 -2.08661004 1.12801004 -2.08665 0 P 0 ;0
L 1.12801004 -2.08665 1.12805 -2.08666998 0 P 0 ;0
L 1.12805 -2.08666998 1.12808002 -2.08668996 0 P 0 ;0
L 1.12808002 -2.08668996 1.12808996 -2.08668996 0 P 0 ;0
L 1.12808996 -2.08668996 1.12953996 -2.08738996 0 P 0 ;0
L 1.12953996 -2.08738996 1.12961998 -2.08743002 0 P 0 ;0
L 1.12961998 -2.08743002 1.12965 -2.08743996 0 P 0 ;0
L 1.12965 -2.08743996 1.1297 -2.08746004 0 P 0 ;0
L 1.1297 -2.08746004 1.13118002 -2.08801998 0 P 0 ;0
L 1.13118002 -2.08801998 1.13133996 -2.08808002 0 P 0 ;0
L 1.13133996 -2.08808002 1.13286998 -2.08851004 0 P 0 ;0
L 1.13286998 -2.08851004 1.13295 -2.08853996 0 P 0 ;0
L 1.13295 -2.08853996 1.13303996 -2.08855 0 P 0 ;0
L 1.13303996 -2.08855 1.1346 -2.08886004 0 P 0 ;0
L 1.1346 -2.08886004 1.13471998 -2.08888996 0 P 0 ;0
L 1.13471998 -2.08888996 1.13476004 -2.08888996 0 P 0 ;0
L 1.13476004 -2.08888996 1.13633996 -2.08906998 0 P 0 ;0
L 1.13633996 -2.08906998 1.13638996 -2.08908002 0 P 0 ;0
L 1.13638996 -2.08908002 1.13651004 -2.08908002 0 P 0 ;0
L 1.13651004 -2.08908002 1.1381 -2.08913002 0 P 0 ;0
L 1.1381 -2.08913002 1.13818996 -2.08913002 0 P 0 ;0
L 1.31623996 -1.98923996 1.3135 -1.98988002 0 P 0 ;0
L 1.3135 -1.98988002 1.31078996 -1.99071004 0 P 0 ;0
L 1.31078996 -1.99071004 1.30813002 -1.99175 0 P 0 ;0
L 1.30813002 -1.99175 1.30553996 -1.99296998 0 P 0 ;0
L 1.30553996 -1.99296998 1.30308996 -1.99431998 0 P 0 ;0
L 1.30308996 -1.99431998 1.30073996 -1.99585 0 P 0 ;0
L 1.30073996 -1.99585 1.29863996 -1.99746004 0 P 0 ;0
L 1.29863996 -1.99746004 1.29666004 -1.99923996 0 P 0 ;0
L 1.29666004 -1.99923996 1.29205 -2.00375 0 P 0 ;0
L 1.29205 -2.00375 1.29205 -1.99243996 0 P 0 ;0
L 1.29205 -1.99243996 1.24316004 -1.99243996 0 P 0 ;0
L 1.24316004 -1.99243996 1.24313996 -2.00521004 0 P 0 ;0
L 1.24313996 -2.00521004 1.24261004 -2.03151004 0 P 0 ;0
L 1.24261004 -2.03151004 1.24086998 -2.07046004 0 P 0 ;0
L 1.24086998 -2.07046004 1.23873996 -2.10921004 0 P 0 ;0
L 1.23873996 -2.10921004 1.23811998 -2.11641998 0 P 0 ;0
L 1.23811998 -2.11641998 1.23711998 -2.12361998 0 P 0 ;0
L 1.23711998 -2.12361998 1.23655 -2.12716004 0 P 0 ;0
L 1.23655 -2.12716004 1.29205 -2.12716004 0 P 0 ;0
L 1.29205 -2.12716004 1.29206998 -2.11766004 0 P 0 ;0
L 1.29206998 -2.11766004 1.29238996 -2.10283996 0 P 0 ;0
L 1.29238996 -2.10283996 1.29336004 -2.08431004 0 P 0 ;0
L 1.29336004 -2.08431004 1.29463996 -2.06673002 0 P 0 ;0
L 1.29463996 -2.06673002 1.29511004 -2.06253002 0 P 0 ;0
L 1.29511004 -2.06253002 1.29583996 -2.05836004 0 P 0 ;0
L 1.29583996 -2.05836004 1.29683002 -2.05446998 0 P 0 ;0
L 1.29683002 -2.05446998 1.29813996 -2.05068996 0 P 0 ;0
L 1.29813996 -2.05068996 1.29978002 -2.04701998 0 P 0 ;0
L 1.29978002 -2.04701998 1.30056998 -2.04556998 0 P 0 ;0
L 1.30056998 -2.04556998 1.30146998 -2.04418996 0 P 0 ;0
L 1.30146998 -2.04418996 1.30246998 -2.04288002 0 P 0 ;0
L 1.30246998 -2.04288002 1.30356998 -2.04165 0 P 0 ;0
L 1.30356998 -2.04165 1.30475 -2.0405 0 P 0 ;0
L 1.30475 -2.0405 1.30603996 -2.03945 0 P 0 ;0
L 1.30603996 -2.03945 1.30773996 -2.03826004 0 P 0 ;0
L 1.30773996 -2.03826004 1.30953002 -2.03723002 0 P 0 ;0
L 1.30953002 -2.03723002 1.31141004 -2.03635 0 P 0 ;0
L 1.31141004 -2.03635 1.31335 -2.03563002 0 P 0 ;0
L 1.31335 -2.03563002 1.31535 -2.03508002 0 P 0 ;0
L 1.31535 -2.03508002 1.31973996 -2.03423002 0 P 0 ;0
L 1.31973996 -2.03423002 1.32416004 -2.03366998 0 P 0 ;0
L 1.32416004 -2.03366998 1.32863002 -2.0334 0 P 0 ;0
L 1.32863002 -2.0334 1.33688002 -2.03318002 0 P 0 ;0
L 1.33688002 -2.03318002 1.33613002 -2.01151004 0 P 0 ;0
L 1.33613002 -2.01151004 1.33581004 -2.00315 0 P 0 ;0
L 1.33581004 -2.00315 1.33543996 -1.99596004 0 P 0 ;0
L 1.33543996 -1.99596004 1.33508002 -1.98971004 0 P 0 ;0
L 1.33508002 -1.98971004 1.33503996 -1.98945 0 P 0 ;0
L 1.33503996 -1.98945 1.335 -1.98931998 0 P 0 ;0
L 1.335 -1.98931998 1.33496004 -1.9892 0 P 0 ;0
L 1.33496004 -1.9892 1.3349 -1.98908002 0 P 0 ;0
L 1.3349 -1.98908002 1.33483996 -1.98896998 0 P 0 ;0
L 1.33483996 -1.98896998 1.33476998 -1.98886004 0 P 0 ;0
L 1.33476998 -1.98886004 1.33468996 -1.98876004 0 P 0 ;0
L 1.33468996 -1.98876004 1.3346 -1.98866998 0 P 0 ;0
L 1.3346 -1.98866998 1.33451004 -1.98858996 0 P 0 ;0
L 1.33451004 -1.98858996 1.3344 -1.98851998 0 P 0 ;0
L 1.3344 -1.98851998 1.3343 -1.98845 0 P 0 ;0
L 1.3343 -1.98845 1.33418002 -1.98838996 0 P 0 ;0
L 1.33418002 -1.98838996 1.33406998 -1.98833996 0 P 0 ;0
L 1.33406998 -1.98833996 1.33395 -1.9883 0 P 0 ;0
L 1.33395 -1.9883 1.33383002 -1.98828002 0 P 0 ;0
L 1.33383002 -1.98828002 1.3337 -1.98826004 0 P 0 ;0
L 1.3337 -1.98826004 1.33356998 -1.98825 0 P 0 ;0
L 1.33356998 -1.98825 1.32756998 -1.98823002 0 P 0 ;0
L 1.32756998 -1.98823002 1.32135 -1.98853996 0 P 0 ;0
L 1.32135 -1.98853996 1.31878996 -1.98881998 0 P 0 ;0
L 1.31878996 -1.98881998 1.31623996 -1.98923996 0 P 0 ;0
L 1.2389 -2.12516004 1.29006004 -2.12516004 0 P 0 ;0
L 1.23906998 -2.12416004 1.29006004 -2.12416004 0 P 0 ;0
L 1.23921004 -2.12316004 1.29006004 -2.12316004 0 P 0 ;0
L 1.23933996 -2.12216004 1.29006004 -2.12216004 0 P 0 ;0
L 1.23948996 -2.12116004 1.29006004 -2.12116004 0 P 0 ;0
L 1.23961998 -2.12016004 1.29006998 -2.12016004 0 P 0 ;0
L 1.23976004 -2.11916004 1.29006998 -2.11916004 0 P 0 ;0
L 1.2399 -2.11816004 1.29006998 -2.11816004 0 P 0 ;0
L 1.24003996 -2.11716004 1.29008002 -2.11716004 0 P 0 ;0
L 1.24015 -2.11616004 1.2901 -2.11616004 0 P 0 ;0
L 1.24023996 -2.11516004 1.29011998 -2.11516004 0 P 0 ;0
L 1.24033002 -2.11416004 1.29013996 -2.11416004 0 P 0 ;0
L 1.24041004 -2.11316004 1.29016004 -2.11316004 0 P 0 ;0
L 1.24048996 -2.11216004 1.29018996 -2.11216004 0 P 0 ;0
L 1.24058002 -2.11116004 1.29021004 -2.11116004 0 P 0 ;0
L 1.24066998 -2.11016004 1.29023002 -2.11016004 0 P 0 ;0
L 1.24075 -2.10916004 1.29025 -2.10916004 0 P 0 ;0
L 1.2408 -2.10816004 1.29026998 -2.10816004 0 P 0 ;0
L 1.24086004 -2.10716004 1.29028996 -2.10716004 0 P 0 ;0
L 1.24091004 -2.10616004 1.29031998 -2.10616004 0 P 0 ;0
L 1.24096998 -2.10516004 1.29033996 -2.10516004 0 P 0 ;0
L 1.24101998 -2.10416004 1.29036004 -2.10416004 0 P 0 ;0
L 1.24108002 -2.10316004 1.29038002 -2.10316004 0 P 0 ;0
L 1.24113002 -2.10216004 1.29041998 -2.10216004 0 P 0 ;0
L 1.24118002 -2.10116004 1.29046998 -2.10116004 0 P 0 ;0
L 1.24123996 -2.10016004 1.29053002 -2.10016004 0 P 0 ;0
L 1.24128996 -2.09916004 1.29058002 -2.09916004 0 P 0 ;0
L 1.24135 -2.09816004 1.29063002 -2.09816004 0 P 0 ;0
L 1.2414 -2.09716004 1.29068002 -2.09716004 0 P 0 ;0
L 1.24146004 -2.09616004 1.29073996 -2.09616004 0 P 0 ;0
L 1.24151004 -2.09516004 1.29078996 -2.09516004 0 P 0 ;0
L 1.24156998 -2.09416004 1.29083996 -2.09416004 0 P 0 ;0
L 1.24161998 -2.09316004 1.2909 -2.09316004 0 P 0 ;0
L 1.24168002 -2.09216004 1.29095 -2.09216004 0 P 0 ;0
L 1.24173002 -2.09116004 1.291 -2.09116004 0 P 0 ;0
L 1.24178996 -2.09016004 1.29105 -2.09016004 0 P 0 ;0
L 1.24183996 -2.08916004 1.2911 -2.08916004 0 P 0 ;0
L 1.2419 -2.08816004 1.29116004 -2.08816004 0 P 0 ;0
L 1.24196004 -2.08716004 1.29121004 -2.08716004 0 P 0 ;0
L 1.24201004 -2.08616004 1.29126998 -2.08616004 0 P 0 ;0
L 1.24206998 -2.08516004 1.29131998 -2.08516004 0 P 0 ;0
L 1.24211998 -2.08416004 1.29136998 -2.08416004 0 P 0 ;0
L 1.2389 -2.12516004 1.2391 -2.12393002 0 P 0 ;0
L 1.2391 -2.12393002 1.2391 -2.1239 0 P 0 ;0
L 1.2391 -2.1239 1.24011004 -2.11665 0 P 0 ;0
L 1.24011004 -2.11665 1.24073002 -2.10935 0 P 0 ;0
L 1.24073002 -2.10935 1.24073996 -2.10931998 0 P 0 ;0
L 1.24073996 -2.10931998 1.24286004 -2.07056004 0 P 0 ;0
L 1.24286004 -2.07056004 1.24461004 -2.03158002 0 P 0 ;0
L 1.24461004 -2.03158002 1.24513996 -2.00523002 0 P 0 ;0
L 1.24513996 -2.00523002 1.24515 -1.99443996 0 P 0 ;0
L 1.24515 -1.99443996 1.29005 -1.99443996 0 P 0 ;0
L 1.29005 -1.99443996 1.29005 -2.00375 0 P 0 ;0
L 1.29005 -2.00375 1.29128002 -2.0056 0 P 0 ;0
L 1.29128002 -2.0056 1.29345 -2.00518002 0 P 0 ;0
L 1.29345 -2.00518002 1.29803002 -2.0007 0 P 0 ;0
L 1.29803002 -2.0007 1.29991998 -1.999 0 P 0 ;0
L 1.29991998 -1.999 1.30188996 -1.99748996 0 P 0 ;0
L 1.30188996 -1.99748996 1.30411998 -1.99603996 0 P 0 ;0
L 1.30411998 -1.99603996 1.30645 -1.99475 0 P 0 ;0
L 1.30645 -1.99475 1.30891998 -1.99358996 0 P 0 ;0
L 1.30891998 -1.99358996 1.31145 -1.9926 0 P 0 ;0
L 1.31145 -1.9926 1.31401998 -1.99181004 0 P 0 ;0
L 1.31401998 -1.99181004 1.31663996 -1.9912 0 P 0 ;0
L 1.31663996 -1.9912 1.31906004 -1.9908 0 P 0 ;0
L 1.31906004 -1.9908 1.32151004 -1.99053002 0 P 0 ;0
L 1.32151004 -1.99053002 1.32761998 -1.99023002 0 P 0 ;0
L 1.32761998 -1.99023002 1.3331 -1.99025 0 P 0 ;0
L 1.3331 -1.99025 1.33345 -1.99608002 0 P 0 ;0
L 1.33345 -1.99608002 1.33381004 -2.00323002 0 P 0 ;0
L 1.33381004 -2.00323002 1.33413002 -2.01158996 0 P 0 ;0
L 1.33413002 -2.01158996 1.33413002 -2.0116 0 P 0 ;0
L 1.33413002 -2.0116 1.33481998 -2.03123002 0 P 0 ;0
L 1.33481998 -2.03123002 1.32853996 -2.0314 0 P 0 ;0
L 1.32853996 -2.0314 1.32398002 -2.03166998 0 P 0 ;0
L 1.32398002 -2.03166998 1.31941998 -2.03225 0 P 0 ;0
L 1.31941998 -2.03225 1.31488996 -2.03313002 0 P 0 ;0
L 1.31488996 -2.03313002 1.31273996 -2.03373002 0 P 0 ;0
L 1.31273996 -2.03373002 1.31063996 -2.0345 0 P 0 ;0
L 1.31063996 -2.0345 1.3086 -2.03545 0 P 0 ;0
L 1.3086 -2.03545 1.30666004 -2.03656998 0 P 0 ;0
L 1.30666004 -2.03656998 1.30658996 -2.03661998 0 P 0 ;0
L 1.30658996 -2.03661998 1.30483002 -2.03786004 0 P 0 ;0
L 1.30483002 -2.03786004 1.30341998 -2.03901004 0 P 0 ;0
L 1.30341998 -2.03901004 1.30336998 -2.03906004 0 P 0 ;0
L 1.30336998 -2.03906004 1.30211998 -2.04026004 0 P 0 ;0
L 1.30211998 -2.04026004 1.30093002 -2.0416 0 P 0 ;0
L 1.30093002 -2.0416 1.29983002 -2.04303996 0 P 0 ;0
L 1.29983002 -2.04303996 1.29978996 -2.0431 0 P 0 ;0
L 1.29978996 -2.0431 1.29885 -2.04453996 0 P 0 ;0
L 1.29885 -2.04453996 1.29798996 -2.04613002 0 P 0 ;0
L 1.29798996 -2.04613002 1.29631998 -2.04986998 0 P 0 ;0
L 1.29631998 -2.04986998 1.29628002 -2.04995 0 P 0 ;0
L 1.29628002 -2.04995 1.29625 -2.05003002 0 P 0 ;0
L 1.29625 -2.05003002 1.29491998 -2.0539 0 P 0 ;0
L 1.29491998 -2.0539 1.29388996 -2.05793996 0 P 0 ;0
L 1.29388996 -2.05793996 1.29386998 -2.05801998 0 P 0 ;0
L 1.29386998 -2.05801998 1.29313996 -2.06221004 0 P 0 ;0
L 1.29313996 -2.06221004 1.29313002 -2.06223996 0 P 0 ;0
L 1.29313002 -2.06223996 1.29311998 -2.0623 0 P 0 ;0
L 1.29311998 -2.0623 1.29265 -2.06655 0 P 0 ;0
L 1.29265 -2.06655 1.29136998 -2.08418996 0 P 0 ;0
L 1.29136998 -2.08418996 1.29038996 -2.10276998 0 P 0 ;0
L 1.29038996 -2.10276998 1.29006998 -2.11763002 0 P 0 ;0
L 1.29006998 -2.11763002 1.29006004 -2.12516004 0 P 0 ;0
L 1.29006004 -2.12516004 1.2389 -2.12516004 0 P 0 ;0
L 1.09846998 -2.00483002 1.21248002 -2.00483002 0 P 0 ;0
L 1.09838002 -2.12083002 1.14708002 -2.12083002 0 P 0 ;0
L 1.11933002 -2.18283002 1.15161998 -2.18283002 0 P 0 ;0
L 1.11001998 -2.18183002 1.15838002 -2.18183002 0 P 0 ;0
L 1.10246998 -2.18083002 1.16333996 -2.18083002 0 P 0 ;0
L 1.04061004 -1.89731004 1.09978002 -1.89731004 0 P 0 ;0
L 1.03565 -1.89631004 1.09821004 -1.89631004 0 P 0 ;0
L 1.03068996 -1.89531004 1.09661004 -1.89531004 0 P 0 ;0
L 1.02573002 -1.89431004 1.09475 -1.89431004 0 P 0 ;0
L 1.019 -1.89331004 1.09288002 -1.89331004 0 P 0 ;0
L 1.01163996 -1.89231004 1.09101998 -1.89231004 0 P 0 ;0
L 0.99518996 -1.89131004 1.08916004 -1.89131004 0 P 0 ;0
L 0.87011998 -1.88331004 1.07278996 -1.88331004 0 P 0 ;0
L 0.86963996 -1.88231004 1.07053002 -1.88231004 0 P 0 ;0
L 0.86916004 -1.88131004 1.06828002 -1.88131004 0 P 0 ;0
L 0.86863002 -1.88031004 1.06603002 -1.88031004 0 P 0 ;0
L 0.86806998 -1.87931004 1.06351004 -1.87931004 0 P 0 ;0
L 0.8675 -1.87831004 1.06076998 -1.87831004 0 P 0 ;0
L 0.86693002 -1.87731004 1.05803996 -1.87731004 0 P 0 ;0
L 0.86631004 -1.87631004 1.05531004 -1.87631004 0 P 0 ;0
L 0.86563996 -1.87531004 1.05256998 -1.87531004 0 P 0 ;0
L 0.86498002 -1.87431004 1.04983996 -1.87431004 0 P 0 ;0
L 0.86431998 -1.87331004 1.0471 -1.87331004 0 P 0 ;0
L 0.86356004 -1.87231004 1.04376004 -1.87231004 0 P 0 ;0
L 0.86278996 -1.87131004 1.04041998 -1.87131004 0 P 0 ;0
L 0.86203002 -1.87031004 1.03708002 -1.87031004 0 P 0 ;0
L 0.86118996 -1.86931004 1.03373996 -1.86931004 0 P 0 ;0
L 0.8603 -1.86831004 1.0304 -1.86831004 0 P 0 ;0
L 0.85941004 -1.86731004 1.02656998 -1.86731004 0 P 0 ;0
L 0.8585 -1.86631004 1.02231998 -1.86631004 0 P 0 ;0
L 0.85756998 -1.86531004 1.01806998 -1.86531004 0 P 0 ;0
L 0.85663002 -1.86431004 1.01381998 -1.86431004 0 P 0 ;0
L 0.85568996 -1.86331004 1.00931998 -1.86331004 0 P 0 ;0
L 0.85481004 -1.86231004 1.00335 -1.86231004 0 P 0 ;0
L 0.85916998 -1.86131004 0.99738002 -1.86131004 0 P 0 ;0
L 0.86716998 -1.86031004 0.99141998 -1.86031004 0 P 0 ;0
L 0.87476998 -1.89731004 0.89943002 -1.89731004 0 P 0 ;0
L 0.87453996 -1.89631004 0.90426004 -1.89631004 0 P 0 ;0
L 0.87431004 -1.89531004 0.9097 -1.89531004 0 P 0 ;0
L 0.87406998 -1.89431004 0.91608002 -1.89431004 0 P 0 ;0
L 0.87383002 -1.89331004 0.92246004 -1.89331004 0 P 0 ;0
L 0.87355 -1.89231004 0.93086004 -1.89231004 0 P 0 ;0
L 0.87323002 -1.89131004 0.95553002 -1.89131004 0 P 0 ;0
L 0.87291004 -1.89031004 1.08728996 -1.89031004 0 P 0 ;0
L 0.87258996 -1.88931004 1.08543002 -1.88931004 0 P 0 ;0
L 0.87223002 -1.88831004 1.08356998 -1.88831004 0 P 0 ;0
L 0.87183002 -1.88731004 1.0817 -1.88731004 0 P 0 ;0
L 0.87143002 -1.88631004 1.07955 -1.88631004 0 P 0 ;0
L 0.87103002 -1.88531004 1.07728996 -1.88531004 0 P 0 ;0
L 0.8706 -1.88431004 1.07503996 -1.88431004 0 P 0 ;0
L 0.87525 -1.85931004 0.98545 -1.85931004 0 P 0 ;0
L 0.88421004 -1.85831004 0.97621004 -1.85831004 0 P 0 ;0
L 0.89393002 -1.85731004 0.96606998 -1.85731004 0 P 0 ;0
L 0.9106 -1.85631004 0.95203002 -1.85631004 0 P 0 ;0
L 1.08716004 -1.91231004 1.12151004 -1.91231004 0 P 0 ;0
L 1.08486004 -1.91131004 1.12018996 -1.91131004 0 P 0 ;0
L 1.08256004 -1.91031004 1.11886004 -1.91031004 0 P 0 ;0
L 1.08023002 -1.90931004 1.11753996 -1.90931004 0 P 0 ;0
L 1.07738002 -1.90831004 1.11621004 -1.90831004 0 P 0 ;0
L 1.07453002 -1.90731004 1.11488996 -1.90731004 0 P 0 ;0
L 1.07168996 -1.90631004 1.11356998 -1.90631004 0 P 0 ;0
L 1.06883996 -1.90531004 1.11223996 -1.90531004 0 P 0 ;0
L 1.066 -1.90431004 1.11076998 -1.90431004 0 P 0 ;0
L 1.06315 -1.90331004 1.1092 -1.90331004 0 P 0 ;0
L 1.0599 -1.90231004 1.10763002 -1.90231004 0 P 0 ;0
L 1.05611998 -1.90131004 1.10606004 -1.90131004 0 P 0 ;0
L 1.05235 -1.90031004 1.10448996 -1.90031004 0 P 0 ;0
L 1.04856998 -1.89931004 1.10291998 -1.89931004 0 P 0 ;0
L 1.04478996 -1.89831004 1.10135 -1.89831004 0 P 0 ;0
L 0.98815 -2.08316004 1.03726998 -2.08316004 0 P 0 ;0
L 0.98818002 -2.08216004 1.03731004 -2.08216004 0 P 0 ;0
L 0.98821998 -2.08116004 1.03735 -2.08116004 0 P 0 ;0
L 0.98825 -2.08016004 1.03738996 -2.08016004 0 P 0 ;0
L 0.98828002 -2.07916004 1.03743002 -2.07916004 0 P 0 ;0
L 0.98831998 -2.07816004 1.03746998 -2.07816004 0 P 0 ;0
L 0.98835 -2.07716004 1.03751004 -2.07716004 0 P 0 ;0
L 0.98838002 -2.07616004 1.03755 -2.07616004 0 P 0 ;0
L 0.98841998 -2.07516004 1.03758002 -2.07516004 0 P 0 ;0
L 0.98845 -2.07416004 1.03761004 -2.07416004 0 P 0 ;0
L 0.98848002 -2.07316004 1.03763996 -2.07316004 0 P 0 ;0
L 0.98851004 -2.07216004 1.03768002 -2.07216004 0 P 0 ;0
L 0.98855 -2.07116004 1.03771004 -2.07116004 0 P 0 ;0
L 0.98858002 -2.07016004 1.03773996 -2.07016004 0 P 0 ;0
L 0.98858996 -2.06916004 1.03776998 -2.06916004 0 P 0 ;0
L 0.98858996 -2.06816004 1.0378 -2.06816004 0 P 0 ;0
L 0.98858996 -2.06716004 1.03783002 -2.06716004 0 P 0 ;0
L 0.98858002 -2.06616004 1.03786004 -2.06616004 0 P 0 ;0
L 0.98856998 -2.06516004 1.0379 -2.06516004 0 P 0 ;0
L 0.98856998 -2.06416004 1.03793002 -2.06416004 0 P 0 ;0
L 0.98856998 -2.06316004 1.03796004 -2.06316004 0 P 0 ;0
L 0.98856004 -2.06216004 1.03798996 -2.06216004 0 P 0 ;0
L 0.98855 -2.06116004 1.03801998 -2.06116004 0 P 0 ;0
L 0.98855 -2.06016004 1.03805 -2.06016004 0 P 0 ;0
L 0.98853996 -2.05916004 1.03808002 -2.05916004 0 P 0 ;0
L 0.98853996 -2.05816004 1.0381 -2.05816004 0 P 0 ;0
L 0.98853002 -2.05716004 1.03811998 -2.05716004 0 P 0 ;0
L 0.98848002 -2.05616004 1.03815 -2.05616004 0 P 0 ;0
L 0.98841004 -2.05516004 1.03818002 -2.05516004 0 P 0 ;0
L 0.98835 -2.05416004 1.0382 -2.05416004 0 P 0 ;0
L 0.98828002 -2.05316004 1.03821998 -2.05316004 0 P 0 ;0
L 0.98821004 -2.05216004 1.03825 -2.05216004 0 P 0 ;0
L 0.98815 -2.05116004 1.03826998 -2.05116004 0 P 0 ;0
L 0.98808996 -2.05016004 1.03828996 -2.05016004 0 P 0 ;0
L 0.98801998 -2.04916004 1.03831998 -2.04916004 0 P 0 ;0
L 0.98796004 -2.04816004 1.03833996 -2.04816004 0 P 0 ;0
L 0.98788996 -2.04716004 1.03836004 -2.04716004 0 P 0 ;0
L 0.98783002 -2.04616004 1.03838996 -2.04616004 0 P 0 ;0
L 0.98768996 -2.04516004 1.0384 -2.04516004 0 P 0 ;0
L 0.98756004 -2.04416004 1.03841004 -2.04416004 0 P 0 ;0
L 0.98738002 -2.04316004 1.03841998 -2.04316004 0 P 0 ;0
L 0.98716004 -2.04216004 1.03843002 -2.04216004 0 P 0 ;0
L 0.98691998 -2.04116004 1.03843996 -2.04116004 0 P 0 ;0
L 0.98661998 -2.04016004 1.03845 -2.04016004 0 P 0 ;0
L 0.98631998 -2.03916004 1.03846004 -2.03916004 0 P 0 ;0
L 0.98593996 -2.03816004 1.03846998 -2.03816004 0 P 0 ;0
L 0.98546998 -2.03716004 1.03848002 -2.03716004 0 P 0 ;0
L 0.98491004 -2.03616004 1.03846998 -2.03616004 0 P 0 ;0
L 0.98425 -2.03516004 1.03846004 -2.03516004 0 P 0 ;0
L 0.98346004 -2.03416004 1.03846004 -2.03416004 0 P 0 ;0
L 0.98251998 -2.03316004 1.03843996 -2.03316004 0 P 0 ;0
L 0.98138002 -2.03216004 1.03843002 -2.03216004 0 P 0 ;0
L 0.97998996 -2.03116004 1.03841998 -2.03116004 0 P 0 ;0
L 0.97813996 -2.03016004 1.03841004 -2.03016004 0 P 0 ;0
L 0.97491004 -2.02916004 1.0384 -2.02916004 0 P 0 ;0
L 0.94763996 -2.00716004 1.03293996 -2.00716004 0 P 0 ;0
L 0.94978996 -2.00616004 1.03231998 -2.00616004 0 P 0 ;0
L 0.95081004 -2.00516004 1.0317 -2.00516004 0 P 0 ;0
L 0.95183002 -2.00416004 1.03098002 -2.00416004 0 P 0 ;0
L 0.95285 -2.00316004 1.03023002 -2.00316004 0 P 0 ;0
L 0.95388996 -2.00216004 1.02936004 -2.00216004 0 P 0 ;0
L 0.95498002 -2.00116004 1.02841998 -2.00116004 0 P 0 ;0
L 0.95621998 -2.00016004 1.02738996 -2.00016004 0 P 0 ;0
L 0.95761998 -1.99916004 1.0262 -1.99916004 0 P 0 ;0
L 0.9592 -1.99816004 1.02486004 -1.99816004 0 P 0 ;0
L 0.96083996 -1.99716004 1.02335 -1.99716004 0 P 0 ;0
L 0.9627 -1.99616004 1.02161004 -1.99616004 0 P 0 ;0
L 0.96468996 -1.99516004 1.01951998 -1.99516004 0 P 0 ;0
L 0.96685 -1.99416004 1.01683002 -1.99416004 0 P 0 ;0
L 0.96936998 -1.99316004 1.01378002 -1.99316004 0 P 0 ;0
L 0.97236998 -1.99216004 1.00981004 -1.99216004 0 P 0 ;0
L 0.97676004 -1.99116004 1.00456998 -1.99116004 0 P 0 ;0
L 1.06713996 -2.08283002 1.12288002 -2.08283002 0 P 0 ;0
L 1.06698996 -2.08183002 1.12193996 -2.08183002 0 P 0 ;0
L 1.06686004 -2.08083002 1.12108996 -2.08083002 0 P 0 ;0
L 1.06673996 -2.07983002 1.12036004 -2.07983002 0 P 0 ;0
L 1.06661998 -2.07883002 1.11971998 -2.07883002 0 P 0 ;0
L 1.06653002 -2.07783002 1.11916004 -2.07783002 0 P 0 ;0
L 1.06648002 -2.07683002 1.11866004 -2.07683002 0 P 0 ;0
L 1.06641998 -2.07583002 1.11826004 -2.07583002 0 P 0 ;0
L 1.06636998 -2.07483002 1.11791998 -2.07483002 0 P 0 ;0
L 1.06631998 -2.07383002 1.11761998 -2.07383002 0 P 0 ;0
L 1.06626004 -2.07283002 1.11741998 -2.07283002 0 P 0 ;0
L 1.06621004 -2.07183002 1.11723996 -2.07183002 0 P 0 ;0
L 1.06616004 -2.07083002 1.11711998 -2.07083002 0 P 0 ;0
L 1.06616004 -2.06983002 1.11701004 -2.06983002 0 P 0 ;0
L 1.06616004 -2.06883002 1.11688996 -2.06883002 0 P 0 ;0
L 1.06616998 -2.06783002 1.11676998 -2.06783002 0 P 0 ;0
L 1.06618002 -2.06683002 1.11666998 -2.06683002 0 P 0 ;0
L 1.06618996 -2.06583002 1.11663002 -2.06583002 0 P 0 ;0
L 1.0662 -2.06483002 1.11658996 -2.06483002 0 P 0 ;0
L 1.06621004 -2.06383002 1.11656004 -2.06383002 0 P 0 ;0
L 1.06623002 -2.06283002 1.11651998 -2.06283002 0 P 0 ;0
L 1.06631004 -2.06183002 1.11648996 -2.06183002 0 P 0 ;0
L 1.06638002 -2.06083002 1.11653002 -2.06083002 0 P 0 ;0
L 1.06645 -2.05983002 1.11656998 -2.05983002 0 P 0 ;0
L 1.06651998 -2.05883002 1.11661998 -2.05883002 0 P 0 ;0
L 1.06658996 -2.05783002 1.11666004 -2.05783002 0 P 0 ;0
L 1.06666998 -2.05683002 1.11671004 -2.05683002 0 P 0 ;0
L 1.06673996 -2.05583002 1.11681004 -2.05583002 0 P 0 ;0
L 1.06686004 -2.05483002 1.11693002 -2.05483002 0 P 0 ;0
L 1.067 -2.05383002 1.11705 -2.05383002 0 P 0 ;0
L 1.06713996 -2.05283002 1.11718002 -2.05283002 0 P 0 ;0
L 1.06728002 -2.05183002 1.11731004 -2.05183002 0 P 0 ;0
L 1.06741998 -2.05083002 1.11746004 -2.05083002 0 P 0 ;0
L 1.06756004 -2.04983002 1.11766004 -2.04983002 0 P 0 ;0
L 1.0677 -2.04883002 1.11786004 -2.04883002 0 P 0 ;0
L 1.06786004 -2.04783002 1.11813996 -2.04783002 0 P 0 ;0
L 1.06806998 -2.04683002 1.11841998 -2.04683002 0 P 0 ;0
L 1.06828002 -2.04583002 1.11876998 -2.04583002 0 P 0 ;0
L 1.06848996 -2.04483002 1.11913002 -2.04483002 0 P 0 ;0
L 1.06871004 -2.04383002 1.11955 -2.04383002 0 P 0 ;0
L 1.06898996 -2.04283002 1.11998996 -2.04283002 0 P 0 ;0
L 1.06928002 -2.04183002 1.12048002 -2.04183002 0 P 0 ;0
L 1.06956004 -2.04083002 1.12101004 -2.04083002 0 P 0 ;0
L 1.06985 -2.03983002 1.12161998 -2.03983002 0 P 0 ;0
L 1.07021004 -2.03883002 1.12225 -2.03883002 0 P 0 ;0
L 1.07056998 -2.03783002 1.12298002 -2.03783002 0 P 0 ;0
L 1.07093002 -2.03683002 1.12373996 -2.03683002 0 P 0 ;0
L 1.07128996 -2.03583002 1.12461998 -2.03583002 0 P 0 ;0
L 1.07173002 -2.03483002 1.12548996 -2.03483002 0 P 0 ;0
L 1.07216998 -2.03383002 1.12646004 -2.03383002 0 P 0 ;0
L 1.07261998 -2.03283002 1.12748996 -2.03283002 0 P 0 ;0
L 1.07308002 -2.03183002 1.12855 -2.03183002 0 P 0 ;0
L 1.07361998 -2.03083002 1.12978996 -2.03083002 0 P 0 ;0
L 1.09761004 -1.91731004 1.12756998 -1.91731004 0 P 0 ;0
L 1.09566004 -1.91631004 1.12645 -1.91631004 0 P 0 ;0
L 1.09371004 -1.91531004 1.12533002 -1.91531004 0 P 0 ;0
L 1.09176004 -1.91431004 1.12416004 -1.91431004 0 P 0 ;0
L 1.08946004 -1.91331004 1.12283996 -1.91331004 0 P 0 ;0
L 1.07415 -2.02983002 1.13101998 -2.02983002 0 P 0 ;0
L 1.07468996 -2.02883002 1.13248996 -2.02883002 0 P 0 ;0
L 1.07528996 -2.02783002 1.134 -2.02783002 0 P 0 ;0
L 1.07591998 -2.02683002 1.13586004 -2.02683002 0 P 0 ;0
L 1.07656004 -2.02583002 1.13828996 -2.02583002 0 P 0 ;0
L 1.07721004 -2.02483002 1.14243002 -2.02483002 0 P 0 ;0
L 1.07795 -2.02383002 1.21126998 -2.02383002 0 P 0 ;0
L 1.07868002 -2.02283002 1.21133002 -2.02283002 0 P 0 ;0
L 1.07941998 -2.02183002 1.2114 -2.02183002 0 P 0 ;0
L 1.08021004 -2.02083002 1.21146004 -2.02083002 0 P 0 ;0
L 1.08103996 -2.01983002 1.21153002 -2.01983002 0 P 0 ;0
L 1.08186998 -2.01883002 1.2116 -2.01883002 0 P 0 ;0
L 1.08273002 -2.01783002 1.21166004 -2.01783002 0 P 0 ;0
L 1.08366998 -2.01683002 1.21173002 -2.01683002 0 P 0 ;0
L 1.0846 -2.01583002 1.2118 -2.01583002 0 P 0 ;0
L 1.08555 -2.01483002 1.21186004 -2.01483002 0 P 0 ;0
L 1.08661004 -2.01383002 1.21193002 -2.01383002 0 P 0 ;0
L 1.08766998 -2.01283002 1.21198996 -2.01283002 0 P 0 ;0
L 1.08873002 -2.01183002 1.21205 -2.01183002 0 P 0 ;0
L 1.0898 -2.01083002 1.21211998 -2.01083002 0 P 0 ;0
L 1.09098996 -2.00983002 1.21218002 -2.00983002 0 P 0 ;0
L 1.09225 -2.00883002 1.21223996 -2.00883002 0 P 0 ;0
L 1.09358996 -2.00783002 1.2123 -2.00783002 0 P 0 ;0
L 1.09506998 -2.00683002 1.21236004 -2.00683002 0 P 0 ;0
L 1.09668996 -2.00583002 1.21241998 -2.00583002 0 P 0 ;0
L 0.98546998 -2.12516004 1.03548996 -2.12516004 0 P 0 ;0
L 0.98558996 -2.12416004 1.03553996 -2.12416004 0 P 0 ;0
L 0.9857 -2.12316004 1.03558002 -2.12316004 0 P 0 ;0
L 0.98581004 -2.12216004 1.03561998 -2.12216004 0 P 0 ;0
L 0.98591004 -2.12116004 1.03566998 -2.12116004 0 P 0 ;0
L 0.98598996 -2.12016004 1.03571004 -2.12016004 0 P 0 ;0
L 0.98608002 -2.11916004 1.03575 -2.11916004 0 P 0 ;0
L 0.98616998 -2.11816004 1.0358 -2.11816004 0 P 0 ;0
L 0.98625 -2.11716004 1.03583996 -2.11716004 0 P 0 ;0
L 0.98633996 -2.11616004 1.03588002 -2.11616004 0 P 0 ;0
L 0.98641998 -2.11516004 1.03593002 -2.11516004 0 P 0 ;0
L 0.98651004 -2.11416004 1.03596998 -2.11416004 0 P 0 ;0
L 0.9866 -2.11316004 1.03601004 -2.11316004 0 P 0 ;0
L 0.98668002 -2.11216004 1.03605 -2.11216004 0 P 0 ;0
L 0.98676998 -2.11116004 1.0361 -2.11116004 0 P 0 ;0
L 0.98685 -2.11016004 1.03613996 -2.11016004 0 P 0 ;0
L 0.98693996 -2.10916004 1.03618002 -2.10916004 0 P 0 ;0
L 0.987 -2.10816004 1.03623002 -2.10816004 0 P 0 ;0
L 0.98705 -2.10716004 1.03626998 -2.10716004 0 P 0 ;0
L 0.9871 -2.10616004 1.03631004 -2.10616004 0 P 0 ;0
L 0.98716004 -2.10516004 1.03636004 -2.10516004 0 P 0 ;0
L 0.9872 -2.10416004 1.0364 -2.10416004 0 P 0 ;0
L 0.98725 -2.10316004 1.03643996 -2.10316004 0 P 0 ;0
L 0.98731004 -2.10216004 1.03648002 -2.10216004 0 P 0 ;0
L 0.98735 -2.10116004 1.03653002 -2.10116004 0 P 0 ;0
L 0.9874 -2.10016004 1.03656998 -2.10016004 0 P 0 ;0
L 0.98746004 -2.09916004 1.03661004 -2.09916004 0 P 0 ;0
L 0.98751004 -2.09816004 1.03666004 -2.09816004 0 P 0 ;0
L 0.98755 -2.09716004 1.0367 -2.09716004 0 P 0 ;0
L 0.9876 -2.09616004 1.03673996 -2.09616004 0 P 0 ;0
L 0.98766004 -2.09516004 1.03678996 -2.09516004 0 P 0 ;0
L 0.9877 -2.09416004 1.03683002 -2.09416004 0 P 0 ;0
L 0.98775 -2.09316004 1.03686998 -2.09316004 0 P 0 ;0
L 0.98781004 -2.09216004 1.03691998 -2.09216004 0 P 0 ;0
L 0.98785 -2.09116004 1.03696004 -2.09116004 0 P 0 ;0
L 0.9879 -2.09016004 1.037 -2.09016004 0 P 0 ;0
L 0.98796004 -2.08916004 1.03703996 -2.08916004 0 P 0 ;0
L 0.98798996 -2.08816004 1.03706998 -2.08816004 0 P 0 ;0
L 0.98801998 -2.08716004 1.03711004 -2.08716004 0 P 0 ;0
L 0.98805 -2.08616004 1.03715 -2.08616004 0 P 0 ;0
L 0.98808996 -2.08516004 1.03718996 -2.08516004 0 P 0 ;0
L 0.98811998 -2.08416004 1.03723002 -2.08416004 0 P 0 ;0
L 1.08216998 -2.15683002 1.19803996 -2.15683002 0 P 0 ;0
L 1.0821 -2.15583002 1.19861004 -2.15583002 0 P 0 ;0
L 1.08201998 -2.15483002 1.19918002 -2.15483002 0 P 0 ;0
L 1.08195 -2.15383002 1.1997 -2.15383002 0 P 0 ;0
L 1.08188996 -2.15283002 1.20018002 -2.15283002 0 P 0 ;0
L 1.08183002 -2.15183002 1.20066004 -2.15183002 0 P 0 ;0
L 1.08176998 -2.15083002 1.20113996 -2.15083002 0 P 0 ;0
L 1.08171998 -2.14983002 1.20153996 -2.14983002 0 P 0 ;0
L 1.08166004 -2.14883002 1.20193002 -2.14883002 0 P 0 ;0
L 1.0816 -2.14783002 1.11538996 -2.14783002 0 P 0 ;0
L 1.08155 -2.14683002 1.10903002 -2.14683002 0 P 0 ;0
L 1.0815 -2.14583002 1.10415 -2.14583002 0 P 0 ;0
L 1.08146004 -2.14483002 1.09953002 -2.14483002 0 P 0 ;0
L 1.08141004 -2.14383002 1.09563996 -2.14383002 0 P 0 ;0
L 1.08136004 -2.14283002 1.09183996 -2.14283002 0 P 0 ;0
L 1.08131004 -2.14183002 1.08821004 -2.14183002 0 P 0 ;0
L 1.08133002 -2.14083002 1.08471998 -2.14083002 0 P 0 ;0
L 1.09586998 -2.11983002 1.14965 -2.11983002 0 P 0 ;0
L 1.09361998 -2.11883002 1.15221998 -2.11883002 0 P 0 ;0
L 1.09158996 -2.11783002 1.20595 -2.11783002 0 P 0 ;0
L 1.08988002 -2.11683002 1.20601004 -2.11683002 0 P 0 ;0
L 1.08823996 -2.11583002 1.20606998 -2.11583002 0 P 0 ;0
L 1.08678996 -2.11483002 1.20613002 -2.11483002 0 P 0 ;0
L 1.08541004 -2.11383002 1.20618996 -2.11383002 0 P 0 ;0
L 1.08416998 -2.11283002 1.20625 -2.11283002 0 P 0 ;0
L 1.08295 -2.11183002 1.20631004 -2.11183002 0 P 0 ;0
L 1.08188002 -2.11083002 1.20638002 -2.11083002 0 P 0 ;0
L 1.08081998 -2.10983002 1.20643996 -2.10983002 0 P 0 ;0
L 1.07986004 -2.10883002 1.2065 -2.10883002 0 P 0 ;0
L 1.07895 -2.10783002 1.20656004 -2.10783002 0 P 0 ;0
L 1.07803002 -2.10683002 1.20661998 -2.10683002 0 P 0 ;0
L 1.07723996 -2.10583002 1.20666998 -2.10583002 0 P 0 ;0
L 1.07646004 -2.10483002 1.20671998 -2.10483002 0 P 0 ;0
L 1.07568002 -2.10383002 1.20678002 -2.10383002 0 P 0 ;0
L 1.075 -2.10283002 1.20683002 -2.10283002 0 P 0 ;0
L 1.07433002 -2.10183002 1.20688002 -2.10183002 0 P 0 ;0
L 1.07366998 -2.10083002 1.20693996 -2.10083002 0 P 0 ;0
L 1.07308996 -2.09983002 1.20698996 -2.09983002 0 P 0 ;0
L 1.07253002 -2.09883002 1.20705 -2.09883002 0 P 0 ;0
L 1.07198002 -2.09783002 1.2071 -2.09783002 0 P 0 ;0
L 1.07146998 -2.09683002 1.20715 -2.09683002 0 P 0 ;0
L 1.07101998 -2.09583002 1.2072 -2.09583002 0 P 0 ;0
L 1.07056998 -2.09483002 1.20726004 -2.09483002 0 P 0 ;0
L 1.07013002 -2.09383002 1.20731004 -2.09383002 0 P 0 ;0
L 1.06976998 -2.09283002 1.20736004 -2.09283002 0 P 0 ;0
L 1.06941998 -2.09183002 1.20741998 -2.09183002 0 P 0 ;0
L 1.06906004 -2.09083002 1.20746998 -2.09083002 0 P 0 ;0
L 1.06876004 -2.08983002 1.20753002 -2.08983002 0 P 0 ;0
L 1.06848996 -2.08883002 1.13443002 -2.08883002 0 P 0 ;0
L 1.06821998 -2.08783002 1.13068002 -2.08783002 0 P 0 ;0
L 1.06795 -2.08683002 1.12836998 -2.08683002 0 P 0 ;0
L 1.06771998 -2.08583002 1.1266 -2.08583002 0 P 0 ;0
L 1.06753002 -2.08483002 1.12516004 -2.08483002 0 P 0 ;0
L 1.06733002 -2.08383002 1.12393996 -2.08383002 0 P 0 ;0
L 0.90273996 -1.85456998 0.89068996 -1.85558002 0 P 0 ;0
L 0.89068996 -1.85558002 0.87421004 -1.85741998 0 P 0 ;0
L 0.87421004 -1.85741998 0.85783002 -1.85946998 0 P 0 ;0
L 0.85783002 -1.85946998 0.85526998 -1.8599 0 P 0 ;0
L 0.85526998 -1.8599 0.85276004 -1.86055 0 P 0 ;0
L 0.85276004 -1.86055 0.85255 -1.86063996 0 P 0 ;0
L 0.85255 -1.86063996 0.85248996 -1.86068996 0 P 0 ;0
L 0.85248996 -1.86068996 0.85243002 -1.86073002 0 P 0 ;0
L 0.85243002 -1.86073002 0.85238002 -1.86078002 0 P 0 ;0
L 0.85238002 -1.86078002 0.85233002 -1.86083996 0 P 0 ;0
L 0.85233002 -1.86083996 0.85225 -1.86096004 0 P 0 ;0
L 0.85225 -1.86096004 0.85218002 -1.8611 0 P 0 ;0
L 0.85218002 -1.8611 0.85216004 -1.86116998 0 P 0 ;0
L 0.85216004 -1.86116998 0.85215 -1.86123996 0 P 0 ;0
L 0.85215 -1.86123996 0.85213996 -1.86136998 0 P 0 ;0
L 0.85213996 -1.86136998 0.85213002 -1.86148996 0 P 0 ;0
L 0.85213002 -1.86148996 0.85213996 -1.86161998 0 P 0 ;0
L 0.85213996 -1.86161998 0.85215 -1.86173996 0 P 0 ;0
L 0.85215 -1.86173996 0.85218002 -1.86186998 0 P 0 ;0
L 0.85218002 -1.86186998 0.85221004 -1.86198996 0 P 0 ;0
L 0.85221004 -1.86198996 0.85225 -1.8621 0 P 0 ;0
L 0.85225 -1.8621 0.85231004 -1.86221998 0 P 0 ;0
L 0.85231004 -1.86221998 0.85236998 -1.86233002 0 P 0 ;0
L 0.85236998 -1.86233002 0.85281998 -1.863 0 P 0 ;0
L 0.85281998 -1.863 0.8533 -1.86363996 0 P 0 ;0
L 0.8533 -1.86363996 0.85383002 -1.86425 0 P 0 ;0
L 0.85383002 -1.86425 0.85736004 -1.86801998 0 P 0 ;0
L 0.85736004 -1.86801998 0.86013002 -1.87113002 0 P 0 ;0
L 0.86013002 -1.87113002 0.86266004 -1.87443002 0 P 0 ;0
L 0.86266004 -1.87443002 0.86501004 -1.87798996 0 P 0 ;0
L 0.86501004 -1.87798996 0.86711998 -1.88171004 0 P 0 ;0
L 0.86711998 -1.88171004 0.86896998 -1.88553996 0 P 0 ;0
L 0.86896998 -1.88553996 0.87055 -1.8895 0 P 0 ;0
L 0.87055 -1.8895 0.8718 -1.89343002 0 P 0 ;0
L 0.8718 -1.89343002 0.87276004 -1.89745 0 P 0 ;0
L 0.87276004 -1.89745 0.87371004 -1.90195 0 P 0 ;0
L 0.87371004 -1.90195 0.87383002 -1.90236004 0 P 0 ;0
L 0.87383002 -1.90236004 0.87396998 -1.90276004 0 P 0 ;0
L 0.87396998 -1.90276004 0.87416004 -1.90313996 0 P 0 ;0
L 0.87416004 -1.90313996 0.87436998 -1.90351004 0 P 0 ;0
L 0.87436998 -1.90351004 0.87443002 -1.9036 0 P 0 ;0
L 0.87443002 -1.9036 0.87456998 -1.90376004 0 P 0 ;0
L 0.87456998 -1.90376004 0.87465 -1.90381998 0 P 0 ;0
L 0.87465 -1.90381998 0.87473002 -1.90388996 0 P 0 ;0
L 0.87473002 -1.90388996 0.87481998 -1.90393996 0 P 0 ;0
L 0.87481998 -1.90393996 0.87491998 -1.90398996 0 P 0 ;0
L 0.87491998 -1.90398996 0.87501004 -1.90403002 0 P 0 ;0
L 0.87501004 -1.90403002 0.87521004 -1.90408996 0 P 0 ;0
L 0.87521004 -1.90408996 0.87531998 -1.9041 0 P 0 ;0
L 0.87531998 -1.9041 0.87573002 -1.90413002 0 P 0 ;0
L 0.87573002 -1.90413002 0.87613996 -1.90411998 0 P 0 ;0
L 0.87613996 -1.90411998 0.87653996 -1.90408002 0 P 0 ;0
L 0.87653996 -1.90408002 0.87695 -1.90401004 0 P 0 ;0
L 0.87695 -1.90401004 0.90756004 -1.89766998 0 P 0 ;0
L 0.90756004 -1.89766998 0.92603996 -1.89478002 0 P 0 ;0
L 0.92603996 -1.89478002 0.93486004 -1.89393996 0 P 0 ;0
L 0.93486004 -1.89393996 0.94371004 -1.8935 0 P 0 ;0
L 0.94371004 -1.8935 0.97045 -1.89308002 0 P 0 ;0
L 0.97045 -1.89308002 0.99468996 -1.89328996 0 P 0 ;0
L 0.99468996 -1.89328996 1.01021004 -1.89413996 0 P 0 ;0
L 1.01021004 -1.89413996 1.0241 -1.89601998 0 P 0 ;0
L 1.0241 -1.89601998 1.04188002 -1.89961004 0 P 0 ;0
L 1.04188002 -1.89961004 1.06095 -1.90466004 0 P 0 ;0
L 1.06095 -1.90466004 1.07963996 -1.91123002 0 P 0 ;0
L 1.07963996 -1.91123002 1.09093996 -1.91613002 0 P 0 ;0
L 1.09093996 -1.91613002 1.10186998 -1.92175 0 P 0 ;0
L 1.10186998 -1.92175 1.11243996 -1.92806998 0 P 0 ;0
L 1.11243996 -1.92806998 1.12163002 -1.93446998 0 P 0 ;0
L 1.12163002 -1.93446998 1.13033002 -1.94148996 0 P 0 ;0
L 1.13033002 -1.94148996 1.1385 -1.94911004 0 P 0 ;0
L 1.1385 -1.94911004 1.14358996 -1.9546 0 P 0 ;0
L 1.14358996 -1.9546 1.14825 -1.96045 0 P 0 ;0
L 1.14825 -1.96045 1.15246998 -1.96663002 0 P 0 ;0
L 1.15246998 -1.96663002 1.15623002 -1.97316004 0 P 0 ;0
L 1.15623002 -1.97316004 1.15895 -1.97831004 0 P 0 ;0
L 1.15895 -1.97831004 1.17358996 -1.97831004 0 P 0 ;0
L 1.17358996 -1.97831004 1.17135 -1.9726 0 P 0 ;0
L 1.17135 -1.9726 1.16696004 -1.96266998 0 P 0 ;0
L 1.16696004 -1.96266998 1.16171998 -1.95313002 0 P 0 ;0
L 1.16171998 -1.95313002 1.1557 -1.94406998 0 P 0 ;0
L 1.1557 -1.94406998 1.14885 -1.93548002 0 P 0 ;0
L 1.14885 -1.93548002 1.13778996 -1.92378002 0 P 0 ;0
L 1.13778996 -1.92378002 1.12576998 -1.91301998 0 P 0 ;0
L 1.12576998 -1.91301998 1.11283996 -1.90326004 0 P 0 ;0
L 1.11283996 -1.90326004 1.09783002 -1.89368996 0 P 0 ;0
L 1.09783002 -1.89368996 1.08213002 -1.88526998 0 P 0 ;0
L 1.08213002 -1.88526998 1.06576998 -1.87801004 0 P 0 ;0
L 1.06576998 -1.87801004 1.04776004 -1.87141998 0 P 0 ;0
L 1.04776004 -1.87141998 1.02938002 -1.86591998 0 P 0 ;0
L 1.02938002 -1.86591998 1.01058002 -1.8615 0 P 0 ;0
L 1.01058002 -1.8615 0.98441998 -1.85711004 0 P 0 ;0
L 0.98441998 -1.85711004 0.95781004 -1.85448996 0 P 0 ;0
L 0.95781004 -1.85448996 0.93061004 -1.85366004 0 P 0 ;0
L 0.93061004 -1.85366004 0.90273996 -1.85456998 0 P 0 ;0
L 1.16015 -1.97631004 1.15798002 -1.97218996 0 P 0 ;0
L 1.15798002 -1.97218996 1.15796004 -1.97216004 0 P 0 ;0
L 1.15796004 -1.97216004 1.15416004 -1.96556998 0 P 0 ;0
L 1.15416004 -1.96556998 1.15411998 -1.96551004 0 P 0 ;0
L 1.15411998 -1.96551004 1.14986004 -1.95926004 0 P 0 ;0
L 1.14986004 -1.95926004 1.14981998 -1.95921004 0 P 0 ;0
L 1.14981998 -1.95921004 1.14511004 -1.9533 0 P 0 ;0
L 1.14511004 -1.9533 1.13991998 -1.9477 0 P 0 ;0
L 1.13991998 -1.9477 1.13986004 -1.94765 0 P 0 ;0
L 1.13986004 -1.94765 1.13163996 -1.93998002 0 P 0 ;0
L 1.13163996 -1.93998002 1.12283002 -1.93286004 0 P 0 ;0
L 1.12283002 -1.93286004 1.11351998 -1.92638996 0 P 0 ;0
L 1.11351998 -1.92638996 1.10283996 -1.92 0 P 0 ;0
L 1.10283996 -1.92 1.0918 -1.91433002 0 P 0 ;0
L 1.0918 -1.91433002 1.08036998 -1.90936004 0 P 0 ;0
L 1.08036998 -1.90936004 1.06153002 -1.90273996 0 P 0 ;0
L 1.06153002 -1.90273996 1.06146004 -1.90273002 0 P 0 ;0
L 1.06146004 -1.90273002 1.04233002 -1.89766004 0 P 0 ;0
L 1.04233002 -1.89766004 1.02443002 -1.89405 0 P 0 ;0
L 1.02443002 -1.89405 1.0104 -1.89213996 0 P 0 ;0
L 1.0104 -1.89213996 0.99475 -1.89128996 0 P 0 ;0
L 0.99475 -1.89128996 0.97045 -1.89108002 0 P 0 ;0
L 0.97045 -1.89108002 0.94365 -1.8915 0 P 0 ;0
L 0.94365 -1.8915 0.94361998 -1.8915 0 P 0 ;0
L 0.94361998 -1.8915 0.93471998 -1.89195 0 P 0 ;0
L 0.93471998 -1.89195 0.92578996 -1.89278996 0 P 0 ;0
L 0.92578996 -1.89278996 0.9072 -1.89571004 0 P 0 ;0
L 0.9072 -1.89571004 0.87656998 -1.90203996 0 P 0 ;0
L 0.87656998 -1.90203996 0.87626998 -1.9021 0 P 0 ;0
L 0.87626998 -1.9021 0.87601998 -1.90211998 0 P 0 ;0
L 0.87601998 -1.90211998 0.87588996 -1.90213002 0 P 0 ;0
L 0.87588996 -1.90213002 0.87583002 -1.90198996 0 P 0 ;0
L 0.87583002 -1.90198996 0.87573002 -1.90175 0 P 0 ;0
L 0.87573002 -1.90175 0.87566004 -1.90146998 0 P 0 ;0
L 0.87566004 -1.90146998 0.87471004 -1.89701004 0 P 0 ;0
L 0.87471004 -1.89701004 0.8747 -1.89698996 0 P 0 ;0
L 0.8747 -1.89698996 0.87373002 -1.89288996 0 P 0 ;0
L 0.87373002 -1.89288996 0.87243002 -1.88881998 0 P 0 ;0
L 0.87243002 -1.88881998 0.8724 -1.88876004 0 P 0 ;0
L 0.8724 -1.88876004 0.8708 -1.88473996 0 P 0 ;0
L 0.8708 -1.88473996 0.8689 -1.88078002 0 P 0 ;0
L 0.8689 -1.88078002 0.86671998 -1.87693996 0 P 0 ;0
L 0.86671998 -1.87693996 0.86428996 -1.87326004 0 P 0 ;0
L 0.86428996 -1.87326004 0.86166998 -1.86985 0 P 0 ;0
L 0.86166998 -1.86985 0.85883996 -1.86668002 0 P 0 ;0
L 0.85883996 -1.86668002 0.85883002 -1.86666004 0 P 0 ;0
L 0.85883002 -1.86666004 0.85531998 -1.86291004 0 P 0 ;0
L 0.85531998 -1.86291004 0.85486004 -1.86238002 0 P 0 ;0
L 0.85486004 -1.86238002 0.85466004 -1.86211998 0 P 0 ;0
L 0.85466004 -1.86211998 0.8557 -1.86186004 0 P 0 ;0
L 0.8557 -1.86186004 0.85811998 -1.86145 0 P 0 ;0
L 0.85811998 -1.86145 0.87443996 -1.85941004 0 P 0 ;0
L 0.87443996 -1.85941004 0.89088996 -1.85756998 0 P 0 ;0
L 0.89088996 -1.85756998 0.90286004 -1.85656998 0 P 0 ;0
L 0.90286004 -1.85656998 0.93061004 -1.85566004 0 P 0 ;0
L 0.93061004 -1.85566004 0.95768002 -1.85648996 0 P 0 ;0
L 0.95768002 -1.85648996 0.98416004 -1.8591 0 P 0 ;0
L 0.98416004 -1.8591 1.01018996 -1.86346004 0 P 0 ;0
L 1.01018996 -1.86346004 1.02886004 -1.86785 0 P 0 ;0
L 1.02886004 -1.86785 1.04711998 -1.87331998 0 P 0 ;0
L 1.04711998 -1.87331998 1.06501004 -1.87986004 0 P 0 ;0
L 1.06501004 -1.87986004 1.08125 -1.88706998 0 P 0 ;0
L 1.08125 -1.88706998 1.09681004 -1.89541998 0 P 0 ;0
L 1.09681004 -1.89541998 1.1117 -1.9049 0 P 0 ;0
L 1.1117 -1.9049 1.1245 -1.91456998 0 P 0 ;0
L 1.1245 -1.91456998 1.13638996 -1.92521004 0 P 0 ;0
L 1.13638996 -1.92521004 1.14733996 -1.93678996 0 P 0 ;0
L 1.14733996 -1.93678996 1.15408002 -1.94525 0 P 0 ;0
L 1.15408002 -1.94525 1.16001004 -1.95416998 0 P 0 ;0
L 1.16001004 -1.95416998 1.16516004 -1.96355 0 P 0 ;0
L 1.16516004 -1.96355 1.1695 -1.97336998 0 P 0 ;0
L 1.1695 -1.97336998 1.17066004 -1.97631004 0 P 0 ;0
L 1.17066004 -1.97631004 1.16015 -1.97631004 0 P 0 ;0
L 0.87563002 -1.90131004 0.8801 -1.90131004 0 P 0 ;0
L 0.87541004 -1.90031004 0.88493996 -1.90031004 0 P 0 ;0
L 0.8752 -1.89931004 0.88976998 -1.89931004 0 P 0 ;0
L 0.87498996 -1.89831004 0.8946 -1.89831004 0 P 0 ;0
L 0.89423002 -2.08316004 0.94355 -2.08316004 0 P 0 ;0
L 0.89428996 -2.08216004 0.9436 -2.08216004 0 P 0 ;0
L 0.89435 -2.08116004 0.94365 -2.08116004 0 P 0 ;0
L 0.89441004 -2.08016004 0.9437 -2.08016004 0 P 0 ;0
L 0.89446004 -2.07916004 0.94375 -2.07916004 0 P 0 ;0
L 0.89451998 -2.07816004 0.94378996 -2.07816004 0 P 0 ;0
L 0.89458002 -2.07716004 0.94383996 -2.07716004 0 P 0 ;0
L 0.89463996 -2.07616004 0.94388996 -2.07616004 0 P 0 ;0
L 0.8947 -2.07516004 0.94393996 -2.07516004 0 P 0 ;0
L 0.89475 -2.07416004 0.94398002 -2.07416004 0 P 0 ;0
L 0.89481004 -2.07316004 0.94403002 -2.07316004 0 P 0 ;0
L 0.89486998 -2.07216004 0.94408002 -2.07216004 0 P 0 ;0
L 0.89493002 -2.07116004 0.94415 -2.07116004 0 P 0 ;0
L 0.89498996 -2.07016004 0.94426004 -2.07016004 0 P 0 ;0
L 0.89505 -2.06916004 0.94436998 -2.06916004 0 P 0 ;0
L 0.8951 -2.06816004 0.94448002 -2.06816004 0 P 0 ;0
L 0.89516004 -2.06716004 0.94458996 -2.06716004 0 P 0 ;0
L 0.89521998 -2.06616004 0.9447 -2.06616004 0 P 0 ;0
L 0.89526998 -2.06516004 0.94481004 -2.06516004 0 P 0 ;0
L 0.89531004 -2.06416004 0.94491998 -2.06416004 0 P 0 ;0
L 0.89535 -2.06316004 0.94503002 -2.06316004 0 P 0 ;0
L 0.8954 -2.06216004 0.94513996 -2.06216004 0 P 0 ;0
L 0.89543996 -2.06116004 0.94531998 -2.06116004 0 P 0 ;0
L 0.89548996 -2.06016004 0.94551004 -2.06016004 0 P 0 ;0
L 0.89553002 -2.05916004 0.9457 -2.05916004 0 P 0 ;0
L 0.89558002 -2.05816004 0.94588996 -2.05816004 0 P 0 ;0
L 0.89561998 -2.05716004 0.94608002 -2.05716004 0 P 0 ;0
L 0.89566998 -2.05616004 0.94626998 -2.05616004 0 P 0 ;0
L 0.89571004 -2.05516004 0.94646998 -2.05516004 0 P 0 ;0
L 0.89575 -2.05416004 0.94666004 -2.05416004 0 P 0 ;0
L 0.8958 -2.05316004 0.94685 -2.05316004 0 P 0 ;0
L 0.89583996 -2.05216004 0.94708002 -2.05216004 0 P 0 ;0
L 0.89588996 -2.05116004 0.94735 -2.05116004 0 P 0 ;0
L 0.89593996 -2.05016004 0.94761998 -2.05016004 0 P 0 ;0
L 0.89598002 -2.04916004 0.9479 -2.04916004 0 P 0 ;0
L 0.89601998 -2.04816004 0.94825 -2.04816004 0 P 0 ;0
L 0.89606998 -2.04716004 0.94858996 -2.04716004 0 P 0 ;0
L 0.89611004 -2.04616004 0.94893002 -2.04616004 0 P 0 ;0
L 0.89616004 -2.04516004 0.94935 -2.04516004 0 P 0 ;0
L 0.8962 -2.04416004 0.94976998 -2.04416004 0 P 0 ;0
L 0.89625 -2.04316004 0.9502 -2.04316004 0 P 0 ;0
L 0.89628002 -2.04216004 0.95068996 -2.04216004 0 P 0 ;0
L 0.89631004 -2.04116004 0.95118996 -2.04116004 0 P 0 ;0
L 0.89633996 -2.04016004 0.95168996 -2.04016004 0 P 0 ;0
L 0.89638002 -2.03916004 0.95228002 -2.03916004 0 P 0 ;0
L 0.89641004 -2.03816004 0.95291004 -2.03816004 0 P 0 ;0
L 0.89643996 -2.03716004 0.95363002 -2.03716004 0 P 0 ;0
L 0.89646998 -2.03616004 0.95445 -2.03616004 0 P 0 ;0
L 0.89651004 -2.03516004 0.95535 -2.03516004 0 P 0 ;0
L 0.89653996 -2.03416004 0.95636998 -2.03416004 0 P 0 ;0
L 0.89656998 -2.03316004 0.95756998 -2.03316004 0 P 0 ;0
L 0.8966 -2.03216004 0.95893996 -2.03216004 0 P 0 ;0
L 0.89663996 -2.03116004 0.96055 -2.03116004 0 P 0 ;0
L 0.89666998 -2.03016004 0.96278002 -2.03016004 0 P 0 ;0
L 0.8967 -2.02916004 0.96676004 -2.02916004 0 P 0 ;0
L 0.89673996 -2.02816004 1.03838996 -2.02816004 0 P 0 ;0
L 0.89676998 -2.02716004 1.03838002 -2.02716004 0 P 0 ;0
L 0.8968 -2.02616004 1.03833996 -2.02616004 0 P 0 ;0
L 0.89683996 -2.02516004 1.03828996 -2.02516004 0 P 0 ;0
L 0.89686998 -2.02416004 1.03823002 -2.02416004 0 P 0 ;0
L 0.8969 -2.02316004 1.03816004 -2.02316004 0 P 0 ;0
L 0.89693996 -2.02216004 1.0381 -2.02216004 0 P 0 ;0
L 0.89696998 -2.02116004 1.03803996 -2.02116004 0 P 0 ;0
L 0.897 -2.02016004 1.0379 -2.02016004 0 P 0 ;0
L 0.89703002 -2.01916004 1.03773996 -2.01916004 0 P 0 ;0
L 0.89706004 -2.01816004 1.03751998 -2.01816004 0 P 0 ;0
L 0.89708996 -2.01716004 1.03728002 -2.01716004 0 P 0 ;0
L 0.89711998 -2.01616004 1.03698996 -2.01616004 0 P 0 ;0
L 0.89713996 -2.01516004 1.03668002 -2.01516004 0 P 0 ;0
L 0.89716998 -2.01416004 1.03631004 -2.01416004 0 P 0 ;0
L 0.8972 -2.01316004 1.03591998 -2.01316004 0 P 0 ;0
L 0.89721998 -2.01216004 1.03548996 -2.01216004 0 P 0 ;0
L 0.89725 -2.01116004 1.03505 -2.01116004 0 P 0 ;0
L 0.89726998 -2.01016004 1.03458002 -2.01016004 0 P 0 ;0
L 0.8973 -2.00916004 1.03405 -2.00916004 0 P 0 ;0
L 0.89733002 -2.00816004 1.03351998 -2.00816004 0 P 0 ;0
L 0.89736004 -2.00716004 0.94676004 -2.00716004 0 P 0 ;0
L 0.89738002 -2.00616004 0.9461 -2.00616004 0 P 0 ;0
L 0.89741004 -2.00516004 0.94563996 -2.00516004 0 P 0 ;0
L 0.89743996 -2.00416004 0.94563996 -2.00416004 0 P 0 ;0
L 0.89746004 -2.00316004 0.94563996 -2.00316004 0 P 0 ;0
L 0.89748996 -2.00216004 0.94563996 -2.00216004 0 P 0 ;0
L 0.89751004 -2.00116004 0.94563996 -2.00116004 0 P 0 ;0
L 0.89753996 -2.00016004 0.94563996 -2.00016004 0 P 0 ;0
L 0.89756998 -1.99916004 0.94563996 -1.99916004 0 P 0 ;0
L 0.8976 -1.99816004 0.94563996 -1.99816004 0 P 0 ;0
L 0.89761998 -1.99716004 0.94563996 -1.99716004 0 P 0 ;0
L 0.89765 -1.99616004 0.94563996 -1.99616004 0 P 0 ;0
L 0.89768002 -1.99516004 0.94563996 -1.99516004 0 P 0 ;0
L 0.97546998 -1.98933996 0.97236998 -1.99006004 0 P 0 ;0
L 0.97236998 -1.99006004 0.96931998 -1.99103002 0 P 0 ;0
L 0.96931998 -1.99103002 0.96603002 -1.99233002 0 P 0 ;0
L 0.96603002 -1.99233002 0.96281004 -1.99383002 0 P 0 ;0
L 0.96281004 -1.99383002 0.95976004 -1.99546998 0 P 0 ;0
L 0.95976004 -1.99546998 0.95681004 -1.99728996 0 P 0 ;0
L 0.95681004 -1.99728996 0.95521004 -1.99841004 0 P 0 ;0
L 0.95521004 -1.99841004 0.95368996 -1.99963002 0 P 0 ;0
L 0.95368996 -1.99963002 0.95223996 -2.00095 0 P 0 ;0
L 0.95223996 -2.00095 0.94763996 -2.00546998 0 P 0 ;0
L 0.94763996 -2.00546998 0.94763996 -1.99243996 0 P 0 ;0
L 0.94763996 -1.99243996 0.89575 -1.99243996 0 P 0 ;0
L 0.89575 -1.99243996 0.89505 -2.01878002 0 P 0 ;0
L 0.89505 -2.01878002 0.89423996 -2.04316004 0 P 0 ;0
L 0.89423996 -2.04316004 0.89321998 -2.0661 0 P 0 ;0
L 0.89321998 -2.0661 0.89198996 -2.08728996 0 P 0 ;0
L 0.89198996 -2.08728996 0.89055 -2.1063 0 P 0 ;0
L 0.89055 -2.1063 0.88993996 -2.11358002 0 P 0 ;0
L 0.88993996 -2.11358002 0.88943002 -2.11988002 0 P 0 ;0
L 0.88943002 -2.11988002 0.88898996 -2.12533996 0 P 0 ;0
L 0.88898996 -2.12533996 0.88896004 -2.12613002 0 P 0 ;0
L 0.88896004 -2.12613002 0.88896998 -2.12621004 0 P 0 ;0
L 0.88896998 -2.12621004 0.88898002 -2.12625 0 P 0 ;0
L 0.88898002 -2.12625 0.88898996 -2.12628002 0 P 0 ;0
L 0.88898996 -2.12628002 0.88901998 -2.12636004 0 P 0 ;0
L 0.88901998 -2.12636004 0.88903996 -2.12638996 0 P 0 ;0
L 0.88903996 -2.12638996 0.88906998 -2.12641998 0 P 0 ;0
L 0.88906998 -2.12641998 0.88908996 -2.12645 0 P 0 ;0
L 0.88908996 -2.12645 0.88911998 -2.12646998 0 P 0 ;0
L 0.88911998 -2.12646998 0.88915 -2.1265 0 P 0 ;0
L 0.88915 -2.1265 0.88921004 -2.12653996 0 P 0 ;0
L 0.88921004 -2.12653996 0.88925 -2.12655 0 P 0 ;0
L 0.88925 -2.12655 0.88928002 -2.12656004 0 P 0 ;0
L 0.88928002 -2.12656004 0.88931998 -2.12658002 0 P 0 ;0
L 0.88931998 -2.12658002 0.8894 -2.12658002 0 P 0 ;0
L 0.8894 -2.12658002 0.89648002 -2.12686998 0 P 0 ;0
L 0.89648002 -2.12686998 0.90518996 -2.1271 0 P 0 ;0
L 0.90518996 -2.1271 0.9165 -2.12716004 0 P 0 ;0
L 0.9165 -2.12716004 0.94403996 -2.12716004 0 P 0 ;0
L 0.94403996 -2.12716004 0.94468996 -2.10135 0 P 0 ;0
L 0.94468996 -2.10135 0.9461 -2.07171998 0 P 0 ;0
L 0.9461 -2.07171998 0.94713002 -2.06233002 0 P 0 ;0
L 0.94713002 -2.06233002 0.9489 -2.05308002 0 P 0 ;0
L 0.9489 -2.05308002 0.94975 -2.04995 0 P 0 ;0
L 0.94975 -2.04995 0.9508 -2.04688996 0 P 0 ;0
L 0.9508 -2.04688996 0.95205 -2.0439 0 P 0 ;0
L 0.95205 -2.0439 0.95351004 -2.041 0 P 0 ;0
L 0.95351004 -2.041 0.9544 -2.03951004 0 P 0 ;0
L 0.9544 -2.03951004 0.95541998 -2.03811004 0 P 0 ;0
L 0.95541998 -2.03811004 0.95655 -2.03678996 0 P 0 ;0
L 0.95655 -2.03678996 0.95778996 -2.03556998 0 P 0 ;0
L 0.95778996 -2.03556998 0.95911998 -2.03446998 0 P 0 ;0
L 0.95911998 -2.03446998 0.96056998 -2.03346998 0 P 0 ;0
L 0.96056998 -2.03346998 0.96151004 -2.03291004 0 P 0 ;0
L 0.96151004 -2.03291004 0.96248996 -2.03243002 0 P 0 ;0
L 0.96248996 -2.03243002 0.96351004 -2.03201998 0 P 0 ;0
L 0.96351004 -2.03201998 0.96455 -2.03168996 0 P 0 ;0
L 0.96455 -2.03168996 0.96613002 -2.0313 0 P 0 ;0
L 0.96613002 -2.0313 0.96773002 -2.03101998 0 P 0 ;0
L 0.96773002 -2.03101998 0.96935 -2.03086004 0 P 0 ;0
L 0.96935 -2.03086004 0.97095 -2.03081004 0 P 0 ;0
L 0.97095 -2.03081004 0.97255 -2.03086998 0 P 0 ;0
L 0.97255 -2.03086998 0.97413002 -2.03105 0 P 0 ;0
L 0.97413002 -2.03105 0.97513002 -2.03123996 0 P 0 ;0
L 0.97513002 -2.03123996 0.9761 -2.03151004 0 P 0 ;0
L 0.9761 -2.03151004 0.97706004 -2.03186004 0 P 0 ;0
L 0.97706004 -2.03186004 0.97796998 -2.0323 0 P 0 ;0
L 0.97796998 -2.0323 0.97885 -2.0328 0 P 0 ;0
L 0.97885 -2.0328 0.97968002 -2.03336998 0 P 0 ;0
L 0.97968002 -2.03336998 0.98046998 -2.03398996 0 P 0 ;0
L 0.98046998 -2.03398996 0.98121998 -2.03468002 0 P 0 ;0
L 0.98121998 -2.03468002 0.98191004 -2.03541998 0 P 0 ;0
L 0.98191004 -2.03541998 0.98253996 -2.0362 0 P 0 ;0
L 0.98253996 -2.0362 0.9831 -2.03703002 0 P 0 ;0
L 0.9831 -2.03703002 0.9836 -2.03788996 0 P 0 ;0
L 0.9836 -2.03788996 0.98403996 -2.0388 0 P 0 ;0
L 0.98403996 -2.0388 0.9844 -2.03973996 0 P 0 ;0
L 0.9844 -2.03973996 0.98505 -2.04188996 0 P 0 ;0
L 0.98505 -2.04188996 0.98553002 -2.04408002 0 P 0 ;0
L 0.98553002 -2.04408002 0.98583002 -2.0463 0 P 0 ;0
L 0.98583002 -2.0463 0.98653002 -2.05705 0 P 0 ;0
L 0.98653002 -2.05705 0.9866 -2.06961004 0 P 0 ;0
L 0.9866 -2.06961004 0.98596004 -2.08908002 0 P 0 ;0
L 0.98596004 -2.08908002 0.98498002 -2.10858002 0 P 0 ;0
L 0.98498002 -2.10858002 0.98388002 -2.12146998 0 P 0 ;0
L 0.98388002 -2.12146998 0.98323002 -2.12716004 0 P 0 ;0
L 0.98323002 -2.12716004 1.03741004 -2.12716004 0 P 0 ;0
L 1.03741004 -2.12716004 1.03896004 -2.09103002 0 P 0 ;0
L 1.03896004 -2.09103002 1.03956004 -2.0759 0 P 0 ;0
L 1.03956004 -2.0759 1.04005 -2.06025 0 P 0 ;0
L 1.04005 -2.06025 1.04038996 -2.04626004 0 P 0 ;0
L 1.04038996 -2.04626004 1.04048002 -2.03698996 0 P 0 ;0
L 1.04048002 -2.03698996 1.04036998 -2.02651998 0 P 0 ;0
L 1.04036998 -2.02651998 1.04003996 -2.02096998 0 P 0 ;0
L 1.04003996 -2.02096998 1.03975 -2.01895 0 P 0 ;0
L 1.03975 -2.01895 1.0393 -2.01693996 0 P 0 ;0
L 1.0393 -2.01693996 1.03868996 -2.01483996 0 P 0 ;0
L 1.03868996 -2.01483996 1.03793996 -2.01278002 0 P 0 ;0
L 1.03793996 -2.01278002 1.03658996 -2.00968002 0 P 0 ;0
L 1.03658996 -2.00968002 1.03501004 -2.00668996 0 P 0 ;0
L 1.03501004 -2.00668996 1.0332 -2.0038 0 P 0 ;0
L 1.0332 -2.0038 1.03186998 -2.002 0 P 0 ;0
L 1.03186998 -2.002 1.0304 -2.0003 0 P 0 ;0
L 1.0304 -2.0003 1.0288 -1.99873002 0 P 0 ;0
L 1.0288 -1.99873002 1.02708002 -1.99728996 0 P 0 ;0
L 1.02708002 -1.99728996 1.02518002 -1.99593002 0 P 0 ;0
L 1.02518002 -1.99593002 1.02318002 -1.99471998 0 P 0 ;0
L 1.02318002 -1.99471998 1.0211 -1.99365 0 P 0 ;0
L 1.0211 -1.99365 1.01893002 -1.99273996 0 P 0 ;0
L 1.01893002 -1.99273996 1.01358996 -1.99098996 0 P 0 ;0
L 1.01358996 -1.99098996 1.0081 -1.98971004 0 P 0 ;0
L 1.0081 -1.98971004 1.00428996 -1.98908996 0 P 0 ;0
L 1.00428996 -1.98908996 1.00043996 -1.98868002 0 P 0 ;0
L 1.00043996 -1.98868002 0.99138002 -1.98826004 0 P 0 ;0
L 0.99138002 -1.98826004 0.98251998 -1.98846998 0 P 0 ;0
L 0.98251998 -1.98846998 0.97898996 -1.98878996 0 P 0 ;0
L 0.97898996 -1.98878996 0.97546998 -1.98933996 0 P 0 ;0
L 0.91651004 -2.12516004 0.94208996 -2.12516004 0 P 0 ;0
L 0.8911 -2.12416004 0.94211004 -2.12416004 0 P 0 ;0
L 0.89118002 -2.12316004 0.94213996 -2.12316004 0 P 0 ;0
L 0.89125 -2.12216004 0.94216004 -2.12216004 0 P 0 ;0
L 0.89133002 -2.12116004 0.94218996 -2.12116004 0 P 0 ;0
L 0.89141004 -2.12016004 0.94221004 -2.12016004 0 P 0 ;0
L 0.89148996 -2.11916004 0.94223996 -2.11916004 0 P 0 ;0
L 0.89156998 -2.11816004 0.94226998 -2.11816004 0 P 0 ;0
L 0.89166004 -2.11716004 0.94228996 -2.11716004 0 P 0 ;0
L 0.89173996 -2.11616004 0.94231004 -2.11616004 0 P 0 ;0
L 0.89181998 -2.11516004 0.94233996 -2.11516004 0 P 0 ;0
L 0.8919 -2.11416004 0.94236004 -2.11416004 0 P 0 ;0
L 0.89198002 -2.11316004 0.94238996 -2.11316004 0 P 0 ;0
L 0.89206998 -2.11216004 0.94241998 -2.11216004 0 P 0 ;0
L 0.89215 -2.11116004 0.94243996 -2.11116004 0 P 0 ;0
L 0.89223002 -2.11016004 0.94246998 -2.11016004 0 P 0 ;0
L 0.89231998 -2.10916004 0.94248996 -2.10916004 0 P 0 ;0
L 0.8924 -2.10816004 0.94251998 -2.10816004 0 P 0 ;0
L 0.89248002 -2.10716004 0.94255 -2.10716004 0 P 0 ;0
L 0.89256998 -2.10616004 0.94256998 -2.10616004 0 P 0 ;0
L 0.89263996 -2.10516004 0.94258996 -2.10516004 0 P 0 ;0
L 0.89271004 -2.10416004 0.94261998 -2.10416004 0 P 0 ;0
L 0.89278996 -2.10316004 0.94263996 -2.10316004 0 P 0 ;0
L 0.89286998 -2.10216004 0.94266998 -2.10216004 0 P 0 ;0
L 0.89293996 -2.10116004 0.9427 -2.10116004 0 P 0 ;0
L 0.89301998 -2.10016004 0.94275 -2.10016004 0 P 0 ;0
L 0.89308996 -2.09916004 0.94278996 -2.09916004 0 P 0 ;0
L 0.89316998 -2.09816004 0.94283996 -2.09816004 0 P 0 ;0
L 0.89325 -2.09716004 0.94288996 -2.09716004 0 P 0 ;0
L 0.89331998 -2.09616004 0.94293996 -2.09616004 0 P 0 ;0
L 0.8934 -2.09516004 0.94298002 -2.09516004 0 P 0 ;0
L 0.89346998 -2.09416004 0.94303002 -2.09416004 0 P 0 ;0
L 0.89355 -2.09316004 0.94308002 -2.09316004 0 P 0 ;0
L 0.89361998 -2.09216004 0.94313002 -2.09216004 0 P 0 ;0
L 0.8937 -2.09116004 0.94318002 -2.09116004 0 P 0 ;0
L 0.89378002 -2.09016004 0.94321998 -2.09016004 0 P 0 ;0
L 0.89385 -2.08916004 0.94326998 -2.08916004 0 P 0 ;0
L 0.89393002 -2.08816004 0.94331998 -2.08816004 0 P 0 ;0
L 0.894 -2.08716004 0.94336004 -2.08716004 0 P 0 ;0
L 0.89406004 -2.08616004 0.94341004 -2.08616004 0 P 0 ;0
L 0.89411998 -2.08516004 0.94346004 -2.08516004 0 P 0 ;0
L 0.89418002 -2.08416004 0.94351004 -2.08416004 0 P 0 ;0
L 0.91651004 -2.12516004 0.90521998 -2.1251 0 P 0 ;0
L 0.90521998 -2.1251 0.89655 -2.12486998 0 P 0 ;0
L 0.89655 -2.12486998 0.89106004 -2.12465 0 P 0 ;0
L 0.89106004 -2.12465 0.89141998 -2.12003996 0 P 0 ;0
L 0.89141998 -2.12003996 0.89193996 -2.11373996 0 P 0 ;0
L 0.89193996 -2.11373996 0.89253996 -2.10645 0 P 0 ;0
L 0.89253996 -2.10645 0.89398002 -2.08741998 0 P 0 ;0
L 0.89398002 -2.08741998 0.89521998 -2.06621998 0 P 0 ;0
L 0.89521998 -2.06621998 0.89521998 -2.06618996 0 P 0 ;0
L 0.89521998 -2.06618996 0.89623996 -2.04323002 0 P 0 ;0
L 0.89623996 -2.04323002 0.89703996 -2.01883002 0 P 0 ;0
L 0.89703996 -2.01883002 0.8977 -1.99443996 0 P 0 ;0
L 0.8977 -1.99443996 0.94563996 -1.99443996 0 P 0 ;0
L 0.94563996 -1.99443996 0.94563996 -2.00546998 0 P 0 ;0
L 0.94563996 -2.00546998 0.94686004 -2.00731004 0 P 0 ;0
L 0.94686004 -2.00731004 0.94903002 -2.00688996 0 P 0 ;0
L 0.94903002 -2.00688996 0.95361998 -2.00241004 0 P 0 ;0
L 0.95361998 -2.00241004 0.95498996 -2.00115 0 P 0 ;0
L 0.95498996 -2.00115 0.95641998 -2.00001004 0 P 0 ;0
L 0.95641998 -2.00001004 0.9579 -1.99896004 0 P 0 ;0
L 0.9579 -1.99896004 0.96076004 -1.9972 0 P 0 ;0
L 0.96076004 -1.9972 0.9637 -1.99561998 0 P 0 ;0
L 0.9637 -1.99561998 0.96683002 -1.99416998 0 P 0 ;0
L 0.96683002 -1.99416998 0.96998996 -1.99291998 0 P 0 ;0
L 0.96998996 -1.99291998 0.9729 -1.99198996 0 P 0 ;0
L 0.9729 -1.99198996 0.97586004 -1.9913 0 P 0 ;0
L 0.97586004 -1.9913 0.97923002 -1.99076998 0 P 0 ;0
L 0.97923002 -1.99076998 0.98263002 -1.99046998 0 P 0 ;0
L 0.98263002 -1.99046998 0.99136004 -1.99026004 0 P 0 ;0
L 0.99136004 -1.99026004 1.00028996 -1.99066998 0 P 0 ;0
L 1.00028996 -1.99066998 1.00403002 -1.99108002 0 P 0 ;0
L 1.00403002 -1.99108002 1.00771004 -1.99166998 0 P 0 ;0
L 1.00771004 -1.99166998 1.01305 -1.99291998 0 P 0 ;0
L 1.01305 -1.99291998 1.01823002 -1.99461998 0 P 0 ;0
L 1.01823002 -1.99461998 1.02026004 -1.99546998 0 P 0 ;0
L 1.02026004 -1.99546998 1.02221004 -1.99646998 0 P 0 ;0
L 1.02221004 -1.99646998 1.02408002 -1.9976 0 P 0 ;0
L 1.02408002 -1.9976 1.02585 -1.99886998 0 P 0 ;0
L 1.02585 -1.99886998 1.02746004 -2.00021004 0 P 0 ;0
L 1.02746004 -2.00021004 1.02893996 -2.00166998 0 P 0 ;0
L 1.02893996 -2.00166998 1.03031004 -2.00325 0 P 0 ;0
L 1.03031004 -2.00325 1.03155 -2.00493002 0 P 0 ;0
L 1.03155 -2.00493002 1.03326998 -2.00768002 0 P 0 ;0
L 1.03326998 -2.00768002 1.03478002 -2.01055 0 P 0 ;0
L 1.03478002 -2.01055 1.03608002 -2.01351998 0 P 0 ;0
L 1.03608002 -2.01351998 1.03678996 -2.01546998 0 P 0 ;0
L 1.03678996 -2.01546998 1.03736004 -2.01743002 0 P 0 ;0
L 1.03736004 -2.01743002 1.03778002 -2.0193 0 P 0 ;0
L 1.03778002 -2.0193 1.03805 -2.02116998 0 P 0 ;0
L 1.03805 -2.02116998 1.03836998 -2.02658996 0 P 0 ;0
L 1.03836998 -2.02658996 1.03848002 -2.03698996 0 P 0 ;0
L 1.03848002 -2.03698996 1.03838996 -2.04623002 0 P 0 ;0
L 1.03838996 -2.04623002 1.03805 -2.06018996 0 P 0 ;0
L 1.03805 -2.06018996 1.03756004 -2.07583002 0 P 0 ;0
L 1.03756004 -2.07583002 1.03696998 -2.09095 0 P 0 ;0
L 1.03696998 -2.09095 1.03548996 -2.12516004 0 P 0 ;0
L 1.03548996 -2.12516004 0.98546998 -2.12516004 0 P 0 ;0
L 0.98546998 -2.12516004 0.98586998 -2.12166004 0 P 0 ;0
L 0.98586998 -2.12166004 0.98696998 -2.10871998 0 P 0 ;0
L 0.98696998 -2.10871998 0.98796004 -2.08916004 0 P 0 ;0
L 0.98796004 -2.08916004 0.9886 -2.06963002 0 P 0 ;0
L 0.9886 -2.06963002 0.98853002 -2.05698002 0 P 0 ;0
L 0.98853002 -2.05698002 0.98781998 -2.0461 0 P 0 ;0
L 0.98781998 -2.0461 0.9875 -2.04373002 0 P 0 ;0
L 0.9875 -2.04373002 0.98748002 -2.04365 0 P 0 ;0
L 0.98748002 -2.04365 0.98698996 -2.04138996 0 P 0 ;0
L 0.98698996 -2.04138996 0.9863 -2.03908002 0 P 0 ;0
L 0.9863 -2.03908002 0.98588002 -2.038 0 P 0 ;0
L 0.98588002 -2.038 0.98538002 -2.03696004 0 P 0 ;0
L 0.98538002 -2.03696004 0.9848 -2.03596004 0 P 0 ;0
L 0.9848 -2.03596004 0.98413996 -2.03501004 0 P 0 ;0
L 0.98413996 -2.03501004 0.98341998 -2.03411004 0 P 0 ;0
L 0.98341998 -2.03411004 0.98336998 -2.03405 0 P 0 ;0
L 0.98336998 -2.03405 0.98263002 -2.03326004 0 P 0 ;0
L 0.98263002 -2.03326004 0.98176998 -2.03246998 0 P 0 ;0
L 0.98176998 -2.03246998 0.98086998 -2.03175 0 P 0 ;0
L 0.98086998 -2.03175 0.97991004 -2.0311 0 P 0 ;0
L 0.97991004 -2.0311 0.9789 -2.03051998 0 P 0 ;0
L 0.9789 -2.03051998 0.97783002 -2.03001998 0 P 0 ;0
L 0.97783002 -2.03001998 0.97673002 -2.02961004 0 P 0 ;0
L 0.97673002 -2.02961004 0.97663996 -2.02958002 0 P 0 ;0
L 0.97663996 -2.02958002 0.97558996 -2.02928996 0 P 0 ;0
L 0.97558996 -2.02928996 0.97443002 -2.02906998 0 P 0 ;0
L 0.97443002 -2.02906998 0.9727 -2.02888002 0 P 0 ;0
L 0.9727 -2.02888002 0.97261998 -2.02886998 0 P 0 ;0
L 0.97261998 -2.02886998 0.97096004 -2.02881004 0 P 0 ;0
L 0.97096004 -2.02881004 0.96921004 -2.02886004 0 P 0 ;0
L 0.96921004 -2.02886004 0.96745 -2.02903996 0 P 0 ;0
L 0.96745 -2.02903996 0.96571004 -2.02933996 0 P 0 ;0
L 0.96571004 -2.02933996 0.964 -2.02976004 0 P 0 ;0
L 0.964 -2.02976004 0.96283002 -2.03013996 0 P 0 ;0
L 0.96283002 -2.03013996 0.96168002 -2.0306 0 P 0 ;0
L 0.96168002 -2.0306 0.96056998 -2.03115 0 P 0 ;0
L 0.96056998 -2.03115 0.95948996 -2.03178002 0 P 0 ;0
L 0.95948996 -2.03178002 0.95791004 -2.03286998 0 P 0 ;0
L 0.95791004 -2.03286998 0.95645 -2.03408996 0 P 0 ;0
L 0.95645 -2.03408996 0.95508996 -2.03541998 0 P 0 ;0
L 0.95508996 -2.03541998 0.95383996 -2.03686998 0 P 0 ;0
L 0.95383996 -2.03686998 0.9538 -2.03693002 0 P 0 ;0
L 0.9538 -2.03693002 0.95273002 -2.03841004 0 P 0 ;0
L 0.95273002 -2.03841004 0.95175 -2.04003996 0 P 0 ;0
L 0.95175 -2.04003996 0.95023002 -2.04306004 0 P 0 ;0
L 0.95023002 -2.04306004 0.94896004 -2.04611004 0 P 0 ;0
L 0.94896004 -2.04611004 0.94893002 -2.04616998 0 P 0 ;0
L 0.94893002 -2.04616998 0.94783002 -2.04936004 0 P 0 ;0
L 0.94783002 -2.04936004 0.94695 -2.05263002 0 P 0 ;0
L 0.94695 -2.05263002 0.94515 -2.06203002 0 P 0 ;0
L 0.94515 -2.06203002 0.9441 -2.07156004 0 P 0 ;0
L 0.9441 -2.07156004 0.9427 -2.10128002 0 P 0 ;0
L 0.9427 -2.10128002 0.94208996 -2.12516004 0 P 0 ;0
L 0.94208996 -2.12516004 0.91651004 -2.12516004 0 P 0 ;0
L 0.93143002 -2.21261998 1.00578996 -2.21261998 0 P 0 ;0
L 0.94051004 -2.21161998 1.00803002 -2.21161998 0 P 0 ;0
L 0.94941998 -2.21061998 1.01026004 -2.21061998 0 P 0 ;0
L 0.9555 -2.20961998 1.0125 -2.20961998 0 P 0 ;0
L 0.96158002 -2.20861998 1.01473996 -2.20861998 0 P 0 ;0
L 0.96766004 -2.20761998 1.01696998 -2.20761998 0 P 0 ;0
L 0.97373002 -2.20661998 1.01921004 -2.20661998 0 P 0 ;0
L 0.97981004 -2.20561998 1.02145 -2.20561998 0 P 0 ;0
L 0.98498996 -2.20461998 1.02368996 -2.20461998 0 P 0 ;0
L 0.98973996 -2.20361998 1.02591998 -2.20361998 0 P 0 ;0
L 0.99448996 -2.20261998 1.02816004 -2.20261998 0 P 0 ;0
L 0.99923996 -2.20161998 1.0304 -2.20161998 0 P 0 ;0
L 1.00398996 -2.20061998 1.03243996 -2.20061998 0 P 0 ;0
L 1.00875 -2.19961998 1.0344 -2.19961998 0 P 0 ;0
L 1.01348996 -2.19861998 1.03636998 -2.19861998 0 P 0 ;0
L 1.0178 -2.19761998 1.03833996 -2.19761998 0 P 0 ;0
L 1.02168996 -2.19661998 1.04031004 -2.19661998 0 P 0 ;0
L 1.02558002 -2.19561998 1.04228002 -2.19561998 0 P 0 ;0
L 1.02946998 -2.19461998 1.04415 -2.19461998 0 P 0 ;0
L 1.03336004 -2.19361998 1.04596998 -2.19361998 0 P 0 ;0
L 1.03725 -2.19261998 1.04778996 -2.19261998 0 P 0 ;0
L 1.04113996 -2.19161998 1.0496 -2.19161998 0 P 0 ;0
L 1.14356998 -1.98926998 1.13261004 -1.99086004 0 P 0 ;0
L 1.13261004 -1.99086004 1.12165 -1.9934 0 P 0 ;0
L 1.12165 -1.9934 1.11125 -1.99673002 0 P 0 ;0
L 1.11125 -1.99673002 1.10658002 -1.99858996 0 P 0 ;0
L 1.10658002 -1.99858996 1.10198996 -2.00071004 0 P 0 ;0
L 1.10198996 -2.00071004 1.09653002 -2.00358996 0 P 0 ;0
L 1.09653002 -2.00358996 1.09436998 -2.00488996 0 P 0 ;0
L 1.09436998 -2.00488996 1.09226004 -2.00631004 0 P 0 ;0
L 1.09226004 -2.00631004 1.09028002 -2.00781004 0 P 0 ;0
L 1.09028002 -2.00781004 1.08836998 -2.00941998 0 P 0 ;0
L 1.08836998 -2.00941998 1.08405 -2.0135 0 P 0 ;0
L 1.08405 -2.0135 1.08096998 -2.01678996 0 P 0 ;0
L 1.08096998 -2.01678996 1.07808002 -2.02026998 0 P 0 ;0
L 1.07808002 -2.02026998 1.0754 -2.02393002 0 P 0 ;0
L 1.0754 -2.02393002 1.07313996 -2.02748002 0 P 0 ;0
L 1.07313996 -2.02748002 1.07116004 -2.03118996 0 P 0 ;0
L 1.07116004 -2.03118996 1.06943996 -2.03505 0 P 0 ;0
L 1.06943996 -2.03505 1.06795 -2.03918996 0 P 0 ;0
L 1.06795 -2.03918996 1.06673996 -2.04343996 0 P 0 ;0
L 1.06673996 -2.04343996 1.06583002 -2.04778002 0 P 0 ;0
L 1.06583002 -2.04778002 1.06476998 -2.05538996 0 P 0 ;0
L 1.06476998 -2.05538996 1.06421004 -2.06306004 0 P 0 ;0
L 1.06421004 -2.06306004 1.06415 -2.07076004 0 P 0 ;0
L 1.06415 -2.07076004 1.06456998 -2.0785 0 P 0 ;0
L 1.06456998 -2.0785 1.06508996 -2.08276004 0 P 0 ;0
L 1.06508996 -2.08276004 1.06591004 -2.08696004 0 P 0 ;0
L 1.06591004 -2.08696004 1.06703002 -2.09108002 0 P 0 ;0
L 1.06703002 -2.09108002 1.06833002 -2.09473002 0 P 0 ;0
L 1.06833002 -2.09473002 1.06991998 -2.09823996 0 P 0 ;0
L 1.06991998 -2.09823996 1.0718 -2.10161998 0 P 0 ;0
L 1.0718 -2.10161998 1.07398002 -2.10491998 0 P 0 ;0
L 1.07398002 -2.10491998 1.07641998 -2.10803002 0 P 0 ;0
L 1.07641998 -2.10803002 1.07908996 -2.11095 0 P 0 ;0
L 1.07908996 -2.11095 1.08175 -2.11345 0 P 0 ;0
L 1.08175 -2.11345 1.08458996 -2.11573996 0 P 0 ;0
L 1.08458996 -2.11573996 1.08758996 -2.1178 0 P 0 ;0
L 1.08758996 -2.1178 1.09073002 -2.11963996 0 P 0 ;0
L 1.09073002 -2.11963996 1.094 -2.12123996 0 P 0 ;0
L 1.094 -2.12123996 1.0986 -2.12306998 0 P 0 ;0
L 1.0986 -2.12306998 1.10331004 -2.12456004 0 P 0 ;0
L 1.10331004 -2.12456004 1.10811004 -2.12568996 0 P 0 ;0
L 1.10811004 -2.12568996 1.11298002 -2.12646998 0 P 0 ;0
L 1.11298002 -2.12646998 1.1182 -2.12693002 0 P 0 ;0
L 1.1182 -2.12693002 1.12343996 -2.12703002 0 P 0 ;0
L 1.12343996 -2.12703002 1.12866998 -2.12676004 0 P 0 ;0
L 1.12866998 -2.12676004 1.13388002 -2.12613002 0 P 0 ;0
L 1.13388002 -2.12613002 1.14086004 -2.12473996 0 P 0 ;0
L 1.14086004 -2.12473996 1.1477 -2.12273996 0 P 0 ;0
L 1.1477 -2.12273996 1.15433996 -2.12015 0 P 0 ;0
L 1.15433996 -2.12015 1.1545 -2.12008996 0 P 0 ;0
L 1.1545 -2.12008996 1.15466004 -2.12003996 0 P 0 ;0
L 1.15466004 -2.12003996 1.15483002 -2.12001004 0 P 0 ;0
L 1.15483002 -2.12001004 1.15498996 -2.11998996 0 P 0 ;0
L 1.15498996 -2.11998996 1.15533002 -2.11998996 0 P 0 ;0
L 1.15533002 -2.11998996 1.15538996 -2.12 0 P 0 ;0
L 1.15538996 -2.12 1.15545 -2.12001998 0 P 0 ;0
L 1.15545 -2.12001998 1.15551004 -2.12003002 0 P 0 ;0
L 1.15551004 -2.12003002 1.15556004 -2.12006004 0 P 0 ;0
L 1.15556004 -2.12006004 1.15561004 -2.12008002 0 P 0 ;0
L 1.15561004 -2.12008002 1.15566004 -2.12011004 0 P 0 ;0
L 1.15566004 -2.12011004 1.15571004 -2.12015 0 P 0 ;0
L 1.15571004 -2.12015 1.15575 -2.12018996 0 P 0 ;0
L 1.15575 -2.12018996 1.15578996 -2.12023996 0 P 0 ;0
L 1.15578996 -2.12023996 1.15583002 -2.12028002 0 P 0 ;0
L 1.15583002 -2.12028002 1.15586004 -2.12033996 0 P 0 ;0
L 1.15586004 -2.12033996 1.15588002 -2.12038996 0 P 0 ;0
L 1.15588002 -2.12038996 1.15591004 -2.12043996 0 P 0 ;0
L 1.15591004 -2.12043996 1.15601998 -2.12076004 0 P 0 ;0
L 1.15601998 -2.12076004 1.1561 -2.12108002 0 P 0 ;0
L 1.1561 -2.12108002 1.15616004 -2.12141998 0 P 0 ;0
L 1.15616004 -2.12141998 1.15618002 -2.12175 0 P 0 ;0
L 1.15618002 -2.12175 1.15623996 -2.12505 0 P 0 ;0
L 1.15623996 -2.12505 1.15616004 -2.12688002 0 P 0 ;0
L 1.15616004 -2.12688002 1.15593002 -2.12871004 0 P 0 ;0
L 1.15593002 -2.12871004 1.15553996 -2.13051998 0 P 0 ;0
L 1.15553996 -2.13051998 1.15516004 -2.1318 0 P 0 ;0
L 1.15516004 -2.1318 1.1547 -2.13305 0 P 0 ;0
L 1.1547 -2.13305 1.15415 -2.13426004 0 P 0 ;0
L 1.15415 -2.13426004 1.15351004 -2.13545 0 P 0 ;0
L 1.15351004 -2.13545 1.15278996 -2.1366 0 P 0 ;0
L 1.15278996 -2.1366 1.15198002 -2.13768996 0 P 0 ;0
L 1.15198002 -2.13768996 1.15111004 -2.13873002 0 P 0 ;0
L 1.15111004 -2.13873002 1.15016004 -2.13971004 0 P 0 ;0
L 1.15016004 -2.13971004 1.14876004 -2.14096004 0 P 0 ;0
L 1.14876004 -2.14096004 1.14726004 -2.1421 0 P 0 ;0
L 1.14726004 -2.1421 1.14566998 -2.14311004 0 P 0 ;0
L 1.14566998 -2.14311004 1.144 -2.144 0 P 0 ;0
L 1.144 -2.144 1.14226004 -2.14476004 0 P 0 ;0
L 1.14226004 -2.14476004 1.14046004 -2.14536998 0 P 0 ;0
L 1.14046004 -2.14536998 1.13863002 -2.14583002 0 P 0 ;0
L 1.13863002 -2.14583002 1.13676004 -2.14613996 0 P 0 ;0
L 1.13676004 -2.14613996 1.13041998 -2.14663996 0 P 0 ;0
L 1.13041998 -2.14663996 1.12403996 -2.1466 0 P 0 ;0
L 1.12403996 -2.1466 1.11621998 -2.14593996 0 P 0 ;0
L 1.11621998 -2.14593996 1.10843996 -2.14471004 0 P 0 ;0
L 1.10843996 -2.14471004 1.09946998 -2.14276998 0 P 0 ;0
L 1.09946998 -2.14276998 1.0905 -2.14041004 0 P 0 ;0
L 1.0905 -2.14041004 1.07963996 -2.13728996 0 P 0 ;0
L 1.07963996 -2.13728996 1.07936004 -2.1401 0 P 0 ;0
L 1.07936004 -2.1401 1.07931004 -2.14103996 0 P 0 ;0
L 1.07931004 -2.14103996 1.07931998 -2.14198002 0 P 0 ;0
L 1.07931998 -2.14198002 1.07956998 -2.14735 0 P 0 ;0
L 1.07956998 -2.14735 1.07993996 -2.15375 0 P 0 ;0
L 1.07993996 -2.15375 1.08045 -2.16081998 0 P 0 ;0
L 1.08045 -2.16081998 1.08181004 -2.17873002 0 P 0 ;0
L 1.08181004 -2.17873002 1.08996004 -2.18061004 0 P 0 ;0
L 1.08996004 -2.18061004 1.09951004 -2.18246004 0 P 0 ;0
L 1.09951004 -2.18246004 1.11243996 -2.18416998 0 P 0 ;0
L 1.11243996 -2.18416998 1.1254 -2.18543002 0 P 0 ;0
L 1.1254 -2.18543002 1.13508002 -2.18583002 0 P 0 ;0
L 1.13508002 -2.18583002 1.14765 -2.18528996 0 P 0 ;0
L 1.14765 -2.18528996 1.15368002 -2.18461004 0 P 0 ;0
L 1.15368002 -2.18461004 1.15971004 -2.18363996 0 P 0 ;0
L 1.15971004 -2.18363996 1.16521004 -2.18248002 0 P 0 ;0
L 1.16521004 -2.18248002 1.17063996 -2.18103002 0 P 0 ;0
L 1.17063996 -2.18103002 1.17528996 -2.17946998 0 P 0 ;0
L 1.17528996 -2.17946998 1.17978002 -2.17753996 0 P 0 ;0
L 1.17978002 -2.17753996 1.18216998 -2.1763 0 P 0 ;0
L 1.18216998 -2.1763 1.18446004 -2.17488996 0 P 0 ;0
L 1.18446004 -2.17488996 1.18663996 -2.17331004 0 P 0 ;0
L 1.18663996 -2.17331004 1.18871004 -2.17156004 0 P 0 ;0
L 1.18871004 -2.17156004 1.19161004 -2.16871998 0 P 0 ;0
L 1.19161004 -2.16871998 1.19431004 -2.16568996 0 P 0 ;0
L 1.19431004 -2.16568996 1.19678996 -2.16246998 0 P 0 ;0
L 1.19678996 -2.16246998 1.19908996 -2.15901998 0 P 0 ;0
L 1.19908996 -2.15901998 1.20113996 -2.15543996 0 P 0 ;0
L 1.20113996 -2.15543996 1.20295 -2.15171004 0 P 0 ;0
L 1.20295 -2.15171004 1.20435 -2.14815 0 P 0 ;0
L 1.20435 -2.14815 1.20543996 -2.14448996 0 P 0 ;0
L 1.20543996 -2.14448996 1.20621004 -2.14073996 0 P 0 ;0
L 1.20621004 -2.14073996 1.20651998 -2.13855 0 P 0 ;0
L 1.20651998 -2.13855 1.20671998 -2.13633996 0 P 0 ;0
L 1.20671998 -2.13633996 1.20761998 -2.12321004 0 P 0 ;0
L 1.20761998 -2.12321004 1.20858002 -2.10753996 0 P 0 ;0
L 1.20858002 -2.10753996 1.20951004 -2.09021998 0 P 0 ;0
L 1.20951004 -2.09021998 1.21048002 -2.07166004 0 P 0 ;0
L 1.21048002 -2.07166004 1.21156004 -2.05228002 0 P 0 ;0
L 1.21156004 -2.05228002 1.21258002 -2.03478996 0 P 0 ;0
L 1.21258002 -2.03478996 1.21333002 -2.02286004 0 P 0 ;0
L 1.21333002 -2.02286004 1.21393996 -2.01373996 0 P 0 ;0
L 1.21393996 -2.01373996 1.21443996 -2.00568996 0 P 0 ;0
L 1.21443996 -2.00568996 1.21485 -1.99883996 0 P 0 ;0
L 1.21485 -1.99883996 1.2149 -1.99721004 0 P 0 ;0
L 1.2149 -1.99721004 1.21488996 -1.99703996 0 P 0 ;0
L 1.21488996 -1.99703996 1.21486998 -1.99686004 0 P 0 ;0
L 1.21486998 -1.99686004 1.21483996 -1.99668996 0 P 0 ;0
L 1.21483996 -1.99668996 1.21478996 -1.99653002 0 P 0 ;0
L 1.21478996 -1.99653002 1.21473002 -1.99636998 0 P 0 ;0
L 1.21473002 -1.99636998 1.21466004 -1.99621004 0 P 0 ;0
L 1.21466004 -1.99621004 1.21458002 -1.99606004 0 P 0 ;0
L 1.21458002 -1.99606004 1.21448002 -1.99591004 0 P 0 ;0
L 1.21448002 -1.99591004 1.21433002 -1.99571998 0 P 0 ;0
L 1.21433002 -1.99571998 1.21416998 -1.99553996 0 P 0 ;0
L 1.21416998 -1.99553996 1.21398996 -1.99538002 0 P 0 ;0
L 1.21398996 -1.99538002 1.21378996 -1.99523996 0 P 0 ;0
L 1.21378996 -1.99523996 1.21358002 -1.99511004 0 P 0 ;0
L 1.21358002 -1.99511004 1.21336004 -1.995 0 P 0 ;0
L 1.21336004 -1.995 1.21261004 -1.99468996 0 P 0 ;0
L 1.21261004 -1.99468996 1.21183996 -1.99443996 0 P 0 ;0
L 1.21183996 -1.99443996 1.21105 -1.99423002 0 P 0 ;0
L 1.21105 -1.99423002 1.20593996 -1.99318002 0 P 0 ;0
L 1.20593996 -1.99318002 1.18996998 -1.99065 0 P 0 ;0
L 1.18996998 -1.99065 1.17318996 -1.98908002 0 P 0 ;0
L 1.17318996 -1.98908002 1.15718996 -1.98858002 0 P 0 ;0
L 1.15718996 -1.98858002 1.1504 -1.98876004 0 P 0 ;0
L 1.1504 -1.98876004 1.14356998 -1.98926998 0 P 0 ;0
L 1.04503996 -2.19061998 1.05141998 -2.19061998 0 P 0 ;0
L 1.04893002 -2.18961998 1.05323002 -2.18961998 0 P 0 ;0
L 1.05263002 -2.18861998 1.05503996 -2.18861998 0 P 0 ;0
L 1.05628996 -2.18761998 1.05676004 -2.18761998 0 P 0 ;0
L 1.09645 -2.17983002 1.16738002 -2.17983002 0 P 0 ;0
L 1.09126004 -2.17883002 1.17091004 -2.17883002 0 P 0 ;0
L 1.0868 -2.17783002 1.17386998 -2.17783002 0 P 0 ;0
L 1.08368002 -2.17683002 1.17636004 -2.17683002 0 P 0 ;0
L 1.0836 -2.17583002 1.1787 -2.17583002 0 P 0 ;0
L 1.08351998 -2.17483002 1.18066998 -2.17483002 0 P 0 ;0
L 1.08345 -2.17383002 1.18236998 -2.17383002 0 P 0 ;0
L 1.08336998 -2.17283002 1.1839 -2.17283002 0 P 0 ;0
L 1.08328996 -2.17183002 1.18526998 -2.17183002 0 P 0 ;0
L 1.08321998 -2.17083002 1.18646998 -2.17083002 0 P 0 ;0
L 1.08313996 -2.16983002 1.18761998 -2.16983002 0 P 0 ;0
L 1.08306998 -2.16883002 1.18863996 -2.16883002 0 P 0 ;0
L 1.08298996 -2.16783002 1.18966004 -2.16783002 0 P 0 ;0
L 1.08291998 -2.16683002 1.19061004 -2.16683002 0 P 0 ;0
L 1.08283996 -2.16583002 1.1915 -2.16583002 0 P 0 ;0
L 1.08276004 -2.16483002 1.19238996 -2.16483002 0 P 0 ;0
L 1.08268996 -2.16383002 1.19321004 -2.16383002 0 P 0 ;0
L 1.08261004 -2.16283002 1.19398002 -2.16283002 0 P 0 ;0
L 1.08253002 -2.16183002 1.19476004 -2.16183002 0 P 0 ;0
L 1.08246004 -2.16083002 1.19548002 -2.16083002 0 P 0 ;0
L 1.08238002 -2.15983002 1.19613996 -2.15983002 0 P 0 ;0
L 1.08231004 -2.15883002 1.19681004 -2.15883002 0 P 0 ;0
L 1.08223996 -2.15783002 1.19746004 -2.15783002 0 P 0 ;0
L 1.13506998 -2.18383002 1.12553002 -2.18343996 0 P 0 ;0
L 1.12553002 -2.18343996 1.11266004 -2.18218002 0 P 0 ;0
L 1.11266004 -2.18218002 1.09983002 -2.18048002 0 P 0 ;0
L 1.09983002 -2.18048002 1.09036998 -2.17866004 0 P 0 ;0
L 1.09036998 -2.17866004 1.0837 -2.17711004 0 P 0 ;0
L 1.0837 -2.17711004 1.08245 -2.16066998 0 P 0 ;0
L 1.08245 -2.16066998 1.08193996 -2.15361998 0 P 0 ;0
L 1.08193996 -2.15361998 1.08156998 -2.14726004 0 P 0 ;0
L 1.08156998 -2.14726004 1.08131998 -2.14191004 0 P 0 ;0
L 1.08131998 -2.14191004 1.08131004 -2.14108996 0 P 0 ;0
L 1.08131004 -2.14108996 1.08136004 -2.14026004 0 P 0 ;0
L 1.08136004 -2.14026004 1.0814 -2.13986998 0 P 0 ;0
L 1.0814 -2.13986998 1.08996004 -2.14233002 0 P 0 ;0
L 1.08996004 -2.14233002 1.08996998 -2.14233996 0 P 0 ;0
L 1.08996998 -2.14233996 1.08998996 -2.14233996 0 P 0 ;0
L 1.08998996 -2.14233996 1.099 -2.14471998 0 P 0 ;0
L 1.099 -2.14471998 1.10806998 -2.14668002 0 P 0 ;0
L 1.10806998 -2.14668002 1.11598002 -2.14791998 0 P 0 ;0
L 1.11598002 -2.14791998 1.12395 -2.1486 0 P 0 ;0
L 1.12395 -2.1486 1.13048996 -2.14863996 0 P 0 ;0
L 1.13048996 -2.14863996 1.137 -2.14811998 0 P 0 ;0
L 1.137 -2.14811998 1.13903002 -2.14778996 0 P 0 ;0
L 1.13903002 -2.14778996 1.14103002 -2.14728996 0 P 0 ;0
L 1.14103002 -2.14728996 1.14298002 -2.14661998 0 P 0 ;0
L 1.14298002 -2.14661998 1.14486998 -2.14581004 0 P 0 ;0
L 1.14486998 -2.14581004 1.14668002 -2.14483996 0 P 0 ;0
L 1.14668002 -2.14483996 1.1484 -2.14373996 0 P 0 ;0
L 1.1484 -2.14373996 1.15003002 -2.1425 0 P 0 ;0
L 1.15003002 -2.1425 1.15155 -2.14115 0 P 0 ;0
L 1.15155 -2.14115 1.1526 -2.14006998 0 P 0 ;0
L 1.1526 -2.14006998 1.15263996 -2.14001998 0 P 0 ;0
L 1.15263996 -2.14001998 1.15356004 -2.13893002 0 P 0 ;0
L 1.15356004 -2.13893002 1.15443996 -2.13771998 0 P 0 ;0
L 1.15443996 -2.13771998 1.15523002 -2.13646004 0 P 0 ;0
L 1.15523002 -2.13646004 1.15593996 -2.13515 0 P 0 ;0
L 1.15593996 -2.13515 1.15655 -2.13381004 0 P 0 ;0
L 1.15655 -2.13381004 1.15706004 -2.13243002 0 P 0 ;0
L 1.15706004 -2.13243002 1.15748002 -2.13101004 0 P 0 ;0
L 1.15748002 -2.13101004 1.1579 -2.12905 0 P 0 ;0
L 1.1579 -2.12905 1.15816004 -2.12706004 0 P 0 ;0
L 1.15816004 -2.12706004 1.15825 -2.12506998 0 P 0 ;0
L 1.15825 -2.12506998 1.15818002 -2.12165 0 P 0 ;0
L 1.15818002 -2.12165 1.15813996 -2.12118002 0 P 0 ;0
L 1.15813996 -2.12118002 1.15813002 -2.1211 0 P 0 ;0
L 1.15813002 -2.1211 1.15806004 -2.12068002 0 P 0 ;0
L 1.15806004 -2.12068002 1.15793996 -2.12018996 0 P 0 ;0
L 1.15793996 -2.12018996 1.15778002 -2.11973002 0 P 0 ;0
L 1.15778002 -2.11973002 1.1577 -2.11953002 0 P 0 ;0
L 1.1577 -2.11953002 1.15758996 -2.11933002 0 P 0 ;0
L 1.15758996 -2.11933002 1.15746998 -2.11913996 0 P 0 ;0
L 1.15746998 -2.11913996 1.15733002 -2.11895 0 P 0 ;0
L 1.15733002 -2.11895 1.15716998 -2.11878002 0 P 0 ;0
L 1.15716998 -2.11878002 1.157 -2.11863002 0 P 0 ;0
L 1.157 -2.11863002 1.15681998 -2.11848996 0 P 0 ;0
L 1.15681998 -2.11848996 1.15663002 -2.11836004 0 P 0 ;0
L 1.15663002 -2.11836004 1.15641998 -2.11825 0 P 0 ;0
L 1.15641998 -2.11825 1.15621004 -2.11816004 0 P 0 ;0
L 1.15621004 -2.11816004 1.15598996 -2.11808996 0 P 0 ;0
L 1.15598996 -2.11808996 1.15576998 -2.11803996 0 P 0 ;0
L 1.15576998 -2.11803996 1.15553002 -2.118 0 P 0 ;0
L 1.15553002 -2.118 1.15518002 -2.11798002 0 P 0 ;0
L 1.15518002 -2.11798002 1.15483996 -2.11798996 0 P 0 ;0
L 1.15483996 -2.11798996 1.15451004 -2.11803002 0 P 0 ;0
L 1.15451004 -2.11803002 1.15418002 -2.1181 0 P 0 ;0
L 1.15418002 -2.1181 1.15386004 -2.1182 0 P 0 ;0
L 1.15386004 -2.1182 1.15361004 -2.11828996 0 P 0 ;0
L 1.15361004 -2.11828996 1.14705 -2.12083996 0 P 0 ;0
L 1.14705 -2.12083996 1.14038996 -2.12278996 0 P 0 ;0
L 1.14038996 -2.12278996 1.13356004 -2.12416004 0 P 0 ;0
L 1.13356004 -2.12416004 1.1285 -2.12476998 0 P 0 ;0
L 1.1285 -2.12476998 1.12341004 -2.12501998 0 P 0 ;0
L 1.12341004 -2.12501998 1.11831004 -2.12493002 0 P 0 ;0
L 1.11831004 -2.12493002 1.11323002 -2.12448996 0 P 0 ;0
L 1.11323002 -2.12448996 1.10848996 -2.12373002 0 P 0 ;0
L 1.10848996 -2.12373002 1.10383996 -2.12263002 0 P 0 ;0
L 1.10383996 -2.12263002 1.09926998 -2.12118996 0 P 0 ;0
L 1.09926998 -2.12118996 1.09481004 -2.11941004 0 P 0 ;0
L 1.09481004 -2.11941004 1.09168002 -2.11788002 0 P 0 ;0
L 1.09168002 -2.11788002 1.08866004 -2.11611998 0 P 0 ;0
L 1.08866004 -2.11611998 1.08578002 -2.11413002 0 P 0 ;0
L 1.08578002 -2.11413002 1.08306998 -2.11193996 0 P 0 ;0
L 1.08306998 -2.11193996 1.08051998 -2.10955 0 P 0 ;0
L 1.08051998 -2.10955 1.07793996 -2.10673002 0 P 0 ;0
L 1.07793996 -2.10673002 1.07561004 -2.10373996 0 P 0 ;0
L 1.07561004 -2.10373996 1.07351004 -2.10058002 0 P 0 ;0
L 1.07351004 -2.10058002 1.07171004 -2.09733996 0 P 0 ;0
L 1.07171004 -2.09733996 1.07018002 -2.09396998 0 P 0 ;0
L 1.07018002 -2.09396998 1.06893996 -2.09048002 0 P 0 ;0
L 1.06893996 -2.09048002 1.06786004 -2.0865 0 P 0 ;0
L 1.06786004 -2.0865 1.06706004 -2.08243996 0 P 0 ;0
L 1.06706004 -2.08243996 1.06656004 -2.07833002 0 P 0 ;0
L 1.06656004 -2.07833002 1.06615 -2.07071004 0 P 0 ;0
L 1.06615 -2.07071004 1.06621004 -2.06313996 0 P 0 ;0
L 1.06621004 -2.06313996 1.06675 -2.0556 0 P 0 ;0
L 1.06675 -2.0556 1.0678 -2.04813002 0 P 0 ;0
L 1.0678 -2.04813002 1.06868996 -2.04391998 0 P 0 ;0
L 1.06868996 -2.04391998 1.06985 -2.03981004 0 P 0 ;0
L 1.06985 -2.03981004 1.0713 -2.03578996 0 P 0 ;0
L 1.0713 -2.03578996 1.07296004 -2.03206998 0 P 0 ;0
L 1.07296004 -2.03206998 1.07486998 -2.02848996 0 P 0 ;0
L 1.07486998 -2.02848996 1.07705 -2.02506004 0 P 0 ;0
L 1.07705 -2.02506004 1.07966004 -2.0215 0 P 0 ;0
L 1.07966004 -2.0215 1.08246998 -2.01811004 0 P 0 ;0
L 1.08246998 -2.01811004 1.08546998 -2.01491004 0 P 0 ;0
L 1.08546998 -2.01491004 1.0897 -2.01091004 0 P 0 ;0
L 1.0897 -2.01091004 1.09153002 -2.00936998 0 P 0 ;0
L 1.09153002 -2.00936998 1.09341998 -2.00793996 0 P 0 ;0
L 1.09341998 -2.00793996 1.09545 -2.00658002 0 P 0 ;0
L 1.09545 -2.00658002 1.09751004 -2.00533996 0 P 0 ;0
L 1.09751004 -2.00533996 1.10288002 -2.0025 0 P 0 ;0
L 1.10288002 -2.0025 1.10736998 -2.00043002 0 P 0 ;0
L 1.10736998 -2.00043002 1.11193002 -1.99861004 0 P 0 ;0
L 1.11193002 -1.99861004 1.12218002 -1.99533002 0 P 0 ;0
L 1.12218002 -1.99533002 1.13298002 -1.99281998 0 P 0 ;0
L 1.13298002 -1.99281998 1.14378996 -1.99126004 0 P 0 ;0
L 1.14378996 -1.99126004 1.1505 -1.99075 0 P 0 ;0
L 1.1505 -1.99075 1.15718002 -1.99058996 0 P 0 ;0
L 1.15718002 -1.99058996 1.17306998 -1.99108002 0 P 0 ;0
L 1.17306998 -1.99108002 1.18971998 -1.99263002 0 P 0 ;0
L 1.18971998 -1.99263002 1.20558002 -1.99515 0 P 0 ;0
L 1.20558002 -1.99515 1.21058996 -1.99618002 0 P 0 ;0
L 1.21058996 -1.99618002 1.21126998 -1.99636004 0 P 0 ;0
L 1.21126998 -1.99636004 1.21191998 -1.99656998 0 P 0 ;0
L 1.21191998 -1.99656998 1.21253002 -1.99681998 0 P 0 ;0
L 1.21253002 -1.99681998 1.21261004 -1.99686004 0 P 0 ;0
L 1.21261004 -1.99686004 1.21266004 -1.99688996 0 P 0 ;0
L 1.21266004 -1.99688996 1.21271998 -1.99693002 0 P 0 ;0
L 1.21271998 -1.99693002 1.21281998 -1.99703002 0 P 0 ;0
L 1.21281998 -1.99703002 1.21286004 -1.99708996 0 P 0 ;0
L 1.21286004 -1.99708996 1.21288002 -1.99711004 0 P 0 ;0
L 1.21288002 -1.99711004 1.21288002 -1.99711998 0 P 0 ;0
L 1.21288002 -1.99711998 1.21288996 -1.99715 0 P 0 ;0
L 1.21288996 -1.99715 1.2129 -1.99716998 0 P 0 ;0
L 1.2129 -1.99716998 1.2129 -1.99721998 0 P 0 ;0
L 1.2129 -1.99721998 1.21285 -1.99875 0 P 0 ;0
L 1.21285 -1.99875 1.21243996 -2.00556998 0 P 0 ;0
L 1.21243996 -2.00556998 1.21193996 -2.01361004 0 P 0 ;0
L 1.21193996 -2.01361004 1.21133996 -2.02273002 0 P 0 ;0
L 1.21133996 -2.02273002 1.21133996 -2.02273996 0 P 0 ;0
L 1.21133996 -2.02273996 1.21058996 -2.03468002 0 P 0 ;0
L 1.21058996 -2.03468002 1.20956004 -2.05216998 0 P 0 ;0
L 1.20956004 -2.05216998 1.20848996 -2.07156004 0 P 0 ;0
L 1.20848996 -2.07156004 1.20848996 -2.07156998 0 P 0 ;0
L 1.20848996 -2.07156998 1.20751004 -2.09011004 0 P 0 ;0
L 1.20751004 -2.09011004 1.20658996 -2.10743996 0 P 0 ;0
L 1.20658996 -2.10743996 1.20561998 -2.12308996 0 P 0 ;0
L 1.20561998 -2.12308996 1.20473002 -2.13618996 0 P 0 ;0
L 1.20473002 -2.13618996 1.20453002 -2.13831998 0 P 0 ;0
L 1.20453002 -2.13831998 1.20423996 -2.14041004 0 P 0 ;0
L 1.20423996 -2.14041004 1.2035 -2.144 0 P 0 ;0
L 1.2035 -2.144 1.20246004 -2.1475 0 P 0 ;0
L 1.20246004 -2.1475 1.20111998 -2.1509 0 P 0 ;0
L 1.20111998 -2.1509 1.19936998 -2.1545 0 P 0 ;0
L 1.19936998 -2.1545 1.19738002 -2.15796998 0 P 0 ;0
L 1.19738002 -2.15796998 1.19516004 -2.1613 0 P 0 ;0
L 1.19516004 -2.1613 1.19276998 -2.16441004 0 P 0 ;0
L 1.19276998 -2.16441004 1.19016004 -2.16733996 0 P 0 ;0
L 1.19016004 -2.16733996 1.18736004 -2.17008002 0 P 0 ;0
L 1.18736004 -2.17008002 1.1854 -2.17173996 0 P 0 ;0
L 1.1854 -2.17173996 1.18335 -2.17323002 0 P 0 ;0
L 1.18335 -2.17323002 1.18118002 -2.17456004 0 P 0 ;0
L 1.18118002 -2.17456004 1.17893002 -2.17573002 0 P 0 ;0
L 1.17893002 -2.17573002 1.17456998 -2.1776 0 P 0 ;0
L 1.17456998 -2.1776 1.17006998 -2.17911998 0 P 0 ;0
L 1.17006998 -2.17911998 1.16473996 -2.18053002 0 P 0 ;0
L 1.16473996 -2.18053002 1.15935 -2.18166998 0 P 0 ;0
L 1.15935 -2.18166998 1.15341998 -2.18263002 0 P 0 ;0
L 1.15341998 -2.18263002 1.1475 -2.18328996 0 P 0 ;0
L 1.1475 -2.18328996 1.13506998 -2.18383002 0 P 0 ;0
L 0.90491998 -2.21461998 1.00131004 -2.21461998 0 P 0 ;0
L 0.92235 -2.21361998 1.00355 -2.21361998 0 P 0 ;0
L 0.76925 -1.8965 0.85586998 -1.8965 0 P 0 ;0
L 0.76958996 -1.8955 0.85556004 -1.8955 0 P 0 ;0
L 0.76995 -1.8945 0.85521004 -1.8945 0 P 0 ;0
L 0.77031004 -1.8935 0.85486004 -1.8935 0 P 0 ;0
L 0.77071004 -1.8925 0.85443996 -1.8925 0 P 0 ;0
L 0.77115 -1.8915 0.85401004 -1.8915 0 P 0 ;0
L 0.7716 -1.8905 0.85355 -1.8905 0 P 0 ;0
L 0.77206004 -1.8895 0.85303002 -1.8895 0 P 0 ;0
L 0.7726 -1.8885 0.85251004 -1.8885 0 P 0 ;0
L 0.77313996 -1.8875 0.85198996 -1.8875 0 P 0 ;0
L 0.77368996 -1.8865 0.85138002 -1.8865 0 P 0 ;0
L 0.77433002 -1.8855 0.85073996 -1.8855 0 P 0 ;0
L 0.77496004 -1.8845 0.85011004 -1.8845 0 P 0 ;0
L 0.77561998 -1.8835 0.84943002 -1.8835 0 P 0 ;0
L 0.77636004 -1.8825 0.84866998 -1.8825 0 P 0 ;0
L 0.77711004 -1.8815 0.84791004 -1.8815 0 P 0 ;0
L 0.7779 -1.8805 0.84713002 -1.8805 0 P 0 ;0
L 0.77876998 -1.8795 0.84623002 -1.8795 0 P 0 ;0
L 0.77963996 -1.8785 0.84533002 -1.8785 0 P 0 ;0
L 0.7806 -1.8775 0.8444 -1.8775 0 P 0 ;0
L 0.78161004 -1.8765 0.84335 -1.8765 0 P 0 ;0
L 0.78265 -1.8755 0.84228996 -1.8755 0 P 0 ;0
L 0.78381998 -1.8745 0.84108996 -1.8745 0 P 0 ;0
L 0.78498996 -1.8735 0.83986998 -1.8735 0 P 0 ;0
L 0.78635 -1.8725 0.83848002 -1.8725 0 P 0 ;0
L 0.78773002 -1.8715 0.83706004 -1.8715 0 P 0 ;0
L 0.78933002 -1.8705 0.83541998 -1.8705 0 P 0 ;0
L 0.791 -1.8695 0.83366004 -1.8695 0 P 0 ;0
L 0.793 -1.8685 0.83171998 -1.8685 0 P 0 ;0
L 0.79525 -1.8675 0.82941998 -1.8675 0 P 0 ;0
L 0.79791998 -1.8665 0.82671004 -1.8665 0 P 0 ;0
L 0.80143996 -1.8655 0.82328996 -1.8655 0 P 0 ;0
L 0.80705 -1.8645 0.81776004 -1.8645 0 P 0 ;0
L 0.74543002 -1.89661998 0.75033002 -1.89661998 0 P 0 ;0
L 0.74751004 -1.89561998 0.75058996 -1.89561998 0 P 0 ;0
L 0.74958996 -1.89461998 0.75086004 -1.89461998 0 P 0 ;0
L 0.76733996 -1.9125 0.85751998 -1.9125 0 P 0 ;0
L 0.76728996 -1.9115 0.85756004 -1.9115 0 P 0 ;0
L 0.76723996 -1.9105 0.85758996 -1.9105 0 P 0 ;0
L 0.76721998 -1.9095 0.85763002 -1.9095 0 P 0 ;0
L 0.76725 -1.9085 0.85761004 -1.9085 0 P 0 ;0
L 0.76728002 -1.9075 0.85756998 -1.9075 0 P 0 ;0
L 0.76731004 -1.9065 0.85753002 -1.9065 0 P 0 ;0
L 0.76741998 -1.9055 0.85748996 -1.9055 0 P 0 ;0
L 0.76753996 -1.9045 0.85738002 -1.9045 0 P 0 ;0
L 0.76766004 -1.9035 0.85726004 -1.9035 0 P 0 ;0
L 0.76781998 -1.9025 0.85713996 -1.9025 0 P 0 ;0
L 0.76801998 -1.9015 0.85701004 -1.9015 0 P 0 ;0
L 0.76821004 -1.9005 0.85683002 -1.9005 0 P 0 ;0
L 0.76841998 -1.8995 0.85661998 -1.8995 0 P 0 ;0
L 0.7687 -1.8985 0.85641004 -1.8985 0 P 0 ;0
L 0.76896998 -1.8975 0.85613996 -1.8975 0 P 0 ;0
L 0.76751004 -2.08325 0.8416 -2.08325 0 P 0 ;0
L 0.76761998 -2.08225 0.84161998 -2.08225 0 P 0 ;0
L 0.76773996 -2.08125 0.84166998 -2.08125 0 P 0 ;0
L 0.76786004 -2.08025 0.84171998 -2.08025 0 P 0 ;0
L 0.76796998 -2.07925 0.84176998 -2.07925 0 P 0 ;0
L 0.76808002 -2.07825 0.84181004 -2.07825 0 P 0 ;0
L 0.76818002 -2.07725 0.84186004 -2.07725 0 P 0 ;0
L 0.76828996 -2.07625 0.8419 -2.07625 0 P 0 ;0
L 0.76838996 -2.07525 0.84195 -2.07525 0 P 0 ;0
L 0.76848996 -2.07425 0.842 -2.07425 0 P 0 ;0
L 0.7686 -2.07325 0.84205 -2.07325 0 P 0 ;0
L 0.7687 -2.07225 0.84208996 -2.07225 0 P 0 ;0
L 0.7688 -2.07125 0.84213996 -2.07125 0 P 0 ;0
L 0.7689 -2.07025 0.84218002 -2.07025 0 P 0 ;0
L 0.76901004 -2.06925 0.84223002 -2.06925 0 P 0 ;0
L 0.76911004 -2.06825 0.84228002 -2.06825 0 P 0 ;0
L 0.76921004 -2.06725 0.84233002 -2.06725 0 P 0 ;0
L 0.76931998 -2.06625 0.84236998 -2.06625 0 P 0 ;0
L 0.76941998 -2.06525 0.84241998 -2.06525 0 P 0 ;0
L 0.76948996 -2.06425 0.84246004 -2.06425 0 P 0 ;0
L 0.76956004 -2.06325 0.84251004 -2.06325 0 P 0 ;0
L 0.76963002 -2.06225 0.84256004 -2.06225 0 P 0 ;0
L 0.7697 -2.06125 0.8426 -2.06125 0 P 0 ;0
L 0.76976998 -2.06025 0.84265 -2.06025 0 P 0 ;0
L 0.76983996 -2.05925 0.8427 -2.05925 0 P 0 ;0
L 0.76991004 -2.05825 0.84273996 -2.05825 0 P 0 ;0
L 0.76996998 -2.05725 0.84278996 -2.05725 0 P 0 ;0
L 0.77001004 -2.05625 0.84283996 -2.05625 0 P 0 ;0
L 0.77003996 -2.05525 0.84288002 -2.05525 0 P 0 ;0
L 0.77008002 -2.05425 0.84295 -2.05425 0 P 0 ;0
L 0.77011998 -2.05325 0.84303996 -2.05325 0 P 0 ;0
L 0.77016004 -2.05225 0.84311998 -2.05225 0 P 0 ;0
L 0.77018996 -2.05125 0.84321004 -2.05125 0 P 0 ;0
L 0.77023002 -2.05025 0.8433 -2.05025 0 P 0 ;0
L 0.77026998 -2.04925 0.84338002 -2.04925 0 P 0 ;0
L 0.77031004 -2.04825 0.84346998 -2.04825 0 P 0 ;0
L 0.77033996 -2.04725 0.84356004 -2.04725 0 P 0 ;0
L 0.77038002 -2.04625 0.84363996 -2.04625 0 P 0 ;0
L 0.77041004 -2.04525 0.84373002 -2.04525 0 P 0 ;0
L 0.77043996 -2.04425 0.84381004 -2.04425 0 P 0 ;0
L 0.77046004 -2.04325 0.8439 -2.04325 0 P 0 ;0
L 0.77048002 -2.04225 0.84398996 -2.04225 0 P 0 ;0
L 0.77051004 -2.04125 0.84406998 -2.04125 0 P 0 ;0
L 0.77053002 -2.04025 0.84416004 -2.04025 0 P 0 ;0
L 0.77055 -2.03925 0.84425 -2.03925 0 P 0 ;0
L 0.77058002 -2.03825 0.84433002 -2.03825 0 P 0 ;0
L 0.7706 -2.03725 0.84441998 -2.03725 0 P 0 ;0
L 0.77061998 -2.03625 0.84451004 -2.03625 0 P 0 ;0
L 0.77065 -2.03525 0.84458996 -2.03525 0 P 0 ;0
L 0.77066998 -2.03425 0.84468002 -2.03425 0 P 0 ;0
L 0.7707 -2.03325 0.84476998 -2.03325 0 P 0 ;0
L 0.77071998 -2.03225 0.84485 -2.03225 0 P 0 ;0
L 0.77073002 -2.03125 0.84493996 -2.03125 0 P 0 ;0
L 0.77073996 -2.03025 0.84503002 -2.03025 0 P 0 ;0
L 0.79986004 -1.8638 0.79643996 -1.86486998 0 P 0 ;0
L 0.79643996 -1.86486998 0.79311998 -1.86621004 0 P 0 ;0
L 0.79311998 -1.86621004 0.78991004 -1.86781004 0 P 0 ;0
L 0.78991004 -1.86781004 0.78683996 -1.86966998 0 P 0 ;0
L 0.78683996 -1.86966998 0.78391998 -1.87178002 0 P 0 ;0
L 0.78391998 -1.87178002 0.78111998 -1.87416998 0 P 0 ;0
L 0.78111998 -1.87416998 0.7785 -1.87676004 0 P 0 ;0
L 0.7785 -1.87676004 0.77608002 -1.87953996 0 P 0 ;0
L 0.77608002 -1.87953996 0.77386998 -1.8825 0 P 0 ;0
L 0.77386998 -1.8825 0.77188002 -1.88561998 0 P 0 ;0
L 0.77188002 -1.88561998 0.77013996 -1.88886004 0 P 0 ;0
L 0.77013996 -1.88886004 0.76863996 -1.89221004 0 P 0 ;0
L 0.76863996 -1.89221004 0.7674 -1.89566998 0 P 0 ;0
L 0.7674 -1.89566998 0.76643002 -1.89921004 0 P 0 ;0
L 0.76643002 -1.89921004 0.76571004 -1.90283996 0 P 0 ;0
L 0.76571004 -1.90283996 0.76531004 -1.90636004 0 P 0 ;0
L 0.76531004 -1.90636004 0.7652 -1.90991004 0 P 0 ;0
L 0.7652 -1.90991004 0.76538996 -1.91345 0 P 0 ;0
L 0.76538996 -1.91345 0.76586998 -1.91696998 0 P 0 ;0
L 0.76586998 -1.91696998 0.76663996 -1.92046004 0 P 0 ;0
L 0.76663996 -1.92046004 0.76803002 -1.92493996 0 P 0 ;0
L 0.76803002 -1.92493996 0.76978002 -1.9293 0 P 0 ;0
L 0.76978002 -1.9293 0.77106998 -1.93193996 0 P 0 ;0
L 0.77106998 -1.93193996 0.77253002 -1.93448002 0 P 0 ;0
L 0.77253002 -1.93448002 0.77416004 -1.93693996 0 P 0 ;0
L 0.77416004 -1.93693996 0.77593002 -1.93923002 0 P 0 ;0
L 0.77593002 -1.93923002 0.77783996 -1.94141004 0 P 0 ;0
L 0.77783996 -1.94141004 0.77988996 -1.94345 0 P 0 ;0
L 0.77988996 -1.94345 0.78216004 -1.94545 0 P 0 ;0
L 0.78216004 -1.94545 0.78453996 -1.9473 0 P 0 ;0
L 0.78453996 -1.9473 0.78703002 -1.94901998 0 P 0 ;0
L 0.78703002 -1.94901998 0.79016998 -1.95088002 0 P 0 ;0
L 0.79016998 -1.95088002 0.79343996 -1.95248996 0 P 0 ;0
L 0.79343996 -1.95248996 0.79683002 -1.95383996 0 P 0 ;0
L 0.79683002 -1.95383996 0.80031998 -1.95491998 0 P 0 ;0
L 0.80031998 -1.95491998 0.80391004 -1.95573996 0 P 0 ;0
L 0.80391004 -1.95573996 0.80751998 -1.95626004 0 P 0 ;0
L 0.80751998 -1.95626004 0.81116004 -1.9565 0 P 0 ;0
L 0.81116004 -1.9565 0.81481004 -1.95646004 0 P 0 ;0
L 0.81481004 -1.95646004 0.81843996 -1.95613002 0 P 0 ;0
L 0.81843996 -1.95613002 0.82205 -1.95551004 0 P 0 ;0
L 0.82205 -1.95551004 0.82561998 -1.95461004 0 P 0 ;0
L 0.82561998 -1.95461004 0.82911004 -1.95345 0 P 0 ;0
L 0.82911004 -1.95345 0.83248996 -1.95201004 0 P 0 ;0
L 0.83248996 -1.95201004 0.83576004 -1.95031998 0 P 0 ;0
L 0.83576004 -1.95031998 0.83891998 -1.94836004 0 P 0 ;0
L 0.83891998 -1.94836004 0.84191998 -1.94616998 0 P 0 ;0
L 0.84191998 -1.94616998 0.84475 -1.94375 0 P 0 ;0
L 0.84475 -1.94375 0.84738996 -1.94113996 0 P 0 ;0
L 0.84738996 -1.94113996 0.84983002 -1.93833996 0 P 0 ;0
L 0.84983002 -1.93833996 0.85206998 -1.93533996 0 P 0 ;0
L 0.85206998 -1.93533996 0.8536 -1.93291998 0 P 0 ;0
L 0.8536 -1.93291998 0.85496004 -1.93041004 0 P 0 ;0
L 0.85496004 -1.93041004 0.85613996 -1.9278 0 P 0 ;0
L 0.85613996 -1.9278 0.85711998 -1.92511004 0 P 0 ;0
L 0.85711998 -1.92511004 0.85823002 -1.92123002 0 P 0 ;0
L 0.85823002 -1.92123002 0.85901998 -1.91726998 0 P 0 ;0
L 0.85901998 -1.91726998 0.85948996 -1.91323996 0 P 0 ;0
L 0.85948996 -1.91323996 0.85963996 -1.90918002 0 P 0 ;0
L 0.85963996 -1.90918002 0.85946998 -1.90513002 0 P 0 ;0
L 0.85946998 -1.90513002 0.85898002 -1.9011 0 P 0 ;0
L 0.85898002 -1.9011 0.85841998 -1.89826004 0 P 0 ;0
L 0.85841998 -1.89826004 0.85766004 -1.89546004 0 P 0 ;0
L 0.85766004 -1.89546004 0.85671004 -1.89273002 0 P 0 ;0
L 0.85671004 -1.89273002 0.85556998 -1.89006004 0 P 0 ;0
L 0.85556998 -1.89006004 0.85361998 -1.88631004 0 P 0 ;0
L 0.85361998 -1.88631004 0.85136004 -1.88273996 0 P 0 ;0
L 0.85136004 -1.88273996 0.84881004 -1.87938002 0 P 0 ;0
L 0.84881004 -1.87938002 0.84596998 -1.87623002 0 P 0 ;0
L 0.84596998 -1.87623002 0.84355 -1.87393996 0 P 0 ;0
L 0.84355 -1.87393996 0.84096998 -1.87181998 0 P 0 ;0
L 0.84096998 -1.87181998 0.83826004 -1.86988996 0 P 0 ;0
L 0.83826004 -1.86988996 0.83541004 -1.86815 0 P 0 ;0
L 0.83541004 -1.86815 0.83243996 -1.86661004 0 P 0 ;0
L 0.83243996 -1.86661004 0.82938996 -1.86531004 0 P 0 ;0
L 0.82938996 -1.86531004 0.82625 -1.86423002 0 P 0 ;0
L 0.82625 -1.86423002 0.82303996 -1.86336004 0 P 0 ;0
L 0.82303996 -1.86336004 0.81978002 -1.86273002 0 P 0 ;0
L 0.81978002 -1.86273002 0.81646998 -1.86233002 0 P 0 ;0
L 0.81646998 -1.86233002 0.81228996 -1.86215 0 P 0 ;0
L 0.81228996 -1.86215 0.80811004 -1.86233996 0 P 0 ;0
L 0.80811004 -1.86233996 0.80396004 -1.86288996 0 P 0 ;0
L 0.80396004 -1.86288996 0.79986004 -1.8638 0 P 0 ;0
L 0.80308996 -1.9535 0.82186004 -1.9535 0 P 0 ;0
L 0.79926004 -1.9525 0.82563996 -1.9525 0 P 0 ;0
L 0.79636004 -1.9515 0.82856998 -1.9515 0 P 0 ;0
L 0.79393002 -1.9505 0.83093996 -1.9505 0 P 0 ;0
L 0.7919 -1.9495 0.83298996 -1.9495 0 P 0 ;0
L 0.79008002 -1.9485 0.8349 -1.9485 0 P 0 ;0
L 0.78838996 -1.9475 0.83651004 -1.9475 0 P 0 ;0
L 0.7869 -1.9465 0.83806998 -1.9465 0 P 0 ;0
L 0.78548002 -1.9455 0.83943996 -1.9455 0 P 0 ;0
L 0.7842 -1.9445 0.84078996 -1.9445 0 P 0 ;0
L 0.78298002 -1.9435 0.84196998 -1.9435 0 P 0 ;0
L 0.78183996 -1.9425 0.84313996 -1.9425 0 P 0 ;0
L 0.78076998 -1.9415 0.84418996 -1.9415 0 P 0 ;0
L 0.77976004 -1.9405 0.8452 -1.9405 0 P 0 ;0
L 0.77883002 -1.9395 0.84616998 -1.9395 0 P 0 ;0
L 0.77793996 -1.9385 0.84703996 -1.9385 0 P 0 ;0
L 0.77711998 -1.9375 0.84791004 -1.9375 0 P 0 ;0
L 0.77635 -1.9365 0.84871004 -1.9365 0 P 0 ;0
L 0.77561004 -1.9355 0.84945 -1.9355 0 P 0 ;0
L 0.77493996 -1.9345 0.8502 -1.9345 0 P 0 ;0
L 0.77428002 -1.9335 0.85086998 -1.9335 0 P 0 ;0
L 0.7737 -1.9325 0.8515 -1.9325 0 P 0 ;0
L 0.77311998 -1.9315 0.8521 -1.9315 0 P 0 ;0
L 0.77258996 -1.9305 0.85263996 -1.9305 0 P 0 ;0
L 0.7721 -1.9295 0.85318002 -1.9295 0 P 0 ;0
L 0.77161004 -1.9285 0.85363002 -1.9285 0 P 0 ;0
L 0.77121004 -1.9275 0.85408002 -1.9275 0 P 0 ;0
L 0.77081004 -1.9265 0.85448002 -1.9265 0 P 0 ;0
L 0.77041004 -1.9255 0.85485 -1.9255 0 P 0 ;0
L 0.77001004 -1.9245 0.85521998 -1.9245 0 P 0 ;0
L 0.76968002 -1.9235 0.8555 -1.9235 0 P 0 ;0
L 0.76936998 -1.9225 0.85578996 -1.9225 0 P 0 ;0
L 0.76906004 -1.9215 0.85606998 -1.9215 0 P 0 ;0
L 0.76875 -1.9205 0.85633002 -1.9205 0 P 0 ;0
L 0.76848002 -1.9195 0.85653002 -1.9195 0 P 0 ;0
L 0.76826004 -1.9185 0.85673002 -1.9185 0 P 0 ;0
L 0.76803002 -1.9175 0.85693002 -1.9175 0 P 0 ;0
L 0.76783002 -1.9165 0.85708996 -1.9165 0 P 0 ;0
L 0.76768996 -1.9155 0.85721004 -1.9155 0 P 0 ;0
L 0.76755 -1.9145 0.85733002 -1.9145 0 P 0 ;0
L 0.76741998 -1.9135 0.85745 -1.9135 0 P 0 ;0
L 0.81121004 -1.9545 0.80773002 -1.95426998 0 P 0 ;0
L 0.80773002 -1.95426998 0.80426998 -1.95376998 0 P 0 ;0
L 0.80426998 -1.95376998 0.80083996 -1.95298996 0 P 0 ;0
L 0.80083996 -1.95298996 0.7975 -1.95195 0 P 0 ;0
L 0.7975 -1.95195 0.79426004 -1.95066004 0 P 0 ;0
L 0.79426004 -1.95066004 0.79111998 -1.94911998 0 P 0 ;0
L 0.79111998 -1.94911998 0.78811004 -1.94733002 0 P 0 ;0
L 0.78811004 -1.94733002 0.78573002 -1.94568996 0 P 0 ;0
L 0.78573002 -1.94568996 0.78343996 -1.9439 0 P 0 ;0
L 0.78343996 -1.9439 0.78126004 -1.94198996 0 P 0 ;0
L 0.78126004 -1.94198996 0.7793 -1.94003996 0 P 0 ;0
L 0.7793 -1.94003996 0.77746998 -1.93796004 0 P 0 ;0
L 0.77746998 -1.93796004 0.77578996 -1.93576998 0 P 0 ;0
L 0.77578996 -1.93576998 0.77423002 -1.93343002 0 P 0 ;0
L 0.77423002 -1.93343002 0.77283996 -1.931 0 P 0 ;0
L 0.77283996 -1.931 0.77161004 -1.92848996 0 P 0 ;0
L 0.77161004 -1.92848996 0.76991998 -1.92426998 0 P 0 ;0
L 0.76991998 -1.92426998 0.76858002 -1.91993996 0 P 0 ;0
L 0.76858002 -1.91993996 0.76783996 -1.91661998 0 P 0 ;0
L 0.76783996 -1.91661998 0.76738002 -1.91326998 0 P 0 ;0
L 0.76738002 -1.91326998 0.76721004 -1.90988996 0 P 0 ;0
L 0.76721004 -1.90988996 0.76731004 -1.90651004 0 P 0 ;0
L 0.76731004 -1.90651004 0.7677 -1.90315 0 P 0 ;0
L 0.7677 -1.90315 0.76838002 -1.89966998 0 P 0 ;0
L 0.76838002 -1.89966998 0.76931004 -1.89626998 0 P 0 ;0
L 0.76931004 -1.89626998 0.7705 -1.89296004 0 P 0 ;0
L 0.7705 -1.89296004 0.77193996 -1.88973996 0 P 0 ;0
L 0.77193996 -1.88973996 0.7736 -1.88663996 0 P 0 ;0
L 0.7736 -1.88663996 0.77551004 -1.88363996 0 P 0 ;0
L 0.77551004 -1.88363996 0.77763002 -1.8808 0 P 0 ;0
L 0.77763002 -1.8808 0.77996004 -1.87813002 0 P 0 ;0
L 0.77996004 -1.87813002 0.78246998 -1.87565 0 P 0 ;0
L 0.78246998 -1.87565 0.78516004 -1.87336004 0 P 0 ;0
L 0.78516004 -1.87336004 0.78795 -1.87133996 0 P 0 ;0
L 0.78795 -1.87133996 0.79088002 -1.86956004 0 P 0 ;0
L 0.79088002 -1.86956004 0.79393996 -1.86803002 0 P 0 ;0
L 0.79393996 -1.86803002 0.79711004 -1.86675 0 P 0 ;0
L 0.79711004 -1.86675 0.80038002 -1.86573002 0 P 0 ;0
L 0.80038002 -1.86573002 0.80431004 -1.86486004 0 P 0 ;0
L 0.80431004 -1.86486004 0.80828996 -1.86433996 0 P 0 ;0
L 0.80828996 -1.86433996 0.8123 -1.86416004 0 P 0 ;0
L 0.8123 -1.86416004 0.81631004 -1.86431998 0 P 0 ;0
L 0.81631004 -1.86431998 0.81946998 -1.86471004 0 P 0 ;0
L 0.81946998 -1.86471004 0.82258996 -1.86531004 0 P 0 ;0
L 0.82258996 -1.86531004 0.82566004 -1.86613996 0 P 0 ;0
L 0.82566004 -1.86613996 0.82866998 -1.86718002 0 P 0 ;0
L 0.82866998 -1.86718002 0.83158996 -1.86843002 0 P 0 ;0
L 0.83158996 -1.86843002 0.83443002 -1.86988996 0 P 0 ;0
L 0.83443002 -1.86988996 0.83716004 -1.87156004 0 P 0 ;0
L 0.83716004 -1.87156004 0.83976004 -1.87341004 0 P 0 ;0
L 0.83976004 -1.87341004 0.84223002 -1.87543996 0 P 0 ;0
L 0.84223002 -1.87543996 0.84453996 -1.87763002 0 P 0 ;0
L 0.84453996 -1.87763002 0.84726998 -1.88065 0 P 0 ;0
L 0.84726998 -1.88065 0.84971998 -1.88388002 0 P 0 ;0
L 0.84971998 -1.88388002 0.85188996 -1.88731004 0 P 0 ;0
L 0.85188996 -1.88731004 0.85376004 -1.89091004 0 P 0 ;0
L 0.85376004 -1.89091004 0.85483996 -1.89345 0 P 0 ;0
L 0.85483996 -1.89345 0.85575 -1.89605 0 P 0 ;0
L 0.85575 -1.89605 0.85646998 -1.89871004 0 P 0 ;0
L 0.85646998 -1.89871004 0.857 -1.90141004 0 P 0 ;0
L 0.857 -1.90141004 0.85748002 -1.9053 0 P 0 ;0
L 0.85748002 -1.9053 0.85763996 -1.90918996 0 P 0 ;0
L 0.85763996 -1.90918996 0.8575 -1.91308002 0 P 0 ;0
L 0.8575 -1.91308002 0.85703996 -1.91696004 0 P 0 ;0
L 0.85703996 -1.91696004 0.85628002 -1.92076004 0 P 0 ;0
L 0.85628002 -1.92076004 0.85521998 -1.92448996 0 P 0 ;0
L 0.85521998 -1.92448996 0.85428002 -1.92705 0 P 0 ;0
L 0.85428002 -1.92705 0.85316998 -1.92951998 0 P 0 ;0
L 0.85316998 -1.92951998 0.85188002 -1.93191004 0 P 0 ;0
L 0.85188002 -1.93191004 0.85041998 -1.9342 0 P 0 ;0
L 0.85041998 -1.9342 0.84826998 -1.93708002 0 P 0 ;0
L 0.84826998 -1.93708002 0.84593002 -1.93976998 0 P 0 ;0
L 0.84593002 -1.93976998 0.8434 -1.94228002 0 P 0 ;0
L 0.8434 -1.94228002 0.84068002 -1.9446 0 P 0 ;0
L 0.84068002 -1.9446 0.8378 -1.9467 0 P 0 ;0
L 0.8378 -1.9467 0.83476998 -1.94858002 0 P 0 ;0
L 0.83476998 -1.94858002 0.83163996 -1.9502 0 P 0 ;0
L 0.83163996 -1.9502 0.8284 -1.95158002 0 P 0 ;0
L 0.8284 -1.95158002 0.82506004 -1.95268996 0 P 0 ;0
L 0.82506004 -1.95268996 0.82163996 -1.95356004 0 P 0 ;0
L 0.82163996 -1.95356004 0.81818002 -1.95413996 0 P 0 ;0
L 0.81818002 -1.95413996 0.8147 -1.95446004 0 P 0 ;0
L 0.8147 -1.95446004 0.81121004 -1.9545 0 P 0 ;0
L 0.77075 -2.02925 0.84511004 -2.02925 0 P 0 ;0
L 0.77076004 -2.02825 0.8452 -2.02825 0 P 0 ;0
L 0.77076998 -2.02725 0.84528996 -2.02725 0 P 0 ;0
L 0.77078002 -2.02625 0.84536998 -2.02625 0 P 0 ;0
L 0.77078996 -2.02525 0.84548996 -2.02525 0 P 0 ;0
L 0.7708 -2.02425 0.84561998 -2.02425 0 P 0 ;0
L 0.77081004 -2.02325 0.84575 -2.02325 0 P 0 ;0
L 0.77081998 -2.02225 0.84588002 -2.02225 0 P 0 ;0
L 0.77083002 -2.02125 0.84601004 -2.02125 0 P 0 ;0
L 0.77083996 -2.02025 0.84613996 -2.02025 0 P 0 ;0
L 0.77085 -2.01925 0.84626004 -2.01925 0 P 0 ;0
L 0.77085 -2.01825 0.84638996 -2.01825 0 P 0 ;0
L 0.77085 -2.01725 0.84651998 -2.01725 0 P 0 ;0
L 0.77086004 -2.01625 0.84663996 -2.01625 0 P 0 ;0
L 0.77086004 -2.01525 0.84676998 -2.01525 0 P 0 ;0
L 0.77086004 -2.01425 0.8469 -2.01425 0 P 0 ;0
L 0.77086004 -2.01325 0.84703002 -2.01325 0 P 0 ;0
L 0.77086004 -2.01225 0.84716004 -2.01225 0 P 0 ;0
L 0.77086004 -2.01125 0.84728996 -2.01125 0 P 0 ;0
L 0.77086004 -2.01025 0.84741004 -2.01025 0 P 0 ;0
L 0.77086998 -2.00925 0.84753996 -2.00925 0 P 0 ;0
L 0.77086998 -2.00825 0.84766998 -2.00825 0 P 0 ;0
L 0.77086998 -2.00725 0.84778996 -2.00725 0 P 0 ;0
L 0.77086998 -2.00625 0.84791998 -2.00625 0 P 0 ;0
L 0.77086998 -2.00525 0.84805 -2.00525 0 P 0 ;0
L 0.77086998 -2.00425 0.84818002 -2.00425 0 P 0 ;0
L 0.77088002 -2.00325 0.84831004 -2.00325 0 P 0 ;0
L 0.77088002 -2.00225 0.84843996 -2.00225 0 P 0 ;0
L 0.77088002 -2.00125 0.84856004 -2.00125 0 P 0 ;0
L 0.77088002 -2.00025 0.84868996 -2.00025 0 P 0 ;0
L 0.77088002 -1.99925 0.84881998 -1.99925 0 P 0 ;0
L 0.77088002 -1.99825 0.84896004 -1.99825 0 P 0 ;0
L 0.77088002 -1.99725 0.84911004 -1.99725 0 P 0 ;0
L 0.77088996 -1.99625 0.84926998 -1.99625 0 P 0 ;0
L 0.77088996 -1.99525 0.84941998 -1.99525 0 P 0 ;0
L 0.77088996 -1.99425 0.84956998 -1.99425 0 P 0 ;0
L 0.77088996 -1.99325 0.84971998 -1.99325 0 P 0 ;0
L 0.77088996 -1.99225 0.84986998 -1.99225 0 P 0 ;0
L 0.77088996 -1.99125 0.85003002 -1.99125 0 P 0 ;0
L 0.7709 -1.99025 0.85018002 -1.99025 0 P 0 ;0
L 0.7709 -1.98925 0.85033002 -1.98925 0 P 0 ;0
L 0.76885 -2.01878002 0.76871998 -2.03201998 0 P 0 ;0
L 0.76871998 -2.03201998 0.7684 -2.04553996 0 P 0 ;0
L 0.7684 -2.04553996 0.76796004 -2.05751004 0 P 0 ;0
L 0.76796004 -2.05751004 0.76741004 -2.06523002 0 P 0 ;0
L 0.76741004 -2.06523002 0.76596004 -2.07933996 0 P 0 ;0
L 0.76596004 -2.07933996 0.7636 -2.09918002 0 P 0 ;0
L 0.7636 -2.09918002 0.76116004 -2.119 0 P 0 ;0
L 0.76116004 -2.119 0.76011998 -2.12526004 0 P 0 ;0
L 0.76011998 -2.12526004 0.75948996 -2.12825 0 P 0 ;0
L 0.75948996 -2.12825 0.84418002 -2.12825 0 P 0 ;0
L 0.84418002 -2.12825 0.84361998 -2.10788002 0 P 0 ;0
L 0.84361998 -2.10788002 0.8436 -2.08276004 0 P 0 ;0
L 0.8436 -2.08276004 0.8449 -2.05491998 0 P 0 ;0
L 0.8449 -2.05491998 0.84736004 -2.02641004 0 P 0 ;0
L 0.84736004 -2.02641004 0.85083996 -1.99923002 0 P 0 ;0
L 0.85083996 -1.99923002 0.85268996 -1.987 0 P 0 ;0
L 0.85268996 -1.987 0.7689 -1.987 0 P 0 ;0
L 0.7689 -1.987 0.76885 -2.01878002 0 P 0 ;0
L 0.76195 -2.12625 0.84211998 -2.12625 0 P 0 ;0
L 0.76213996 -2.12525 0.8421 -2.12525 0 P 0 ;0
L 0.76231004 -2.12425 0.84206998 -2.12425 0 P 0 ;0
L 0.76248002 -2.12325 0.84203996 -2.12325 0 P 0 ;0
L 0.76263996 -2.12225 0.84201004 -2.12225 0 P 0 ;0
L 0.76281004 -2.12125 0.84198996 -2.12125 0 P 0 ;0
L 0.76296998 -2.12025 0.84196004 -2.12025 0 P 0 ;0
L 0.76313996 -2.11925 0.84193002 -2.11925 0 P 0 ;0
L 0.76326998 -2.11825 0.8419 -2.11825 0 P 0 ;0
L 0.76338996 -2.11725 0.84188002 -2.11725 0 P 0 ;0
L 0.76351004 -2.11625 0.84185 -2.11625 0 P 0 ;0
L 0.76363996 -2.11525 0.84181998 -2.11525 0 P 0 ;0
L 0.76376004 -2.11425 0.84178996 -2.11425 0 P 0 ;0
L 0.76388002 -2.11325 0.84176998 -2.11325 0 P 0 ;0
L 0.76401004 -2.11225 0.84173996 -2.11225 0 P 0 ;0
L 0.76413002 -2.11125 0.84171004 -2.11125 0 P 0 ;0
L 0.76425 -2.11025 0.84168002 -2.11025 0 P 0 ;0
L 0.76438002 -2.10925 0.84166004 -2.10925 0 P 0 ;0
L 0.7645 -2.10825 0.84163002 -2.10825 0 P 0 ;0
L 0.76461998 -2.10725 0.84161998 -2.10725 0 P 0 ;0
L 0.76475 -2.10625 0.84161998 -2.10625 0 P 0 ;0
L 0.76486998 -2.10525 0.84161998 -2.10525 0 P 0 ;0
L 0.76498996 -2.10425 0.84161998 -2.10425 0 P 0 ;0
L 0.76511998 -2.10325 0.84161998 -2.10325 0 P 0 ;0
L 0.76523996 -2.10225 0.84161998 -2.10225 0 P 0 ;0
L 0.76536004 -2.10125 0.84161998 -2.10125 0 P 0 ;0
L 0.76548996 -2.10025 0.84161998 -2.10025 0 P 0 ;0
L 0.76561004 -2.09925 0.84161998 -2.09925 0 P 0 ;0
L 0.76573002 -2.09825 0.84161004 -2.09825 0 P 0 ;0
L 0.76583996 -2.09725 0.84161004 -2.09725 0 P 0 ;0
L 0.76596998 -2.09625 0.84161004 -2.09625 0 P 0 ;0
L 0.76608996 -2.09525 0.84161004 -2.09525 0 P 0 ;0
L 0.7662 -2.09425 0.84161004 -2.09425 0 P 0 ;0
L 0.76631998 -2.09325 0.84161004 -2.09325 0 P 0 ;0
L 0.76643996 -2.09225 0.84161004 -2.09225 0 P 0 ;0
L 0.76656004 -2.09125 0.84161004 -2.09125 0 P 0 ;0
L 0.76668002 -2.09025 0.84161004 -2.09025 0 P 0 ;0
L 0.76678996 -2.08925 0.84161004 -2.08925 0 P 0 ;0
L 0.76691998 -2.08825 0.84161004 -2.08825 0 P 0 ;0
L 0.76703002 -2.08725 0.84161004 -2.08725 0 P 0 ;0
L 0.76715 -2.08625 0.8416 -2.08625 0 P 0 ;0
L 0.76726998 -2.08525 0.8416 -2.08525 0 P 0 ;0
L 0.76738996 -2.08425 0.8416 -2.08425 0 P 0 ;0
L 0.76195 -2.12625 0.76208002 -2.12561998 0 P 0 ;0
L 0.76208002 -2.12561998 0.76313996 -2.11928996 0 P 0 ;0
L 0.76313996 -2.11928996 0.76558996 -2.09941998 0 P 0 ;0
L 0.76558996 -2.09941998 0.76558996 -2.09941004 0 P 0 ;0
L 0.76558996 -2.09941004 0.76793996 -2.07956004 0 P 0 ;0
L 0.76793996 -2.07956004 0.7694 -2.0654 0 P 0 ;0
L 0.7694 -2.0654 0.76941004 -2.06536004 0 P 0 ;0
L 0.76941004 -2.06536004 0.76996004 -2.05761998 0 P 0 ;0
L 0.76996004 -2.05761998 0.76996004 -2.05758996 0 P 0 ;0
L 0.76996004 -2.05758996 0.7704 -2.0456 0 P 0 ;0
L 0.7704 -2.0456 0.77071998 -2.03206004 0 P 0 ;0
L 0.77071998 -2.03206004 0.77085 -2.01878002 0 P 0 ;0
L 0.77085 -2.01878002 0.7709 -1.989 0 P 0 ;0
L 0.7709 -1.989 0.85036004 -1.989 0 P 0 ;0
L 0.85036004 -1.989 0.84886004 -1.99895 0 P 0 ;0
L 0.84886004 -1.99895 0.84538002 -2.02618996 0 P 0 ;0
L 0.84538002 -2.02618996 0.8429 -2.05478996 0 P 0 ;0
L 0.8429 -2.05478996 0.8416 -2.08271004 0 P 0 ;0
L 0.8416 -2.08271004 0.84161998 -2.10791004 0 P 0 ;0
L 0.84161998 -2.10791004 0.84211998 -2.12625 0 P 0 ;0
L 0.84211998 -2.12625 0.76195 -2.12625 0 P 0 ;0
L 0.71628996 -1.91261998 0.74938002 -1.91261998 0 P 0 ;0
L 0.71783002 -1.91161998 0.74933002 -1.91161998 0 P 0 ;0
L 0.71953002 -1.91061998 0.74931004 -1.91061998 0 P 0 ;0
L 0.72133002 -1.90961998 0.74928996 -1.90961998 0 P 0 ;0
L 0.72313996 -1.90861998 0.74926998 -1.90861998 0 P 0 ;0
L 0.72493996 -1.90761998 0.74928996 -1.90761998 0 P 0 ;0
L 0.72673996 -1.90661998 0.74931998 -1.90661998 0 P 0 ;0
L 0.72855 -1.90561998 0.74935 -1.90561998 0 P 0 ;0
L 0.73035 -1.90461998 0.74938996 -1.90461998 0 P 0 ;0
L 0.73215 -1.90361998 0.74946998 -1.90361998 0 P 0 ;0
L 0.73396004 -1.90261998 0.74953996 -1.90261998 0 P 0 ;0
L 0.73576004 -1.90161998 0.74961998 -1.90161998 0 P 0 ;0
L 0.73756998 -1.90061998 0.74973996 -1.90061998 0 P 0 ;0
L 0.73943002 -1.89961998 0.74986004 -1.89961998 0 P 0 ;0
L 0.74141998 -1.89861998 0.74998996 -1.89861998 0 P 0 ;0
L 0.74341004 -1.89761998 0.75015 -1.89761998 0 P 0 ;0
L 0.59843002 -2.08361998 0.6754 -2.08361998 0 P 0 ;0
L 0.59846004 -2.08261998 0.67538996 -2.08261998 0 P 0 ;0
L 0.59848002 -2.08161998 0.67538002 -2.08161998 0 P 0 ;0
L 0.59851004 -2.08061998 0.67538002 -2.08061998 0 P 0 ;0
L 0.59853002 -2.07961998 0.67546004 -2.07961998 0 P 0 ;0
L 0.59856004 -2.07861998 0.67553996 -2.07861998 0 P 0 ;0
L 0.59861998 -2.07761998 0.67561004 -2.07761998 0 P 0 ;0
L 0.5987 -2.07661998 0.67568996 -2.07661998 0 P 0 ;0
L 0.59878002 -2.07561998 0.67576004 -2.07561998 0 P 0 ;0
L 0.59885 -2.07461998 0.67583996 -2.07461998 0 P 0 ;0
L 0.59893002 -2.07361998 0.67591998 -2.07361998 0 P 0 ;0
L 0.59901004 -2.07261998 0.67598996 -2.07261998 0 P 0 ;0
L 0.59908002 -2.07161998 0.67606998 -2.07161998 0 P 0 ;0
L 0.59916004 -2.07061998 0.67613996 -2.07061998 0 P 0 ;0
L 0.59923002 -2.06961998 0.67621004 -2.06961998 0 P 0 ;0
L 0.59936004 -2.06861998 0.6763 -2.06861998 0 P 0 ;0
L 0.59948996 -2.06761998 0.67645 -2.06761998 0 P 0 ;0
L 0.59963002 -2.06661998 0.6766 -2.06661998 0 P 0 ;0
L 0.59976998 -2.06561998 0.67676004 -2.06561998 0 P 0 ;0
L 0.5999 -2.06461998 0.67691998 -2.06461998 0 P 0 ;0
L 0.60003002 -2.06361998 0.67706998 -2.06361998 0 P 0 ;0
L 0.60016998 -2.06261998 0.6773 -2.06261998 0 P 0 ;0
L 0.60031004 -2.06161998 0.67753002 -2.06161998 0 P 0 ;0
L 0.60051004 -2.06061998 0.67776004 -2.06061998 0 P 0 ;0
L 0.60071004 -2.05961998 0.67798996 -2.05961998 0 P 0 ;0
L 0.60091998 -2.05861998 0.67823002 -2.05861998 0 P 0 ;0
L 0.60111998 -2.05761998 0.67853002 -2.05761998 0 P 0 ;0
L 0.60133002 -2.05661998 0.67883996 -2.05661998 0 P 0 ;0
L 0.60153996 -2.05561998 0.67913996 -2.05561998 0 P 0 ;0
L 0.60173996 -2.05461998 0.67945 -2.05461998 0 P 0 ;0
L 0.60195 -2.05361998 0.67975 -2.05361998 0 P 0 ;0
L 0.60223002 -2.05261998 0.68006004 -2.05261998 0 P 0 ;0
L 0.60251004 -2.05161998 0.68036004 -2.05161998 0 P 0 ;0
L 0.60278996 -2.05061998 0.68066998 -2.05061998 0 P 0 ;0
L 0.60306004 -2.04961998 0.68096998 -2.04961998 0 P 0 ;0
L 0.60333996 -2.04861998 0.68135 -2.04861998 0 P 0 ;0
L 0.60361998 -2.04761998 0.68173002 -2.04761998 0 P 0 ;0
L 0.6039 -2.04661998 0.68211004 -2.04661998 0 P 0 ;0
L 0.60418002 -2.04561998 0.68248996 -2.04561998 0 P 0 ;0
L 0.60453002 -2.04461998 0.68288002 -2.04461998 0 P 0 ;0
L 0.60488002 -2.04361998 0.68326004 -2.04361998 0 P 0 ;0
L 0.60523002 -2.04261998 0.68363996 -2.04261998 0 P 0 ;0
L 0.60556998 -2.04161998 0.68401998 -2.04161998 0 P 0 ;0
L 0.60591998 -2.04061998 0.6844 -2.04061998 0 P 0 ;0
L 0.60626998 -2.03961998 0.68486004 -2.03961998 0 P 0 ;0
L 0.60661998 -2.03861998 0.68531998 -2.03861998 0 P 0 ;0
L 0.60698996 -2.03761998 0.68578002 -2.03761998 0 P 0 ;0
L 0.60743002 -2.03661998 0.68623996 -2.03661998 0 P 0 ;0
L 0.60786004 -2.03561998 0.6867 -2.03561998 0 P 0 ;0
L 0.60828996 -2.03461998 0.68716004 -2.03461998 0 P 0 ;0
L 0.60873002 -2.03361998 0.68761998 -2.03361998 0 P 0 ;0
L 0.60916004 -2.03261998 0.68808996 -2.03261998 0 P 0 ;0
L 0.60958996 -2.03161998 0.68856998 -2.03161998 0 P 0 ;0
L 0.61003002 -2.03061998 0.68911004 -2.03061998 0 P 0 ;0
L 0.61046004 -2.02961998 0.68965 -2.02961998 0 P 0 ;0
L 0.61088996 -2.02861998 0.69018996 -2.02861998 0 P 0 ;0
L 0.61133002 -2.02761998 0.69073002 -2.02761998 0 P 0 ;0
L 0.61176004 -2.02661998 0.69126998 -2.02661998 0 P 0 ;0
L 0.6122 -2.02561998 0.69181004 -2.02561998 0 P 0 ;0
L 0.61263002 -2.02461998 0.69235 -2.02461998 0 P 0 ;0
L 0.61306004 -2.02361998 0.69288002 -2.02361998 0 P 0 ;0
L 0.61348996 -2.02261998 0.69346998 -2.02261998 0 P 0 ;0
L 0.61393002 -2.02161998 0.69408996 -2.02161998 0 P 0 ;0
L 0.61436004 -2.02061998 0.6947 -2.02061998 0 P 0 ;0
L 0.61478996 -2.01961998 0.69531998 -2.01961998 0 P 0 ;0
L 0.61531004 -2.01861998 0.69593996 -2.01861998 0 P 0 ;0
L 0.61583996 -2.01761998 0.69656004 -2.01761998 0 P 0 ;0
L 0.61636004 -2.01661998 0.69718002 -2.01661998 0 P 0 ;0
L 0.61688002 -2.01561998 0.69778996 -2.01561998 0 P 0 ;0
L 0.6174 -2.01461998 0.69841998 -2.01461998 0 P 0 ;0
L 0.61791998 -2.01361998 0.69911998 -2.01361998 0 P 0 ;0
L 0.61843996 -2.01261998 0.69981998 -2.01261998 0 P 0 ;0
L 0.61896004 -2.01161998 0.70051998 -2.01161998 0 P 0 ;0
L 0.61948002 -2.01061998 0.70123002 -2.01061998 0 P 0 ;0
L 0.62 -2.00961998 0.70193002 -2.00961998 0 P 0 ;0
L 0.62051998 -2.00861998 0.70263002 -2.00861998 0 P 0 ;0
L 0.62103996 -2.00761998 0.70333002 -2.00761998 0 P 0 ;0
L 0.62163996 -2.00661998 0.70403996 -2.00661998 0 P 0 ;0
L 0.62225 -2.00561998 0.70483002 -2.00561998 0 P 0 ;0
L 0.62285 -2.00461998 0.70565 -2.00461998 0 P 0 ;0
L 0.62346004 -2.00361998 0.70646004 -2.00361998 0 P 0 ;0
L 0.62406004 -2.00261998 0.70726998 -2.00261998 0 P 0 ;0
L 0.62466004 -2.00161998 0.70808996 -2.00161998 0 P 0 ;0
L 0.62526998 -2.00061998 0.7089 -2.00061998 0 P 0 ;0
L 0.62586998 -1.99961998 0.70971004 -1.99961998 0 P 0 ;0
L 0.62648002 -1.99861998 0.71053002 -1.99861998 0 P 0 ;0
L 0.62708002 -1.99761998 0.71133996 -1.99761998 0 P 0 ;0
L 0.62768996 -1.99661998 0.71216004 -1.99661998 0 P 0 ;0
L 0.62831998 -1.99561998 0.71296998 -1.99561998 0 P 0 ;0
L 0.62901004 -1.99461998 0.71378996 -1.99461998 0 P 0 ;0
L 0.62971004 -1.99361998 0.71466004 -1.99361998 0 P 0 ;0
L 0.6304 -1.99261998 0.71561004 -1.99261998 0 P 0 ;0
L 0.6311 -1.99161998 0.71656998 -1.99161998 0 P 0 ;0
L 0.63178996 -1.99061998 0.71753002 -1.99061998 0 P 0 ;0
L 0.63248996 -1.98961998 0.71848996 -1.98961998 0 P 0 ;0
L 0.63318002 -1.98861998 0.71945 -1.98861998 0 P 0 ;0
L 0.63388002 -1.98761998 0.72041004 -1.98761998 0 P 0 ;0
L 0.63456998 -1.98661998 0.72136998 -1.98661998 0 P 0 ;0
L 0.63526998 -1.98561998 0.72233002 -1.98561998 0 P 0 ;0
L 0.63598002 -1.98461998 0.72328996 -1.98461998 0 P 0 ;0
L 0.63678996 -1.98361998 0.72425 -1.98361998 0 P 0 ;0
L 0.6376 -1.98261998 0.72521004 -1.98261998 0 P 0 ;0
L 0.63841004 -1.98161998 0.72628002 -1.98161998 0 P 0 ;0
L 0.63921998 -1.98061998 0.72738996 -1.98061998 0 P 0 ;0
L 0.64003002 -1.97961998 0.7285 -1.97961998 0 P 0 ;0
L 0.64083996 -1.97861998 0.72961004 -1.97861998 0 P 0 ;0
L 0.64165 -1.97761998 0.73071004 -1.97761998 0 P 0 ;0
L 0.64246004 -1.97661998 0.73181998 -1.97661998 0 P 0 ;0
L 0.64326998 -1.97561998 0.73293002 -1.97561998 0 P 0 ;0
L 0.64406998 -1.97461998 0.73403996 -1.97461998 0 P 0 ;0
L 0.64488002 -1.97361998 0.73515 -1.97361998 0 P 0 ;0
L 0.64568996 -1.97261998 0.73625 -1.97261998 0 P 0 ;0
L 0.6465 -1.97161998 0.73736004 -1.97161998 0 P 0 ;0
L 0.64731004 -1.97061998 0.73848002 -1.97061998 0 P 0 ;0
L 0.64811998 -1.96961998 0.73973002 -1.96961998 0 P 0 ;0
L 0.64893002 -1.96861998 0.74098996 -1.96861998 0 P 0 ;0
L 0.64981004 -1.96761998 0.74225 -1.96761998 0 P 0 ;0
L 0.65076004 -1.96661998 0.74351004 -1.96661998 0 P 0 ;0
L 0.65171004 -1.96561998 0.74476998 -1.96561998 0 P 0 ;0
L 0.65266998 -1.96461998 0.74603002 -1.96461998 0 P 0 ;0
L 0.65361998 -1.96361998 0.74728996 -1.96361998 0 P 0 ;0
L 0.65458002 -1.96261998 0.74855 -1.96261998 0 P 0 ;0
L 0.65553002 -1.96161998 0.74981004 -1.96161998 0 P 0 ;0
L 0.65648996 -1.96061998 0.75106004 -1.96061998 0 P 0 ;0
L 0.65743996 -1.95961998 0.75233996 -1.95961998 0 P 0 ;0
L 0.6584 -1.95861998 0.7537 -1.95861998 0 P 0 ;0
L 0.65935 -1.95761998 0.75506004 -1.95761998 0 P 0 ;0
L 0.66031004 -1.95661998 0.75641998 -1.95661998 0 P 0 ;0
L 0.66126004 -1.95561998 0.75778996 -1.95561998 0 P 0 ;0
L 0.66221004 -1.95461998 0.75916004 -1.95461998 0 P 0 ;0
L 0.66316998 -1.95361998 0.76053996 -1.95361998 0 P 0 ;0
L 0.66411998 -1.95261998 0.76193996 -1.95261998 0 P 0 ;0
L 0.66523002 -1.95161998 0.76333996 -1.95161998 0 P 0 ;0
L 0.66636004 -1.95061998 0.76406998 -1.95061998 0 P 0 ;0
L 0.66746998 -1.94961998 0.76355 -1.94961998 0 P 0 ;0
L 0.6686 -1.94861998 0.76291998 -1.94861998 0 P 0 ;0
L 0.66971004 -1.94761998 0.76226998 -1.94761998 0 P 0 ;0
L 0.67083996 -1.94661998 0.76161998 -1.94661998 0 P 0 ;0
L 0.67196004 -1.94561998 0.76096998 -1.94561998 0 P 0 ;0
L 0.67306998 -1.94461998 0.76033002 -1.94461998 0 P 0 ;0
L 0.6742 -1.94361998 0.75968996 -1.94361998 0 P 0 ;0
L 0.67531004 -1.94261998 0.75905 -1.94261998 0 P 0 ;0
L 0.67643996 -1.94161998 0.75846004 -1.94161998 0 P 0 ;0
L 0.67755 -1.94061998 0.75788996 -1.94061998 0 P 0 ;0
L 0.67868002 -1.93961998 0.75731998 -1.93961998 0 P 0 ;0
L 0.67978996 -1.93861998 0.75676998 -1.93861998 0 P 0 ;0
L 0.68091998 -1.93761998 0.75626998 -1.93761998 0 P 0 ;0
L 0.68221004 -1.93661998 0.75576998 -1.93661998 0 P 0 ;0
L 0.68353002 -1.93561998 0.75528002 -1.93561998 0 P 0 ;0
L 0.68483996 -1.93461998 0.75483996 -1.93461998 0 P 0 ;0
L 0.68616004 -1.93361998 0.75441004 -1.93361998 0 P 0 ;0
L 0.68746998 -1.93261998 0.75398002 -1.93261998 0 P 0 ;0
L 0.68878002 -1.93161998 0.7536 -1.93161998 0 P 0 ;0
L 0.6901 -1.93061998 0.75323996 -1.93061998 0 P 0 ;0
L 0.69141004 -1.92961998 0.75286998 -1.92961998 0 P 0 ;0
L 0.69271998 -1.92861998 0.75253996 -1.92861998 0 P 0 ;0
L 0.69403002 -1.92761998 0.75223002 -1.92761998 0 P 0 ;0
L 0.69535 -1.92661998 0.75193002 -1.92661998 0 P 0 ;0
L 0.69666004 -1.92561998 0.75163002 -1.92561998 0 P 0 ;0
L 0.69796998 -1.92461998 0.75138002 -1.92461998 0 P 0 ;0
L 0.69936998 -1.92361998 0.75113996 -1.92361998 0 P 0 ;0
L 0.70091004 -1.92261998 0.75088996 -1.92261998 0 P 0 ;0
L 0.70243996 -1.92161998 0.75066004 -1.92161998 0 P 0 ;0
L 0.70398002 -1.92061998 0.75046004 -1.92061998 0 P 0 ;0
L 0.70551998 -1.91961998 0.75026004 -1.91961998 0 P 0 ;0
L 0.70706004 -1.91861998 0.75006998 -1.91861998 0 P 0 ;0
L 0.7086 -1.91761998 0.7499 -1.91761998 0 P 0 ;0
L 0.71013996 -1.91661998 0.74976998 -1.91661998 0 P 0 ;0
L 0.71166998 -1.91561998 0.74961998 -1.91561998 0 P 0 ;0
L 0.71321004 -1.91461998 0.74951998 -1.91461998 0 P 0 ;0
L 0.71475 -1.91361998 0.74945 -1.91361998 0 P 0 ;0
L 0.61556998 -2.15661998 0.70655 -2.15661998 0 P 0 ;0
L 0.61503002 -2.15561998 0.7056 -2.15561998 0 P 0 ;0
L 0.61448996 -2.15461998 0.70465 -2.15461998 0 P 0 ;0
L 0.61395 -2.15361998 0.7037 -2.15361998 0 P 0 ;0
L 0.61341004 -2.15261998 0.70273996 -2.15261998 0 P 0 ;0
L 0.61286998 -2.15161998 0.70178996 -2.15161998 0 P 0 ;0
L 0.61233002 -2.15061998 0.70095 -2.15061998 0 P 0 ;0
L 0.61188002 -2.14961998 0.70015 -2.14961998 0 P 0 ;0
L 0.61143002 -2.14861998 0.69935 -2.14861998 0 P 0 ;0
L 0.61098002 -2.14761998 0.69855 -2.14761998 0 P 0 ;0
L 0.61053002 -2.14661998 0.69775 -2.14661998 0 P 0 ;0
L 0.61008002 -2.14561998 0.69695 -2.14561998 0 P 0 ;0
L 0.60963002 -2.14461998 0.69615 -2.14461998 0 P 0 ;0
L 0.60918002 -2.14361998 0.69535 -2.14361998 0 P 0 ;0
L 0.60873002 -2.14261998 0.69455 -2.14261998 0 P 0 ;0
L 0.60831004 -2.14161998 0.69381998 -2.14161998 0 P 0 ;0
L 0.60793996 -2.14061998 0.69315 -2.14061998 0 P 0 ;0
L 0.60756998 -2.13961998 0.69248002 -2.13961998 0 P 0 ;0
L 0.60721004 -2.13861998 0.69181004 -2.13861998 0 P 0 ;0
L 0.60683996 -2.13761998 0.69115 -2.13761998 0 P 0 ;0
L 0.60646998 -2.13661998 0.69048002 -2.13661998 0 P 0 ;0
L 0.60611004 -2.13561998 0.68981004 -2.13561998 0 P 0 ;0
L 0.60573996 -2.13461998 0.68918002 -2.13461998 0 P 0 ;0
L 0.60538002 -2.13361998 0.68863002 -2.13361998 0 P 0 ;0
L 0.60503996 -2.13261998 0.68808002 -2.13261998 0 P 0 ;0
L 0.60476004 -2.13161998 0.68753002 -2.13161998 0 P 0 ;0
L 0.60446998 -2.13061998 0.68698002 -2.13061998 0 P 0 ;0
L 0.60418002 -2.12961998 0.68643002 -2.12961998 0 P 0 ;0
L 0.6039 -2.12861998 0.68588002 -2.12861998 0 P 0 ;0
L 0.60361004 -2.12761998 0.68533002 -2.12761998 0 P 0 ;0
L 0.60331998 -2.12661998 0.68486004 -2.12661998 0 P 0 ;0
L 0.60303002 -2.12561998 0.68441998 -2.12561998 0 P 0 ;0
L 0.60275 -2.12461998 0.68396998 -2.12461998 0 P 0 ;0
L 0.60246004 -2.12361998 0.68353002 -2.12361998 0 P 0 ;0
L 0.60218002 -2.12261998 0.68308996 -2.12261998 0 P 0 ;0
L 0.60188996 -2.12161998 0.68263996 -2.12161998 0 P 0 ;0
L 0.60166998 -2.12061998 0.6822 -2.12061998 0 P 0 ;0
L 0.60145 -2.11961998 0.68176004 -2.11961998 0 P 0 ;0
L 0.60123002 -2.11861998 0.68138996 -2.11861998 0 P 0 ;0
L 0.60101004 -2.11761998 0.68105 -2.11761998 0 P 0 ;0
L 0.60078002 -2.11661998 0.68071004 -2.11661998 0 P 0 ;0
L 0.6006 -2.11561998 0.68036004 -2.11561998 0 P 0 ;0
L 0.60043002 -2.11461998 0.68001998 -2.11461998 0 P 0 ;0
L 0.60025 -2.11361998 0.67968002 -2.11361998 0 P 0 ;0
L 0.60008002 -2.11261998 0.67933002 -2.11261998 0 P 0 ;0
L 0.59991004 -2.11161998 0.67898996 -2.11161998 0 P 0 ;0
L 0.59976004 -2.11061998 0.6787 -2.11061998 0 P 0 ;0
L 0.59963996 -2.10961998 0.67845 -2.10961998 0 P 0 ;0
L 0.59951004 -2.10861998 0.6782 -2.10861998 0 P 0 ;0
L 0.59938002 -2.10761998 0.67795 -2.10761998 0 P 0 ;0
L 0.59925 -2.10661998 0.6777 -2.10661998 0 P 0 ;0
L 0.59913002 -2.10561998 0.67746004 -2.10561998 0 P 0 ;0
L 0.59905 -2.10461998 0.67721004 -2.10461998 0 P 0 ;0
L 0.59896998 -2.10361998 0.67696004 -2.10361998 0 P 0 ;0
L 0.59888002 -2.10261998 0.67671004 -2.10261998 0 P 0 ;0
L 0.5988 -2.10161998 0.67653996 -2.10161998 0 P 0 ;0
L 0.59871998 -2.10061998 0.67638002 -2.10061998 0 P 0 ;0
L 0.59866998 -2.09961998 0.67621004 -2.09961998 0 P 0 ;0
L 0.59863996 -2.09861998 0.67605 -2.09861998 0 P 0 ;0
L 0.59861004 -2.09761998 0.67588996 -2.09761998 0 P 0 ;0
L 0.59858996 -2.09661998 0.6758 -2.09661998 0 P 0 ;0
L 0.59856004 -2.09561998 0.67571004 -2.09561998 0 P 0 ;0
L 0.59853002 -2.09461998 0.67563002 -2.09461998 0 P 0 ;0
L 0.5985 -2.09361998 0.67553996 -2.09361998 0 P 0 ;0
L 0.59846998 -2.09261998 0.67546004 -2.09261998 0 P 0 ;0
L 0.59843996 -2.09161998 0.67546004 -2.09161998 0 P 0 ;0
L 0.59841998 -2.09061998 0.67545 -2.09061998 0 P 0 ;0
L 0.59838002 -2.08961998 0.67543996 -2.08961998 0 P 0 ;0
L 0.59836004 -2.08861998 0.67543002 -2.08861998 0 P 0 ;0
L 0.59833002 -2.08761998 0.67543002 -2.08761998 0 P 0 ;0
L 0.59835 -2.08661998 0.67541998 -2.08661998 0 P 0 ;0
L 0.59836998 -2.08561998 0.67541004 -2.08561998 0 P 0 ;0
L 0.5984 -2.08461998 0.67541004 -2.08461998 0 P 0 ;0
L 0.80005 -2.25161998 0.85543996 -2.25161998 0 P 0 ;0
L 0.78651998 -2.25061998 0.86596004 -2.25061998 0 P 0 ;0
L 0.77878996 -2.24961998 0.87636004 -2.24961998 0 P 0 ;0
L 0.77106004 -2.24861998 0.88285 -2.24861998 0 P 0 ;0
L 0.76398996 -2.24761998 0.88933996 -2.24761998 0 P 0 ;0
L 0.75891998 -2.24661998 0.89583996 -2.24661998 0 P 0 ;0
L 0.73781004 -1.8982 0.71738996 -1.90951998 0 P 0 ;0
L 0.71738996 -1.90951998 0.69766998 -1.92233996 0 P 0 ;0
L 0.69766998 -1.92233996 0.67971004 -1.93601998 0 P 0 ;0
L 0.67971004 -1.93601998 0.66278996 -1.95113002 0 P 0 ;0
L 0.66278996 -1.95113002 0.64786998 -1.96675 0 P 0 ;0
L 0.64786998 -1.96675 0.63423996 -1.98358996 0 P 0 ;0
L 0.63423996 -1.98358996 0.62643996 -1.99483002 0 P 0 ;0
L 0.62643996 -1.99483002 0.61933996 -2.00655 0 P 0 ;0
L 0.61933996 -2.00655 0.61298996 -2.01873996 0 P 0 ;0
L 0.61298996 -2.01873996 0.60503002 -2.03713002 0 P 0 ;0
L 0.60503002 -2.03713002 0.60225 -2.04506004 0 P 0 ;0
L 0.60225 -2.04506004 0.59998996 -2.05323002 0 P 0 ;0
L 0.59998996 -2.05323002 0.59833996 -2.0612 0 P 0 ;0
L 0.59833996 -2.0612 0.59725 -2.06928996 0 P 0 ;0
L 0.59725 -2.06928996 0.59656998 -2.07833996 0 P 0 ;0
L 0.59656998 -2.07833996 0.59633002 -2.0875 0 P 0 ;0
L 0.59633002 -2.0875 0.59668996 -2.10036998 0 P 0 ;0
L 0.59668996 -2.10036998 0.59715 -2.10596004 0 P 0 ;0
L 0.59715 -2.10596004 0.59786004 -2.11151004 0 P 0 ;0
L 0.59786004 -2.11151004 0.59878996 -2.11686998 0 P 0 ;0
L 0.59878996 -2.11686998 0.59996998 -2.1222 0 P 0 ;0
L 0.59996998 -2.1222 0.60326998 -2.13368996 0 P 0 ;0
L 0.60326998 -2.13368996 0.60656998 -2.1427 0 P 0 ;0
L 0.60656998 -2.1427 0.6105 -2.15143996 0 P 0 ;0
L 0.6105 -2.15143996 0.61505 -2.15988002 0 P 0 ;0
L 0.61505 -2.15988002 0.62023996 -2.16803996 0 P 0 ;0
L 0.62023996 -2.16803996 0.62828996 -2.17873002 0 P 0 ;0
L 0.62828996 -2.17873002 0.63718996 -2.18871004 0 P 0 ;0
L 0.63718996 -2.18871004 0.64693002 -2.19795 0 P 0 ;0
L 0.64693002 -2.19795 0.6582 -2.20701998 0 P 0 ;0
L 0.6582 -2.20701998 0.67011004 -2.21518996 0 P 0 ;0
L 0.67011004 -2.21518996 0.68261004 -2.22243002 0 P 0 ;0
L 0.68261004 -2.22243002 0.69673996 -2.22936004 0 P 0 ;0
L 0.69673996 -2.22936004 0.71123002 -2.23543996 0 P 0 ;0
L 0.71123002 -2.23543996 0.72611998 -2.24066998 0 P 0 ;0
L 0.72611998 -2.24066998 0.74536004 -2.24598996 0 P 0 ;0
L 0.74536004 -2.24598996 0.76493002 -2.24985 0 P 0 ;0
L 0.76493002 -2.24985 0.78671998 -2.25266998 0 P 0 ;0
L 0.78671998 -2.25266998 0.80863002 -2.25425 0 P 0 ;0
L 0.80863002 -2.25425 0.83146004 -2.25463002 0 P 0 ;0
L 0.83146004 -2.25463002 0.85418002 -2.25375 0 P 0 ;0
L 0.85418002 -2.25375 0.87641004 -2.25163996 0 P 0 ;0
L 0.87641004 -2.25163996 0.89853002 -2.24823002 0 P 0 ;0
L 0.89853002 -2.24823002 0.93045 -2.24101998 0 P 0 ;0
L 0.93045 -2.24101998 0.96466004 -2.23063002 0 P 0 ;0
L 0.96466004 -2.23063002 0.99911004 -2.2178 0 P 0 ;0
L 0.99911004 -2.2178 1.03183002 -2.20318002 0 P 0 ;0
L 1.03183002 -2.20318002 1.04391998 -2.19703002 0 P 0 ;0
L 1.04391998 -2.19703002 1.05581004 -2.19048996 0 P 0 ;0
L 1.05581004 -2.19048996 1.06676004 -2.18411998 0 P 0 ;0
L 1.06676004 -2.18411998 1.06681004 -2.18408996 0 P 0 ;0
L 1.06681004 -2.18408996 1.06685 -2.18405 0 P 0 ;0
L 1.06685 -2.18405 1.0669 -2.18401004 0 P 0 ;0
L 1.0669 -2.18401004 1.06693996 -2.18396998 0 P 0 ;0
L 1.06693996 -2.18396998 1.06696998 -2.18391998 0 P 0 ;0
L 1.06696998 -2.18391998 1.06701004 -2.18386998 0 P 0 ;0
L 1.06701004 -2.18386998 1.06703002 -2.18381998 0 P 0 ;0
L 1.06703002 -2.18381998 1.06706004 -2.18376004 0 P 0 ;0
L 1.06706004 -2.18376004 1.06706998 -2.18371004 0 P 0 ;0
L 1.06706998 -2.18371004 1.06708996 -2.18365 0 P 0 ;0
L 1.06708996 -2.18365 1.06708996 -2.18358996 0 P 0 ;0
L 1.06708996 -2.18358996 1.0671 -2.18353002 0 P 0 ;0
L 1.0671 -2.18353002 1.0671 -2.18346998 0 P 0 ;0
L 1.0671 -2.18346998 1.06708996 -2.18341004 0 P 0 ;0
L 1.06708996 -2.18341004 1.06706998 -2.18336004 0 P 0 ;0
L 1.06706998 -2.18336004 1.06706004 -2.1833 0 P 0 ;0
L 1.06706004 -2.1833 1.06703002 -2.18323996 0 P 0 ;0
L 1.06703002 -2.18323996 1.06701004 -2.18318996 0 P 0 ;0
L 1.06701004 -2.18318996 1.06696998 -2.18313996 0 P 0 ;0
L 1.06696998 -2.18313996 1.06693996 -2.18308996 0 P 0 ;0
L 1.06693996 -2.18308996 1.06688002 -2.18303002 0 P 0 ;0
L 1.06688002 -2.18303002 1.06678996 -2.18296998 0 P 0 ;0
L 1.06678996 -2.18296998 1.06673002 -2.18295 0 P 0 ;0
L 1.06673002 -2.18295 1.0667 -2.18295 0 P 0 ;0
L 1.0667 -2.18295 1.06666004 -2.18293996 0 P 0 ;0
L 1.06666004 -2.18293996 1.0666 -2.18293996 0 P 0 ;0
L 1.0666 -2.18293996 1.06656998 -2.18295 0 P 0 ;0
L 1.06656998 -2.18295 1.06653002 -2.18295 0 P 0 ;0
L 1.06653002 -2.18295 1.06153002 -2.1842 0 P 0 ;0
L 1.06153002 -2.1842 1.05583996 -2.18566998 0 P 0 ;0
L 1.05583996 -2.18566998 1.04916998 -2.1875 0 P 0 ;0
L 1.04916998 -2.1875 1.0153 -2.1962 0 P 0 ;0
L 1.0153 -2.1962 0.9814 -2.20333996 0 P 0 ;0
L 0.9814 -2.20333996 0.94881998 -2.2087 0 P 0 ;0
L 0.94881998 -2.2087 0.9189 -2.21198996 0 P 0 ;0
L 0.9189 -2.21198996 0.90113996 -2.21278996 0 P 0 ;0
L 0.90113996 -2.21278996 0.87738002 -2.21265 0 P 0 ;0
L 0.87738002 -2.21265 0.854 -2.21183002 0 P 0 ;0
L 0.854 -2.21183002 0.83788996 -2.21033996 0 P 0 ;0
L 0.83788996 -2.21033996 0.8174 -2.20693002 0 P 0 ;0
L 0.8174 -2.20693002 0.79708996 -2.2023 0 P 0 ;0
L 0.79708996 -2.2023 0.7769 -2.19641004 0 P 0 ;0
L 0.7769 -2.19641004 0.76433002 -2.19183996 0 P 0 ;0
L 0.76433002 -2.19183996 0.75208996 -2.18638002 0 P 0 ;0
L 0.75208996 -2.18638002 0.74026998 -2.18006998 0 P 0 ;0
L 0.74026998 -2.18006998 0.72886998 -2.17291004 0 P 0 ;0
L 0.72886998 -2.17291004 0.71961998 -2.16603002 0 P 0 ;0
L 0.71961998 -2.16603002 0.71098996 -2.15838996 0 P 0 ;0
L 0.71098996 -2.15838996 0.70303002 -2.15003002 0 P 0 ;0
L 0.70303002 -2.15003002 0.6958 -2.14098996 0 P 0 ;0
L 0.6958 -2.14098996 0.69106998 -2.1339 0 P 0 ;0
L 0.69106998 -2.1339 0.68696004 -2.12643002 0 P 0 ;0
L 0.68696004 -2.12643002 0.68351004 -2.11863002 0 P 0 ;0
L 0.68351004 -2.11863002 0.68073996 -2.11056004 0 P 0 ;0
L 0.68073996 -2.11056004 0.67866004 -2.10218996 0 P 0 ;0
L 0.67866004 -2.10218996 0.67788002 -2.09741998 0 P 0 ;0
L 0.67788002 -2.09741998 0.67746004 -2.0926 0 P 0 ;0
L 0.67746004 -2.0926 0.67738002 -2.08076004 0 P 0 ;0
L 0.67738002 -2.08076004 0.67828002 -2.06891004 0 P 0 ;0
L 0.67828002 -2.06891004 0.67903002 -2.06403996 0 P 0 ;0
L 0.67903002 -2.06403996 0.68013002 -2.05923996 0 P 0 ;0
L 0.68013002 -2.05923996 0.68288002 -2.05021998 0 P 0 ;0
L 0.68288002 -2.05021998 0.68623996 -2.04141004 0 P 0 ;0
L 0.68623996 -2.04141004 0.69018002 -2.03286004 0 P 0 ;0
L 0.69018002 -2.03286004 0.69486004 -2.02418002 0 P 0 ;0
L 0.69486004 -2.02418002 0.70003996 -2.0158 0 P 0 ;0
L 0.70003996 -2.0158 0.70573002 -2.00768996 0 P 0 ;0
L 0.70573002 -2.00768996 0.7158 -1.99531998 0 P 0 ;0
L 0.7158 -1.99531998 0.72681004 -1.98385 0 P 0 ;0
L 0.72681004 -1.98385 0.73971004 -1.9722 0 P 0 ;0
L 0.73971004 -1.9722 0.7533 -1.9614 0 P 0 ;0
L 0.7533 -1.9614 0.75753996 -1.95828002 0 P 0 ;0
L 0.75753996 -1.95828002 0.76138002 -1.95548002 0 P 0 ;0
L 0.76138002 -1.95548002 0.76463002 -1.95316004 0 P 0 ;0
L 0.76463002 -1.95316004 0.76516004 -1.95281004 0 P 0 ;0
L 0.76516004 -1.95281004 0.7657 -1.95248996 0 P 0 ;0
L 0.7657 -1.95248996 0.76578002 -1.95243996 0 P 0 ;0
L 0.76578002 -1.95243996 0.76586004 -1.95238002 0 P 0 ;0
L 0.76586004 -1.95238002 0.76593002 -1.95231998 0 P 0 ;0
L 0.76593002 -1.95231998 0.766 -1.95223996 0 P 0 ;0
L 0.766 -1.95223996 0.76606004 -1.95216998 0 P 0 ;0
L 0.76606004 -1.95216998 0.76616004 -1.95201004 0 P 0 ;0
L 0.76616004 -1.95201004 0.7662 -1.95191998 0 P 0 ;0
L 0.7662 -1.95191998 0.76626004 -1.95173996 0 P 0 ;0
L 0.76626004 -1.95173996 0.76628002 -1.95163996 0 P 0 ;0
L 0.76628002 -1.95163996 0.7663 -1.95143002 0 P 0 ;0
L 0.7663 -1.95143002 0.7663 -1.95121004 0 P 0 ;0
L 0.7663 -1.95121004 0.76628996 -1.951 0 P 0 ;0
L 0.76628996 -1.951 0.76625 -1.95078996 0 P 0 ;0
L 0.76625 -1.95078996 0.7662 -1.95058002 0 P 0 ;0
L 0.7662 -1.95058002 0.76613002 -1.95036998 0 P 0 ;0
L 0.76613002 -1.95036998 0.76583002 -1.94966998 0 P 0 ;0
L 0.76583002 -1.94966998 0.76548996 -1.94896998 0 P 0 ;0
L 0.76548996 -1.94896998 0.76508996 -1.9483 0 P 0 ;0
L 0.76508996 -1.9483 0.76253002 -1.94436004 0 P 0 ;0
L 0.76253002 -1.94436004 0.76056998 -1.94126998 0 P 0 ;0
L 0.76056998 -1.94126998 0.75871998 -1.93806004 0 P 0 ;0
L 0.75871998 -1.93806004 0.75716998 -1.93496998 0 P 0 ;0
L 0.75716998 -1.93496998 0.7558 -1.93178002 0 P 0 ;0
L 0.7558 -1.93178002 0.7546 -1.92853996 0 P 0 ;0
L 0.7546 -1.92853996 0.75358996 -1.92521004 0 P 0 ;0
L 0.75358996 -1.92521004 0.7527 -1.92161998 0 P 0 ;0
L 0.7527 -1.92161998 0.75196998 -1.91796004 0 P 0 ;0
L 0.75196998 -1.91796004 0.75155 -1.91496004 0 P 0 ;0
L 0.75155 -1.91496004 0.75133002 -1.91193002 0 P 0 ;0
L 0.75133002 -1.91193002 0.75126998 -1.9085 0 P 0 ;0
L 0.75126998 -1.9085 0.75136004 -1.90506004 0 P 0 ;0
L 0.75136004 -1.90506004 0.75161004 -1.90181998 0 P 0 ;0
L 0.75161004 -1.90181998 0.752 -1.8986 0 P 0 ;0
L 0.752 -1.8986 0.75228996 -1.89701998 0 P 0 ;0
L 0.75228996 -1.89701998 0.75268996 -1.89546998 0 P 0 ;0
L 0.75268996 -1.89546998 0.7532 -1.89395 0 P 0 ;0
L 0.7532 -1.89395 0.75358996 -1.89281998 0 P 0 ;0
L 0.75358996 -1.89281998 0.75373002 -1.89231998 0 P 0 ;0
L 0.75373002 -1.89231998 0.75383996 -1.8918 0 P 0 ;0
L 0.75383996 -1.8918 0.75391998 -1.89138996 0 P 0 ;0
L 0.75391998 -1.89138996 0.75396998 -1.89098996 0 P 0 ;0
L 0.75396998 -1.89098996 0.75396998 -1.89086004 0 P 0 ;0
L 0.75396998 -1.89086004 0.75393996 -1.89076998 0 P 0 ;0
L 0.75393996 -1.89076998 0.7539 -1.89071004 0 P 0 ;0
L 0.7539 -1.89071004 0.75386004 -1.89066998 0 P 0 ;0
L 0.75386004 -1.89066998 0.75381004 -1.89063002 0 P 0 ;0
L 0.75381004 -1.89063002 0.75378996 -1.89061004 0 P 0 ;0
L 0.75378996 -1.89061004 0.75373002 -1.89058996 0 P 0 ;0
L 0.75373002 -1.89058996 0.75368002 -1.89056998 0 P 0 ;0
L 0.75368002 -1.89056998 0.75356004 -1.89056998 0 P 0 ;0
L 0.75356004 -1.89056998 0.75346998 -1.8906 0 P 0 ;0
L 0.75346998 -1.8906 0.74898002 -1.8927 0 P 0 ;0
L 0.74898002 -1.8927 0.74383002 -1.89518002 0 P 0 ;0
L 0.74383002 -1.89518002 0.73781004 -1.8982 0 P 0 ;0
L 0.69776998 -2.22761998 0.96701004 -2.22761998 0 P 0 ;0
L 0.6957 -2.22661998 0.96968996 -2.22661998 0 P 0 ;0
L 0.69366998 -2.22561998 0.97238002 -2.22561998 0 P 0 ;0
L 0.69163002 -2.22461998 0.97506004 -2.22461998 0 P 0 ;0
L 0.68958996 -2.22361998 0.97775 -2.22361998 0 P 0 ;0
L 0.68756004 -2.22261998 0.98043002 -2.22261998 0 P 0 ;0
L 0.68551998 -2.22161998 0.98311004 -2.22161998 0 P 0 ;0
L 0.68348996 -2.22061998 0.9858 -2.22061998 0 P 0 ;0
L 0.68176998 -2.21961998 0.98848002 -2.21961998 0 P 0 ;0
L 0.68003996 -2.21861998 0.99116998 -2.21861998 0 P 0 ;0
L 0.67831004 -2.21761998 0.99385 -2.21761998 0 P 0 ;0
L 0.67658002 -2.21661998 0.99653996 -2.21661998 0 P 0 ;0
L 0.67485 -2.21561998 0.99908002 -2.21561998 0 P 0 ;0
L 0.67311998 -2.21461998 0.87665 -2.21461998 0 P 0 ;0
L 0.6714 -2.21361998 0.85166004 -2.21361998 0 P 0 ;0
L 0.6699 -2.21261998 0.84083002 -2.21261998 0 P 0 ;0
L 0.66845 -2.21161998 0.8334 -2.21161998 0 P 0 ;0
L 0.66698996 -2.21061998 0.8274 -2.21061998 0 P 0 ;0
L 0.66553002 -2.20961998 0.82138996 -2.20961998 0 P 0 ;0
L 0.66406998 -2.20861998 0.81583002 -2.20861998 0 P 0 ;0
L 0.66261998 -2.20761998 0.81143996 -2.20761998 0 P 0 ;0
L 0.66116004 -2.20661998 0.80706004 -2.20661998 0 P 0 ;0
L 0.6597 -2.20561998 0.80266998 -2.20561998 0 P 0 ;0
L 0.65841004 -2.20461998 0.79828996 -2.20461998 0 P 0 ;0
L 0.65716998 -2.20361998 0.79448996 -2.20361998 0 P 0 ;0
L 0.65593002 -2.20261998 0.79106004 -2.20261998 0 P 0 ;0
L 0.65468996 -2.20161998 0.78763996 -2.20161998 0 P 0 ;0
L 0.83143002 -2.25261998 0.80871998 -2.25225 0 P 0 ;0
L 0.80871998 -2.25225 0.78691998 -2.25066998 0 P 0 ;0
L 0.78691998 -2.25066998 0.76525 -2.24786998 0 P 0 ;0
L 0.76525 -2.24786998 0.74581998 -2.24403996 0 P 0 ;0
L 0.74581998 -2.24403996 0.72671004 -2.23876004 0 P 0 ;0
L 0.72671004 -2.23876004 0.71196004 -2.23356998 0 P 0 ;0
L 0.71196004 -2.23356998 0.69756998 -2.22753996 0 P 0 ;0
L 0.69756998 -2.22753996 0.68355 -2.22066004 0 P 0 ;0
L 0.68355 -2.22066004 0.67118002 -2.2135 0 P 0 ;0
L 0.67118002 -2.2135 0.65938996 -2.20541004 0 P 0 ;0
L 0.65938996 -2.20541004 0.64825 -2.19643996 0 P 0 ;0
L 0.64825 -2.19643996 0.63861998 -2.18731998 0 P 0 ;0
L 0.63861998 -2.18731998 0.62983002 -2.17746998 0 P 0 ;0
L 0.62983002 -2.17746998 0.62188996 -2.1669 0 P 0 ;0
L 0.62188996 -2.1669 0.61678002 -2.15886998 0 P 0 ;0
L 0.61678002 -2.15886998 0.6123 -2.15056004 0 P 0 ;0
L 0.6123 -2.15056004 0.60841998 -2.14193996 0 P 0 ;0
L 0.60841998 -2.14193996 0.60516998 -2.13306998 0 P 0 ;0
L 0.60516998 -2.13306998 0.60191004 -2.12171004 0 P 0 ;0
L 0.60191004 -2.12171004 0.60075 -2.11648002 0 P 0 ;0
L 0.60075 -2.11648002 0.59983996 -2.11121004 0 P 0 ;0
L 0.59983996 -2.11121004 0.59913996 -2.10576004 0 P 0 ;0
L 0.59913996 -2.10576004 0.59868996 -2.10026004 0 P 0 ;0
L 0.59868996 -2.10026004 0.59833002 -2.0875 0 P 0 ;0
L 0.59833002 -2.0875 0.59856998 -2.07843996 0 P 0 ;0
L 0.59856998 -2.07843996 0.59923996 -2.0695 0 P 0 ;0
L 0.59923996 -2.0695 0.60031998 -2.06153996 0 P 0 ;0
L 0.60031998 -2.06153996 0.60193002 -2.05368996 0 P 0 ;0
L 0.60193002 -2.05368996 0.60416004 -2.04566004 0 P 0 ;0
L 0.60416004 -2.04566004 0.60688996 -2.03786004 0 P 0 ;0
L 0.60688996 -2.03786004 0.6148 -2.01961004 0 P 0 ;0
L 0.6148 -2.01961004 0.62108996 -2.00753002 0 P 0 ;0
L 0.62108996 -2.00753002 0.62811998 -1.99591998 0 P 0 ;0
L 0.62811998 -1.99591998 0.63583996 -1.98478996 0 P 0 ;0
L 0.63583996 -1.98478996 0.64936998 -1.96808002 0 P 0 ;0
L 0.64936998 -1.96808002 0.66418002 -1.95256998 0 P 0 ;0
L 0.66418002 -1.95256998 0.68098002 -1.93756004 0 P 0 ;0
L 0.68098002 -1.93756004 0.69881998 -1.92398002 0 P 0 ;0
L 0.69881998 -1.92398002 0.71841998 -1.91123996 0 P 0 ;0
L 0.71841998 -1.91123996 0.73875 -1.89996998 0 P 0 ;0
L 0.73875 -1.89996998 0.74471004 -1.89696998 0 P 0 ;0
L 0.74471004 -1.89696998 0.74983002 -1.89451004 0 P 0 ;0
L 0.74983002 -1.89451004 0.7511 -1.89391004 0 P 0 ;0
L 0.7511 -1.89391004 0.75076998 -1.89488996 0 P 0 ;0
L 0.75076998 -1.89488996 0.75033996 -1.89658996 0 P 0 ;0
L 0.75033996 -1.89658996 0.75003002 -1.8983 0 P 0 ;0
L 0.75003002 -1.8983 0.74961998 -1.90161998 0 P 0 ;0
L 0.74961998 -1.90161998 0.74936004 -1.90496004 0 P 0 ;0
L 0.74936004 -1.90496004 0.74926998 -1.9085 0 P 0 ;0
L 0.74926998 -1.9085 0.74933002 -1.91201998 0 P 0 ;0
L 0.74933002 -1.91201998 0.74956004 -1.91516998 0 P 0 ;0
L 0.74956004 -1.91516998 0.75 -1.91828996 0 P 0 ;0
L 0.75 -1.91828996 0.75075 -1.92205 0 P 0 ;0
L 0.75075 -1.92205 0.75166004 -1.92573996 0 P 0 ;0
L 0.75166004 -1.92573996 0.7527 -1.92916998 0 P 0 ;0
L 0.7527 -1.92916998 0.75393996 -1.93253002 0 P 0 ;0
L 0.75393996 -1.93253002 0.75536004 -1.93581998 0 P 0 ;0
L 0.75536004 -1.93581998 0.75696004 -1.939 0 P 0 ;0
L 0.75696004 -1.939 0.75885 -1.94231004 0 P 0 ;0
L 0.75885 -1.94231004 0.76083996 -1.94543996 0 P 0 ;0
L 0.76083996 -1.94543996 0.76338996 -1.94933996 0 P 0 ;0
L 0.76338996 -1.94933996 0.76371998 -1.94991998 0 P 0 ;0
L 0.76371998 -1.94991998 0.76401004 -1.9505 0 P 0 ;0
L 0.76401004 -1.9505 0.76423996 -1.95103002 0 P 0 ;0
L 0.76423996 -1.95103002 0.76408996 -1.95111004 0 P 0 ;0
L 0.76408996 -1.95111004 0.76348996 -1.95151004 0 P 0 ;0
L 0.76348996 -1.95151004 0.76021004 -1.95386004 0 P 0 ;0
L 0.76021004 -1.95386004 0.7602 -1.95386998 0 P 0 ;0
L 0.7602 -1.95386998 0.75636998 -1.95666004 0 P 0 ;0
L 0.75636998 -1.95666004 0.75636004 -1.95666998 0 P 0 ;0
L 0.75636004 -1.95666998 0.75635 -1.95666998 0 P 0 ;0
L 0.75635 -1.95666998 0.75208996 -1.95981004 0 P 0 ;0
L 0.75208996 -1.95981004 0.73841004 -1.97066998 0 P 0 ;0
L 0.73841004 -1.97066998 0.72541004 -1.98241004 0 P 0 ;0
L 0.72541004 -1.98241004 0.7143 -1.994 0 P 0 ;0
L 0.7143 -1.994 0.71425 -1.99406004 0 P 0 ;0
L 0.71425 -1.99406004 0.70413996 -2.00648002 0 P 0 ;0
L 0.70413996 -2.00648002 0.69836998 -2.01468996 0 P 0 ;0
L 0.69836998 -2.01468996 0.69313002 -2.02318002 0 P 0 ;0
L 0.69313002 -2.02318002 0.68838996 -2.03196004 0 P 0 ;0
L 0.68838996 -2.03196004 0.68438996 -2.04063996 0 P 0 ;0
L 0.68438996 -2.04063996 0.68098996 -2.04958002 0 P 0 ;0
L 0.68098996 -2.04958002 0.6782 -2.05873002 0 P 0 ;0
L 0.6782 -2.05873002 0.67706004 -2.06366004 0 P 0 ;0
L 0.67706004 -2.06366004 0.67628996 -2.06866998 0 P 0 ;0
L 0.67628996 -2.06866998 0.67538002 -2.08068996 0 P 0 ;0
L 0.67538002 -2.08068996 0.67546004 -2.09268996 0 P 0 ;0
L 0.67546004 -2.09268996 0.67588996 -2.09766998 0 P 0 ;0
L 0.67588996 -2.09766998 0.6767 -2.10258996 0 P 0 ;0
L 0.6767 -2.10258996 0.67881998 -2.11111998 0 P 0 ;0
L 0.67881998 -2.11111998 0.68163996 -2.11936004 0 P 0 ;0
L 0.68163996 -2.11936004 0.68516004 -2.12731998 0 P 0 ;0
L 0.68516004 -2.12731998 0.68935 -2.13493996 0 P 0 ;0
L 0.68935 -2.13493996 0.69418002 -2.14216998 0 P 0 ;0
L 0.69418002 -2.14216998 0.70153002 -2.15135 0 P 0 ;0
L 0.70153002 -2.15135 0.7096 -2.15983002 0 P 0 ;0
L 0.7096 -2.15983002 0.71836004 -2.16758996 0 P 0 ;0
L 0.71836004 -2.16758996 0.71843002 -2.16763996 0 P 0 ;0
L 0.71843002 -2.16763996 0.72773996 -2.17456004 0 P 0 ;0
L 0.72773996 -2.17456004 0.73926998 -2.1818 0 P 0 ;0
L 0.73926998 -2.1818 0.75121004 -2.18818002 0 P 0 ;0
L 0.75121004 -2.18818002 0.75128002 -2.18821004 0 P 0 ;0
L 0.75128002 -2.18821004 0.76358002 -2.19368996 0 P 0 ;0
L 0.76358002 -2.19368996 0.77628002 -2.19831004 0 P 0 ;0
L 0.77628002 -2.19831004 0.79658996 -2.20423996 0 P 0 ;0
L 0.79658996 -2.20423996 0.81701004 -2.20888996 0 P 0 ;0
L 0.81701004 -2.20888996 0.83763996 -2.21233002 0 P 0 ;0
L 0.83763996 -2.21233002 0.85388002 -2.21383002 0 P 0 ;0
L 0.85388002 -2.21383002 0.87733996 -2.21465 0 P 0 ;0
L 0.87733996 -2.21465 0.90118002 -2.21478996 0 P 0 ;0
L 0.90118002 -2.21478996 0.91906004 -2.21398996 0 P 0 ;0
L 0.91906004 -2.21398996 0.94908996 -2.21068002 0 P 0 ;0
L 0.94908996 -2.21068002 0.98176998 -2.2053 0 P 0 ;0
L 0.98176998 -2.2053 1.01575 -2.19815 0 P 0 ;0
L 1.01575 -2.19815 1.04968002 -2.18943002 0 P 0 ;0
L 1.04968002 -2.18943002 1.05633996 -2.18761004 0 P 0 ;0
L 1.05633996 -2.18761004 1.05713996 -2.1874 0 P 0 ;0
L 1.05713996 -2.1874 1.05483002 -2.18875 0 P 0 ;0
L 1.05483002 -2.18875 1.04298996 -2.19526004 0 P 0 ;0
L 1.04298996 -2.19526004 1.03096998 -2.20136998 0 P 0 ;0
L 1.03096998 -2.20136998 0.99835 -2.21595 0 P 0 ;0
L 0.99835 -2.21595 0.96401998 -2.22873996 0 P 0 ;0
L 0.96401998 -2.22873996 0.92993996 -2.23908002 0 P 0 ;0
L 0.92993996 -2.23908002 0.89816004 -2.24626004 0 P 0 ;0
L 0.89816004 -2.24626004 0.87616004 -2.24965 0 P 0 ;0
L 0.87616004 -2.24965 0.85405 -2.25176004 0 P 0 ;0
L 0.85405 -2.25176004 0.83143002 -2.25261998 0 P 0 ;0
L 0.65345 -2.20061998 0.78421004 -2.20061998 0 P 0 ;0
L 0.65221004 -2.19961998 0.78078002 -2.19961998 0 P 0 ;0
L 0.65096004 -2.19861998 0.77735 -2.19861998 0 P 0 ;0
L 0.64971998 -2.19761998 0.77438996 -2.19761998 0 P 0 ;0
L 0.64848002 -2.19661998 0.77163996 -2.19661998 0 P 0 ;0
L 0.64738996 -2.19561998 0.76888996 -2.19561998 0 P 0 ;0
L 0.64633996 -2.19461998 0.76613996 -2.19461998 0 P 0 ;0
L 0.64528002 -2.19361998 0.76343002 -2.19361998 0 P 0 ;0
L 0.64421998 -2.19261998 0.76118996 -2.19261998 0 P 0 ;0
L 0.64316998 -2.19161998 0.75893996 -2.19161998 0 P 0 ;0
L 0.64211004 -2.19061998 0.7567 -2.19061998 0 P 0 ;0
L 0.64106004 -2.18961998 0.75446004 -2.18961998 0 P 0 ;0
L 0.64 -2.18861998 0.75221004 -2.18861998 0 P 0 ;0
L 0.63895 -2.18761998 0.75018002 -2.18761998 0 P 0 ;0
L 0.63801004 -2.18661998 0.74831004 -2.18661998 0 P 0 ;0
L 0.63711004 -2.18561998 0.74643002 -2.18561998 0 P 0 ;0
L 0.63621998 -2.18461998 0.74456004 -2.18461998 0 P 0 ;0
L 0.63533002 -2.18361998 0.74268002 -2.18361998 0 P 0 ;0
L 0.63443996 -2.18261998 0.74081004 -2.18261998 0 P 0 ;0
L 0.63353996 -2.18161998 0.73898996 -2.18161998 0 P 0 ;0
L 0.63265 -2.18061998 0.73738996 -2.18061998 0 P 0 ;0
L 0.63176004 -2.17961998 0.7358 -2.17961998 0 P 0 ;0
L 0.63086998 -2.17861998 0.73421004 -2.17861998 0 P 0 ;0
L 0.62996998 -2.17761998 0.73261998 -2.17761998 0 P 0 ;0
L 0.6292 -2.17661998 0.73103002 -2.17661998 0 P 0 ;0
L 0.62845 -2.17561998 0.72943996 -2.17561998 0 P 0 ;0
L 0.6277 -2.17461998 0.72783996 -2.17461998 0 P 0 ;0
L 0.62693996 -2.17361998 0.72648002 -2.17361998 0 P 0 ;0
L 0.62618996 -2.17261998 0.72513996 -2.17261998 0 P 0 ;0
L 0.62543996 -2.17161998 0.72378996 -2.17161998 0 P 0 ;0
L 0.62468996 -2.17061998 0.72245 -2.17061998 0 P 0 ;0
L 0.62393996 -2.16961998 0.7211 -2.16961998 0 P 0 ;0
L 0.62318002 -2.16861998 0.71976004 -2.16861998 0 P 0 ;0
L 0.62243996 -2.16761998 0.71841004 -2.16761998 0 P 0 ;0
L 0.62171004 -2.16661998 0.71726998 -2.16661998 0 P 0 ;0
L 0.62108002 -2.16561998 0.71613996 -2.16561998 0 P 0 ;0
L 0.62043996 -2.16461998 0.71501004 -2.16461998 0 P 0 ;0
L 0.61981004 -2.16361998 0.71388002 -2.16361998 0 P 0 ;0
L 0.61916998 -2.16261998 0.71276004 -2.16261998 0 P 0 ;0
L 0.61853002 -2.16161998 0.71163002 -2.16161998 0 P 0 ;0
L 0.6179 -2.16061998 0.7105 -2.16061998 0 P 0 ;0
L 0.61726004 -2.15961998 0.7094 -2.15961998 0 P 0 ;0
L 0.61665 -2.15861998 0.70845 -2.15861998 0 P 0 ;0
L 0.61611004 -2.15761998 0.7075 -2.15761998 0 P 0 ;0
L 0.75383996 -2.24561998 0.901 -2.24561998 0 P 0 ;0
L 0.74876998 -2.24461998 0.90541998 -2.24461998 0 P 0 ;0
L 0.74431004 -2.24361998 0.90985 -2.24361998 0 P 0 ;0
L 0.7407 -2.24261998 0.91426998 -2.24261998 0 P 0 ;0
L 0.73708002 -2.24161998 0.9187 -2.24161998 0 P 0 ;0
L 0.73346998 -2.24061998 0.92311998 -2.24061998 0 P 0 ;0
L 0.72986004 -2.23961998 0.92753996 -2.23961998 0 P 0 ;0
L 0.72633996 -2.23861998 0.93145 -2.23861998 0 P 0 ;0
L 0.72348996 -2.23761998 0.93473996 -2.23761998 0 P 0 ;0
L 0.72063996 -2.23661998 0.93803996 -2.23661998 0 P 0 ;0
L 0.7178 -2.23561998 0.94133002 -2.23561998 0 P 0 ;0
L 0.71495 -2.23461998 0.94461998 -2.23461998 0 P 0 ;0
L 0.7121 -2.23361998 0.94791998 -2.23361998 0 P 0 ;0
L 0.70968996 -2.23261998 0.95121004 -2.23261998 0 P 0 ;0
L 0.70731004 -2.23161998 0.95451004 -2.23161998 0 P 0 ;0
L 0.70491998 -2.23061998 0.9578 -2.23061998 0 P 0 ;0
L 0.70253996 -2.22961998 0.9611 -2.22961998 0 P 0 ;0
L 0.70015 -2.22861998 0.96431998 -2.22861998 0 P 0 ;0
P 7.17716998 5.7874 25 P 0 0;4=42
P 7.17716998 0.23621998 25 P 0 0;4=42
P 0.22245 0.68898002 24 P 0 0;4=43
P 0.22245 5.11811004 24 P 0 0;4=43
P 12.68701998 5.15748002 24 P 0 0;4=43
P 12.68701998 0.72835 24 P 0 0;4=43
P 6.11811004 1.52756004 24 P 0 0;4=43
P 6.11811004 4.20473002 24 P 0 0;4=43
P 4.83268002 4.22441004 24 P 0 0;4=43
P 2.24606004 4.22441004 24 P 0 0;4=43
P 0.96063002 4.20473002 24 P 0 0;4=43
P 0.96063002 1.52756004 24 P 0 0;4=43
P 2.24606004 1.50786998 24 P 0 0;4=43
P 4.83268002 1.50786998 24 P 0 0;4=43
P 6.04921004 2.58268002 23 P 0 0;4=44
P 1.05905 2.58268002 33 P 0 0;4=45
P 12.12205 1.52756004 24 P 0 0;4=43
P 12.12205 4.20473002 24 P 0 0;4=43
P 10.83661998 4.22441004 24 P 0 0;4=43
P 8.25 4.22441004 24 P 0 0;4=43
P 6.96456998 4.20473002 24 P 0 0;4=43
P 6.96456998 1.52756004 24 P 0 0;4=43
P 8.25 1.50786998 24 P 0 0;4=43
P 10.83661998 1.50786998 24 P 0 0;4=43
P 12.05315 2.58268002 23 P 0 0;4=44
P 7.06298996 2.58268002 33 P 0 0;4=45
P 12.33465 5.69528002 20 P 0 0;4=46
P 3.58311004 4.91851004 16 P 0 0;4=47
P 2.72091004 4.91851004 16 P 0 0;4=47
P 9.58665 4.91851004 16 P 0 0;4=47
P 8.72445 4.91851004 16 P 0 0;4=47
P 2.41851004 4.91851004 16 P 0 0;4=47
P 1.55631004 4.91851004 16 P 0 0;4=47
P 8.42205 4.91851004 16 P 0 0;4=47
P 7.55985 4.91851004 16 P 0 0;4=47
P 0.22243996 1.79331004 18 P 0 0;4=48
P 0.22243996 4.67323002 18 P 0 0;4=48
P 12.687 1.83268002 18 P 0 0;4=48
P 12.687 4.7126 18 P 0 0;4=48
P 0.7687 5.62008002 12 P 0 0;4=49
P 1.47736004 5.62008002 12 P 0 0;4=49
L 0.73681004 -0.44173002 0.74861998 -0.44173002 1 P 0 
A 0.74861998 -0.44173002 0.75650394 -0.41810512 0.7565 -0.43123179 1 P 0 Y
A 0.75650394 -0.41810512 0.76436998 -0.44173002 0.7565 -0.43122844 1 P 0 Y
L 0.76436998 -0.44173002 0.77618002 -0.44173002 1 P 0 
L 0.68501998 -0.44173002 0.68501998 -0.41673002 2 P 0 ;0,5=50,7=0.000000
L 0.68501998 -0.41673002 0.67515295 -0.43464675 2 P 0 ;0,5=50,7=0.000000
L 0.67515295 -0.43464675 0.68848691 -0.43464675 2 P 0 ;0,5=50,7=0.000000
L 0.69995325 -0.43798091 0.70155295 -0.44006378 2 P 0 ;0,5=50,7=0.000000
L 0.70155295 -0.44006378 0.70341969 -0.44131348 2 P 0 ;0,5=50,7=0.000000
L 0.70341969 -0.44131348 0.70581969 -0.44173002 2 P 0 ;0,5=50,7=0.000000
L 0.70581969 -0.44173002 0.70822018 -0.44089695 2 P 0 ;0,5=50,7=0.000000
L 0.70822018 -0.44089695 0.71008642 -0.43923061 2 P 0 ;0,5=50,7=0.000000
L 0.71008642 -0.43923061 0.71141998 -0.43631378 2 P 0 ;0,5=50,7=0.000000
L 0.71141998 -0.43631378 0.71168661 -0.43298041 2 P 0 ;0,5=50,7=0.000000
L 0.71168661 -0.43298041 0.71115335 -0.42964705 2 P 0 ;0,5=50,7=0.000000
L 0.71115335 -0.42964705 0.70981978 -0.42756339 2 P 0 ;0,5=50,7=0.000000
L 0.70981978 -0.42756339 0.70795305 -0.42589705 2 P 0 ;0,5=50,7=0.000000
L 0.70795305 -0.42589705 0.70608681 -0.42548051 2 P 0 ;0,5=50,7=0.000000
L 0.70608681 -0.42548051 0.70421998 -0.42589705 2 P 0 ;0,5=50,7=0.000000
L 0.70421998 -0.42589705 0.70182008 -0.42756339 2 P 0 ;0,5=50,7=0.000000
L 0.70182008 -0.42756339 0.70261988 -0.41673002 2 P 0 ;0,5=50,7=0.000000
L 0.70261988 -0.41673002 0.70981978 -0.41673002 2 P 0 ;0,5=50,7=0.000000
L 0.69266654 -0.155 0.69266654 -0.18 2 P 0 ;0,5=51,7=0.000000
L 0.69266654 -0.18 0.70333337 -0.18 2 P 0 ;0,5=51,7=0.000000
L 0.7219997 -0.18 0.7219997 -0.155 2 P 0 ;0,5=51,7=0.000000
L 0.7219997 -0.155 0.7187999 -0.1599997 2 P 0 ;0,5=51,7=0.000000
L 0.7187999 -0.18 0.72519951 -0.18 2 P 0 ;0,5=51,7=0.000000
L 0.74093317 -0.15916663 0.74253327 -0.15666713 2 P 0 ;0,5=51,7=0.000000
L 0.74253327 -0.15666713 0.7444 -0.15541663 2 P 0 ;0,5=51,7=0.000000
L 0.7444 -0.15541663 0.74653337 -0.155 2 P 0 ;0,5=51,7=0.000000
L 0.74653337 -0.155 0.7492 -0.15583317 2 P 0 ;0,5=51,7=0.000000
L 0.7492 -0.15583317 0.75106673 -0.15791683 2 P 0 ;0,5=51,7=0.000000
L 0.75106673 -0.15791683 0.7516 -0.16041634 2 P 0 ;0,5=51,7=0.000000
L 0.7516 -0.16041634 0.75133337 -0.16291732 2 P 0 ;0,5=51,7=0.000000
L 0.75133337 -0.16291732 0.75026644 -0.1650002 2 P 0 ;0,5=51,7=0.000000
L 0.75026644 -0.1650002 0.74493327 -0.16916673 2 P 0 ;0,5=51,7=0.000000
L 0.74493327 -0.16916673 0.74253327 -0.17208356 2 P 0 ;0,5=51,7=0.000000
L 0.74253327 -0.17208356 0.74093317 -0.17625089 2 P 0 ;0,5=51,7=0.000000
L 0.74093317 -0.17625089 0.7403999 -0.18 2 P 0 ;0,5=51,7=0.000000
L 0.7403999 -0.18 0.7516 -0.18 2 P 0 ;0,5=51,7=0.000000
L 0.88681004 -0.44173002 0.89861998 -0.44173002 1 P 0 
A 0.89861998 -0.44173002 0.90650394 -0.41810512 0.9065 -0.43123179 1 P 0 Y
A 0.90650394 -0.41810512 0.91436998 -0.44173002 0.9065 -0.43122844 1 P 0 Y
L 0.91436998 -0.44173002 0.92618002 -0.44173002 1 P 0 
L 0.83501998 -0.44173002 0.83501998 -0.41673002 2 P 0 ;0,5=50,7=0.000000
L 0.83501998 -0.41673002 0.82515295 -0.43464675 2 P 0 ;0,5=50,7=0.000000
L 0.82515295 -0.43464675 0.83848691 -0.43464675 2 P 0 ;0,5=50,7=0.000000
L 0.84995325 -0.43798091 0.85155295 -0.44006378 2 P 0 ;0,5=50,7=0.000000
L 0.85155295 -0.44006378 0.85341969 -0.44131348 2 P 0 ;0,5=50,7=0.000000
L 0.85341969 -0.44131348 0.85581969 -0.44173002 2 P 0 ;0,5=50,7=0.000000
L 0.85581969 -0.44173002 0.85822018 -0.44089695 2 P 0 ;0,5=50,7=0.000000
L 0.85822018 -0.44089695 0.86008642 -0.43923061 2 P 0 ;0,5=50,7=0.000000
L 0.86008642 -0.43923061 0.86141998 -0.43631378 2 P 0 ;0,5=50,7=0.000000
L 0.86141998 -0.43631378 0.86168661 -0.43298041 2 P 0 ;0,5=50,7=0.000000
L 0.86168661 -0.43298041 0.86115335 -0.42964705 2 P 0 ;0,5=50,7=0.000000
L 0.86115335 -0.42964705 0.85981978 -0.42756339 2 P 0 ;0,5=50,7=0.000000
L 0.85981978 -0.42756339 0.85795305 -0.42589705 2 P 0 ;0,5=50,7=0.000000
L 0.85795305 -0.42589705 0.85608681 -0.42548051 2 P 0 ;0,5=50,7=0.000000
L 0.85608681 -0.42548051 0.85421998 -0.42589705 2 P 0 ;0,5=50,7=0.000000
L 0.85421998 -0.42589705 0.85182008 -0.42756339 2 P 0 ;0,5=50,7=0.000000
L 0.85182008 -0.42756339 0.85261988 -0.41673002 2 P 0 ;0,5=50,7=0.000000
L 0.85261988 -0.41673002 0.85981978 -0.41673002 2 P 0 ;0,5=50,7=0.000000
L 0.84266654 -0.155 0.84266654 -0.18 2 P 0 ;0,5=52,7=0.000000
L 0.84266654 -0.18 0.85333337 -0.18 2 P 0 ;0,5=52,7=0.000000
L 0.8719997 -0.18 0.8719997 -0.155 2 P 0 ;0,5=52,7=0.000000
L 0.8719997 -0.155 0.8687999 -0.1599997 2 P 0 ;0,5=52,7=0.000000
L 0.8687999 -0.18 0.87519951 -0.18 2 P 0 ;0,5=52,7=0.000000
L 0.8959997 -0.155 0.89386634 -0.15583317 2 P 0 ;0,5=52,7=0.000000
L 0.89386634 -0.15583317 0.89226663 -0.15791683 2 P 0 ;0,5=52,7=0.000000
L 0.89226663 -0.15791683 0.8911998 -0.16041634 2 P 0 ;0,5=52,7=0.000000
L 0.8911998 -0.16041634 0.8903999 -0.16375049 2 P 0 ;0,5=52,7=0.000000
L 0.8903999 -0.16375049 0.89013327 -0.16750039 2 P 0 ;0,5=52,7=0.000000
L 0.89013327 -0.16750039 0.8903999 -0.17125039 2 P 0 ;0,5=52,7=0.000000
L 0.8903999 -0.17125039 0.8911998 -0.17458376 2 P 0 ;0,5=52,7=0.000000
L 0.8911998 -0.17458376 0.89226663 -0.17708396 2 P 0 ;0,5=52,7=0.000000
L 0.89226663 -0.17708396 0.89386634 -0.17916693 2 P 0 ;0,5=52,7=0.000000
L 0.89386634 -0.17916693 0.8959997 -0.18 2 P 0 ;0,5=52,7=0.000000
L 0.8959997 -0.18 0.89813307 -0.17916693 2 P 0 ;0,5=52,7=0.000000
L 0.89813307 -0.17916693 0.89973327 -0.17708396 2 P 0 ;0,5=52,7=0.000000
L 0.89973327 -0.17708396 0.9008001 -0.17458376 2 P 0 ;0,5=52,7=0.000000
L 0.9008001 -0.17458376 0.9016 -0.17125039 2 P 0 ;0,5=52,7=0.000000
L 0.9016 -0.17125039 0.90186663 -0.16750039 2 P 0 ;0,5=52,7=0.000000
L 0.90186663 -0.16750039 0.9016 -0.16375049 2 P 0 ;0,5=52,7=0.000000
L 0.9016 -0.16375049 0.9008001 -0.16041634 2 P 0 ;0,5=52,7=0.000000
L 0.9008001 -0.16041634 0.89973327 -0.15791683 2 P 0 ;0,5=52,7=0.000000
L 0.89973327 -0.15791683 0.89813307 -0.15583317 2 P 0 ;0,5=52,7=0.000000
L 0.89813307 -0.15583317 0.8959997 -0.155 2 P 0 ;0,5=52,7=0.000000
L 1.03181004 -0.44173002 1.04361998 -0.44173002 1 P 0 
A 1.04361998 -0.44173002 1.05148602 -0.41810512 1.05148996 -0.43122844 1 P 0 Y
A 1.05148602 -0.41810512 1.05936998 -0.44173002 1.05148996 -0.43123179 1 P 0 Y
L 1.05936998 -0.44173002 1.07118002 -0.44173002 1 P 0 
L 0.98001998 -0.44173002 0.98001998 -0.41673002 2 P 0 ;0,5=50,7=0.000000
L 0.98001998 -0.41673002 0.97015295 -0.43464675 2 P 0 ;0,5=50,7=0.000000
L 0.97015295 -0.43464675 0.98348691 -0.43464675 2 P 0 ;0,5=50,7=0.000000
L 0.99495325 -0.43798091 0.99655295 -0.44006378 2 P 0 ;0,5=50,7=0.000000
L 0.99655295 -0.44006378 0.99841969 -0.44131348 2 P 0 ;0,5=50,7=0.000000
L 0.99841969 -0.44131348 1.00081969 -0.44173002 2 P 0 ;0,5=50,7=0.000000
L 1.00081969 -0.44173002 1.00322018 -0.44089695 2 P 0 ;0,5=50,7=0.000000
L 1.00322018 -0.44089695 1.00508642 -0.43923061 2 P 0 ;0,5=50,7=0.000000
L 1.00508642 -0.43923061 1.00641998 -0.43631378 2 P 0 ;0,5=50,7=0.000000
L 1.00641998 -0.43631378 1.00668661 -0.43298041 2 P 0 ;0,5=50,7=0.000000
L 1.00668661 -0.43298041 1.00615335 -0.42964705 2 P 0 ;0,5=50,7=0.000000
L 1.00615335 -0.42964705 1.00481978 -0.42756339 2 P 0 ;0,5=50,7=0.000000
L 1.00481978 -0.42756339 1.00295305 -0.42589705 2 P 0 ;0,5=50,7=0.000000
L 1.00295305 -0.42589705 1.00108681 -0.42548051 2 P 0 ;0,5=50,7=0.000000
L 1.00108681 -0.42548051 0.99921998 -0.42589705 2 P 0 ;0,5=50,7=0.000000
L 0.99921998 -0.42589705 0.99682008 -0.42756339 2 P 0 ;0,5=50,7=0.000000
L 0.99682008 -0.42756339 0.99761988 -0.41673002 2 P 0 ;0,5=50,7=0.000000
L 0.99761988 -0.41673002 1.00481978 -0.41673002 2 P 0 ;0,5=50,7=0.000000
L 1.00766654 -0.155 1.00766654 -0.18 2 P 0 ;0,5=53,7=0.000000
L 1.00766654 -0.18 1.01833337 -0.18 2 P 0 ;0,5=53,7=0.000000
L 1.03113327 -0.17625089 1.03273297 -0.17833376 2 P 0 ;0,5=53,7=0.000000
L 1.03273297 -0.17833376 1.0345997 -0.17958346 2 P 0 ;0,5=53,7=0.000000
L 1.0345997 -0.17958346 1.0369997 -0.18 2 P 0 ;0,5=53,7=0.000000
L 1.0369997 -0.18 1.0394002 -0.17916693 2 P 0 ;0,5=53,7=0.000000
L 1.0394002 -0.17916693 1.04126644 -0.17750059 2 P 0 ;0,5=53,7=0.000000
L 1.04126644 -0.17750059 1.0426 -0.17458376 2 P 0 ;0,5=53,7=0.000000
L 1.0426 -0.17458376 1.04286663 -0.17125039 2 P 0 ;0,5=53,7=0.000000
L 1.04286663 -0.17125039 1.04233337 -0.16791703 2 P 0 ;0,5=53,7=0.000000
L 1.04233337 -0.16791703 1.0409998 -0.16583337 2 P 0 ;0,5=53,7=0.000000
L 1.0409998 -0.16583337 1.03913307 -0.16416703 2 P 0 ;0,5=53,7=0.000000
L 1.03913307 -0.16416703 1.03726683 -0.16375049 2 P 0 ;0,5=53,7=0.000000
L 1.03726683 -0.16375049 1.0354 -0.16416703 2 P 0 ;0,5=53,7=0.000000
L 1.0354 -0.16416703 1.0330001 -0.16583337 2 P 0 ;0,5=53,7=0.000000
L 1.0330001 -0.16583337 1.0337999 -0.155 2 P 0 ;0,5=53,7=0.000000
L 1.0337999 -0.155 1.0409998 -0.155 2 P 0 ;0,5=53,7=0.000000
L 1.18181004 -0.44173002 1.19361998 -0.44173002 1 P 0 
A 1.19361998 -0.44173002 1.20148602 -0.41810512 1.20148996 -0.43122844 1 P 0 Y
A 1.20148602 -0.41810512 1.20936998 -0.44173002 1.20148996 -0.43123179 1 P 0 Y
L 1.20936998 -0.44173002 1.22118002 -0.44173002 1 P 0 
L 1.13001998 -0.44173002 1.13001998 -0.41673002 2 P 0 ;0,5=50,7=0.000000
L 1.13001998 -0.41673002 1.12015295 -0.43464675 2 P 0 ;0,5=50,7=0.000000
L 1.12015295 -0.43464675 1.13348691 -0.43464675 2 P 0 ;0,5=50,7=0.000000
L 1.14495325 -0.43798091 1.14655295 -0.44006378 2 P 0 ;0,5=50,7=0.000000
L 1.14655295 -0.44006378 1.14841969 -0.44131348 2 P 0 ;0,5=50,7=0.000000
L 1.14841969 -0.44131348 1.15081969 -0.44173002 2 P 0 ;0,5=50,7=0.000000
L 1.15081969 -0.44173002 1.15322018 -0.44089695 2 P 0 ;0,5=50,7=0.000000
L 1.15322018 -0.44089695 1.15508642 -0.43923061 2 P 0 ;0,5=50,7=0.000000
L 1.15508642 -0.43923061 1.15641998 -0.43631378 2 P 0 ;0,5=50,7=0.000000
L 1.15641998 -0.43631378 1.15668661 -0.43298041 2 P 0 ;0,5=50,7=0.000000
L 1.15668661 -0.43298041 1.15615335 -0.42964705 2 P 0 ;0,5=50,7=0.000000
L 1.15615335 -0.42964705 1.15481978 -0.42756339 2 P 0 ;0,5=50,7=0.000000
L 1.15481978 -0.42756339 1.15295305 -0.42589705 2 P 0 ;0,5=50,7=0.000000
L 1.15295305 -0.42589705 1.15108681 -0.42548051 2 P 0 ;0,5=50,7=0.000000
L 1.15108681 -0.42548051 1.14921998 -0.42589705 2 P 0 ;0,5=50,7=0.000000
L 1.14921998 -0.42589705 1.14682008 -0.42756339 2 P 0 ;0,5=50,7=0.000000
L 1.14682008 -0.42756339 1.14761988 -0.41673002 2 P 0 ;0,5=50,7=0.000000
L 1.14761988 -0.41673002 1.15481978 -0.41673002 2 P 0 ;0,5=50,7=0.000000
L 1.15766654 -0.155 1.15766654 -0.18 2 P 0 ;0,5=54,7=0.000000
L 1.15766654 -0.18 1.16833337 -0.18 2 P 0 ;0,5=54,7=0.000000
L 1.18113327 -0.17500039 1.18273297 -0.17791713 2 P 0 ;0,5=54,7=0.000000
L 1.18273297 -0.17791713 1.18486634 -0.17958346 2 P 0 ;0,5=54,7=0.000000
L 1.18486634 -0.17958346 1.18726683 -0.18 2 P 0 ;0,5=54,7=0.000000
L 1.18726683 -0.18 1.1894002 -0.17958346 2 P 0 ;0,5=54,7=0.000000
L 1.1894002 -0.17958346 1.19153356 -0.17750059 2 P 0 ;0,5=54,7=0.000000
L 1.19153356 -0.17750059 1.19286663 -0.17500039 2 P 0 ;0,5=54,7=0.000000
L 1.19286663 -0.17500039 1.19313317 -0.1725001 2 P 0 ;0,5=54,7=0.000000
L 1.19313317 -0.1725001 1.1926 -0.16958406 2 P 0 ;0,5=54,7=0.000000
L 1.1926 -0.16958406 1.19073327 -0.16750039 2 P 0 ;0,5=54,7=0.000000
L 1.19073327 -0.16750039 1.18886644 -0.16666654 2 P 0 ;0,5=54,7=0.000000
L 1.18886644 -0.16666654 1.18646654 -0.16666654 2 P 0 ;0,5=54,7=0.000000
L 1.18886644 -0.16666654 1.19046663 -0.16541673 2 P 0 ;0,5=54,7=0.000000
L 1.19046663 -0.16541673 1.1918001 -0.16333386 2 P 0 ;0,5=54,7=0.000000
L 1.1918001 -0.16333386 1.19233337 -0.16083366 2 P 0 ;0,5=54,7=0.000000
L 1.19233337 -0.16083366 1.1918001 -0.15833346 2 P 0 ;0,5=54,7=0.000000
L 1.1918001 -0.15833346 1.19046663 -0.15625059 2 P 0 ;0,5=54,7=0.000000
L 1.19046663 -0.15625059 1.18806663 -0.155 2 P 0 ;0,5=54,7=0.000000
L 1.18806663 -0.155 1.18566663 -0.15541663 2 P 0 ;0,5=54,7=0.000000
L 1.18566663 -0.15541663 1.18326663 -0.15708366 2 P 0 ;0,5=54,7=0.000000
L 1.33681004 -0.44173002 1.34861998 -0.44173002 1 P 0 
A 1.34861998 -0.44173002 1.35648602 -0.41810512 1.35648996 -0.43122844 1 P 0 Y
A 1.35648602 -0.41810512 1.36436998 -0.44173002 1.35648996 -0.43123179 1 P 0 Y
L 1.36436998 -0.44173002 1.37618002 -0.44173002 1 P 0 
L 1.28501998 -0.44173002 1.28501998 -0.41673002 2 P 0 ;0,5=50,7=0.000000
L 1.28501998 -0.41673002 1.27515295 -0.43464675 2 P 0 ;0,5=50,7=0.000000
L 1.27515295 -0.43464675 1.28848691 -0.43464675 2 P 0 ;0,5=50,7=0.000000
L 1.29995325 -0.43798091 1.30155295 -0.44006378 2 P 0 ;0,5=50,7=0.000000
L 1.30155295 -0.44006378 1.30341969 -0.44131348 2 P 0 ;0,5=50,7=0.000000
L 1.30341969 -0.44131348 1.30581969 -0.44173002 2 P 0 ;0,5=50,7=0.000000
L 1.30581969 -0.44173002 1.30822018 -0.44089695 2 P 0 ;0,5=50,7=0.000000
L 1.30822018 -0.44089695 1.31008642 -0.43923061 2 P 0 ;0,5=50,7=0.000000
L 1.31008642 -0.43923061 1.31141998 -0.43631378 2 P 0 ;0,5=50,7=0.000000
L 1.31141998 -0.43631378 1.31168661 -0.43298041 2 P 0 ;0,5=50,7=0.000000
L 1.31168661 -0.43298041 1.31115335 -0.42964705 2 P 0 ;0,5=50,7=0.000000
L 1.31115335 -0.42964705 1.30981978 -0.42756339 2 P 0 ;0,5=50,7=0.000000
L 1.30981978 -0.42756339 1.30795305 -0.42589705 2 P 0 ;0,5=50,7=0.000000
L 1.30795305 -0.42589705 1.30608681 -0.42548051 2 P 0 ;0,5=50,7=0.000000
L 1.30608681 -0.42548051 1.30421998 -0.42589705 2 P 0 ;0,5=50,7=0.000000
L 1.30421998 -0.42589705 1.30182008 -0.42756339 2 P 0 ;0,5=50,7=0.000000
L 1.30182008 -0.42756339 1.30261988 -0.41673002 2 P 0 ;0,5=50,7=0.000000
L 1.30261988 -0.41673002 1.30981978 -0.41673002 2 P 0 ;0,5=50,7=0.000000
L 1.31266654 -0.155 1.31266654 -0.18 2 P 0 ;0,5=55,7=0.000000
L 1.31266654 -0.18 1.32333337 -0.18 2 P 0 ;0,5=55,7=0.000000
L 1.3419997 -0.18 1.3419997 -0.155 2 P 0 ;0,5=55,7=0.000000
L 1.3419997 -0.155 1.3387999 -0.1599997 2 P 0 ;0,5=55,7=0.000000
L 1.3387999 -0.18 1.34519951 -0.18 2 P 0 ;0,5=55,7=0.000000
L 0.84181004 6.42326998 0.85361998 6.42326998 1 P 0 
A 0.85361998 6.42326998 0.86150394 6.44689488 0.8615 6.43376821 1 P 0 Y
A 0.86150394 6.44689488 0.86936998 6.42326998 0.8615 6.43377156 1 P 0 Y
L 0.86936998 6.42326998 0.88118002 6.42326998 1 P 0 
L 0.78681969 6.42326998 0.78868642 6.42368652 2 P 0 ;0,5=56,7=0.000000
L 0.78868642 6.42368652 0.79081978 6.42493622 2 P 0 ;0,5=56,7=0.000000
L 0.79081978 6.42493622 0.79215335 6.42701909 2 P 0 ;0,5=56,7=0.000000
L 0.79215335 6.42701909 0.79268661 6.42993671 2 P 0 ;0,5=56,7=0.000000
L 0.79268661 6.42993671 0.79215335 6.43285276 2 P 0 ;0,5=56,7=0.000000
L 0.79215335 6.43285276 0.79055325 6.43535295 2 P 0 ;0,5=56,7=0.000000
L 0.79055325 6.43535295 0.78815325 6.43660344 2 P 0 ;0,5=56,7=0.000000
L 0.78815325 6.43660344 0.78548661 6.43660344 2 P 0 ;0,5=56,7=0.000000
L 0.78548661 6.43660344 0.78388652 6.43743661 2 P 0 ;0,5=56,7=0.000000
L 0.78388652 6.43743661 0.78255295 6.43951949 2 P 0 ;0,5=56,7=0.000000
L 0.78255295 6.43951949 0.78201978 6.44243632 2 P 0 ;0,5=56,7=0.000000
L 0.78201978 6.44243632 0.78282008 6.44535315 2 P 0 ;0,5=56,7=0.000000
L 0.78282008 6.44535315 0.78468632 6.44743681 2 P 0 ;0,5=56,7=0.000000
L 0.78468632 6.44743681 0.78681969 6.44826998 2 P 0 ;0,5=56,7=0.000000
L 0.78681969 6.44826998 0.78895305 6.44743681 2 P 0 ;0,5=56,7=0.000000
L 0.78895305 6.44743681 0.79081978 6.44535315 2 P 0 ;0,5=56,7=0.000000
L 0.79081978 6.44535315 0.79162008 6.44243632 2 P 0 ;0,5=56,7=0.000000
L 0.79162008 6.44243632 0.79108642 6.43951949 2 P 0 ;0,5=56,7=0.000000
L 0.79108642 6.43951949 0.78975335 6.43743661 2 P 0 ;0,5=56,7=0.000000
L 0.78975335 6.43743661 0.78815325 6.43660344 2 P 0 ;0,5=56,7=0.000000
L 0.78815325 6.43660344 0.78548661 6.43660344 2 P 0 ;0,5=56,7=0.000000
L 0.78548661 6.43660344 0.78308661 6.43535295 2 P 0 ;0,5=56,7=0.000000
L 0.78308661 6.43535295 0.78148652 6.43285276 2 P 0 ;0,5=56,7=0.000000
L 0.78148652 6.43285276 0.78095325 6.42993671 2 P 0 ;0,5=56,7=0.000000
L 0.78095325 6.42993671 0.78148652 6.42701909 2 P 0 ;0,5=56,7=0.000000
L 0.78148652 6.42701909 0.78282008 6.42493622 2 P 0 ;0,5=56,7=0.000000
L 0.78282008 6.42493622 0.78495344 6.42368652 2 P 0 ;0,5=56,7=0.000000
L 0.78495344 6.42368652 0.78681969 6.42326998 2 P 0 ;0,5=56,7=0.000000
L 0.80495325 6.42701909 0.80655295 6.42493622 2 P 0 ;0,5=56,7=0.000000
L 0.80655295 6.42493622 0.80841969 6.42368652 2 P 0 ;0,5=56,7=0.000000
L 0.80841969 6.42368652 0.81081969 6.42326998 2 P 0 ;0,5=56,7=0.000000
L 0.81081969 6.42326998 0.81322018 6.42410305 2 P 0 ;0,5=56,7=0.000000
L 0.81322018 6.42410305 0.81508642 6.42576939 2 P 0 ;0,5=56,7=0.000000
L 0.81508642 6.42576939 0.81641998 6.42868622 2 P 0 ;0,5=56,7=0.000000
L 0.81641998 6.42868622 0.81668661 6.43201959 2 P 0 ;0,5=56,7=0.000000
L 0.81668661 6.43201959 0.81615335 6.43535295 2 P 0 ;0,5=56,7=0.000000
L 0.81615335 6.43535295 0.81481978 6.43743661 2 P 0 ;0,5=56,7=0.000000
L 0.81481978 6.43743661 0.81295305 6.43910295 2 P 0 ;0,5=56,7=0.000000
L 0.81295305 6.43910295 0.81108681 6.43951949 2 P 0 ;0,5=56,7=0.000000
L 0.81108681 6.43951949 0.80921998 6.43910295 2 P 0 ;0,5=56,7=0.000000
L 0.80921998 6.43910295 0.80682008 6.43743661 2 P 0 ;0,5=56,7=0.000000
L 0.80682008 6.43743661 0.80761988 6.44826998 2 P 0 ;0,5=56,7=0.000000
L 0.80761988 6.44826998 0.81481978 6.44826998 2 P 0 ;0,5=56,7=0.000000
L 0.68691654 6.44916998 0.68691654 6.42416998 2 P 0 ;0,5=51,7=0.000000
L 0.68691654 6.42416998 0.69758337 6.42416998 2 P 0 ;0,5=51,7=0.000000
L 0.7162497 6.42416998 0.7162497 6.44916998 2 P 0 ;0,5=51,7=0.000000
L 0.7162497 6.44916998 0.7130499 6.44417028 2 P 0 ;0,5=51,7=0.000000
L 0.7130499 6.42416998 0.71944951 6.42416998 2 P 0 ;0,5=51,7=0.000000
L 0.73518317 6.44500335 0.73678327 6.44750285 2 P 0 ;0,5=51,7=0.000000
L 0.73678327 6.44750285 0.73865 6.44875335 2 P 0 ;0,5=51,7=0.000000
L 0.73865 6.44875335 0.74078337 6.44916998 2 P 0 ;0,5=51,7=0.000000
L 0.74078337 6.44916998 0.74345 6.44833681 2 P 0 ;0,5=51,7=0.000000
L 0.74345 6.44833681 0.74531673 6.44625315 2 P 0 ;0,5=51,7=0.000000
L 0.74531673 6.44625315 0.74585 6.44375364 2 P 0 ;0,5=51,7=0.000000
L 0.74585 6.44375364 0.74558337 6.44125266 2 P 0 ;0,5=51,7=0.000000
L 0.74558337 6.44125266 0.74451644 6.43916978 2 P 0 ;0,5=51,7=0.000000
L 0.74451644 6.43916978 0.73918327 6.43500325 2 P 0 ;0,5=51,7=0.000000
L 0.73918327 6.43500325 0.73678327 6.43208642 2 P 0 ;0,5=51,7=0.000000
L 0.73678327 6.43208642 0.73518317 6.42791909 2 P 0 ;0,5=51,7=0.000000
L 0.73518317 6.42791909 0.7346499 6.42416998 2 P 0 ;0,5=51,7=0.000000
L 0.7346499 6.42416998 0.74585 6.42416998 2 P 0 ;0,5=51,7=0.000000
L 1.06181004 6.42326998 1.07361998 6.42326998 1 P 0 
A 1.07361998 6.42326998 1.08148602 6.44689488 1.08148996 6.43377156 1 P 0 Y
A 1.08148602 6.44689488 1.08936998 6.42326998 1.08148996 6.43376821 1 P 0 Y
L 1.08936998 6.42326998 1.10118002 6.42326998 1 P 0 
L 1.00681969 6.42326998 1.00868642 6.42368652 2 P 0 ;0,5=56,7=0.000000
L 1.00868642 6.42368652 1.01081978 6.42493622 2 P 0 ;0,5=56,7=0.000000
L 1.01081978 6.42493622 1.01215335 6.42701909 2 P 0 ;0,5=56,7=0.000000
L 1.01215335 6.42701909 1.01268661 6.42993671 2 P 0 ;0,5=56,7=0.000000
L 1.01268661 6.42993671 1.01215335 6.43285276 2 P 0 ;0,5=56,7=0.000000
L 1.01215335 6.43285276 1.01055325 6.43535295 2 P 0 ;0,5=56,7=0.000000
L 1.01055325 6.43535295 1.00815325 6.43660344 2 P 0 ;0,5=56,7=0.000000
L 1.00815325 6.43660344 1.00548661 6.43660344 2 P 0 ;0,5=56,7=0.000000
L 1.00548661 6.43660344 1.00388652 6.43743661 2 P 0 ;0,5=56,7=0.000000
L 1.00388652 6.43743661 1.00255295 6.43951949 2 P 0 ;0,5=56,7=0.000000
L 1.00255295 6.43951949 1.00201978 6.44243632 2 P 0 ;0,5=56,7=0.000000
L 1.00201978 6.44243632 1.00282008 6.44535315 2 P 0 ;0,5=56,7=0.000000
L 1.00282008 6.44535315 1.00468632 6.44743681 2 P 0 ;0,5=56,7=0.000000
L 1.00468632 6.44743681 1.00681969 6.44826998 2 P 0 ;0,5=56,7=0.000000
L 1.00681969 6.44826998 1.00895305 6.44743681 2 P 0 ;0,5=56,7=0.000000
L 1.00895305 6.44743681 1.01081978 6.44535315 2 P 0 ;0,5=56,7=0.000000
L 1.01081978 6.44535315 1.01162008 6.44243632 2 P 0 ;0,5=56,7=0.000000
L 1.01162008 6.44243632 1.01108642 6.43951949 2 P 0 ;0,5=56,7=0.000000
L 1.01108642 6.43951949 1.00975335 6.43743661 2 P 0 ;0,5=56,7=0.000000
L 1.00975335 6.43743661 1.00815325 6.43660344 2 P 0 ;0,5=56,7=0.000000
L 1.00815325 6.43660344 1.00548661 6.43660344 2 P 0 ;0,5=56,7=0.000000
L 1.00548661 6.43660344 1.00308661 6.43535295 2 P 0 ;0,5=56,7=0.000000
L 1.00308661 6.43535295 1.00148652 6.43285276 2 P 0 ;0,5=56,7=0.000000
L 1.00148652 6.43285276 1.00095325 6.42993671 2 P 0 ;0,5=56,7=0.000000
L 1.00095325 6.42993671 1.00148652 6.42701909 2 P 0 ;0,5=56,7=0.000000
L 1.00148652 6.42701909 1.00282008 6.42493622 2 P 0 ;0,5=56,7=0.000000
L 1.00282008 6.42493622 1.00495344 6.42368652 2 P 0 ;0,5=56,7=0.000000
L 1.00495344 6.42368652 1.00681969 6.42326998 2 P 0 ;0,5=56,7=0.000000
L 1.02495325 6.42701909 1.02655295 6.42493622 2 P 0 ;0,5=56,7=0.000000
L 1.02655295 6.42493622 1.02841969 6.42368652 2 P 0 ;0,5=56,7=0.000000
L 1.02841969 6.42368652 1.03081969 6.42326998 2 P 0 ;0,5=56,7=0.000000
L 1.03081969 6.42326998 1.03322018 6.42410305 2 P 0 ;0,5=56,7=0.000000
L 1.03322018 6.42410305 1.03508642 6.42576939 2 P 0 ;0,5=56,7=0.000000
L 1.03508642 6.42576939 1.03641998 6.42868622 2 P 0 ;0,5=56,7=0.000000
L 1.03641998 6.42868622 1.03668661 6.43201959 2 P 0 ;0,5=56,7=0.000000
L 1.03668661 6.43201959 1.03615335 6.43535295 2 P 0 ;0,5=56,7=0.000000
L 1.03615335 6.43535295 1.03481978 6.43743661 2 P 0 ;0,5=56,7=0.000000
L 1.03481978 6.43743661 1.03295305 6.43910295 2 P 0 ;0,5=56,7=0.000000
L 1.03295305 6.43910295 1.03108681 6.43951949 2 P 0 ;0,5=56,7=0.000000
L 1.03108681 6.43951949 1.02921998 6.43910295 2 P 0 ;0,5=56,7=0.000000
L 1.02921998 6.43910295 1.02682008 6.43743661 2 P 0 ;0,5=56,7=0.000000
L 1.02682008 6.43743661 1.02761988 6.44826998 2 P 0 ;0,5=56,7=0.000000
L 1.02761988 6.44826998 1.03481978 6.44826998 2 P 0 ;0,5=56,7=0.000000
L 0.91691654 6.44916998 0.91691654 6.42416998 2 P 0 ;0,5=52,7=0.000000
L 0.91691654 6.42416998 0.92758337 6.42416998 2 P 0 ;0,5=52,7=0.000000
L 0.9462497 6.42416998 0.9462497 6.44916998 2 P 0 ;0,5=52,7=0.000000
L 0.9462497 6.44916998 0.9430499 6.44417028 2 P 0 ;0,5=52,7=0.000000
L 0.9430499 6.42416998 0.94944951 6.42416998 2 P 0 ;0,5=52,7=0.000000
L 0.9702497 6.44916998 0.96811634 6.44833681 2 P 0 ;0,5=52,7=0.000000
L 0.96811634 6.44833681 0.96651663 6.44625315 2 P 0 ;0,5=52,7=0.000000
L 0.96651663 6.44625315 0.9654498 6.44375364 2 P 0 ;0,5=52,7=0.000000
L 0.9654498 6.44375364 0.9646499 6.44041949 2 P 0 ;0,5=52,7=0.000000
L 0.9646499 6.44041949 0.96438327 6.43666959 2 P 0 ;0,5=52,7=0.000000
L 0.96438327 6.43666959 0.9646499 6.43291959 2 P 0 ;0,5=52,7=0.000000
L 0.9646499 6.43291959 0.9654498 6.42958622 2 P 0 ;0,5=52,7=0.000000
L 0.9654498 6.42958622 0.96651663 6.42708602 2 P 0 ;0,5=52,7=0.000000
L 0.96651663 6.42708602 0.96811634 6.42500305 2 P 0 ;0,5=52,7=0.000000
L 0.96811634 6.42500305 0.9702497 6.42416998 2 P 0 ;0,5=52,7=0.000000
L 0.9702497 6.42416998 0.97238307 6.42500305 2 P 0 ;0,5=52,7=0.000000
L 0.97238307 6.42500305 0.97398327 6.42708602 2 P 0 ;0,5=52,7=0.000000
L 0.97398327 6.42708602 0.9750501 6.42958622 2 P 0 ;0,5=52,7=0.000000
L 0.9750501 6.42958622 0.97585 6.43291959 2 P 0 ;0,5=52,7=0.000000
L 0.97585 6.43291959 0.97611663 6.43666959 2 P 0 ;0,5=52,7=0.000000
L 0.97611663 6.43666959 0.97585 6.44041949 2 P 0 ;0,5=52,7=0.000000
L 0.97585 6.44041949 0.9750501 6.44375364 2 P 0 ;0,5=52,7=0.000000
L 0.9750501 6.44375364 0.97398327 6.44625315 2 P 0 ;0,5=52,7=0.000000
L 0.97398327 6.44625315 0.97238307 6.44833681 2 P 0 ;0,5=52,7=0.000000
L 0.97238307 6.44833681 0.9702497 6.44916998 2 P 0 ;0,5=52,7=0.000000
L 1.74681004 6.42326998 1.75861998 6.42326998 1 P 0 
A 1.75861998 6.42326998 1.76648602 6.44689488 1.76648996 6.43377156 1 P 0 Y
A 1.76648602 6.44689488 1.77436998 6.42326998 1.76648996 6.43376821 1 P 0 Y
L 1.77436998 6.42326998 1.78618002 6.42326998 1 P 0 
L 1.69181969 6.42326998 1.69368642 6.42368652 2 P 0 ;0,5=56,7=0.000000
L 1.69368642 6.42368652 1.69581978 6.42493622 2 P 0 ;0,5=56,7=0.000000
L 1.69581978 6.42493622 1.69715335 6.42701909 2 P 0 ;0,5=56,7=0.000000
L 1.69715335 6.42701909 1.69768661 6.42993671 2 P 0 ;0,5=56,7=0.000000
L 1.69768661 6.42993671 1.69715335 6.43285276 2 P 0 ;0,5=56,7=0.000000
L 1.69715335 6.43285276 1.69555325 6.43535295 2 P 0 ;0,5=56,7=0.000000
L 1.69555325 6.43535295 1.69315325 6.43660344 2 P 0 ;0,5=56,7=0.000000
L 1.69315325 6.43660344 1.69048661 6.43660344 2 P 0 ;0,5=56,7=0.000000
L 1.69048661 6.43660344 1.68888652 6.43743661 2 P 0 ;0,5=56,7=0.000000
L 1.68888652 6.43743661 1.68755295 6.43951949 2 P 0 ;0,5=56,7=0.000000
L 1.68755295 6.43951949 1.68701978 6.44243632 2 P 0 ;0,5=56,7=0.000000
L 1.68701978 6.44243632 1.68782008 6.44535315 2 P 0 ;0,5=56,7=0.000000
L 1.68782008 6.44535315 1.68968632 6.44743681 2 P 0 ;0,5=56,7=0.000000
L 1.68968632 6.44743681 1.69181969 6.44826998 2 P 0 ;0,5=56,7=0.000000
L 1.69181969 6.44826998 1.69395305 6.44743681 2 P 0 ;0,5=56,7=0.000000
L 1.69395305 6.44743681 1.69581978 6.44535315 2 P 0 ;0,5=56,7=0.000000
L 1.69581978 6.44535315 1.69662008 6.44243632 2 P 0 ;0,5=56,7=0.000000
L 1.69662008 6.44243632 1.69608642 6.43951949 2 P 0 ;0,5=56,7=0.000000
L 1.69608642 6.43951949 1.69475335 6.43743661 2 P 0 ;0,5=56,7=0.000000
L 1.69475335 6.43743661 1.69315325 6.43660344 2 P 0 ;0,5=56,7=0.000000
L 1.69315325 6.43660344 1.69048661 6.43660344 2 P 0 ;0,5=56,7=0.000000
L 1.69048661 6.43660344 1.68808661 6.43535295 2 P 0 ;0,5=56,7=0.000000
L 1.68808661 6.43535295 1.68648652 6.43285276 2 P 0 ;0,5=56,7=0.000000
L 1.68648652 6.43285276 1.68595325 6.42993671 2 P 0 ;0,5=56,7=0.000000
L 1.68595325 6.42993671 1.68648652 6.42701909 2 P 0 ;0,5=56,7=0.000000
L 1.68648652 6.42701909 1.68782008 6.42493622 2 P 0 ;0,5=56,7=0.000000
L 1.68782008 6.42493622 1.68995344 6.42368652 2 P 0 ;0,5=56,7=0.000000
L 1.68995344 6.42368652 1.69181969 6.42326998 2 P 0 ;0,5=56,7=0.000000
L 1.70995325 6.42701909 1.71155295 6.42493622 2 P 0 ;0,5=56,7=0.000000
L 1.71155295 6.42493622 1.71341969 6.42368652 2 P 0 ;0,5=56,7=0.000000
L 1.71341969 6.42368652 1.71581969 6.42326998 2 P 0 ;0,5=56,7=0.000000
L 1.71581969 6.42326998 1.71822018 6.42410305 2 P 0 ;0,5=56,7=0.000000
L 1.71822018 6.42410305 1.72008642 6.42576939 2 P 0 ;0,5=56,7=0.000000
L 1.72008642 6.42576939 1.72141998 6.42868622 2 P 0 ;0,5=56,7=0.000000
L 1.72141998 6.42868622 1.72168661 6.43201959 2 P 0 ;0,5=56,7=0.000000
L 1.72168661 6.43201959 1.72115335 6.43535295 2 P 0 ;0,5=56,7=0.000000
L 1.72115335 6.43535295 1.71981978 6.43743661 2 P 0 ;0,5=56,7=0.000000
L 1.71981978 6.43743661 1.71795305 6.43910295 2 P 0 ;0,5=56,7=0.000000
L 1.71795305 6.43910295 1.71608681 6.43951949 2 P 0 ;0,5=56,7=0.000000
L 1.71608681 6.43951949 1.71421998 6.43910295 2 P 0 ;0,5=56,7=0.000000
L 1.71421998 6.43910295 1.71182008 6.43743661 2 P 0 ;0,5=56,7=0.000000
L 1.71182008 6.43743661 1.71261988 6.44826998 2 P 0 ;0,5=56,7=0.000000
L 1.71261988 6.44826998 1.71981978 6.44826998 2 P 0 ;0,5=56,7=0.000000
L 1.59691654 6.44916998 1.59691654 6.42416998 2 P 0 ;0,5=55,7=0.000000
L 1.59691654 6.42416998 1.60758337 6.42416998 2 P 0 ;0,5=55,7=0.000000
L 1.6262497 6.42416998 1.6262497 6.44916998 2 P 0 ;0,5=55,7=0.000000
L 1.6262497 6.44916998 1.6230499 6.44417028 2 P 0 ;0,5=55,7=0.000000
L 1.6230499 6.42416998 1.62944951 6.42416998 2 P 0 ;0,5=55,7=0.000000
L 1.52181004 6.42326998 1.53361998 6.42326998 1 P 0 
A 1.53361998 6.42326998 1.54148602 6.44689488 1.54148996 6.43377156 1 P 0 Y
A 1.54148602 6.44689488 1.54936998 6.42326998 1.54148996 6.43376821 1 P 0 Y
L 1.54936998 6.42326998 1.56118002 6.42326998 1 P 0 
L 1.46681969 6.42326998 1.46868642 6.42368652 2 P 0 ;0,5=56,7=0.000000
L 1.46868642 6.42368652 1.47081978 6.42493622 2 P 0 ;0,5=56,7=0.000000
L 1.47081978 6.42493622 1.47215335 6.42701909 2 P 0 ;0,5=56,7=0.000000
L 1.47215335 6.42701909 1.47268661 6.42993671 2 P 0 ;0,5=56,7=0.000000
L 1.47268661 6.42993671 1.47215335 6.43285276 2 P 0 ;0,5=56,7=0.000000
L 1.47215335 6.43285276 1.47055325 6.43535295 2 P 0 ;0,5=56,7=0.000000
L 1.47055325 6.43535295 1.46815325 6.43660344 2 P 0 ;0,5=56,7=0.000000
L 1.46815325 6.43660344 1.46548661 6.43660344 2 P 0 ;0,5=56,7=0.000000
L 1.46548661 6.43660344 1.46388652 6.43743661 2 P 0 ;0,5=56,7=0.000000
L 1.46388652 6.43743661 1.46255295 6.43951949 2 P 0 ;0,5=56,7=0.000000
L 1.46255295 6.43951949 1.46201978 6.44243632 2 P 0 ;0,5=56,7=0.000000
L 1.46201978 6.44243632 1.46282008 6.44535315 2 P 0 ;0,5=56,7=0.000000
L 1.46282008 6.44535315 1.46468632 6.44743681 2 P 0 ;0,5=56,7=0.000000
L 1.46468632 6.44743681 1.46681969 6.44826998 2 P 0 ;0,5=56,7=0.000000
L 1.46681969 6.44826998 1.46895305 6.44743681 2 P 0 ;0,5=56,7=0.000000
L 1.46895305 6.44743681 1.47081978 6.44535315 2 P 0 ;0,5=56,7=0.000000
L 1.47081978 6.44535315 1.47162008 6.44243632 2 P 0 ;0,5=56,7=0.000000
L 1.47162008 6.44243632 1.47108642 6.43951949 2 P 0 ;0,5=56,7=0.000000
L 1.47108642 6.43951949 1.46975335 6.43743661 2 P 0 ;0,5=56,7=0.000000
L 1.46975335 6.43743661 1.46815325 6.43660344 2 P 0 ;0,5=56,7=0.000000
L 1.46815325 6.43660344 1.46548661 6.43660344 2 P 0 ;0,5=56,7=0.000000
L 1.46548661 6.43660344 1.46308661 6.43535295 2 P 0 ;0,5=56,7=0.000000
L 1.46308661 6.43535295 1.46148652 6.43285276 2 P 0 ;0,5=56,7=0.000000
L 1.46148652 6.43285276 1.46095325 6.42993671 2 P 0 ;0,5=56,7=0.000000
L 1.46095325 6.42993671 1.46148652 6.42701909 2 P 0 ;0,5=56,7=0.000000
L 1.46148652 6.42701909 1.46282008 6.42493622 2 P 0 ;0,5=56,7=0.000000
L 1.46282008 6.42493622 1.46495344 6.42368652 2 P 0 ;0,5=56,7=0.000000
L 1.46495344 6.42368652 1.46681969 6.42326998 2 P 0 ;0,5=56,7=0.000000
L 1.48495325 6.42701909 1.48655295 6.42493622 2 P 0 ;0,5=56,7=0.000000
L 1.48655295 6.42493622 1.48841969 6.42368652 2 P 0 ;0,5=56,7=0.000000
L 1.48841969 6.42368652 1.49081969 6.42326998 2 P 0 ;0,5=56,7=0.000000
L 1.49081969 6.42326998 1.49322018 6.42410305 2 P 0 ;0,5=56,7=0.000000
L 1.49322018 6.42410305 1.49508642 6.42576939 2 P 0 ;0,5=56,7=0.000000
L 1.49508642 6.42576939 1.49641998 6.42868622 2 P 0 ;0,5=56,7=0.000000
L 1.49641998 6.42868622 1.49668661 6.43201959 2 P 0 ;0,5=56,7=0.000000
L 1.49668661 6.43201959 1.49615335 6.43535295 2 P 0 ;0,5=56,7=0.000000
L 1.49615335 6.43535295 1.49481978 6.43743661 2 P 0 ;0,5=56,7=0.000000
L 1.49481978 6.43743661 1.49295305 6.43910295 2 P 0 ;0,5=56,7=0.000000
L 1.49295305 6.43910295 1.49108681 6.43951949 2 P 0 ;0,5=56,7=0.000000
L 1.49108681 6.43951949 1.48921998 6.43910295 2 P 0 ;0,5=56,7=0.000000
L 1.48921998 6.43910295 1.48682008 6.43743661 2 P 0 ;0,5=56,7=0.000000
L 1.48682008 6.43743661 1.48761988 6.44826998 2 P 0 ;0,5=56,7=0.000000
L 1.48761988 6.44826998 1.49481978 6.44826998 2 P 0 ;0,5=56,7=0.000000
L 1.37191654 6.44916998 1.37191654 6.42416998 2 P 0 ;0,5=54,7=0.000000
L 1.37191654 6.42416998 1.38258337 6.42416998 2 P 0 ;0,5=54,7=0.000000
L 1.39538327 6.42916959 1.39698297 6.42625285 2 P 0 ;0,5=54,7=0.000000
L 1.39698297 6.42625285 1.39911634 6.42458652 2 P 0 ;0,5=54,7=0.000000
L 1.39911634 6.42458652 1.40151683 6.42416998 2 P 0 ;0,5=54,7=0.000000
L 1.40151683 6.42416998 1.4036502 6.42458652 2 P 0 ;0,5=54,7=0.000000
L 1.4036502 6.42458652 1.40578356 6.42666939 2 P 0 ;0,5=54,7=0.000000
L 1.40578356 6.42666939 1.40711663 6.42916959 2 P 0 ;0,5=54,7=0.000000
L 1.40711663 6.42916959 1.40738317 6.43166988 2 P 0 ;0,5=54,7=0.000000
L 1.40738317 6.43166988 1.40685 6.43458593 2 P 0 ;0,5=54,7=0.000000
L 1.40685 6.43458593 1.40498327 6.43666959 2 P 0 ;0,5=54,7=0.000000
L 1.40498327 6.43666959 1.40311644 6.43750344 2 P 0 ;0,5=54,7=0.000000
L 1.40311644 6.43750344 1.40071654 6.43750344 2 P 0 ;0,5=54,7=0.000000
L 1.40311644 6.43750344 1.40471663 6.43875325 2 P 0 ;0,5=54,7=0.000000
L 1.40471663 6.43875325 1.4060501 6.44083612 2 P 0 ;0,5=54,7=0.000000
L 1.4060501 6.44083612 1.40658337 6.44333632 2 P 0 ;0,5=54,7=0.000000
L 1.40658337 6.44333632 1.4060501 6.44583652 2 P 0 ;0,5=54,7=0.000000
L 1.4060501 6.44583652 1.40471663 6.44791939 2 P 0 ;0,5=54,7=0.000000
L 1.40471663 6.44791939 1.40231663 6.44916998 2 P 0 ;0,5=54,7=0.000000
L 1.40231663 6.44916998 1.39991663 6.44875335 2 P 0 ;0,5=54,7=0.000000
L 1.39991663 6.44875335 1.39751663 6.44708632 2 P 0 ;0,5=54,7=0.000000
L 1.29681004 6.42326998 1.30861998 6.42326998 1 P 0 
A 1.30861998 6.42326998 1.31648602 6.44689488 1.31648996 6.43377156 1 P 0 Y
A 1.31648602 6.44689488 1.32436998 6.42326998 1.31648996 6.43376821 1 P 0 Y
L 1.32436998 6.42326998 1.33618002 6.42326998 1 P 0 
L 1.24181969 6.42326998 1.24368642 6.42368652 2 P 0 ;0,5=56,7=0.000000
L 1.24368642 6.42368652 1.24581978 6.42493622 2 P 0 ;0,5=56,7=0.000000
L 1.24581978 6.42493622 1.24715335 6.42701909 2 P 0 ;0,5=56,7=0.000000
L 1.24715335 6.42701909 1.24768661 6.42993671 2 P 0 ;0,5=56,7=0.000000
L 1.24768661 6.42993671 1.24715335 6.43285276 2 P 0 ;0,5=56,7=0.000000
L 1.24715335 6.43285276 1.24555325 6.43535295 2 P 0 ;0,5=56,7=0.000000
L 1.24555325 6.43535295 1.24315325 6.43660344 2 P 0 ;0,5=56,7=0.000000
L 1.24315325 6.43660344 1.24048661 6.43660344 2 P 0 ;0,5=56,7=0.000000
L 1.24048661 6.43660344 1.23888652 6.43743661 2 P 0 ;0,5=56,7=0.000000
L 1.23888652 6.43743661 1.23755295 6.43951949 2 P 0 ;0,5=56,7=0.000000
L 1.23755295 6.43951949 1.23701978 6.44243632 2 P 0 ;0,5=56,7=0.000000
L 1.23701978 6.44243632 1.23782008 6.44535315 2 P 0 ;0,5=56,7=0.000000
L 1.23782008 6.44535315 1.23968632 6.44743681 2 P 0 ;0,5=56,7=0.000000
L 1.23968632 6.44743681 1.24181969 6.44826998 2 P 0 ;0,5=56,7=0.000000
L 1.24181969 6.44826998 1.24395305 6.44743681 2 P 0 ;0,5=56,7=0.000000
L 1.24395305 6.44743681 1.24581978 6.44535315 2 P 0 ;0,5=56,7=0.000000
L 1.24581978 6.44535315 1.24662008 6.44243632 2 P 0 ;0,5=56,7=0.000000
L 1.24662008 6.44243632 1.24608642 6.43951949 2 P 0 ;0,5=56,7=0.000000
L 1.24608642 6.43951949 1.24475335 6.43743661 2 P 0 ;0,5=56,7=0.000000
L 1.24475335 6.43743661 1.24315325 6.43660344 2 P 0 ;0,5=56,7=0.000000
L 1.24315325 6.43660344 1.24048661 6.43660344 2 P 0 ;0,5=56,7=0.000000
L 1.24048661 6.43660344 1.23808661 6.43535295 2 P 0 ;0,5=56,7=0.000000
L 1.23808661 6.43535295 1.23648652 6.43285276 2 P 0 ;0,5=56,7=0.000000
L 1.23648652 6.43285276 1.23595325 6.42993671 2 P 0 ;0,5=56,7=0.000000
L 1.23595325 6.42993671 1.23648652 6.42701909 2 P 0 ;0,5=56,7=0.000000
L 1.23648652 6.42701909 1.23782008 6.42493622 2 P 0 ;0,5=56,7=0.000000
L 1.23782008 6.42493622 1.23995344 6.42368652 2 P 0 ;0,5=56,7=0.000000
L 1.23995344 6.42368652 1.24181969 6.42326998 2 P 0 ;0,5=56,7=0.000000
L 1.25995325 6.42701909 1.26155295 6.42493622 2 P 0 ;0,5=56,7=0.000000
L 1.26155295 6.42493622 1.26341969 6.42368652 2 P 0 ;0,5=56,7=0.000000
L 1.26341969 6.42368652 1.26581969 6.42326998 2 P 0 ;0,5=56,7=0.000000
L 1.26581969 6.42326998 1.26822018 6.42410305 2 P 0 ;0,5=56,7=0.000000
L 1.26822018 6.42410305 1.27008642 6.42576939 2 P 0 ;0,5=56,7=0.000000
L 1.27008642 6.42576939 1.27141998 6.42868622 2 P 0 ;0,5=56,7=0.000000
L 1.27141998 6.42868622 1.27168661 6.43201959 2 P 0 ;0,5=56,7=0.000000
L 1.27168661 6.43201959 1.27115335 6.43535295 2 P 0 ;0,5=56,7=0.000000
L 1.27115335 6.43535295 1.26981978 6.43743661 2 P 0 ;0,5=56,7=0.000000
L 1.26981978 6.43743661 1.26795305 6.43910295 2 P 0 ;0,5=56,7=0.000000
L 1.26795305 6.43910295 1.26608681 6.43951949 2 P 0 ;0,5=56,7=0.000000
L 1.26608681 6.43951949 1.26421998 6.43910295 2 P 0 ;0,5=56,7=0.000000
L 1.26421998 6.43910295 1.26182008 6.43743661 2 P 0 ;0,5=56,7=0.000000
L 1.26182008 6.43743661 1.26261988 6.44826998 2 P 0 ;0,5=56,7=0.000000
L 1.26261988 6.44826998 1.26981978 6.44826998 2 P 0 ;0,5=56,7=0.000000
L 1.14691654 6.44916998 1.14691654 6.42416998 2 P 0 ;0,5=53,7=0.000000
L 1.14691654 6.42416998 1.15758337 6.42416998 2 P 0 ;0,5=53,7=0.000000
L 1.17038327 6.42791909 1.17198297 6.42583622 2 P 0 ;0,5=53,7=0.000000
L 1.17198297 6.42583622 1.1738497 6.42458652 2 P 0 ;0,5=53,7=0.000000
L 1.1738497 6.42458652 1.1762497 6.42416998 2 P 0 ;0,5=53,7=0.000000
L 1.1762497 6.42416998 1.1786502 6.42500305 2 P 0 ;0,5=53,7=0.000000
L 1.1786502 6.42500305 1.18051644 6.42666939 2 P 0 ;0,5=53,7=0.000000
L 1.18051644 6.42666939 1.18185 6.42958622 2 P 0 ;0,5=53,7=0.000000
L 1.18185 6.42958622 1.18211663 6.43291959 2 P 0 ;0,5=53,7=0.000000
L 1.18211663 6.43291959 1.18158337 6.43625295 2 P 0 ;0,5=53,7=0.000000
L 1.18158337 6.43625295 1.1802498 6.43833661 2 P 0 ;0,5=53,7=0.000000
L 1.1802498 6.43833661 1.17838307 6.44000295 2 P 0 ;0,5=53,7=0.000000
L 1.17838307 6.44000295 1.17651683 6.44041949 2 P 0 ;0,5=53,7=0.000000
L 1.17651683 6.44041949 1.17465 6.44000295 2 P 0 ;0,5=53,7=0.000000
L 1.17465 6.44000295 1.1722501 6.43833661 2 P 0 ;0,5=53,7=0.000000
L 1.1722501 6.43833661 1.1730499 6.44916998 2 P 0 ;0,5=53,7=0.000000
L 1.1730499 6.44916998 1.1802498 6.44916998 2 P 0 ;0,5=53,7=0.000000
L 0.0349 -2.3038 0.0349 -1.0038 7 P 0 ;0
L 0.0349 -1.0038 4.5349 -1.0038 7 P 0 ;0
L 4.5349 -1.0038 4.5349 -2.3038 7 P 0 ;0
L 4.5349 -2.3038 0.0349 -2.3038 7 P 0 ;0
L 0.0349 -1.6038 4.5349 -1.6038 7 P 0 ;0
L 0.0349 -1.8038 4.5349 -1.8038 7 P 0 ;0
L 2.4349 -2.1038 4.0349 -2.1038 7 P 0 ;0
L 2.4349 -2.3038 2.4349 -1.8038 7 P 0 ;0
L 3.2349 -2.1038 3.2349 -1.8038 7 P 0 ;0
L 4.0349 -2.3038 4.0349 -1.8038 7 P 0 ;0
L 0.0723999 -1.6844687 0.07906663 -1.69030079 2 P 0 ;0,5=57,7=0.000000
L 0.07906663 -1.69030079 0.08656654 -1.6938 2 P 0 ;0,5=57,7=0.000000
L 0.08656654 -1.6938 0.09323337 -1.6938 2 P 0 ;0,5=57,7=0.000000
L 0.09323337 -1.6938 0.0999001 -1.69030079 2 P 0 ;0,5=57,7=0.000000
L 0.0999001 -1.69030079 0.10490059 -1.6844687 2 P 0 ;0,5=57,7=0.000000
L 0.10490059 -1.6844687 0.1074 -1.67629951 2 P 0 ;0,5=57,7=0.000000
L 0.1074 -1.67629951 0.10573376 -1.66813455 2 P 0 ;0,5=57,7=0.000000
L 0.10573376 -1.66813455 0.10156644 -1.66113396 2 P 0 ;0,5=57,7=0.000000
L 0.10156644 -1.66113396 0.09406654 -1.65646614 2 P 0 ;0,5=57,7=0.000000
L 0.09406654 -1.65646614 0.08406713 -1.65413327 2 P 0 ;0,5=57,7=0.000000
L 0.08406713 -1.65413327 0.07823346 -1.64946762 2 P 0 ;0,5=57,7=0.000000
L 0.07823346 -1.64946762 0.07573248 -1.64130059 2 P 0 ;0,5=57,7=0.000000
L 0.07573248 -1.64130059 0.0774003 -1.63313356 2 P 0 ;0,5=57,7=0.000000
L 0.0774003 -1.63313356 0.08156614 -1.62730148 2 P 0 ;0,5=57,7=0.000000
L 0.08156614 -1.62730148 0.0873997 -1.6238 2 P 0 ;0,5=57,7=0.000000
L 0.0873997 -1.6238 0.09323337 -1.6238 2 P 0 ;0,5=57,7=0.000000
L 0.09323337 -1.6238 0.09906693 -1.62613287 2 P 0 ;0,5=57,7=0.000000
L 0.09906693 -1.62613287 0.10406742 -1.63196713 2 P 0 ;0,5=57,7=0.000000
L 0.1383999 -1.6938 0.1383999 -1.6238 2 P 0 ;0,5=57,7=0.000000
L 0.1734 -1.6238 0.1734 -1.6938 2 P 0 ;0,5=57,7=0.000000
L 0.1734 -1.65880108 0.1383999 -1.65880108 2 P 0 ;0,5=57,7=0.000000
L 0.23856683 -1.6938 0.20523307 -1.6938 2 P 0 ;0,5=57,7=0.000000
L 0.20523307 -1.6938 0.20523307 -1.6238 2 P 0 ;0,5=57,7=0.000000
L 0.20523307 -1.6238 0.23856683 -1.6238 2 P 0 ;0,5=57,7=0.000000
L 0.22523337 -1.65763258 0.20523307 -1.65763258 2 P 0 ;0,5=57,7=0.000000
L 0.30456683 -1.6938 0.27123307 -1.6938 2 P 0 ;0,5=57,7=0.000000
L 0.27123307 -1.6938 0.27123307 -1.6238 2 P 0 ;0,5=57,7=0.000000
L 0.27123307 -1.6238 0.30456683 -1.6238 2 P 0 ;0,5=57,7=0.000000
L 0.29123337 -1.65763258 0.27123307 -1.65763258 2 P 0 ;0,5=57,7=0.000000
L 0.35389921 -1.6238 0.35389921 -1.6938 2 P 0 ;0,5=57,7=0.000000
L 0.33473356 -1.6238 0.37306634 -1.6238 2 P 0 ;0,5=57,7=0.000000
L 0.09489921 -1.7188 0.09489921 -1.7888 2 P 0 ;0,5=58,7=0.000000
L 0.07573356 -1.7188 0.11406634 -1.7188 2 P 0 ;0,5=58,7=0.000000
L 0.1508998 -1.7188 0.17089862 -1.7188 2 P 0 ;0,5=58,7=0.000000
L 0.16089921 -1.7188 0.16089921 -1.7888 2 P 0 ;0,5=58,7=0.000000
L 0.1508998 -1.7888 0.17089862 -1.7888 2 P 0 ;0,5=58,7=0.000000
L 0.22689921 -1.7188 0.22689921 -1.7888 2 P 0 ;0,5=58,7=0.000000
L 0.20773356 -1.7188 0.24606634 -1.7188 2 P 0 ;0,5=58,7=0.000000
L 0.27623307 -1.7188 0.27623307 -1.7888 2 P 0 ;0,5=58,7=0.000000
L 0.27623307 -1.7888 0.30956683 -1.7888 2 P 0 ;0,5=58,7=0.000000
L 0.37556683 -1.7888 0.34223307 -1.7888 2 P 0 ;0,5=58,7=0.000000
L 0.34223307 -1.7888 0.34223307 -1.7188 2 P 0 ;0,5=58,7=0.000000
L 0.34223307 -1.7188 0.37556683 -1.7188 2 P 0 ;0,5=58,7=0.000000
L 0.36223337 -1.75263258 0.34223307 -1.75263258 2 P 0 ;0,5=58,7=0.000000
L 2.5438999 -1.96813563 2.5519 -1.97480089 2 P 0 ;0,5=59,7=0.000000
L 2.5519 -1.97480089 2.5608999 -1.9788 2 P 0 ;0,5=59,7=0.000000
L 2.5608999 -1.9788 2.5689 -1.9788 2 P 0 ;0,5=59,7=0.000000
L 2.5689 -1.9788 2.5769001 -1.97480089 2 P 0 ;0,5=59,7=0.000000
L 2.5769001 -1.97480089 2.58290069 -1.96813563 2 P 0 ;0,5=59,7=0.000000
L 2.58290069 -1.96813563 2.5859 -1.95879941 2 P 0 ;0,5=59,7=0.000000
L 2.5859 -1.95879941 2.58390049 -1.94946811 2 P 0 ;0,5=59,7=0.000000
L 2.58390049 -1.94946811 2.5788997 -1.94146732 2 P 0 ;0,5=59,7=0.000000
L 2.5788997 -1.94146732 2.5698998 -1.93613278 2 P 0 ;0,5=59,7=0.000000
L 2.5698998 -1.93613278 2.55790049 -1.93346663 2 P 0 ;0,5=59,7=0.000000
L 2.55790049 -1.93346663 2.5509002 -1.92813445 2 P 0 ;0,5=59,7=0.000000
L 2.5509002 -1.92813445 2.54789902 -1.91880069 2 P 0 ;0,5=59,7=0.000000
L 2.54789902 -1.91880069 2.54990039 -1.90946683 2 P 0 ;0,5=59,7=0.000000
L 2.54990039 -1.90946683 2.55489931 -1.90280167 2 P 0 ;0,5=59,7=0.000000
L 2.55489931 -1.90280167 2.5618997 -1.8988 2 P 0 ;0,5=59,7=0.000000
L 2.5618997 -1.8988 2.5689 -1.8988 2 P 0 ;0,5=59,7=0.000000
L 2.5689 -1.8988 2.57590039 -1.90146614 2 P 0 ;0,5=59,7=0.000000
L 2.57590039 -1.90146614 2.58190089 -1.90813386 2 P 0 ;0,5=59,7=0.000000
L 2.6648998 -1.90546772 2.65889931 -1.90146614 2 P 0 ;0,5=59,7=0.000000
L 2.65889931 -1.90146614 2.65190079 -1.8988 2 P 0 ;0,5=59,7=0.000000
L 2.65190079 -1.8988 2.64390069 -1.8988 2 P 0 ;0,5=59,7=0.000000
L 2.64390069 -1.8988 2.63489892 -1.90280167 2 P 0 ;0,5=59,7=0.000000
L 2.63489892 -1.90280167 2.62790039 -1.90946683 2 P 0 ;0,5=59,7=0.000000
L 2.62790039 -1.90946683 2.62289961 -1.91746762 2 P 0 ;0,5=59,7=0.000000
L 2.62289961 -1.91746762 2.61889862 -1.93080049 2 P 0 ;0,5=59,7=0.000000
L 2.61889862 -1.93080049 2.61789892 -1.94280039 2 P 0 ;0,5=59,7=0.000000
L 2.61789892 -1.94280039 2.6199003 -1.9548003 2 P 0 ;0,5=59,7=0.000000
L 2.6199003 -1.9548003 2.62289961 -1.96280098 2 P 0 ;0,5=59,7=0.000000
L 2.62289961 -1.96280098 2.6289002 -1.97080177 2 P 0 ;0,5=59,7=0.000000
L 2.6289002 -1.97080177 2.63590049 -1.97613396 2 P 0 ;0,5=59,7=0.000000
L 2.63590049 -1.97613396 2.64289902 -1.9788 2 P 0 ;0,5=59,7=0.000000
L 2.64289902 -1.9788 2.64989941 -1.9788 2 P 0 ;0,5=59,7=0.000000
L 2.64989941 -1.9788 2.6568997 -1.97613396 2 P 0 ;0,5=59,7=0.000000
L 2.6568997 -1.97613396 2.6629003 -1.97213484 2 P 0 ;0,5=59,7=0.000000
L 2.6629003 -1.97213484 2.66790098 -1.96680266 2 P 0 ;0,5=59,7=0.000000
L 2.69589892 -1.9788 2.72089902 -1.8988 2 P 0 ;0,5=59,7=0.000000
L 2.72089902 -1.8988 2.74590098 -1.9788 2 P 0 ;0,5=59,7=0.000000
L 2.73689931 -1.95080118 2.70489882 -1.95080118 2 P 0 ;0,5=59,7=0.000000
L 2.77889961 -1.8988 2.77889961 -1.9788 2 P 0 ;0,5=59,7=0.000000
L 2.77889961 -1.9788 2.8189003 -1.9788 2 P 0 ;0,5=59,7=0.000000
L 2.8969003 -1.9788 2.85689961 -1.9788 2 P 0 ;0,5=59,7=0.000000
L 2.85689961 -1.9788 2.85689961 -1.8988 2 P 0 ;0,5=59,7=0.000000
L 2.85689961 -1.8988 2.8969003 -1.8988 2 P 0 ;0,5=59,7=0.000000
L 2.8809 -1.93746575 2.85689961 -1.93746575 2 P 0 ;0,5=59,7=0.000000
L 3.03289902 -1.9788 3.03289902 -1.8988 2 P 0 ;0,5=59,7=0.000000
L 3.03289902 -1.8988 3.0208998 -1.91479911 2 P 0 ;0,5=59,7=0.000000
L 3.0208998 -1.9788 3.04489833 -1.9788 2 P 0 ;0,5=59,7=0.000000
L 3.11089902 -1.98146604 3.10889951 -1.98013297 2 P 0 ;0,5=59,7=0.000000
L 3.10889951 -1.98013297 3.10889951 -1.97746703 2 P 0 ;0,5=59,7=0.000000
L 3.10889951 -1.97746703 3.11089902 -1.97613396 2 P 0 ;0,5=59,7=0.000000
L 3.11089902 -1.97613396 3.11290039 -1.97746703 2 P 0 ;0,5=59,7=0.000000
L 3.11290039 -1.97746703 3.11290039 -1.98013297 2 P 0 ;0,5=59,7=0.000000
L 3.11290039 -1.98013297 3.11089902 -1.98146604 2 P 0 ;0,5=59,7=0.000000
L 3.11089902 -1.945469 3.10889951 -1.94413346 2 P 0 ;0,5=59,7=0.000000
L 3.10889951 -1.94413346 3.10889951 -1.94146732 2 P 0 ;0,5=59,7=0.000000
L 3.10889951 -1.94146732 3.11089902 -1.94013435 2 P 0 ;0,5=59,7=0.000000
L 3.11089902 -1.94013435 3.11290039 -1.94146732 2 P 0 ;0,5=59,7=0.000000
L 3.11290039 -1.94146732 3.11290039 -1.94413346 2 P 0 ;0,5=59,7=0.000000
L 3.11290039 -1.94413346 3.11089902 -1.945469 2 P 0 ;0,5=59,7=0.000000
L 3.18889902 -1.9788 3.18889902 -1.8988 2 P 0 ;0,5=59,7=0.000000
L 3.18889902 -1.8988 3.1768998 -1.91479911 2 P 0 ;0,5=59,7=0.000000
L 3.1768998 -1.9788 3.20089833 -1.9788 2 P 0 ;0,5=59,7=0.000000
L 2.5138999 -2.23313563 2.5219 -2.23980089 2 P 0 ;0,5=57,7=0.000000
L 2.5219 -2.23980089 2.5308999 -2.2438 2 P 0 ;0,5=57,7=0.000000
L 2.5308999 -2.2438 2.5389 -2.2438 2 P 0 ;0,5=57,7=0.000000
L 2.5389 -2.2438 2.5469001 -2.23980089 2 P 0 ;0,5=57,7=0.000000
L 2.5469001 -2.23980089 2.55290069 -2.23313563 2 P 0 ;0,5=57,7=0.000000
L 2.55290069 -2.23313563 2.5559 -2.22379941 2 P 0 ;0,5=57,7=0.000000
L 2.5559 -2.22379941 2.55390049 -2.21446811 2 P 0 ;0,5=57,7=0.000000
L 2.55390049 -2.21446811 2.5488997 -2.20646732 2 P 0 ;0,5=57,7=0.000000
L 2.5488997 -2.20646732 2.5398998 -2.20113278 2 P 0 ;0,5=57,7=0.000000
L 2.5398998 -2.20113278 2.52790049 -2.19846663 2 P 0 ;0,5=57,7=0.000000
L 2.52790049 -2.19846663 2.5209002 -2.19313445 2 P 0 ;0,5=57,7=0.000000
L 2.5209002 -2.19313445 2.51789902 -2.18380069 2 P 0 ;0,5=57,7=0.000000
L 2.51789902 -2.18380069 2.51990039 -2.17446683 2 P 0 ;0,5=57,7=0.000000
L 2.51990039 -2.17446683 2.52489931 -2.16780167 2 P 0 ;0,5=57,7=0.000000
L 2.52489931 -2.16780167 2.5318997 -2.1638 2 P 0 ;0,5=57,7=0.000000
L 2.5318997 -2.1638 2.5389 -2.1638 2 P 0 ;0,5=57,7=0.000000
L 2.5389 -2.1638 2.54590039 -2.16646614 2 P 0 ;0,5=57,7=0.000000
L 2.54590039 -2.16646614 2.55190089 -2.17313386 2 P 0 ;0,5=57,7=0.000000
L 2.5918999 -2.2438 2.5918999 -2.1638 2 P 0 ;0,5=57,7=0.000000
L 2.6339 -2.1638 2.6339 -2.2438 2 P 0 ;0,5=57,7=0.000000
L 2.6339 -2.20380128 2.5918999 -2.20380128 2 P 0 ;0,5=57,7=0.000000
L 2.7109003 -2.2438 2.67089961 -2.2438 2 P 0 ;0,5=57,7=0.000000
L 2.67089961 -2.2438 2.67089961 -2.1638 2 P 0 ;0,5=57,7=0.000000
L 2.67089961 -2.1638 2.7109003 -2.1638 2 P 0 ;0,5=57,7=0.000000
L 2.6949 -2.20246575 2.67089961 -2.20246575 2 P 0 ;0,5=57,7=0.000000
L 2.7889003 -2.2438 2.74889961 -2.2438 2 P 0 ;0,5=57,7=0.000000
L 2.74889961 -2.2438 2.74889961 -2.1638 2 P 0 ;0,5=57,7=0.000000
L 2.74889961 -2.1638 2.7889003 -2.1638 2 P 0 ;0,5=57,7=0.000000
L 2.7729 -2.20246575 2.74889961 -2.20246575 2 P 0 ;0,5=57,7=0.000000
L 2.84689902 -2.1638 2.84689902 -2.2438 2 P 0 ;0,5=57,7=0.000000
L 2.8239003 -2.1638 2.86989961 -2.1638 2 P 0 ;0,5=57,7=0.000000
L 3.29489961 -1.9238 3.29489961 -2.0038 2 P 0 ;0,5=60,7=0.000000
L 3.29489961 -2.0038 3.3349003 -2.0038 2 P 0 ;0,5=60,7=0.000000
L 3.36789892 -2.0038 3.39289902 -1.9238 2 P 0 ;0,5=60,7=0.000000
L 3.39289902 -1.9238 3.41790098 -2.0038 2 P 0 ;0,5=60,7=0.000000
L 3.40889931 -1.97580118 3.37689882 -1.97580118 2 P 0 ;0,5=60,7=0.000000
L 3.47089902 -2.0038 3.47089902 -1.96780039 2 P 0 ;0,5=60,7=0.000000
L 3.47089902 -1.96780039 3.45089961 -1.9238 2 P 0 ;0,5=60,7=0.000000
L 3.4909003 -1.9238 3.47089902 -1.96780039 2 P 0 ;0,5=60,7=0.000000
L 3.5689003 -2.0038 3.52889961 -2.0038 2 P 0 ;0,5=60,7=0.000000
L 3.52889961 -2.0038 3.52889961 -1.9238 2 P 0 ;0,5=60,7=0.000000
L 3.52889961 -1.9238 3.5689003 -1.9238 2 P 0 ;0,5=60,7=0.000000
L 3.5529 -1.96246575 3.52889961 -1.96246575 2 P 0 ;0,5=60,7=0.000000
L 3.60689961 -2.0038 3.60689961 -1.9238 2 P 0 ;0,5=60,7=0.000000
L 3.60689961 -1.9238 3.6318998 -1.9238 2 P 0 ;0,5=60,7=0.000000
L 3.6318998 -1.9238 3.6398999 -1.92780167 2 P 0 ;0,5=60,7=0.000000
L 3.6398999 -1.92780167 3.64490069 -1.93313386 2 P 0 ;0,5=60,7=0.000000
L 3.64490069 -1.93313386 3.6469003 -1.94380069 2 P 0 ;0,5=60,7=0.000000
L 3.6469003 -1.94380069 3.64490069 -1.95446752 2 P 0 ;0,5=60,7=0.000000
L 3.64490069 -1.95446752 3.6389001 -1.96113278 2 P 0 ;0,5=60,7=0.000000
L 3.6389001 -1.96113278 3.6318998 -1.96513435 2 P 0 ;0,5=60,7=0.000000
L 3.6318998 -1.96513435 3.60689961 -1.96513435 2 P 0 ;0,5=60,7=0.000000
L 3.6318998 -1.96513435 3.6469003 -2.0038 2 P 0 ;0,5=60,7=0.000000
L 3.33989902 -2.2538 3.33189892 -2.25246703 2 P 0 ;0,5=61,7=0.000000
L 3.33189892 -2.25246703 3.32490039 -2.24713484 2 P 0 ;0,5=61,7=0.000000
L 3.32490039 -2.24713484 3.3188999 -2.23913406 2 P 0 ;0,5=61,7=0.000000
L 3.3188999 -2.23913406 3.31489892 -2.2298003 2 P 0 ;0,5=61,7=0.000000
L 3.31489892 -2.2298003 3.31289931 -2.21913346 2 P 0 ;0,5=61,7=0.000000
L 3.31289931 -2.21913346 3.31289931 -2.20846663 2 P 0 ;0,5=61,7=0.000000
L 3.31289931 -2.20846663 3.31489892 -2.1977998 2 P 0 ;0,5=61,7=0.000000
L 3.31489892 -2.1977998 3.3188999 -2.18846604 2 P 0 ;0,5=61,7=0.000000
L 3.3188999 -2.18846604 3.32490039 -2.18046772 2 P 0 ;0,5=61,7=0.000000
L 3.32490039 -2.18046772 3.33189892 -2.17513307 2 P 0 ;0,5=61,7=0.000000
L 3.33189892 -2.17513307 3.33989902 -2.1738 2 P 0 ;0,5=61,7=0.000000
L 3.33989902 -2.1738 3.34789911 -2.17513307 2 P 0 ;0,5=61,7=0.000000
L 3.34789911 -2.17513307 3.35489951 -2.18046772 2 P 0 ;0,5=61,7=0.000000
L 3.35489951 -2.18046772 3.3609 -2.18846604 2 P 0 ;0,5=61,7=0.000000
L 3.3609 -2.18846604 3.36490098 -2.1977998 2 P 0 ;0,5=61,7=0.000000
L 3.36490098 -2.1977998 3.36690059 -2.20846663 2 P 0 ;0,5=61,7=0.000000
L 3.36690059 -2.20846663 3.36690059 -2.21913346 2 P 0 ;0,5=61,7=0.000000
L 3.36690059 -2.21913346 3.36490098 -2.2298003 2 P 0 ;0,5=61,7=0.000000
L 3.36490098 -2.2298003 3.3609 -2.23913406 2 P 0 ;0,5=61,7=0.000000
L 3.3609 -2.23913406 3.35489951 -2.24713484 2 P 0 ;0,5=61,7=0.000000
L 3.35489951 -2.24713484 3.34789911 -2.25246703 2 P 0 ;0,5=61,7=0.000000
L 3.34789911 -2.25246703 3.33989902 -2.2538 2 P 0 ;0,5=61,7=0.000000
L 3.39889941 -2.2538 3.39889941 -2.1738 2 P 0 ;0,5=61,7=0.000000
L 3.39889941 -2.1738 3.43690049 -2.1738 2 P 0 ;0,5=61,7=0.000000
L 3.4228998 -2.21246575 3.39889941 -2.21246575 2 P 0 ;0,5=61,7=0.000000
L 0.16489872 -1.0538 0.16489872 -1.1538 2 P 0 ;0,5=58,7=0.000000
L 0.13423376 -1.0538 0.19556614 -1.0538 2 P 0 ;0,5=58,7=0.000000
L 0.2588997 -1.0538 0.29089774 -1.0538 2 P 0 ;0,5=58,7=0.000000
L 0.27489872 -1.0538 0.27489872 -1.1538 2 P 0 ;0,5=58,7=0.000000
L 0.2588997 -1.1538 0.29089774 -1.1538 2 P 0 ;0,5=58,7=0.000000
L 0.38489872 -1.0538 0.38489872 -1.1538 2 P 0 ;0,5=58,7=0.000000
L 0.35423376 -1.0538 0.41556614 -1.0538 2 P 0 ;0,5=58,7=0.000000
L 0.46823287 -1.0538 0.46823287 -1.1538 2 P 0 ;0,5=58,7=0.000000
L 0.46823287 -1.1538 0.52156703 -1.1538 2 P 0 ;0,5=58,7=0.000000
L 0.63156703 -1.1538 0.57823287 -1.1538 2 P 0 ;0,5=58,7=0.000000
L 0.57823287 -1.1538 0.57823287 -1.0538 2 P 0 ;0,5=58,7=0.000000
L 0.57823287 -1.0538 0.63156703 -1.0538 2 P 0 ;0,5=58,7=0.000000
L 0.61023337 -1.10213219 0.57823287 -1.10213219 2 P 0 ;0,5=58,7=0.000000
L 4.18989892 -1.9538 4.21489902 -1.8738 2 P 0 ;0,5=62,7=0.000000
L 4.21489902 -1.8738 4.23990098 -1.9538 2 P 0 ;0,5=62,7=0.000000
L 4.23089931 -1.92580118 4.19889882 -1.92580118 2 P 0 ;0,5=62,7=0.000000
L 4.27289961 -1.9538 4.27289961 -1.8738 2 P 0 ;0,5=62,7=0.000000
L 4.27289961 -1.8738 4.2978998 -1.8738 2 P 0 ;0,5=62,7=0.000000
L 4.2978998 -1.8738 4.3058999 -1.87780167 2 P 0 ;0,5=62,7=0.000000
L 4.3058999 -1.87780167 4.31090069 -1.88313386 2 P 0 ;0,5=62,7=0.000000
L 4.31090069 -1.88313386 4.3129003 -1.89380069 2 P 0 ;0,5=62,7=0.000000
L 4.3129003 -1.89380069 4.31090069 -1.90446752 2 P 0 ;0,5=62,7=0.000000
L 4.31090069 -1.90446752 4.3049001 -1.91113278 2 P 0 ;0,5=62,7=0.000000
L 4.3049001 -1.91113278 4.2978998 -1.91513435 2 P 0 ;0,5=62,7=0.000000
L 4.2978998 -1.91513435 4.27289961 -1.91513435 2 P 0 ;0,5=62,7=0.000000
L 4.2978998 -1.91513435 4.3129003 -1.9538 2 P 0 ;0,5=62,7=0.000000
L 4.37089902 -1.8738 4.37089902 -1.9538 2 P 0 ;0,5=62,7=0.000000
L 4.3479003 -1.8738 4.39389961 -1.8738 2 P 0 ;0,5=62,7=0.000000
L 3.61989892 -2.2538 3.61989892 -2.1638 2 P 0 ;0,5=63,7=0.000000
L 3.61989892 -2.1638 3.6058997 -2.18179892 2 P 0 ;0,5=63,7=0.000000
L 3.6058997 -2.2538 3.63389803 -2.2538 2 P 0 ;0,5=63,7=0.000000
L 3.68773268 -2.17879961 3.69473337 -2.16980148 2 P 0 ;0,5=63,7=0.000000
L 3.69473337 -2.16980148 3.70290039 -2.1652997 2 P 0 ;0,5=63,7=0.000000
L 3.70290039 -2.1652997 3.71223386 -2.1638 2 P 0 ;0,5=63,7=0.000000
L 3.71223386 -2.1638 3.7239002 -2.16679941 2 P 0 ;0,5=63,7=0.000000
L 3.7239002 -2.16679941 3.73206722 -2.17430059 2 P 0 ;0,5=63,7=0.000000
L 3.73206722 -2.17430059 3.7344001 -2.18329862 2 P 0 ;0,5=63,7=0.000000
L 3.7344001 -2.18329862 3.73323366 -2.19230217 2 P 0 ;0,5=63,7=0.000000
L 3.73323366 -2.19230217 3.72856585 -2.19980059 2 P 0 ;0,5=63,7=0.000000
L 3.72856585 -2.19980059 3.70523317 -2.2148001 2 P 0 ;0,5=63,7=0.000000
L 3.70523317 -2.2148001 3.69473337 -2.22530069 2 P 0 ;0,5=63,7=0.000000
L 3.69473337 -2.22530069 3.68773268 -2.24030295 2 P 0 ;0,5=63,7=0.000000
L 3.68773268 -2.24030295 3.6853998 -2.2538 2 P 0 ;0,5=63,7=0.000000
L 3.6853998 -2.2538 3.7344001 -2.2538 2 P 0 ;0,5=63,7=0.000000
L 3.81989892 -2.0038 3.81989892 -1.9138 2 P 0 ;0,5=64,7=0.000000
L 3.81989892 -1.9138 3.8058997 -1.93179892 2 P 0 ;0,5=64,7=0.000000
L 3.8058997 -2.0038 3.83389803 -2.0038 2 P 0 ;0,5=64,7=0.000000
L 0.51989892 -1.6638 0.51989892 -1.7538 2 P 0 ;0,5=65,7=0.000000
L 0.49306703 -1.6638 0.54673287 -1.6638 2 P 0 ;0,5=65,7=0.000000
L 0.60989892 -1.7538 0.60056545 -1.75230039 2 P 0 ;0,5=65,7=0.000000
L 0.60056545 -1.75230039 0.59240049 -1.74630167 2 P 0 ;0,5=65,7=0.000000
L 0.59240049 -1.74630167 0.5853998 -1.73730079 2 P 0 ;0,5=65,7=0.000000
L 0.5853998 -1.73730079 0.58073209 -1.7268003 2 P 0 ;0,5=65,7=0.000000
L 0.58073209 -1.7268003 0.57839921 -1.7148001 2 P 0 ;0,5=65,7=0.000000
L 0.57839921 -1.7148001 0.57839921 -1.7028 2 P 0 ;0,5=65,7=0.000000
L 0.57839921 -1.7028 0.58073209 -1.6907998 2 P 0 ;0,5=65,7=0.000000
L 0.58073209 -1.6907998 0.5853998 -1.68029931 2 P 0 ;0,5=65,7=0.000000
L 0.5853998 -1.68029931 0.59240049 -1.67130118 2 P 0 ;0,5=65,7=0.000000
L 0.59240049 -1.67130118 0.60056545 -1.6652997 2 P 0 ;0,5=65,7=0.000000
L 0.60056545 -1.6652997 0.60989892 -1.6638 2 P 0 ;0,5=65,7=0.000000
L 0.60989892 -1.6638 0.61923238 -1.6652997 2 P 0 ;0,5=65,7=0.000000
L 0.61923238 -1.6652997 0.62739941 -1.67130118 2 P 0 ;0,5=65,7=0.000000
L 0.62739941 -1.67130118 0.6344001 -1.68029931 2 P 0 ;0,5=65,7=0.000000
L 0.6344001 -1.68029931 0.63906782 -1.6907998 2 P 0 ;0,5=65,7=0.000000
L 0.63906782 -1.6907998 0.64140069 -1.7028 2 P 0 ;0,5=65,7=0.000000
L 0.64140069 -1.7028 0.64140069 -1.7148001 2 P 0 ;0,5=65,7=0.000000
L 0.64140069 -1.7148001 0.63906782 -1.7268003 2 P 0 ;0,5=65,7=0.000000
L 0.63906782 -1.7268003 0.6344001 -1.73730079 2 P 0 ;0,5=65,7=0.000000
L 0.6344001 -1.73730079 0.62739941 -1.74630167 2 P 0 ;0,5=65,7=0.000000
L 0.62739941 -1.74630167 0.61923238 -1.75230039 2 P 0 ;0,5=65,7=0.000000
L 0.61923238 -1.75230039 0.60989892 -1.7538 2 P 0 ;0,5=65,7=0.000000
L 0.67656624 -1.7538 0.67656624 -1.6638 2 P 0 ;0,5=65,7=0.000000
L 0.67656624 -1.6638 0.70456673 -1.6638 2 P 0 ;0,5=65,7=0.000000
L 0.70456673 -1.6638 0.7139002 -1.66830187 2 P 0 ;0,5=65,7=0.000000
L 0.7139002 -1.66830187 0.72090079 -1.67879961 2 P 0 ;0,5=65,7=0.000000
L 0.72090079 -1.67879961 0.72323366 -1.6907998 2 P 0 ;0,5=65,7=0.000000
L 0.72323366 -1.6907998 0.72090079 -1.7028 2 P 0 ;0,5=65,7=0.000000
L 0.72090079 -1.7028 0.71506654 -1.71180079 2 P 0 ;0,5=65,7=0.000000
L 0.71506654 -1.71180079 0.70456673 -1.71630256 2 P 0 ;0,5=65,7=0.000000
L 0.70456673 -1.71630256 0.67656624 -1.71630256 2 P 0 ;0,5=65,7=0.000000
L 0.8553998 -1.74180266 0.86473337 -1.74930098 2 P 0 ;0,5=65,7=0.000000
L 0.86473337 -1.74930098 0.87523317 -1.7538 2 P 0 ;0,5=65,7=0.000000
L 0.87523317 -1.7538 0.88456673 -1.7538 2 P 0 ;0,5=65,7=0.000000
L 0.88456673 -1.7538 0.8939002 -1.74930098 2 P 0 ;0,5=65,7=0.000000
L 0.8939002 -1.74930098 0.90090079 -1.74180266 2 P 0 ;0,5=65,7=0.000000
L 0.90090079 -1.74180266 0.9044001 -1.73129941 2 P 0 ;0,5=65,7=0.000000
L 0.9044001 -1.73129941 0.90206722 -1.72080157 2 P 0 ;0,5=65,7=0.000000
L 0.90206722 -1.72080157 0.89623297 -1.71180079 2 P 0 ;0,5=65,7=0.000000
L 0.89623297 -1.71180079 0.88573307 -1.70579931 2 P 0 ;0,5=65,7=0.000000
L 0.88573307 -1.70579931 0.87173396 -1.7028 2 P 0 ;0,5=65,7=0.000000
L 0.87173396 -1.7028 0.86356693 -1.69680128 2 P 0 ;0,5=65,7=0.000000
L 0.86356693 -1.69680128 0.86006555 -1.68630069 2 P 0 ;0,5=65,7=0.000000
L 0.86006555 -1.68630069 0.86240049 -1.6758002 2 P 0 ;0,5=65,7=0.000000
L 0.86240049 -1.6758002 0.86823258 -1.66830187 2 P 0 ;0,5=65,7=0.000000
L 0.86823258 -1.66830187 0.87639961 -1.6638 2 P 0 ;0,5=65,7=0.000000
L 0.87639961 -1.6638 0.88456673 -1.6638 2 P 0 ;0,5=65,7=0.000000
L 0.88456673 -1.6638 0.89273376 -1.66679941 2 P 0 ;0,5=65,7=0.000000
L 0.89273376 -1.66679941 0.89973435 -1.67430059 2 P 0 ;0,5=65,7=0.000000
L 0.9558997 -1.6638 0.98389803 -1.6638 2 P 0 ;0,5=65,7=0.000000
L 0.96989892 -1.6638 0.96989892 -1.7538 2 P 0 ;0,5=65,7=0.000000
L 0.9558997 -1.7538 0.98389803 -1.7538 2 P 0 ;0,5=65,7=0.000000
L 1.03423346 -1.7538 1.03423346 -1.6638 2 P 0 ;0,5=65,7=0.000000
L 1.03423346 -1.6638 1.05756604 -1.6638 2 P 0 ;0,5=65,7=0.000000
L 1.05756604 -1.6638 1.06689951 -1.66830187 2 P 0 ;0,5=65,7=0.000000
L 1.06689951 -1.66830187 1.0739002 -1.67430059 2 P 0 ;0,5=65,7=0.000000
L 1.0739002 -1.67430059 1.07973435 -1.68329862 2 P 0 ;0,5=65,7=0.000000
L 1.07973435 -1.68329862 1.0844001 -1.69380187 2 P 0 ;0,5=65,7=0.000000
L 1.0844001 -1.69380187 1.08556644 -1.70880138 2 P 0 ;0,5=65,7=0.000000
L 1.08556644 -1.70880138 1.0844001 -1.72380098 2 P 0 ;0,5=65,7=0.000000
L 1.0844001 -1.72380098 1.07973435 -1.73430148 2 P 0 ;0,5=65,7=0.000000
L 1.07973435 -1.73430148 1.0739002 -1.74330226 2 P 0 ;0,5=65,7=0.000000
L 1.0739002 -1.74330226 1.06689951 -1.74930098 2 P 0 ;0,5=65,7=0.000000
L 1.06689951 -1.74930098 1.05756604 -1.7538 2 P 0 ;0,5=65,7=0.000000
L 1.05756604 -1.7538 1.03423346 -1.7538 2 P 0 ;0,5=65,7=0.000000
L 1.17323366 -1.7538 1.12656624 -1.7538 2 P 0 ;0,5=65,7=0.000000
L 1.12656624 -1.7538 1.12656624 -1.6638 2 P 0 ;0,5=65,7=0.000000
L 1.12656624 -1.6638 1.17323366 -1.6638 2 P 0 ;0,5=65,7=0.000000
L 1.15456673 -1.70729902 1.12656624 -1.70729902 2 P 0 ;0,5=65,7=0.000000
L 3.06989892 -2.2538 3.06989892 -2.1638 2 P 0 ;0,5=64,7=0.000000
L 3.06989892 -2.1638 3.0558997 -2.18179892 2 P 0 ;0,5=64,7=0.000000
L 3.0558997 -2.2538 3.08389803 -2.2538 2 P 0 ;0,5=64,7=0.000000
L 0.59099833 -1.36499882 0.5990003 -1.35750039 2 P 0 ;0,5=66,7=0.000000
L 0.5990003 -1.35750039 0.60499902 -1.34500315 2 P 0 ;0,5=66,7=0.000000
L 0.60499902 -1.34500315 0.60900187 -1.32749764 2 P 0 ;0,5=66,7=0.000000
L 0.60900187 -1.32749764 0.60499902 -1.31250089 2 P 0 ;0,5=66,7=0.000000
L 0.60499902 -1.31250089 0.59700079 -1.30250305 2 P 0 ;0,5=66,7=0.000000
L 0.59700079 -1.30250305 0.5830001 -1.295 2 P 0 ;0,5=66,7=0.000000
L 0.5830001 -1.295 0.52900059 -1.295 2 P 0 ;0,5=66,7=0.000000
L 0.52900059 -1.295 0.52900059 -1.445 2 P 0 ;0,5=66,7=0.000000
L 0.52900059 -1.445 0.59500118 -1.445 2 P 0 ;0,5=66,7=0.000000
L 0.59500118 -1.445 0.60900187 -1.43500217 2 P 0 ;0,5=66,7=0.000000
L 0.60900187 -1.43500217 0.6170001 -1.42000079 2 P 0 ;0,5=66,7=0.000000
L 0.6170001 -1.42000079 0.62099931 -1.4025 2 P 0 ;0,5=66,7=0.000000
L 0.62099931 -1.4025 0.6170001 -1.38500374 2 P 0 ;0,5=66,7=0.000000
L 0.6170001 -1.38500374 0.60499902 -1.37000236 2 P 0 ;0,5=66,7=0.000000
L 0.60499902 -1.37000236 0.59099833 -1.36499882 2 P 0 ;0,5=66,7=0.000000
L 0.59099833 -1.36499882 0.52900059 -1.36499882 2 P 0 ;0,5=66,7=0.000000
L 0.77100138 -1.445 0.77100138 -1.34500315 2 P 0 ;0,5=66,7=0.000000
L 0.77100138 -1.36249941 0.76299951 -1.35250148 2 P 0 ;0,5=66,7=0.000000
L 0.76299951 -1.35250148 0.75099833 -1.34750256 2 P 0 ;0,5=66,7=0.000000
L 0.75099833 -1.34750256 0.73700138 -1.34500315 2 P 0 ;0,5=66,7=0.000000
L 0.73700138 -1.34500315 0.72300069 -1.35000207 2 P 0 ;0,5=66,7=0.000000
L 0.72300069 -1.35000207 0.71099961 -1.3599999 2 P 0 ;0,5=66,7=0.000000
L 0.71099961 -1.3599999 0.70299764 -1.37500128 2 P 0 ;0,5=66,7=0.000000
L 0.70299764 -1.37500128 0.69899852 -1.39500157 2 P 0 ;0,5=66,7=0.000000
L 0.69899852 -1.39500157 0.70299764 -1.41500187 2 P 0 ;0,5=66,7=0.000000
L 0.70299764 -1.41500187 0.71099961 -1.43000325 2 P 0 ;0,5=66,7=0.000000
L 0.71099961 -1.43000325 0.72300069 -1.44000108 2 P 0 ;0,5=66,7=0.000000
L 0.72300069 -1.44000108 0.73700138 -1.445 2 P 0 ;0,5=66,7=0.000000
L 0.73700138 -1.445 0.75099833 -1.44250059 2 P 0 ;0,5=66,7=0.000000
L 0.75099833 -1.44250059 0.76299951 -1.43500217 2 P 0 ;0,5=66,7=0.000000
L 0.76299951 -1.43500217 0.77100138 -1.42500433 2 P 0 ;0,5=66,7=0.000000
L 0.86700039 -1.445 0.86700039 -1.34500315 2 P 0 ;0,5=66,7=0.000000
L 0.86700039 -1.36499882 0.87699833 -1.35500098 2 P 0 ;0,5=66,7=0.000000
L 0.87699833 -1.35500098 0.8869998 -1.34750256 2 P 0 ;0,5=66,7=0.000000
L 0.8869998 -1.34750256 0.90100049 -1.34500315 2 P 0 ;0,5=66,7=0.000000
L 0.90100049 -1.34500315 0.91099833 -1.34750256 2 P 0 ;0,5=66,7=0.000000
L 0.91099833 -1.34750256 0.92299951 -1.35500098 2 P 0 ;0,5=66,7=0.000000
L 1.02700039 -1.445 1.02700039 -1.34500315 2 P 0 ;0,5=66,7=0.000000
L 1.02700039 -1.36499882 1.03699833 -1.35500098 2 P 0 ;0,5=66,7=0.000000
L 1.03699833 -1.35500098 1.0469998 -1.34750256 2 P 0 ;0,5=66,7=0.000000
L 1.0469998 -1.34750256 1.06100049 -1.34500315 2 P 0 ;0,5=66,7=0.000000
L 1.06100049 -1.34500315 1.07099833 -1.34750256 2 P 0 ;0,5=66,7=0.000000
L 1.07099833 -1.34750256 1.08299951 -1.35500098 2 P 0 ;0,5=66,7=0.000000
L 1.18500089 -1.37750069 1.24900187 -1.37750069 2 P 0 ;0,5=66,7=0.000000
L 1.24900187 -1.37750069 1.24299951 -1.3599999 2 P 0 ;0,5=66,7=0.000000
L 1.24299951 -1.3599999 1.23300157 -1.35000207 2 P 0 ;0,5=66,7=0.000000
L 1.23300157 -1.35000207 1.21900089 -1.34500315 2 P 0 ;0,5=66,7=0.000000
L 1.21900089 -1.34500315 1.2050003 -1.34750256 2 P 0 ;0,5=66,7=0.000000
L 1.2050003 -1.34750256 1.19299911 -1.35500098 2 P 0 ;0,5=66,7=0.000000
L 1.19299911 -1.35500098 1.18500089 -1.37250177 2 P 0 ;0,5=66,7=0.000000
L 1.18500089 -1.37250177 1.18099803 -1.38750315 2 P 0 ;0,5=66,7=0.000000
L 1.18099803 -1.38750315 1.18099803 -1.4025 2 P 0 ;0,5=66,7=0.000000
L 1.18099803 -1.4025 1.18500089 -1.41750138 2 P 0 ;0,5=66,7=0.000000
L 1.18500089 -1.41750138 1.19499872 -1.43250276 2 P 0 ;0,5=66,7=0.000000
L 1.19499872 -1.43250276 1.2069998 -1.44250059 2 P 0 ;0,5=66,7=0.000000
L 1.2069998 -1.44250059 1.22100049 -1.445 2 P 0 ;0,5=66,7=0.000000
L 1.22100049 -1.445 1.23500118 -1.44000108 2 P 0 ;0,5=66,7=0.000000
L 1.23500118 -1.44000108 1.24900187 -1.42500433 2 P 0 ;0,5=66,7=0.000000
L 1.37499813 -1.445 1.37499813 -1.295 2 P 0 ;0,5=66,7=0.000000
L 1.50500089 -1.37750069 1.56900187 -1.37750069 2 P 0 ;0,5=66,7=0.000000
L 1.56900187 -1.37750069 1.56299951 -1.3599999 2 P 0 ;0,5=66,7=0.000000
L 1.56299951 -1.3599999 1.55300157 -1.35000207 2 P 0 ;0,5=66,7=0.000000
L 1.55300157 -1.35000207 1.53900089 -1.34500315 2 P 0 ;0,5=66,7=0.000000
L 1.53900089 -1.34500315 1.5250003 -1.34750256 2 P 0 ;0,5=66,7=0.000000
L 1.5250003 -1.34750256 1.51299911 -1.35500098 2 P 0 ;0,5=66,7=0.000000
L 1.51299911 -1.35500098 1.50500089 -1.37250177 2 P 0 ;0,5=66,7=0.000000
L 1.50500089 -1.37250177 1.50099803 -1.38750315 2 P 0 ;0,5=66,7=0.000000
L 1.50099803 -1.38750315 1.50099803 -1.4025 2 P 0 ;0,5=66,7=0.000000
L 1.50099803 -1.4025 1.50500089 -1.41750138 2 P 0 ;0,5=66,7=0.000000
L 1.50500089 -1.41750138 1.51499872 -1.43250276 2 P 0 ;0,5=66,7=0.000000
L 1.51499872 -1.43250276 1.5269998 -1.44250059 2 P 0 ;0,5=66,7=0.000000
L 1.5269998 -1.44250059 1.54100049 -1.445 2 P 0 ;0,5=66,7=0.000000
L 1.54100049 -1.445 1.55500118 -1.44000108 2 P 0 ;0,5=66,7=0.000000
L 1.55500118 -1.44000108 1.56900187 -1.42500433 2 P 0 ;0,5=66,7=0.000000
L 1.6529998 -1.48999951 1.66500089 -1.49499843 2 P 0 ;0,5=66,7=0.000000
L 1.66500089 -1.49499843 1.68100108 -1.48999951 2 P 0 ;0,5=66,7=0.000000
L 1.68100108 -1.48999951 1.69099902 -1.48000167 2 P 0 ;0,5=66,7=0.000000
L 1.69099902 -1.48000167 1.69900089 -1.4674997 2 P 0 ;0,5=66,7=0.000000
L 1.69900089 -1.4674997 1.71099833 -1.42750374 2 P 0 ;0,5=66,7=0.000000
L 1.71099833 -1.42750374 1.7370001 -1.34500315 2 P 0 ;0,5=66,7=0.000000
L 1.67299911 -1.34500315 1.71099833 -1.42750374 2 P 0 ;0,5=66,7=0.000000
L 1.82500089 -1.37750069 1.88900187 -1.37750069 2 P 0 ;0,5=66,7=0.000000
L 1.88900187 -1.37750069 1.88299951 -1.3599999 2 P 0 ;0,5=66,7=0.000000
L 1.88299951 -1.3599999 1.87300157 -1.35000207 2 P 0 ;0,5=66,7=0.000000
L 1.87300157 -1.35000207 1.85900089 -1.34500315 2 P 0 ;0,5=66,7=0.000000
L 1.85900089 -1.34500315 1.8450003 -1.34750256 2 P 0 ;0,5=66,7=0.000000
L 1.8450003 -1.34750256 1.83299911 -1.35500098 2 P 0 ;0,5=66,7=0.000000
L 1.83299911 -1.35500098 1.82500089 -1.37250177 2 P 0 ;0,5=66,7=0.000000
L 1.82500089 -1.37250177 1.82099803 -1.38750315 2 P 0 ;0,5=66,7=0.000000
L 1.82099803 -1.38750315 1.82099803 -1.4025 2 P 0 ;0,5=66,7=0.000000
L 1.82099803 -1.4025 1.82500089 -1.41750138 2 P 0 ;0,5=66,7=0.000000
L 1.82500089 -1.41750138 1.83499872 -1.43250276 2 P 0 ;0,5=66,7=0.000000
L 1.83499872 -1.43250276 1.8469998 -1.44250059 2 P 0 ;0,5=66,7=0.000000
L 1.8469998 -1.44250059 1.86100049 -1.445 2 P 0 ;0,5=66,7=0.000000
L 1.86100049 -1.445 1.87500118 -1.44000108 2 P 0 ;0,5=66,7=0.000000
L 1.87500118 -1.44000108 1.88900187 -1.42500433 2 P 0 ;0,5=66,7=0.000000
L 2.18699921 -1.37000236 2.22700167 -1.37000236 2 P 0 ;0,5=66,7=0.000000
L 2.22700167 -1.37000236 2.22700167 -1.41500187 2 P 0 ;0,5=66,7=0.000000
L 2.22700167 -1.41500187 2.21500059 -1.43000325 2 P 0 ;0,5=66,7=0.000000
L 2.21500059 -1.43000325 2.2009999 -1.44000108 2 P 0 ;0,5=66,7=0.000000
L 2.2009999 -1.44000108 2.18100049 -1.445 2 P 0 ;0,5=66,7=0.000000
L 2.18100049 -1.445 2.16100108 -1.44000108 2 P 0 ;0,5=66,7=0.000000
L 2.16100108 -1.44000108 2.14700039 -1.43000325 2 P 0 ;0,5=66,7=0.000000
L 2.14700039 -1.43000325 2.13499931 -1.41500187 2 P 0 ;0,5=66,7=0.000000
L 2.13499931 -1.41500187 2.12699734 -1.39750108 2 P 0 ;0,5=66,7=0.000000
L 2.12699734 -1.39750108 2.12299823 -1.37750069 2 P 0 ;0,5=66,7=0.000000
L 2.12299823 -1.37750069 2.12299823 -1.3599999 2 P 0 ;0,5=66,7=0.000000
L 2.12299823 -1.3599999 2.12699734 -1.34500315 2 P 0 ;0,5=66,7=0.000000
L 2.12699734 -1.34500315 2.13499931 -1.32749764 2 P 0 ;0,5=66,7=0.000000
L 2.13499931 -1.32749764 2.14700039 -1.31250089 2 P 0 ;0,5=66,7=0.000000
L 2.14700039 -1.31250089 2.15899783 -1.30250305 2 P 0 ;0,5=66,7=0.000000
L 2.15899783 -1.30250305 2.17499813 -1.295 2 P 0 ;0,5=66,7=0.000000
L 2.17499813 -1.295 2.18899882 -1.295 2 P 0 ;0,5=66,7=0.000000
L 2.18899882 -1.295 2.20499902 -1.29999902 2 P 0 ;0,5=66,7=0.000000
L 2.20499902 -1.29999902 2.2170001 -1.31000138 2 P 0 ;0,5=66,7=0.000000
L 2.29699892 -1.31999931 2.309 -1.30500246 2 P 0 ;0,5=66,7=0.000000
L 2.309 -1.30500246 2.32300069 -1.29749951 2 P 0 ;0,5=66,7=0.000000
L 2.32300069 -1.29749951 2.33900089 -1.295 2 P 0 ;0,5=66,7=0.000000
L 2.33900089 -1.295 2.3590003 -1.29999902 2 P 0 ;0,5=66,7=0.000000
L 2.3590003 -1.29999902 2.37300098 -1.31250089 2 P 0 ;0,5=66,7=0.000000
L 2.37300098 -1.31250089 2.3770001 -1.32749764 2 P 0 ;0,5=66,7=0.000000
L 2.3770001 -1.32749764 2.37500059 -1.34250364 2 P 0 ;0,5=66,7=0.000000
L 2.37500059 -1.34250364 2.36699862 -1.35500098 2 P 0 ;0,5=66,7=0.000000
L 2.36699862 -1.35500098 2.3269998 -1.3800002 2 P 0 ;0,5=66,7=0.000000
L 2.3269998 -1.3800002 2.309 -1.39750108 2 P 0 ;0,5=66,7=0.000000
L 2.309 -1.39750108 2.29699892 -1.42250482 2 P 0 ;0,5=66,7=0.000000
L 2.29699892 -1.42250482 2.2929998 -1.445 2 P 0 ;0,5=66,7=0.000000
L 2.2929998 -1.445 2.3770001 -1.445 2 P 0 ;0,5=66,7=0.000000
L 2.6129998 -1.42500433 2.629 -1.43750167 2 P 0 ;0,5=66,7=0.000000
L 2.629 -1.43750167 2.6469998 -1.445 2 P 0 ;0,5=66,7=0.000000
L 2.6469998 -1.445 2.6630001 -1.445 2 P 0 ;0,5=66,7=0.000000
L 2.6630001 -1.445 2.6790003 -1.43750167 2 P 0 ;0,5=66,7=0.000000
L 2.6790003 -1.43750167 2.69100138 -1.42500433 2 P 0 ;0,5=66,7=0.000000
L 2.69100138 -1.42500433 2.6970001 -1.40749892 2 P 0 ;0,5=66,7=0.000000
L 2.6970001 -1.40749892 2.69300098 -1.39000266 2 P 0 ;0,5=66,7=0.000000
L 2.69300098 -1.39000266 2.68299951 -1.37500128 2 P 0 ;0,5=66,7=0.000000
L 2.68299951 -1.37500128 2.66499961 -1.36499882 2 P 0 ;0,5=66,7=0.000000
L 2.66499961 -1.36499882 2.64100108 -1.3599999 2 P 0 ;0,5=66,7=0.000000
L 2.64100108 -1.3599999 2.62700039 -1.35000207 2 P 0 ;0,5=66,7=0.000000
L 2.62700039 -1.35000207 2.62099803 -1.33250118 2 P 0 ;0,5=66,7=0.000000
L 2.62099803 -1.33250118 2.62500089 -1.31500039 2 P 0 ;0,5=66,7=0.000000
L 2.62500089 -1.31500039 2.63499872 -1.30250305 2 P 0 ;0,5=66,7=0.000000
L 2.63499872 -1.30250305 2.64899941 -1.295 2 P 0 ;0,5=66,7=0.000000
L 2.64899941 -1.295 2.6630001 -1.295 2 P 0 ;0,5=66,7=0.000000
L 2.6630001 -1.295 2.67700079 -1.29999902 2 P 0 ;0,5=66,7=0.000000
L 2.67700079 -1.29999902 2.68900187 -1.31250089 2 P 0 ;0,5=66,7=0.000000
L 2.7729998 -1.445 2.8570001 -1.295 2 P 0 ;0,5=66,7=0.000000
L 2.7729998 -1.295 2.8570001 -1.445 2 P 0 ;0,5=66,7=0.000000
L 2.92299823 -1.445 2.92299823 -1.295 2 P 0 ;0,5=66,7=0.000000
L 2.92299823 -1.295 2.97499813 -1.42000079 2 P 0 ;0,5=66,7=0.000000
L 2.97499813 -1.42000079 3.02700167 -1.295 2 P 0 ;0,5=66,7=0.000000
L 3.02700167 -1.295 3.02700167 -1.445 2 P 0 ;0,5=66,7=0.000000
L 3.09699892 -1.31999931 3.109 -1.30500246 2 P 0 ;0,5=66,7=0.000000
L 3.109 -1.30500246 3.12300069 -1.29749951 2 P 0 ;0,5=66,7=0.000000
L 3.12300069 -1.29749951 3.13900089 -1.295 2 P 0 ;0,5=66,7=0.000000
L 3.13900089 -1.295 3.1590003 -1.29999902 2 P 0 ;0,5=66,7=0.000000
L 3.1590003 -1.29999902 3.17300098 -1.31250089 2 P 0 ;0,5=66,7=0.000000
L 3.17300098 -1.31250089 3.1770001 -1.32749764 2 P 0 ;0,5=66,7=0.000000
L 3.1770001 -1.32749764 3.17500059 -1.34250364 2 P 0 ;0,5=66,7=0.000000
L 3.17500059 -1.34250364 3.16699862 -1.35500098 2 P 0 ;0,5=66,7=0.000000
L 3.16699862 -1.35500098 3.1269998 -1.3800002 2 P 0 ;0,5=66,7=0.000000
L 3.1269998 -1.3800002 3.109 -1.39750108 2 P 0 ;0,5=66,7=0.000000
L 3.109 -1.39750108 3.09699892 -1.42250482 2 P 0 ;0,5=66,7=0.000000
L 3.09699892 -1.42250482 3.0929998 -1.445 2 P 0 ;0,5=66,7=0.000000
L 3.0929998 -1.445 3.1770001 -1.445 2 P 0 ;0,5=66,7=0.000000
L 3.269 -1.39500157 3.3209999 -1.39500157 2 P 0 ;0,5=66,7=0.000000
L 3.41499931 -1.445 3.41499931 -1.295 2 P 0 ;0,5=66,7=0.000000
L 3.41499931 -1.295 3.46499961 -1.295 2 P 0 ;0,5=66,7=0.000000
L 3.46499961 -1.295 3.4809999 -1.30250305 2 P 0 ;0,5=66,7=0.000000
L 3.4809999 -1.30250305 3.49100138 -1.31250089 2 P 0 ;0,5=66,7=0.000000
L 3.49100138 -1.31250089 3.49500059 -1.33250118 2 P 0 ;0,5=66,7=0.000000
L 3.49500059 -1.33250118 3.49100138 -1.35250148 2 P 0 ;0,5=66,7=0.000000
L 3.49100138 -1.35250148 3.4790003 -1.36499882 2 P 0 ;0,5=66,7=0.000000
L 3.4790003 -1.36499882 3.46499961 -1.37250177 2 P 0 ;0,5=66,7=0.000000
L 3.46499961 -1.37250177 3.41499931 -1.37250177 2 P 0 ;0,5=66,7=0.000000
L 3.46499961 -1.37250177 3.49500059 -1.445 2 P 0 ;0,5=66,7=0.000000
L 3.61499813 -1.34500315 3.61499813 -1.445 2 P 0 ;0,5=66,7=0.000000
L 3.61499813 -1.30500246 3.61099902 -1.30250305 2 P 0 ;0,5=66,7=0.000000
L 3.61099902 -1.30250305 3.61099902 -1.29749951 2 P 0 ;0,5=66,7=0.000000
L 3.61099902 -1.29749951 3.61499813 -1.295 2 P 0 ;0,5=66,7=0.000000
L 3.61499813 -1.295 3.61900089 -1.29749951 2 P 0 ;0,5=66,7=0.000000
L 3.61900089 -1.29749951 3.61900089 -1.30250305 2 P 0 ;0,5=66,7=0.000000
L 3.61900089 -1.30250305 3.61499813 -1.30500246 2 P 0 ;0,5=66,7=0.000000
L 3.74500089 -1.42750374 3.75499872 -1.43750167 2 P 0 ;0,5=66,7=0.000000
L 3.75499872 -1.43750167 3.76899941 -1.445 2 P 0 ;0,5=66,7=0.000000
L 3.76899941 -1.445 3.78100049 -1.445 2 P 0 ;0,5=66,7=0.000000
L 3.78100049 -1.445 3.79300157 -1.44000108 2 P 0 ;0,5=66,7=0.000000
L 3.79300157 -1.44000108 3.8009999 -1.43250276 2 P 0 ;0,5=66,7=0.000000
L 3.8009999 -1.43250276 3.80499902 -1.42250482 2 P 0 ;0,5=66,7=0.000000
L 3.80499902 -1.42250482 3.80299951 -1.40749892 2 P 0 ;0,5=66,7=0.000000
L 3.80299951 -1.40749892 3.79500118 -1.40000049 2 P 0 ;0,5=66,7=0.000000
L 3.79500118 -1.40000049 3.75899783 -1.38500374 2 P 0 ;0,5=66,7=0.000000
L 3.75899783 -1.38500374 3.75099961 -1.36749833 2 P 0 ;0,5=66,7=0.000000
L 3.75099961 -1.36749833 3.75499872 -1.35500098 2 P 0 ;0,5=66,7=0.000000
L 3.75499872 -1.35500098 3.76300069 -1.34750256 2 P 0 ;0,5=66,7=0.000000
L 3.76300069 -1.34750256 3.77499813 -1.34500315 2 P 0 ;0,5=66,7=0.000000
L 3.77499813 -1.34500315 3.78699921 -1.34750256 2 P 0 ;0,5=66,7=0.000000
L 3.78699921 -1.34750256 3.7990003 -1.35500098 2 P 0 ;0,5=66,7=0.000000
L 3.90500089 -1.37750069 3.96900187 -1.37750069 2 P 0 ;0,5=66,7=0.000000
L 3.96900187 -1.37750069 3.96299951 -1.3599999 2 P 0 ;0,5=66,7=0.000000
L 3.96299951 -1.3599999 3.95300157 -1.35000207 2 P 0 ;0,5=66,7=0.000000
L 3.95300157 -1.35000207 3.93900089 -1.34500315 2 P 0 ;0,5=66,7=0.000000
L 3.93900089 -1.34500315 3.9250003 -1.34750256 2 P 0 ;0,5=66,7=0.000000
L 3.9250003 -1.34750256 3.91299911 -1.35500098 2 P 0 ;0,5=66,7=0.000000
L 3.91299911 -1.35500098 3.90500089 -1.37250177 2 P 0 ;0,5=66,7=0.000000
L 3.90500089 -1.37250177 3.90099803 -1.38750315 2 P 0 ;0,5=66,7=0.000000
L 3.90099803 -1.38750315 3.90099803 -1.4025 2 P 0 ;0,5=66,7=0.000000
L 3.90099803 -1.4025 3.90500089 -1.41750138 2 P 0 ;0,5=66,7=0.000000
L 3.90500089 -1.41750138 3.91499872 -1.43250276 2 P 0 ;0,5=66,7=0.000000
L 3.91499872 -1.43250276 3.9269998 -1.44250059 2 P 0 ;0,5=66,7=0.000000
L 3.9269998 -1.44250059 3.94100049 -1.445 2 P 0 ;0,5=66,7=0.000000
L 3.94100049 -1.445 3.95500118 -1.44000108 2 P 0 ;0,5=66,7=0.000000
L 3.95500118 -1.44000108 3.96900187 -1.42500433 2 P 0 ;0,5=66,7=0.000000
L 4.06700039 -1.445 4.06700039 -1.34500315 2 P 0 ;0,5=66,7=0.000000
L 4.06700039 -1.36499882 4.07699833 -1.35500098 2 P 0 ;0,5=66,7=0.000000
L 4.07699833 -1.35500098 4.0869998 -1.34750256 2 P 0 ;0,5=66,7=0.000000
L 4.0869998 -1.34750256 4.10100049 -1.34500315 2 P 0 ;0,5=66,7=0.000000
L 4.10100049 -1.34500315 4.11099833 -1.34750256 2 P 0 ;0,5=66,7=0.000000
L 4.11099833 -1.34750256 4.12299951 -1.35500098 2 P 0 ;0,5=66,7=0.000000
L 4.16964783 -2.2038 4.21839813 -2.0478 2 P 0 ;0,5=67,7=0.000000
L 4.21839813 -2.0478 4.26715207 -2.2038 2 P 0 ;0,5=67,7=0.000000
L 4.24959862 -2.14920217 4.18719774 -2.14920217 2 P 0 ;0,5=67,7=0.000000
L 4.37939813 -2.2038 4.37939813 -2.0478 2 P 0 ;0,5=67,7=0.000000
L 4.37939813 -2.0478 4.35599961 -2.07899813 2 P 0 ;0,5=67,7=0.000000
L 4.35599961 -2.2038 4.40279675 -2.2038 2 P 0 ;0,5=67,7=0.000000
L 2.0009002 -0.9538 2.0009002 -0.8038 2 P 0 ;0,5=68,7=0.000000
L 2.0009002 -0.8038 2.04089902 -0.8038 2 P 0 ;0,5=68,7=0.000000
L 2.04089902 -0.8038 2.05689921 -0.81130305 2 P 0 ;0,5=68,7=0.000000
L 2.05689921 -0.81130305 2.0689003 -0.82130089 2 P 0 ;0,5=68,7=0.000000
L 2.0689003 -0.82130089 2.07890187 -0.83629764 2 P 0 ;0,5=68,7=0.000000
L 2.07890187 -0.83629764 2.0869001 -0.85380315 2 P 0 ;0,5=68,7=0.000000
L 2.0869001 -0.85380315 2.0888997 -0.87880236 2 P 0 ;0,5=68,7=0.000000
L 2.0888997 -0.87880236 2.0869001 -0.90380157 2 P 0 ;0,5=68,7=0.000000
L 2.0869001 -0.90380157 2.07890187 -0.92130246 2 P 0 ;0,5=68,7=0.000000
L 2.07890187 -0.92130246 2.0689003 -0.93630374 2 P 0 ;0,5=68,7=0.000000
L 2.0689003 -0.93630374 2.05689921 -0.94630167 2 P 0 ;0,5=68,7=0.000000
L 2.05689921 -0.94630167 2.04089902 -0.9538 2 P 0 ;0,5=68,7=0.000000
L 2.04089902 -0.9538 2.0009002 -0.9538 2 P 0 ;0,5=68,7=0.000000
L 2.15489783 -0.9538 2.20489813 -0.8038 2 P 0 ;0,5=68,7=0.000000
L 2.20489813 -0.8038 2.25490207 -0.9538 2 P 0 ;0,5=68,7=0.000000
L 2.23689862 -0.90130207 2.17289764 -0.90130207 2 P 0 ;0,5=68,7=0.000000
L 2.36489813 -0.8038 2.36489813 -0.9538 2 P 0 ;0,5=68,7=0.000000
L 2.31890059 -0.8038 2.41089931 -0.8038 2 P 0 ;0,5=68,7=0.000000
L 2.56490059 -0.9538 2.48489931 -0.9538 2 P 0 ;0,5=68,7=0.000000
L 2.48489931 -0.9538 2.48489931 -0.8038 2 P 0 ;0,5=68,7=0.000000
L 2.48489931 -0.8038 2.56490059 -0.8038 2 P 0 ;0,5=68,7=0.000000
L 2.5329001 -0.87629833 2.48489931 -0.87629833 2 P 0 ;0,5=68,7=0.000000
L 2.84489813 -0.9538 2.82889783 -0.95130059 2 P 0 ;0,5=68,7=0.000000
L 2.82889783 -0.95130059 2.81490089 -0.94130276 2 P 0 ;0,5=68,7=0.000000
L 2.81490089 -0.94130276 2.8028998 -0.92630138 2 P 0 ;0,5=68,7=0.000000
L 2.8028998 -0.92630138 2.79489783 -0.90880049 2 P 0 ;0,5=68,7=0.000000
L 2.79489783 -0.90880049 2.79089862 -0.8888002 2 P 0 ;0,5=68,7=0.000000
L 2.79089862 -0.8888002 2.79089862 -0.8687999 2 P 0 ;0,5=68,7=0.000000
L 2.79089862 -0.8687999 2.79489783 -0.84879961 2 P 0 ;0,5=68,7=0.000000
L 2.79489783 -0.84879961 2.8028998 -0.83129872 2 P 0 ;0,5=68,7=0.000000
L 2.8028998 -0.83129872 2.81490089 -0.81630197 2 P 0 ;0,5=68,7=0.000000
L 2.81490089 -0.81630197 2.82889783 -0.80629951 2 P 0 ;0,5=68,7=0.000000
L 2.82889783 -0.80629951 2.84489813 -0.8038 2 P 0 ;0,5=68,7=0.000000
L 2.84489813 -0.8038 2.86089833 -0.80629951 2 P 0 ;0,5=68,7=0.000000
L 2.86089833 -0.80629951 2.87489902 -0.81630197 2 P 0 ;0,5=68,7=0.000000
L 2.87489902 -0.81630197 2.8869001 -0.83129872 2 P 0 ;0,5=68,7=0.000000
L 2.8869001 -0.83129872 2.89490207 -0.84879961 2 P 0 ;0,5=68,7=0.000000
L 2.89490207 -0.84879961 2.89890128 -0.8687999 2 P 0 ;0,5=68,7=0.000000
L 2.89890128 -0.8687999 2.89890128 -0.8888002 2 P 0 ;0,5=68,7=0.000000
L 2.89890128 -0.8888002 2.89490207 -0.90880049 2 P 0 ;0,5=68,7=0.000000
L 2.89490207 -0.90880049 2.8869001 -0.92630138 2 P 0 ;0,5=68,7=0.000000
L 2.8869001 -0.92630138 2.87489902 -0.94130276 2 P 0 ;0,5=68,7=0.000000
L 2.87489902 -0.94130276 2.86089833 -0.95130059 2 P 0 ;0,5=68,7=0.000000
L 2.86089833 -0.95130059 2.84489813 -0.9538 2 P 0 ;0,5=68,7=0.000000
L 3.0488997 -0.81630197 3.03689862 -0.80879902 2 P 0 ;0,5=68,7=0.000000
L 3.03689862 -0.80879902 3.02290157 -0.8038 2 P 0 ;0,5=68,7=0.000000
L 3.02290157 -0.8038 3.00690138 -0.8038 2 P 0 ;0,5=68,7=0.000000
L 3.00690138 -0.8038 2.98889783 -0.81130305 2 P 0 ;0,5=68,7=0.000000
L 2.98889783 -0.81130305 2.97490089 -0.82380039 2 P 0 ;0,5=68,7=0.000000
L 2.97490089 -0.82380039 2.96489931 -0.83880177 2 P 0 ;0,5=68,7=0.000000
L 2.96489931 -0.83880177 2.95689734 -0.86380098 2 P 0 ;0,5=68,7=0.000000
L 2.95689734 -0.86380098 2.95489783 -0.88630069 2 P 0 ;0,5=68,7=0.000000
L 2.95489783 -0.88630069 2.95890059 -0.90880049 2 P 0 ;0,5=68,7=0.000000
L 2.95890059 -0.90880049 2.96489931 -0.92380187 2 P 0 ;0,5=68,7=0.000000
L 2.96489931 -0.92380187 2.97690039 -0.93880325 2 P 0 ;0,5=68,7=0.000000
L 2.97690039 -0.93880325 2.99090108 -0.94880108 2 P 0 ;0,5=68,7=0.000000
L 2.99090108 -0.94880108 3.00489813 -0.9538 2 P 0 ;0,5=68,7=0.000000
L 3.00489813 -0.9538 3.01889882 -0.9538 2 P 0 ;0,5=68,7=0.000000
L 3.01889882 -0.9538 3.03289951 -0.94880108 2 P 0 ;0,5=68,7=0.000000
L 3.03289951 -0.94880108 3.04490059 -0.94130276 2 P 0 ;0,5=68,7=0.000000
L 3.04490059 -0.94130276 3.05490207 -0.93130482 2 P 0 ;0,5=68,7=0.000000
L 3.16489813 -0.8038 3.16489813 -0.9538 2 P 0 ;0,5=68,7=0.000000
L 3.11890059 -0.8038 3.21089931 -0.8038 2 P 0 ;0,5=68,7=0.000000
L 3.28889852 -0.95879892 3.36090138 -0.8038 2 P 0 ;0,5=68,7=0.000000
L 3.44689892 -0.82879931 3.4589 -0.81380246 2 P 0 ;0,5=68,7=0.000000
L 3.4589 -0.81380246 3.47290069 -0.80629951 2 P 0 ;0,5=68,7=0.000000
L 3.47290069 -0.80629951 3.48890089 -0.8038 2 P 0 ;0,5=68,7=0.000000
L 3.48890089 -0.8038 3.5089003 -0.80879902 2 P 0 ;0,5=68,7=0.000000
L 3.5089003 -0.80879902 3.52290098 -0.82130089 2 P 0 ;0,5=68,7=0.000000
L 3.52290098 -0.82130089 3.5269001 -0.83629764 2 P 0 ;0,5=68,7=0.000000
L 3.5269001 -0.83629764 3.52490059 -0.85130364 2 P 0 ;0,5=68,7=0.000000
L 3.52490059 -0.85130364 3.51689862 -0.86380098 2 P 0 ;0,5=68,7=0.000000
L 3.51689862 -0.86380098 3.4768998 -0.8888002 2 P 0 ;0,5=68,7=0.000000
L 3.4768998 -0.8888002 3.4589 -0.90630108 2 P 0 ;0,5=68,7=0.000000
L 3.4589 -0.90630108 3.44689892 -0.93130482 2 P 0 ;0,5=68,7=0.000000
L 3.44689892 -0.93130482 3.4428998 -0.9538 2 P 0 ;0,5=68,7=0.000000
L 3.4428998 -0.9538 3.5269001 -0.9538 2 P 0 ;0,5=68,7=0.000000
L 3.64089902 -0.9538 3.64489813 -0.92130246 2 P 0 ;0,5=68,7=0.000000
L 3.64489813 -0.92130246 3.65090049 -0.89380374 2 P 0 ;0,5=68,7=0.000000
L 3.65090049 -0.89380374 3.65889882 -0.8687999 2 P 0 ;0,5=68,7=0.000000
L 3.65889882 -0.8687999 3.6689003 -0.84130118 2 P 0 ;0,5=68,7=0.000000
L 3.6689003 -0.84130118 3.68490059 -0.8038 2 P 0 ;0,5=68,7=0.000000
L 3.68490059 -0.8038 3.60489931 -0.8038 2 P 0 ;0,5=68,7=0.000000
L 3.76889852 -0.95879892 3.84090138 -0.8038 2 P 0 ;0,5=68,7=0.000000
L 3.92689892 -0.82879931 3.9389 -0.81380246 2 P 0 ;0,5=68,7=0.000000
L 3.9389 -0.81380246 3.95290069 -0.80629951 2 P 0 ;0,5=68,7=0.000000
L 3.95290069 -0.80629951 3.96890089 -0.8038 2 P 0 ;0,5=68,7=0.000000
L 3.96890089 -0.8038 3.9889003 -0.80879902 2 P 0 ;0,5=68,7=0.000000
L 3.9889003 -0.80879902 4.00290098 -0.82130089 2 P 0 ;0,5=68,7=0.000000
L 4.00290098 -0.82130089 4.0069001 -0.83629764 2 P 0 ;0,5=68,7=0.000000
L 4.0069001 -0.83629764 4.00490059 -0.85130364 2 P 0 ;0,5=68,7=0.000000
L 4.00490059 -0.85130364 3.99689862 -0.86380098 2 P 0 ;0,5=68,7=0.000000
L 3.99689862 -0.86380098 3.9568998 -0.8888002 2 P 0 ;0,5=68,7=0.000000
L 3.9568998 -0.8888002 3.9389 -0.90630108 2 P 0 ;0,5=68,7=0.000000
L 3.9389 -0.90630108 3.92689892 -0.93130482 2 P 0 ;0,5=68,7=0.000000
L 3.92689892 -0.93130482 3.9228998 -0.9538 2 P 0 ;0,5=68,7=0.000000
L 3.9228998 -0.9538 4.0069001 -0.9538 2 P 0 ;0,5=68,7=0.000000
L 4.12489813 -0.8038 4.10889783 -0.80879902 2 P 0 ;0,5=68,7=0.000000
L 4.10889783 -0.80879902 4.09690039 -0.82130089 2 P 0 ;0,5=68,7=0.000000
L 4.09690039 -0.82130089 4.08889852 -0.83629764 2 P 0 ;0,5=68,7=0.000000
L 4.08889852 -0.83629764 4.0828998 -0.85630256 2 P 0 ;0,5=68,7=0.000000
L 4.0828998 -0.85630256 4.0809002 -0.87880236 2 P 0 ;0,5=68,7=0.000000
L 4.0809002 -0.87880236 4.0828998 -0.90130207 2 P 0 ;0,5=68,7=0.000000
L 4.0828998 -0.90130207 4.08889852 -0.92130246 2 P 0 ;0,5=68,7=0.000000
L 4.08889852 -0.92130246 4.09690039 -0.93630374 2 P 0 ;0,5=68,7=0.000000
L 4.09690039 -0.93630374 4.10889783 -0.94880108 2 P 0 ;0,5=68,7=0.000000
L 4.10889783 -0.94880108 4.12489813 -0.9538 2 P 0 ;0,5=68,7=0.000000
L 4.12489813 -0.9538 4.14089833 -0.94880108 2 P 0 ;0,5=68,7=0.000000
L 4.14089833 -0.94880108 4.15289951 -0.93630374 2 P 0 ;0,5=68,7=0.000000
L 4.15289951 -0.93630374 4.16090138 -0.92130246 2 P 0 ;0,5=68,7=0.000000
L 4.16090138 -0.92130246 4.1669001 -0.90130207 2 P 0 ;0,5=68,7=0.000000
L 4.1669001 -0.90130207 4.1688997 -0.87880236 2 P 0 ;0,5=68,7=0.000000
L 4.1688997 -0.87880236 4.1669001 -0.85630256 2 P 0 ;0,5=68,7=0.000000
L 4.1669001 -0.85630256 4.16090138 -0.83629764 2 P 0 ;0,5=68,7=0.000000
L 4.16090138 -0.83629764 4.15289951 -0.82130089 2 P 0 ;0,5=68,7=0.000000
L 4.15289951 -0.82130089 4.14089833 -0.80879902 2 P 0 ;0,5=68,7=0.000000
L 4.14089833 -0.80879902 4.12489813 -0.8038 2 P 0 ;0,5=68,7=0.000000
L 4.28489813 -0.9538 4.28489813 -0.8038 2 P 0 ;0,5=68,7=0.000000
L 4.28489813 -0.8038 4.26089961 -0.83379823 2 P 0 ;0,5=68,7=0.000000
L 4.26089961 -0.9538 4.30889665 -0.9538 2 P 0 ;0,5=68,7=0.000000
L 4.44089902 -0.9538 4.44489813 -0.92130246 2 P 0 ;0,5=68,7=0.000000
L 4.44489813 -0.92130246 4.45090049 -0.89380374 2 P 0 ;0,5=68,7=0.000000
L 4.45090049 -0.89380374 4.45889882 -0.8687999 2 P 0 ;0,5=68,7=0.000000
L 4.45889882 -0.8687999 4.4689003 -0.84130118 2 P 0 ;0,5=68,7=0.000000
L 4.4689003 -0.84130118 4.48490059 -0.8038 2 P 0 ;0,5=68,7=0.000000
L 4.48490059 -0.8038 4.40489931 -0.8038 2 P 0 ;0,5=68,7=0.000000
A 12.4952 6.31661998 12.4952 6.31661998 12.4252 6.31661998 9 P 0 N
A 0.57 6.31661998 0.57 6.31661998 0.5 6.31661998 9 P 0 N
A 12.4952 -0.293 12.4952 -0.293 12.4252 -0.293 9 P 0 N
A 0.57 -0.293 0.57 -0.293 0.5 -0.293 9 P 0 N
A 12.06518996 0.29 12.06518996 0.29 11.99518996 0.29 9 P 0 N
A 0.9911 0.2854 0.9911 0.2854 0.9211 0.2854 9 P 0 N
A 0.6536 5.36731998 0.6536 5.36731998 0.5836 5.36731998 9 P 0 N
L 0.1575 0.1575 0.1575 0.1575 27 P 0 ;1
L 0.1575 0.2075 0.1575 0.2075 27 P 0 ;1
L 0.1575 0.2575 0.1575 0.2575 27 P 0 ;1
L 0.1575 1.0575 0.1575 1.0575 27 P 0 ;1
L 0.1575 1.1075 0.1575 1.1075 27 P 0 ;1
L 0.1575 1.1575 0.1575 1.1575 27 P 0 ;1
L 0.1575 1.2075 0.1575 1.2075 27 P 0 ;1
L 0.1575 5.5575 0.1575 5.5575 27 P 0 ;1
L 0.1575 5.6075 0.1575 5.6075 27 P 0 ;1
L 0.1575 5.6575 0.1575 5.6575 27 P 0 ;1
L 0.2075 0.1575 0.2075 0.1575 27 P 0 ;1
L 0.2075 0.2075 0.2075 0.2075 27 P 0 ;1
L 0.2075 0.2575 0.2075 0.2575 27 P 0 ;1
L 0.2075 1.1075 0.2075 1.1075 27 P 0 ;1
L 0.2075 1.1575 0.2075 1.1575 27 P 0 ;1
L 0.2075 1.2075 0.2075 1.2075 27 P 0 ;1
L 0.2075 5.5575 0.2075 5.5575 27 P 0 ;1
L 0.2075 5.6075 0.2075 5.6075 27 P 0 ;1
L 0.2075 5.6575 0.2075 5.6575 27 P 0 ;1
L 0.2575 0.1575 0.2575 0.1575 27 P 0 ;1
L 0.2575 0.2075 0.2575 0.2075 27 P 0 ;1
L 0.2575 0.2575 0.2575 0.2575 27 P 0 ;1
L 0.2575 1.1075 0.2575 1.1075 27 P 0 ;1
L 0.2575 1.1575 0.2575 1.1575 27 P 0 ;1
L 0.2575 1.2075 0.2575 1.2075 27 P 0 ;1
L 0.2575 5.5575 0.2575 5.5575 27 P 0 ;1
L 0.2575 5.6075 0.2575 5.6075 27 P 0 ;1
L 0.2575 5.6575 0.2575 5.6575 27 P 0 ;1
L 0.3075 0.1575 0.3075 0.1575 27 P 0 ;1
L 0.3075 0.2075 0.3075 0.2075 27 P 0 ;1
L 0.3075 0.2575 0.3075 0.2575 27 P 0 ;1
L 0.3075 1.0575 0.3075 1.0575 27 P 0 ;1
L 0.3075 1.1075 0.3075 1.1075 27 P 0 ;1
L 0.3075 1.1575 0.3075 1.1575 27 P 0 ;1
L 0.3075 1.2075 0.3075 1.2075 27 P 0 ;1
L 0.3075 5.5575 0.3075 5.5575 27 P 0 ;1
L 0.3075 5.6075 0.3075 5.6075 27 P 0 ;1
L 0.3075 5.6575 0.3075 5.6575 27 P 0 ;1
L 0.3075 5.7075 0.3075 5.7075 27 P 0 ;1
L 0.3575 0.1575 0.3575 0.1575 27 P 0 ;1
L 0.3575 0.2075 0.3575 0.2075 27 P 0 ;1
L 0.3575 0.2575 0.3575 0.2575 27 P 0 ;1
L 0.3575 0.3075 0.3575 0.3075 27 P 0 ;1
L 0.3575 0.9075 0.3575 0.9075 27 P 0 ;1
L 0.3575 0.9575 0.3575 0.9575 27 P 0 ;1
L 0.3575 1.0075 0.3575 1.0075 27 P 0 ;1
L 0.3575 1.0575 0.3575 1.0575 27 P 0 ;1
L 0.3575 1.1075 0.3575 1.1075 27 P 0 ;1
L 0.3575 1.1575 0.3575 1.1575 27 P 0 ;1
L 0.3575 1.2075 0.3575 1.2075 27 P 0 ;1
L 0.3575 4.7075 0.3575 4.7075 27 P 0 ;1
L 0.3575 4.7575 0.3575 4.7575 27 P 0 ;1
L 0.3575 4.8075 0.3575 4.8075 27 P 0 ;1
L 0.3575 4.8575 0.3575 4.8575 27 P 0 ;1
L 0.3575 4.9075 0.3575 4.9075 27 P 0 ;1
L 0.3575 5.4575 0.3575 5.4575 27 P 0 ;1
L 0.3575 5.5075 0.3575 5.5075 27 P 0 ;1
L 0.3575 5.5575 0.3575 5.5575 27 P 0 ;1
L 0.3575 5.6075 0.3575 5.6075 27 P 0 ;1
L 0.3575 5.6575 0.3575 5.6575 27 P 0 ;1
L 0.3575 5.7075 0.3575 5.7075 27 P 0 ;1
L 0.3575 5.7575 0.3575 5.7575 27 P 0 ;1
L 0.3575 5.8075 0.3575 5.8075 27 P 0 ;1
L 0.3575 5.8575 0.3575 5.8575 27 P 0 ;1
L 0.4075 0.1575 0.4075 0.1575 27 P 0 ;1
L 0.4075 0.2075 0.4075 0.2075 27 P 0 ;1
L 0.4075 0.2575 0.4075 0.2575 27 P 0 ;1
L 0.4075 0.3075 0.4075 0.3075 27 P 0 ;1
L 0.4075 0.3575 0.4075 0.3575 27 P 0 ;1
L 0.4075 0.4075 0.4075 0.4075 27 P 0 ;1
L 0.4075 0.4575 0.4075 0.4575 27 P 0 ;1
L 0.4075 0.5075 0.4075 0.5075 27 P 0 ;1
L 0.4075 0.8575 0.4075 0.8575 27 P 0 ;1
L 0.4075 0.9075 0.4075 0.9075 27 P 0 ;1
L 0.4075 0.9575 0.4075 0.9575 27 P 0 ;1
L 0.4075 1.0075 0.4075 1.0075 27 P 0 ;1
L 0.4075 1.0575 0.4075 1.0575 27 P 0 ;1
L 0.4075 1.1075 0.4075 1.1075 27 P 0 ;1
L 0.4075 1.1575 0.4075 1.1575 27 P 0 ;1
L 0.4075 1.2075 0.4075 1.2075 27 P 0 ;1
L 0.4075 1.2575 0.4075 1.2575 27 P 0 ;1
L 0.4075 4.7075 0.4075 4.7075 27 P 0 ;1
L 0.4075 4.7575 0.4075 4.7575 27 P 0 ;1
L 0.4075 4.8075 0.4075 4.8075 27 P 0 ;1
L 0.4075 4.8575 0.4075 4.8575 27 P 0 ;1
L 0.4075 4.9075 0.4075 4.9075 27 P 0 ;1
L 0.4075 4.9575 0.4075 4.9575 27 P 0 ;1
L 0.4075 5.3075 0.4075 5.3075 27 P 0 ;1
L 0.4075 5.3575 0.4075 5.3575 27 P 0 ;1
L 0.4075 5.4075 0.4075 5.4075 27 P 0 ;1
L 0.4075 5.4575 0.4075 5.4575 27 P 0 ;1
L 0.4075 5.5075 0.4075 5.5075 27 P 0 ;1
L 0.4075 5.5575 0.4075 5.5575 27 P 0 ;1
L 0.4575 0.1575 0.4575 0.1575 27 P 0 ;1
L 0.4575 0.2075 0.4575 0.2075 27 P 0 ;1
L 0.4575 0.2575 0.4575 0.2575 27 P 0 ;1
L 0.4575 0.3075 0.4575 0.3075 27 P 0 ;1
L 0.4575 0.3575 0.4575 0.3575 27 P 0 ;1
L 0.4575 0.4075 0.4575 0.4075 27 P 0 ;1
L 0.4575 0.4575 0.4575 0.4575 27 P 0 ;1
L 0.4575 0.5075 0.4575 0.5075 27 P 0 ;1
L 0.4575 0.5575 0.4575 0.5575 27 P 0 ;1
L 0.4575 0.6075 0.4575 0.6075 27 P 0 ;1
L 0.4575 0.7575 0.4575 0.7575 27 P 0 ;1
L 0.4575 0.8075 0.4575 0.8075 27 P 0 ;1
L 0.4575 0.8575 0.4575 0.8575 27 P 0 ;1
L 0.4575 0.9075 0.4575 0.9075 27 P 0 ;1
L 0.4575 0.9575 0.4575 0.9575 27 P 0 ;1
L 0.4575 1.0075 0.4575 1.0075 27 P 0 ;1
L 0.4575 1.0575 0.4575 1.0575 27 P 0 ;1
L 0.4575 1.1075 0.4575 1.1075 27 P 0 ;1
L 0.4575 1.1575 0.4575 1.1575 27 P 0 ;1
L 0.4575 1.2075 0.4575 1.2075 27 P 0 ;1
L 0.4575 1.2575 0.4575 1.2575 27 P 0 ;1
L 0.4575 1.3075 0.4575 1.3075 27 P 0 ;1
L 0.4575 1.3575 0.4575 1.3575 27 P 0 ;1
L 0.4575 1.4075 0.4575 1.4075 27 P 0 ;1
L 0.4575 1.4575 0.4575 1.4575 27 P 0 ;1
L 0.4575 1.5075 0.4575 1.5075 27 P 0 ;1
L 0.4575 1.5575 0.4575 1.5575 27 P 0 ;1
L 0.4575 1.6075 0.4575 1.6075 27 P 0 ;1
L 0.4575 1.6575 0.4575 1.6575 27 P 0 ;1
L 0.4575 1.7075 0.4575 1.7075 27 P 0 ;1
L 0.4575 1.7575 0.4575 1.7575 27 P 0 ;1
L 0.4575 1.8075 0.4575 1.8075 27 P 0 ;1
L 0.4575 1.8575 0.4575 1.8575 27 P 0 ;1
L 0.4575 1.9075 0.4575 1.9075 27 P 0 ;1
L 0.4575 1.9575 0.4575 1.9575 27 P 0 ;1
L 0.4575 2.0075 0.4575 2.0075 27 P 0 ;1
L 0.4575 2.0575 0.4575 2.0575 27 P 0 ;1
L 0.4575 2.1075 0.4575 2.1075 27 P 0 ;1
L 0.4575 2.1575 0.4575 2.1575 27 P 0 ;1
L 0.4575 2.2075 0.4575 2.2075 27 P 0 ;1
L 0.4575 2.2575 0.4575 2.2575 27 P 0 ;1
L 0.4575 2.3075 0.4575 2.3075 27 P 0 ;1
L 0.4575 2.3575 0.4575 2.3575 27 P 0 ;1
L 0.4575 2.4075 0.4575 2.4075 27 P 0 ;1
L 0.4575 2.4575 0.4575 2.4575 27 P 0 ;1
L 0.4575 2.5075 0.4575 2.5075 27 P 0 ;1
L 0.4575 2.5575 0.4575 2.5575 27 P 0 ;1
L 0.4575 2.6075 0.4575 2.6075 27 P 0 ;1
L 0.4575 2.6575 0.4575 2.6575 27 P 0 ;1
L 0.4575 2.7075 0.4575 2.7075 27 P 0 ;1
L 0.4575 2.7575 0.4575 2.7575 27 P 0 ;1
L 0.4575 2.8075 0.4575 2.8075 27 P 0 ;1
L 0.4575 2.8575 0.4575 2.8575 27 P 0 ;1
L 0.4575 2.9075 0.4575 2.9075 27 P 0 ;1
L 0.4575 2.9575 0.4575 2.9575 27 P 0 ;1
L 0.4575 3.0075 0.4575 3.0075 27 P 0 ;1
L 0.4575 3.0575 0.4575 3.0575 27 P 0 ;1
L 0.4575 3.1075 0.4575 3.1075 27 P 0 ;1
L 0.4575 3.1575 0.4575 3.1575 27 P 0 ;1
L 0.4575 3.2075 0.4575 3.2075 27 P 0 ;1
L 0.4575 3.2575 0.4575 3.2575 27 P 0 ;1
L 0.4575 3.3075 0.4575 3.3075 27 P 0 ;1
L 0.4575 3.3575 0.4575 3.3575 27 P 0 ;1
L 0.4575 3.4075 0.4575 3.4075 27 P 0 ;1
L 0.4575 3.4575 0.4575 3.4575 27 P 0 ;1
L 0.4575 3.5075 0.4575 3.5075 27 P 0 ;1
L 0.4575 3.5575 0.4575 3.5575 27 P 0 ;1
L 0.4575 3.6075 0.4575 3.6075 27 P 0 ;1
L 0.4575 3.6575 0.4575 3.6575 27 P 0 ;1
L 0.4575 3.7075 0.4575 3.7075 27 P 0 ;1
L 0.4575 3.7575 0.4575 3.7575 27 P 0 ;1
L 0.4575 3.8075 0.4575 3.8075 27 P 0 ;1
L 0.4575 3.8575 0.4575 3.8575 27 P 0 ;1
L 0.4575 3.9075 0.4575 3.9075 27 P 0 ;1
L 0.4575 3.9575 0.4575 3.9575 27 P 0 ;1
L 0.4575 4.0075 0.4575 4.0075 27 P 0 ;1
L 0.4575 4.0575 0.4575 4.0575 27 P 0 ;1
L 0.4575 4.1075 0.4575 4.1075 27 P 0 ;1
L 0.4575 4.1575 0.4575 4.1575 27 P 0 ;1
L 0.4575 4.2075 0.4575 4.2075 27 P 0 ;1
L 0.4575 4.2575 0.4575 4.2575 27 P 0 ;1
L 0.4575 4.3075 0.4575 4.3075 27 P 0 ;1
L 0.4575 4.3575 0.4575 4.3575 27 P 0 ;1
L 0.4575 4.4075 0.4575 4.4075 27 P 0 ;1
L 0.4575 4.4575 0.4575 4.4575 27 P 0 ;1
L 0.4575 4.5075 0.4575 4.5075 27 P 0 ;1
L 0.4575 4.5575 0.4575 4.5575 27 P 0 ;1
L 0.4575 4.6075 0.4575 4.6075 27 P 0 ;1
L 0.4575 4.6575 0.4575 4.6575 27 P 0 ;1
L 0.4575 4.7075 0.4575 4.7075 27 P 0 ;1
L 0.4575 4.7575 0.4575 4.7575 27 P 0 ;1
L 0.4575 4.8075 0.4575 4.8075 27 P 0 ;1
L 0.4575 4.8575 0.4575 4.8575 27 P 0 ;1
L 0.4575 4.9075 0.4575 4.9075 27 P 0 ;1
L 0.4575 4.9575 0.4575 4.9575 27 P 0 ;1
L 0.4575 5.0075 0.4575 5.0075 27 P 0 ;1
L 0.4575 5.0575 0.4575 5.0575 27 P 0 ;1
L 0.4575 5.2075 0.4575 5.2075 27 P 0 ;1
L 0.4575 5.2575 0.4575 5.2575 27 P 0 ;1
L 0.5075 0.1575 0.5075 0.1575 27 P 0 ;1
L 0.5075 0.2075 0.5075 0.2075 27 P 0 ;1
L 0.5075 0.2575 0.5075 0.2575 27 P 0 ;1
L 0.5075 0.3075 0.5075 0.3075 27 P 0 ;1
L 0.5075 0.3575 0.5075 0.3575 27 P 0 ;1
L 0.5075 0.4075 0.5075 0.4075 27 P 0 ;1
L 0.5075 0.4575 0.5075 0.4575 27 P 0 ;1
L 0.5075 0.5075 0.5075 0.5075 27 P 0 ;1
L 0.5075 0.5575 0.5075 0.5575 27 P 0 ;1
L 0.5075 0.6075 0.5075 0.6075 27 P 0 ;1
L 0.5075 0.6575 0.5075 0.6575 27 P 0 ;1
L 0.5075 0.7075 0.5075 0.7075 27 P 0 ;1
L 0.5075 0.7575 0.5075 0.7575 27 P 0 ;1
L 0.5075 0.8075 0.5075 0.8075 27 P 0 ;1
L 0.5075 0.8575 0.5075 0.8575 27 P 0 ;1
L 0.5075 0.9075 0.5075 0.9075 27 P 0 ;1
L 0.5075 0.9575 0.5075 0.9575 27 P 0 ;1
L 0.5075 1.0075 0.5075 1.0075 27 P 0 ;1
L 0.5075 1.0575 0.5075 1.0575 27 P 0 ;1
L 0.5075 1.1075 0.5075 1.1075 27 P 0 ;1
L 0.5075 1.1575 0.5075 1.1575 27 P 0 ;1
L 0.5075 1.2075 0.5075 1.2075 27 P 0 ;1
L 0.5075 1.2575 0.5075 1.2575 27 P 0 ;1
L 0.5075 1.3075 0.5075 1.3075 27 P 0 ;1
L 0.5075 1.3575 0.5075 1.3575 27 P 0 ;1
L 0.5075 1.4075 0.5075 1.4075 27 P 0 ;1
L 0.5075 1.4575 0.5075 1.4575 27 P 0 ;1
L 0.5075 1.5075 0.5075 1.5075 27 P 0 ;1
L 0.5075 1.5575 0.5075 1.5575 27 P 0 ;1
L 0.5075 1.6075 0.5075 1.6075 27 P 0 ;1
L 0.5075 1.6575 0.5075 1.6575 27 P 0 ;1
L 0.5075 1.7075 0.5075 1.7075 27 P 0 ;1
L 0.5075 1.7575 0.5075 1.7575 27 P 0 ;1
L 0.5075 1.8075 0.5075 1.8075 27 P 0 ;1
L 0.5075 1.8575 0.5075 1.8575 27 P 0 ;1
L 0.5075 1.9075 0.5075 1.9075 27 P 0 ;1
L 0.5075 1.9575 0.5075 1.9575 27 P 0 ;1
L 0.5075 2.0075 0.5075 2.0075 27 P 0 ;1
L 0.5075 2.0575 0.5075 2.0575 27 P 0 ;1
L 0.5075 2.1075 0.5075 2.1075 27 P 0 ;1
L 0.5075 2.1575 0.5075 2.1575 27 P 0 ;1
L 0.5075 2.2075 0.5075 2.2075 27 P 0 ;1
L 0.5075 2.2575 0.5075 2.2575 27 P 0 ;1
L 0.5075 2.3075 0.5075 2.3075 27 P 0 ;1
L 0.5075 2.3575 0.5075 2.3575 27 P 0 ;1
L 0.5075 2.4075 0.5075 2.4075 27 P 0 ;1
L 0.5075 2.4575 0.5075 2.4575 27 P 0 ;1
L 0.5075 2.5075 0.5075 2.5075 27 P 0 ;1
L 0.5075 2.5575 0.5075 2.5575 27 P 0 ;1
L 0.5075 2.6075 0.5075 2.6075 27 P 0 ;1
L 0.5075 2.6575 0.5075 2.6575 27 P 0 ;1
L 0.5075 2.7075 0.5075 2.7075 27 P 0 ;1
L 0.5075 2.7575 0.5075 2.7575 27 P 0 ;1
L 0.5075 2.8075 0.5075 2.8075 27 P 0 ;1
L 0.5075 2.8575 0.5075 2.8575 27 P 0 ;1
L 0.5075 2.9075 0.5075 2.9075 27 P 0 ;1
L 0.5075 2.9575 0.5075 2.9575 27 P 0 ;1
L 0.5075 3.0075 0.5075 3.0075 27 P 0 ;1
L 0.5075 3.0575 0.5075 3.0575 27 P 0 ;1
L 0.5075 3.1075 0.5075 3.1075 27 P 0 ;1
L 0.5075 3.1575 0.5075 3.1575 27 P 0 ;1
L 0.5075 3.2075 0.5075 3.2075 27 P 0 ;1
L 0.5075 3.2575 0.5075 3.2575 27 P 0 ;1
L 0.5075 3.3075 0.5075 3.3075 27 P 0 ;1
L 0.5075 3.3575 0.5075 3.3575 27 P 0 ;1
L 0.5075 3.4075 0.5075 3.4075 27 P 0 ;1
L 0.5075 3.4575 0.5075 3.4575 27 P 0 ;1
L 0.5075 3.5075 0.5075 3.5075 27 P 0 ;1
L 0.5075 3.5575 0.5075 3.5575 27 P 0 ;1
L 0.5075 3.6075 0.5075 3.6075 27 P 0 ;1
L 0.5075 3.6575 0.5075 3.6575 27 P 0 ;1
L 0.5075 3.7075 0.5075 3.7075 27 P 0 ;1
L 0.5075 3.7575 0.5075 3.7575 27 P 0 ;1
L 0.5075 3.8075 0.5075 3.8075 27 P 0 ;1
L 0.5075 3.8575 0.5075 3.8575 27 P 0 ;1
L 0.5075 3.9075 0.5075 3.9075 27 P 0 ;1
L 0.5075 3.9575 0.5075 3.9575 27 P 0 ;1
L 0.5075 4.0075 0.5075 4.0075 27 P 0 ;1
L 0.5075 4.0575 0.5075 4.0575 27 P 0 ;1
L 0.5075 4.1075 0.5075 4.1075 27 P 0 ;1
L 0.5075 4.1575 0.5075 4.1575 27 P 0 ;1
L 0.5075 4.2075 0.5075 4.2075 27 P 0 ;1
L 0.5075 4.2575 0.5075 4.2575 27 P 0 ;1
L 0.5075 4.3075 0.5075 4.3075 27 P 0 ;1
L 0.5075 4.3575 0.5075 4.3575 27 P 0 ;1
L 0.5075 4.4075 0.5075 4.4075 27 P 0 ;1
L 0.5075 4.4575 0.5075 4.4575 27 P 0 ;1
L 0.5075 4.5075 0.5075 4.5075 27 P 0 ;1
L 0.5075 4.5575 0.5075 4.5575 27 P 0 ;1
L 0.5075 4.6075 0.5075 4.6075 27 P 0 ;1
L 0.5075 4.6575 0.5075 4.6575 27 P 0 ;1
L 0.5075 4.7075 0.5075 4.7075 27 P 0 ;1
L 0.5075 4.7575 0.5075 4.7575 27 P 0 ;1
L 0.5075 4.8075 0.5075 4.8075 27 P 0 ;1
L 0.5075 4.8575 0.5075 4.8575 27 P 0 ;1
L 0.5075 4.9075 0.5075 4.9075 27 P 0 ;1
L 0.5075 4.9575 0.5075 4.9575 27 P 0 ;1
L 0.5075 5.0075 0.5075 5.0075 27 P 0 ;1
L 0.5075 5.0575 0.5075 5.0575 27 P 0 ;1
L 0.5075 5.1075 0.5075 5.1075 27 P 0 ;1
L 0.5075 5.1575 0.5075 5.1575 27 P 0 ;1
L 0.5075 5.2075 0.5075 5.2075 27 P 0 ;1
L 0.5575 0.1575 0.5575 0.1575 27 P 0 ;1
L 0.5575 0.4075 0.5575 0.4075 27 P 0 ;1
L 0.5575 0.4575 0.5575 0.4575 27 P 0 ;1
L 0.5575 0.5075 0.5575 0.5075 27 P 0 ;1
L 0.5575 0.5575 0.5575 0.5575 27 P 0 ;1
L 0.5575 0.6075 0.5575 0.6075 27 P 0 ;1
L 0.5575 0.6575 0.5575 0.6575 27 P 0 ;1
L 0.5575 0.7075 0.5575 0.7075 27 P 0 ;1
L 0.5575 0.7575 0.5575 0.7575 27 P 0 ;1
L 0.5575 0.8075 0.5575 0.8075 27 P 0 ;1
L 0.5575 0.8575 0.5575 0.8575 27 P 0 ;1
L 0.5575 0.9075 0.5575 0.9075 27 P 0 ;1
L 0.5575 0.9575 0.5575 0.9575 27 P 0 ;1
L 0.5575 1.0075 0.5575 1.0075 27 P 0 ;1
L 0.5575 1.0575 0.5575 1.0575 27 P 0 ;1
L 0.5575 1.1075 0.5575 1.1075 27 P 0 ;1
L 0.5575 1.1575 0.5575 1.1575 27 P 0 ;1
L 0.5575 1.2075 0.5575 1.2075 27 P 0 ;1
L 0.5575 1.2575 0.5575 1.2575 27 P 0 ;1
L 0.5575 1.3075 0.5575 1.3075 27 P 0 ;1
L 0.5575 1.3575 0.5575 1.3575 27 P 0 ;1
L 0.5575 1.4075 0.5575 1.4075 27 P 0 ;1
L 0.5575 1.4575 0.5575 1.4575 27 P 0 ;1
L 0.5575 1.5075 0.5575 1.5075 27 P 0 ;1
L 0.5575 1.5575 0.5575 1.5575 27 P 0 ;1
L 0.5575 1.6075 0.5575 1.6075 27 P 0 ;1
L 0.5575 1.7075 0.5575 1.7075 27 P 0 ;1
L 0.5575 1.7575 0.5575 1.7575 27 P 0 ;1
L 0.5575 1.8075 0.5575 1.8075 27 P 0 ;1
L 0.5575 1.8575 0.5575 1.8575 27 P 0 ;1
L 0.5575 1.9075 0.5575 1.9075 27 P 0 ;1
L 0.5575 1.9575 0.5575 1.9575 27 P 0 ;1
L 0.5575 2.0075 0.5575 2.0075 27 P 0 ;1
L 0.5575 2.0575 0.5575 2.0575 27 P 0 ;1
L 0.5575 2.1075 0.5575 2.1075 27 P 0 ;1
L 0.5575 2.1575 0.5575 2.1575 27 P 0 ;1
L 0.5575 2.2075 0.5575 2.2075 27 P 0 ;1
L 0.5575 2.2575 0.5575 2.2575 27 P 0 ;1
L 0.5575 2.3075 0.5575 2.3075 27 P 0 ;1
L 0.5575 2.3575 0.5575 2.3575 27 P 0 ;1
L 0.5575 2.4075 0.5575 2.4075 27 P 0 ;1
L 0.5575 2.4575 0.5575 2.4575 27 P 0 ;1
L 0.5575 2.5075 0.5575 2.5075 27 P 0 ;1
L 0.5575 2.5575 0.5575 2.5575 27 P 0 ;1
L 0.5575 2.6075 0.5575 2.6075 27 P 0 ;1
L 0.5575 2.6575 0.5575 2.6575 27 P 0 ;1
L 0.5575 2.7075 0.5575 2.7075 27 P 0 ;1
L 0.5575 2.7575 0.5575 2.7575 27 P 0 ;1
L 0.5575 2.8075 0.5575 2.8075 27 P 0 ;1
L 0.5575 2.8575 0.5575 2.8575 27 P 0 ;1
L 0.5575 2.9075 0.5575 2.9075 27 P 0 ;1
L 0.5575 2.9575 0.5575 2.9575 27 P 0 ;1
L 0.5575 3.0075 0.5575 3.0075 27 P 0 ;1
L 0.5575 3.0575 0.5575 3.0575 27 P 0 ;1
L 0.5575 3.1075 0.5575 3.1075 27 P 0 ;1
L 0.5575 3.1575 0.5575 3.1575 27 P 0 ;1
L 0.5575 3.2075 0.5575 3.2075 27 P 0 ;1
L 0.5575 3.2575 0.5575 3.2575 27 P 0 ;1
L 0.5575 3.3075 0.5575 3.3075 27 P 0 ;1
L 0.5575 3.3575 0.5575 3.3575 27 P 0 ;1
L 0.5575 3.4075 0.5575 3.4075 27 P 0 ;1
L 0.5575 3.4575 0.5575 3.4575 27 P 0 ;1
L 0.5575 3.5075 0.5575 3.5075 27 P 0 ;1
L 0.5575 3.5575 0.5575 3.5575 27 P 0 ;1
L 0.5575 3.6075 0.5575 3.6075 27 P 0 ;1
L 0.5575 3.6575 0.5575 3.6575 27 P 0 ;1
L 0.5575 3.7075 0.5575 3.7075 27 P 0 ;1
L 0.5575 3.7575 0.5575 3.7575 27 P 0 ;1
L 0.5575 3.8075 0.5575 3.8075 27 P 0 ;1
L 0.5575 3.8575 0.5575 3.8575 27 P 0 ;1
L 0.5575 3.9075 0.5575 3.9075 27 P 0 ;1
L 0.5575 3.9575 0.5575 3.9575 27 P 0 ;1
L 0.5575 4.0075 0.5575 4.0075 27 P 0 ;1
L 0.5575 4.0575 0.5575 4.0575 27 P 0 ;1
L 0.5575 4.1075 0.5575 4.1075 27 P 0 ;1
L 0.5575 4.1575 0.5575 4.1575 27 P 0 ;1
L 0.5575 4.2075 0.5575 4.2075 27 P 0 ;1
L 0.5575 4.2575 0.5575 4.2575 27 P 0 ;1
L 0.5575 4.3075 0.5575 4.3075 27 P 0 ;1
L 0.5575 4.3575 0.5575 4.3575 27 P 0 ;1
L 0.5575 4.4075 0.5575 4.4075 27 P 0 ;1
L 0.5575 4.4575 0.5575 4.4575 27 P 0 ;1
L 0.5575 4.5075 0.5575 4.5075 27 P 0 ;1
L 0.5575 4.5575 0.5575 4.5575 27 P 0 ;1
L 0.5575 4.6075 0.5575 4.6075 27 P 0 ;1
L 0.5575 4.6575 0.5575 4.6575 27 P 0 ;1
L 0.5575 4.7075 0.5575 4.7075 27 P 0 ;1
L 0.5575 4.7575 0.5575 4.7575 27 P 0 ;1
L 0.5575 4.8075 0.5575 4.8075 27 P 0 ;1
L 0.5575 4.8575 0.5575 4.8575 27 P 0 ;1
L 0.5575 4.9075 0.5575 4.9075 27 P 0 ;1
L 0.5575 4.9575 0.5575 4.9575 27 P 0 ;1
L 0.5575 5.0075 0.5575 5.0075 27 P 0 ;1
L 0.5575 5.0575 0.5575 5.0575 27 P 0 ;1
L 0.5575 5.1075 0.5575 5.1075 27 P 0 ;1
L 0.5575 5.1575 0.5575 5.1575 27 P 0 ;1
L 0.6075 0.4575 0.6075 0.4575 27 P 0 ;1
L 0.6075 0.5075 0.6075 0.5075 27 P 0 ;1
L 0.6075 0.5575 0.6075 0.5575 27 P 0 ;1
L 0.6075 0.6075 0.6075 0.6075 27 P 0 ;1
L 0.6075 0.6575 0.6075 0.6575 27 P 0 ;1
L 0.6075 0.7075 0.6075 0.7075 27 P 0 ;1
L 0.6075 0.7575 0.6075 0.7575 27 P 0 ;1
L 0.6075 0.8075 0.6075 0.8075 27 P 0 ;1
L 0.6075 0.8575 0.6075 0.8575 27 P 0 ;1
L 0.6075 0.9075 0.6075 0.9075 27 P 0 ;1
L 0.6075 0.9575 0.6075 0.9575 27 P 0 ;1
L 0.6075 1.0075 0.6075 1.0075 27 P 0 ;1
L 0.6075 1.0575 0.6075 1.0575 27 P 0 ;1
L 0.6075 1.1075 0.6075 1.1075 27 P 0 ;1
L 0.6075 1.1575 0.6075 1.1575 27 P 0 ;1
L 0.6075 1.2075 0.6075 1.2075 27 P 0 ;1
L 0.6075 1.2575 0.6075 1.2575 27 P 0 ;1
L 0.6075 1.3075 0.6075 1.3075 27 P 0 ;1
L 0.6075 1.3575 0.6075 1.3575 27 P 0 ;1
L 0.6075 1.4075 0.6075 1.4075 27 P 0 ;1
L 0.6075 1.4575 0.6075 1.4575 27 P 0 ;1
L 0.6075 1.5075 0.6075 1.5075 27 P 0 ;1
L 0.6075 1.5575 0.6075 1.5575 27 P 0 ;1
L 0.6075 1.7575 0.6075 1.7575 27 P 0 ;1
L 0.6075 2.1575 0.6075 2.1575 27 P 0 ;1
L 0.6075 2.2075 0.6075 2.2075 27 P 0 ;1
L 0.6075 2.2575 0.6075 2.2575 27 P 0 ;1
L 0.6075 2.3075 0.6075 2.3075 27 P 0 ;1
L 0.6075 2.3575 0.6075 2.3575 27 P 0 ;1
L 0.6075 2.4075 0.6075 2.4075 27 P 0 ;1
L 0.6075 2.4575 0.6075 2.4575 27 P 0 ;1
L 0.6075 2.5075 0.6075 2.5075 27 P 0 ;1
L 0.6075 2.5575 0.6075 2.5575 27 P 0 ;1
L 0.6075 2.6075 0.6075 2.6075 27 P 0 ;1
L 0.6075 2.6575 0.6075 2.6575 27 P 0 ;1
L 0.6075 2.7075 0.6075 2.7075 27 P 0 ;1
L 0.6075 2.7575 0.6075 2.7575 27 P 0 ;1
L 0.6075 2.8075 0.6075 2.8075 27 P 0 ;1
L 0.6075 2.8575 0.6075 2.8575 27 P 0 ;1
L 0.6075 2.9075 0.6075 2.9075 27 P 0 ;1
L 0.6075 2.9575 0.6075 2.9575 27 P 0 ;1
L 0.6075 3.0075 0.6075 3.0075 27 P 0 ;1
L 0.6075 3.0575 0.6075 3.0575 27 P 0 ;1
L 0.6075 3.1075 0.6075 3.1075 27 P 0 ;1
L 0.6075 3.1575 0.6075 3.1575 27 P 0 ;1
L 0.6075 3.2075 0.6075 3.2075 27 P 0 ;1
L 0.6075 3.2575 0.6075 3.2575 27 P 0 ;1
L 0.6075 3.3075 0.6075 3.3075 27 P 0 ;1
L 0.6075 3.3575 0.6075 3.3575 27 P 0 ;1
L 0.6075 3.4075 0.6075 3.4075 27 P 0 ;1
L 0.6075 3.4575 0.6075 3.4575 27 P 0 ;1
L 0.6075 3.5075 0.6075 3.5075 27 P 0 ;1
L 0.6075 3.5575 0.6075 3.5575 27 P 0 ;1
L 0.6075 3.6075 0.6075 3.6075 27 P 0 ;1
L 0.6075 3.6575 0.6075 3.6575 27 P 0 ;1
L 0.6075 3.7075 0.6075 3.7075 27 P 0 ;1
L 0.6075 3.7575 0.6075 3.7575 27 P 0 ;1
L 0.6075 3.8075 0.6075 3.8075 27 P 0 ;1
L 0.6075 3.8575 0.6075 3.8575 27 P 0 ;1
L 0.6075 3.9075 0.6075 3.9075 27 P 0 ;1
L 0.6075 3.9575 0.6075 3.9575 27 P 0 ;1
L 0.6075 4.0075 0.6075 4.0075 27 P 0 ;1
L 0.6075 4.0575 0.6075 4.0575 27 P 0 ;1
L 0.6075 4.1075 0.6075 4.1075 27 P 0 ;1
L 0.6075 4.1575 0.6075 4.1575 27 P 0 ;1
L 0.6075 4.2075 0.6075 4.2075 27 P 0 ;1
L 0.6075 4.2575 0.6075 4.2575 27 P 0 ;1
L 0.6075 4.3075 0.6075 4.3075 27 P 0 ;1
L 0.6075 4.3575 0.6075 4.3575 27 P 0 ;1
L 0.6075 4.4075 0.6075 4.4075 27 P 0 ;1
L 0.6075 4.4575 0.6075 4.4575 27 P 0 ;1
L 0.6075 4.5075 0.6075 4.5075 27 P 0 ;1
L 0.6075 4.5575 0.6075 4.5575 27 P 0 ;1
L 0.6075 4.6075 0.6075 4.6075 27 P 0 ;1
L 0.6075 4.6575 0.6075 4.6575 27 P 0 ;1
L 0.6075 4.7075 0.6075 4.7075 27 P 0 ;1
L 0.6075 4.7575 0.6075 4.7575 27 P 0 ;1
L 0.6075 4.8075 0.6075 4.8075 27 P 0 ;1
L 0.6075 4.8575 0.6075 4.8575 27 P 0 ;1
L 0.6075 4.9075 0.6075 4.9075 27 P 0 ;1
L 0.6075 4.9575 0.6075 4.9575 27 P 0 ;1
L 0.6075 5.0075 0.6075 5.0075 27 P 0 ;1
L 0.6575 0.4575 0.6575 0.4575 27 P 0 ;1
L 0.6575 0.5075 0.6575 0.5075 27 P 0 ;1
L 0.6575 0.5575 0.6575 0.5575 27 P 0 ;1
L 0.6575 0.6075 0.6575 0.6075 27 P 0 ;1
L 0.6575 0.6575 0.6575 0.6575 27 P 0 ;1
L 0.6575 0.7075 0.6575 0.7075 27 P 0 ;1
L 0.6575 0.7575 0.6575 0.7575 27 P 0 ;1
L 0.6575 0.8075 0.6575 0.8075 27 P 0 ;1
L 0.6575 0.8575 0.6575 0.8575 27 P 0 ;1
L 0.6575 0.9075 0.6575 0.9075 27 P 0 ;1
L 0.6575 0.9575 0.6575 0.9575 27 P 0 ;1
L 0.6575 1.0075 0.6575 1.0075 27 P 0 ;1
L 0.6575 1.0575 0.6575 1.0575 27 P 0 ;1
L 0.6575 1.1075 0.6575 1.1075 27 P 0 ;1
L 0.6575 1.1575 0.6575 1.1575 27 P 0 ;1
L 0.6575 1.2075 0.6575 1.2075 27 P 0 ;1
L 0.6575 1.2575 0.6575 1.2575 27 P 0 ;1
L 0.6575 1.3075 0.6575 1.3075 27 P 0 ;1
L 0.6575 1.3575 0.6575 1.3575 27 P 0 ;1
L 0.6575 1.4075 0.6575 1.4075 27 P 0 ;1
L 0.6575 1.4575 0.6575 1.4575 27 P 0 ;1
L 0.6575 1.5075 0.6575 1.5075 27 P 0 ;1
L 0.6575 1.5575 0.6575 1.5575 27 P 0 ;1
L 0.6575 1.7575 0.6575 1.7575 27 P 0 ;1
L 0.6575 2.1575 0.6575 2.1575 27 P 0 ;1
L 0.6575 2.2075 0.6575 2.2075 27 P 0 ;1
L 0.6575 2.2575 0.6575 2.2575 27 P 0 ;1
L 0.6575 2.3075 0.6575 2.3075 27 P 0 ;1
L 0.6575 2.3575 0.6575 2.3575 27 P 0 ;1
L 0.6575 2.4075 0.6575 2.4075 27 P 0 ;1
L 0.6575 2.4575 0.6575 2.4575 27 P 0 ;1
L 0.6575 2.5075 0.6575 2.5075 27 P 0 ;1
L 0.6575 2.5575 0.6575 2.5575 27 P 0 ;1
L 0.6575 2.6075 0.6575 2.6075 27 P 0 ;1
L 0.6575 2.6575 0.6575 2.6575 27 P 0 ;1
L 0.6575 2.7075 0.6575 2.7075 27 P 0 ;1
L 0.6575 2.7575 0.6575 2.7575 27 P 0 ;1
L 0.6575 2.8075 0.6575 2.8075 27 P 0 ;1
L 0.6575 2.8575 0.6575 2.8575 27 P 0 ;1
L 0.6575 2.9075 0.6575 2.9075 27 P 0 ;1
L 0.6575 2.9575 0.6575 2.9575 27 P 0 ;1
L 0.6575 3.0075 0.6575 3.0075 27 P 0 ;1
L 0.6575 3.0575 0.6575 3.0575 27 P 0 ;1
L 0.6575 3.1075 0.6575 3.1075 27 P 0 ;1
L 0.6575 3.1575 0.6575 3.1575 27 P 0 ;1
L 0.6575 3.2075 0.6575 3.2075 27 P 0 ;1
L 0.6575 3.2575 0.6575 3.2575 27 P 0 ;1
L 0.6575 3.3075 0.6575 3.3075 27 P 0 ;1
L 0.6575 3.3575 0.6575 3.3575 27 P 0 ;1
L 0.6575 3.4075 0.6575 3.4075 27 P 0 ;1
L 0.6575 3.4575 0.6575 3.4575 27 P 0 ;1
L 0.6575 3.5075 0.6575 3.5075 27 P 0 ;1
L 0.6575 3.5575 0.6575 3.5575 27 P 0 ;1
L 0.6575 3.6075 0.6575 3.6075 27 P 0 ;1
L 0.6575 3.6575 0.6575 3.6575 27 P 0 ;1
L 0.6575 3.7075 0.6575 3.7075 27 P 0 ;1
L 0.6575 3.7575 0.6575 3.7575 27 P 0 ;1
L 0.6575 3.8075 0.6575 3.8075 27 P 0 ;1
L 0.6575 3.8575 0.6575 3.8575 27 P 0 ;1
L 0.6575 3.9075 0.6575 3.9075 27 P 0 ;1
L 0.6575 3.9575 0.6575 3.9575 27 P 0 ;1
L 0.6575 4.0075 0.6575 4.0075 27 P 0 ;1
L 0.6575 4.0575 0.6575 4.0575 27 P 0 ;1
L 0.6575 4.1075 0.6575 4.1075 27 P 0 ;1
L 0.6575 4.1575 0.6575 4.1575 27 P 0 ;1
L 0.6575 4.2075 0.6575 4.2075 27 P 0 ;1
L 0.6575 4.2575 0.6575 4.2575 27 P 0 ;1
L 0.6575 4.3075 0.6575 4.3075 27 P 0 ;1
L 0.6575 4.3575 0.6575 4.3575 27 P 0 ;1
L 0.6575 4.4075 0.6575 4.4075 27 P 0 ;1
L 0.6575 4.4575 0.6575 4.4575 27 P 0 ;1
L 0.6575 4.5075 0.6575 4.5075 27 P 0 ;1
L 0.6575 4.5575 0.6575 4.5575 27 P 0 ;1
L 0.6575 4.6075 0.6575 4.6075 27 P 0 ;1
L 0.6575 4.6575 0.6575 4.6575 27 P 0 ;1
L 0.6575 4.7075 0.6575 4.7075 27 P 0 ;1
L 0.6575 4.7575 0.6575 4.7575 27 P 0 ;1
L 0.6575 4.8075 0.6575 4.8075 27 P 0 ;1
L 0.6575 4.8575 0.6575 4.8575 27 P 0 ;1
L 0.7075 0.4575 0.7075 0.4575 27 P 0 ;1
L 0.7075 0.5075 0.7075 0.5075 27 P 0 ;1
L 0.7075 0.5575 0.7075 0.5575 27 P 0 ;1
L 0.7075 0.6075 0.7075 0.6075 27 P 0 ;1
L 0.7075 0.6575 0.7075 0.6575 27 P 0 ;1
L 0.7075 0.7075 0.7075 0.7075 27 P 0 ;1
L 0.7075 0.7575 0.7075 0.7575 27 P 0 ;1
L 0.7075 0.8075 0.7075 0.8075 27 P 0 ;1
L 0.7075 0.8575 0.7075 0.8575 27 P 0 ;1
L 0.7075 0.9075 0.7075 0.9075 27 P 0 ;1
L 0.7075 0.9575 0.7075 0.9575 27 P 0 ;1
L 0.7075 1.0075 0.7075 1.0075 27 P 0 ;1
L 0.7075 1.0575 0.7075 1.0575 27 P 0 ;1
L 0.7075 1.1075 0.7075 1.1075 27 P 0 ;1
L 0.7075 1.1575 0.7075 1.1575 27 P 0 ;1
L 0.7075 1.2075 0.7075 1.2075 27 P 0 ;1
L 0.7075 1.2575 0.7075 1.2575 27 P 0 ;1
L 0.7075 1.3075 0.7075 1.3075 27 P 0 ;1
L 0.7075 1.3575 0.7075 1.3575 27 P 0 ;1
L 0.7075 1.4075 0.7075 1.4075 27 P 0 ;1
L 0.7075 1.4575 0.7075 1.4575 27 P 0 ;1
L 0.7075 1.5075 0.7075 1.5075 27 P 0 ;1
L 0.7075 1.5575 0.7075 1.5575 27 P 0 ;1
L 0.7075 1.7575 0.7075 1.7575 27 P 0 ;1
L 0.7075 2.1575 0.7075 2.1575 27 P 0 ;1
L 0.7075 2.2075 0.7075 2.2075 27 P 0 ;1
L 0.7075 2.2575 0.7075 2.2575 27 P 0 ;1
L 0.7075 2.3075 0.7075 2.3075 27 P 0 ;1
L 0.7075 2.3575 0.7075 2.3575 27 P 0 ;1
L 0.7075 2.4075 0.7075 2.4075 27 P 0 ;1
L 0.7075 2.4575 0.7075 2.4575 27 P 0 ;1
L 0.7075 2.5075 0.7075 2.5075 27 P 0 ;1
L 0.7075 2.5575 0.7075 2.5575 27 P 0 ;1
L 0.7075 2.6075 0.7075 2.6075 27 P 0 ;1
L 0.7075 2.6575 0.7075 2.6575 27 P 0 ;1
L 0.7075 2.7075 0.7075 2.7075 27 P 0 ;1
L 0.7075 2.7575 0.7075 2.7575 27 P 0 ;1
L 0.7075 2.8075 0.7075 2.8075 27 P 0 ;1
L 0.7075 2.8575 0.7075 2.8575 27 P 0 ;1
L 0.7075 2.9075 0.7075 2.9075 27 P 0 ;1
L 0.7075 2.9575 0.7075 2.9575 27 P 0 ;1
L 0.7075 3.0075 0.7075 3.0075 27 P 0 ;1
L 0.7075 3.0575 0.7075 3.0575 27 P 0 ;1
L 0.7075 3.1075 0.7075 3.1075 27 P 0 ;1
L 0.7075 3.1575 0.7075 3.1575 27 P 0 ;1
L 0.7075 3.2075 0.7075 3.2075 27 P 0 ;1
L 0.7075 3.2575 0.7075 3.2575 27 P 0 ;1
L 0.7075 3.3075 0.7075 3.3075 27 P 0 ;1
L 0.7075 3.3575 0.7075 3.3575 27 P 0 ;1
L 0.7075 3.4075 0.7075 3.4075 27 P 0 ;1
L 0.7075 3.4575 0.7075 3.4575 27 P 0 ;1
L 0.7075 3.5075 0.7075 3.5075 27 P 0 ;1
L 0.7075 3.5575 0.7075 3.5575 27 P 0 ;1
L 0.7075 3.6075 0.7075 3.6075 27 P 0 ;1
L 0.7075 3.6575 0.7075 3.6575 27 P 0 ;1
L 0.7075 3.7075 0.7075 3.7075 27 P 0 ;1
L 0.7075 3.7575 0.7075 3.7575 27 P 0 ;1
L 0.7075 3.8075 0.7075 3.8075 27 P 0 ;1
L 0.7075 3.8575 0.7075 3.8575 27 P 0 ;1
L 0.7075 3.9075 0.7075 3.9075 27 P 0 ;1
L 0.7075 3.9575 0.7075 3.9575 27 P 0 ;1
L 0.7075 4.0075 0.7075 4.0075 27 P 0 ;1
L 0.7075 4.0575 0.7075 4.0575 27 P 0 ;1
L 0.7075 4.1075 0.7075 4.1075 27 P 0 ;1
L 0.7075 4.1575 0.7075 4.1575 27 P 0 ;1
L 0.7075 4.2075 0.7075 4.2075 27 P 0 ;1
L 0.7075 4.2575 0.7075 4.2575 27 P 0 ;1
L 0.7075 4.3075 0.7075 4.3075 27 P 0 ;1
L 0.7075 4.3575 0.7075 4.3575 27 P 0 ;1
L 0.7075 4.4075 0.7075 4.4075 27 P 0 ;1
L 0.7075 4.4575 0.7075 4.4575 27 P 0 ;1
L 0.7075 4.5075 0.7075 4.5075 27 P 0 ;1
L 0.7075 4.5575 0.7075 4.5575 27 P 0 ;1
L 0.7075 4.6075 0.7075 4.6075 27 P 0 ;1
L 0.7075 4.6575 0.7075 4.6575 27 P 0 ;1
L 0.7075 4.7075 0.7075 4.7075 27 P 0 ;1
L 0.7075 4.7575 0.7075 4.7575 27 P 0 ;1
L 0.7075 4.8075 0.7075 4.8075 27 P 0 ;1
L 0.7075 4.8575 0.7075 4.8575 27 P 0 ;1
L 0.7575 0.1575 0.7575 0.1575 27 P 0 ;1
L 0.7575 0.4075 0.7575 0.4075 27 P 0 ;1
L 0.7575 0.4575 0.7575 0.4575 27 P 0 ;1
L 0.7575 0.5075 0.7575 0.5075 27 P 0 ;1
L 0.7575 0.5575 0.7575 0.5575 27 P 0 ;1
L 0.7575 0.6075 0.7575 0.6075 27 P 0 ;1
L 0.7575 0.6575 0.7575 0.6575 27 P 0 ;1
L 0.7575 0.7075 0.7575 0.7075 27 P 0 ;1
L 0.7575 0.7575 0.7575 0.7575 27 P 0 ;1
L 0.7575 0.8075 0.7575 0.8075 27 P 0 ;1
L 0.7575 0.8575 0.7575 0.8575 27 P 0 ;1
L 0.7575 0.9075 0.7575 0.9075 27 P 0 ;1
L 0.7575 0.9575 0.7575 0.9575 27 P 0 ;1
L 0.7575 1.0075 0.7575 1.0075 27 P 0 ;1
L 0.7575 1.0575 0.7575 1.0575 27 P 0 ;1
L 0.7575 1.1075 0.7575 1.1075 27 P 0 ;1
L 0.7575 1.1575 0.7575 1.1575 27 P 0 ;1
L 0.7575 1.2075 0.7575 1.2075 27 P 0 ;1
L 0.7575 1.2575 0.7575 1.2575 27 P 0 ;1
L 0.7575 1.3075 0.7575 1.3075 27 P 0 ;1
L 0.7575 1.3575 0.7575 1.3575 27 P 0 ;1
L 0.7575 1.7075 0.7575 1.7075 27 P 0 ;1
L 0.7575 1.7575 0.7575 1.7575 27 P 0 ;1
L 0.7575 2.0075 0.7575 2.0075 27 P 0 ;1
L 0.7575 2.0575 0.7575 2.0575 27 P 0 ;1
L 0.7575 2.1075 0.7575 2.1075 27 P 0 ;1
L 0.7575 2.1575 0.7575 2.1575 27 P 0 ;1
L 0.7575 2.2075 0.7575 2.2075 27 P 0 ;1
L 0.7575 2.2575 0.7575 2.2575 27 P 0 ;1
L 0.7575 2.3075 0.7575 2.3075 27 P 0 ;1
L 0.7575 2.3575 0.7575 2.3575 27 P 0 ;1
L 0.7575 2.4075 0.7575 2.4075 27 P 0 ;1
L 0.7575 2.4575 0.7575 2.4575 27 P 0 ;1
L 0.7575 2.5075 0.7575 2.5075 27 P 0 ;1
L 0.7575 2.5575 0.7575 2.5575 27 P 0 ;1
L 0.7575 2.6075 0.7575 2.6075 27 P 0 ;1
L 0.7575 2.6575 0.7575 2.6575 27 P 0 ;1
L 0.7575 2.7075 0.7575 2.7075 27 P 0 ;1
L 0.7575 2.7575 0.7575 2.7575 27 P 0 ;1
L 0.7575 2.8075 0.7575 2.8075 27 P 0 ;1
L 0.7575 2.8575 0.7575 2.8575 27 P 0 ;1
L 0.7575 2.9075 0.7575 2.9075 27 P 0 ;1
L 0.7575 2.9575 0.7575 2.9575 27 P 0 ;1
L 0.7575 3.0075 0.7575 3.0075 27 P 0 ;1
L 0.7575 3.0575 0.7575 3.0575 27 P 0 ;1
L 0.7575 3.1075 0.7575 3.1075 27 P 0 ;1
L 0.7575 3.1575 0.7575 3.1575 27 P 0 ;1
L 0.7575 3.2075 0.7575 3.2075 27 P 0 ;1
L 0.7575 3.2575 0.7575 3.2575 27 P 0 ;1
L 0.7575 3.3075 0.7575 3.3075 27 P 0 ;1
L 0.7575 3.3575 0.7575 3.3575 27 P 0 ;1
L 0.7575 3.4075 0.7575 3.4075 27 P 0 ;1
L 0.7575 3.4575 0.7575 3.4575 27 P 0 ;1
L 0.7575 3.5075 0.7575 3.5075 27 P 0 ;1
L 0.7575 3.5575 0.7575 3.5575 27 P 0 ;1
L 0.7575 3.6075 0.7575 3.6075 27 P 0 ;1
L 0.7575 3.6575 0.7575 3.6575 27 P 0 ;1
L 0.7575 3.7075 0.7575 3.7075 27 P 0 ;1
L 0.7575 3.7575 0.7575 3.7575 27 P 0 ;1
L 0.7575 3.8075 0.7575 3.8075 27 P 0 ;1
L 0.7575 3.8575 0.7575 3.8575 27 P 0 ;1
L 0.7575 3.9075 0.7575 3.9075 27 P 0 ;1
L 0.7575 3.9575 0.7575 3.9575 27 P 0 ;1
L 0.7575 4.0075 0.7575 4.0075 27 P 0 ;1
L 0.7575 4.0575 0.7575 4.0575 27 P 0 ;1
L 0.7575 4.3575 0.7575 4.3575 27 P 0 ;1
L 0.7575 4.4075 0.7575 4.4075 27 P 0 ;1
L 0.7575 4.4575 0.7575 4.4575 27 P 0 ;1
L 0.7575 4.5075 0.7575 4.5075 27 P 0 ;1
L 0.7575 4.5575 0.7575 4.5575 27 P 0 ;1
L 0.7575 4.6075 0.7575 4.6075 27 P 0 ;1
L 0.7575 4.6575 0.7575 4.6575 27 P 0 ;1
L 0.7575 4.7075 0.7575 4.7075 27 P 0 ;1
L 0.7575 4.7575 0.7575 4.7575 27 P 0 ;1
L 0.7575 4.8075 0.7575 4.8075 27 P 0 ;1
L 0.7575 4.8575 0.7575 4.8575 27 P 0 ;1
L 0.8075 0.1575 0.8075 0.1575 27 P 0 ;1
L 0.8075 0.4075 0.8075 0.4075 27 P 0 ;1
L 0.8075 0.4575 0.8075 0.4575 27 P 0 ;1
L 0.8075 0.5075 0.8075 0.5075 27 P 0 ;1
L 0.8075 0.5575 0.8075 0.5575 27 P 0 ;1
L 0.8075 0.6075 0.8075 0.6075 27 P 0 ;1
L 0.8075 0.6575 0.8075 0.6575 27 P 0 ;1
L 0.8075 0.7075 0.8075 0.7075 27 P 0 ;1
L 0.8075 0.7575 0.8075 0.7575 27 P 0 ;1
L 0.8075 0.8075 0.8075 0.8075 27 P 0 ;1
L 0.8075 0.8575 0.8075 0.8575 27 P 0 ;1
L 0.8075 0.9075 0.8075 0.9075 27 P 0 ;1
L 0.8075 0.9575 0.8075 0.9575 27 P 0 ;1
L 0.8075 1.0075 0.8075 1.0075 27 P 0 ;1
L 0.8075 1.0575 0.8075 1.0575 27 P 0 ;1
L 0.8075 1.1075 0.8075 1.1075 27 P 0 ;1
L 0.8075 1.1575 0.8075 1.1575 27 P 0 ;1
L 0.8075 1.2075 0.8075 1.2075 27 P 0 ;1
L 0.8075 1.2575 0.8075 1.2575 27 P 0 ;1
L 0.8075 1.3075 0.8075 1.3075 27 P 0 ;1
L 0.8075 1.7575 0.8075 1.7575 27 P 0 ;1
L 0.8075 1.8075 0.8075 1.8075 27 P 0 ;1
L 0.8075 1.8575 0.8075 1.8575 27 P 0 ;1
L 0.8075 1.9075 0.8075 1.9075 27 P 0 ;1
L 0.8075 1.9575 0.8075 1.9575 27 P 0 ;1
L 0.8075 2.0075 0.8075 2.0075 27 P 0 ;1
L 0.8075 2.0575 0.8075 2.0575 27 P 0 ;1
L 0.8075 2.1075 0.8075 2.1075 27 P 0 ;1
L 0.8075 2.1575 0.8075 2.1575 27 P 0 ;1
L 0.8075 2.2075 0.8075 2.2075 27 P 0 ;1
L 0.8075 2.2575 0.8075 2.2575 27 P 0 ;1
L 0.8075 2.3075 0.8075 2.3075 27 P 0 ;1
L 0.8075 2.3575 0.8075 2.3575 27 P 0 ;1
L 0.8075 2.4075 0.8075 2.4075 27 P 0 ;1
L 0.8075 2.4575 0.8075 2.4575 27 P 0 ;1
L 0.8075 2.5075 0.8075 2.5075 27 P 0 ;1
L 0.8075 2.5575 0.8075 2.5575 27 P 0 ;1
L 0.8075 2.6075 0.8075 2.6075 27 P 0 ;1
L 0.8075 2.6575 0.8075 2.6575 27 P 0 ;1
L 0.8075 2.7075 0.8075 2.7075 27 P 0 ;1
L 0.8075 2.7575 0.8075 2.7575 27 P 0 ;1
L 0.8075 2.8075 0.8075 2.8075 27 P 0 ;1
L 0.8075 2.8575 0.8075 2.8575 27 P 0 ;1
L 0.8075 2.9075 0.8075 2.9075 27 P 0 ;1
L 0.8075 2.9575 0.8075 2.9575 27 P 0 ;1
L 0.8075 3.0075 0.8075 3.0075 27 P 0 ;1
L 0.8075 3.0575 0.8075 3.0575 27 P 0 ;1
L 0.8075 3.1075 0.8075 3.1075 27 P 0 ;1
L 0.8075 3.1575 0.8075 3.1575 27 P 0 ;1
L 0.8075 3.2075 0.8075 3.2075 27 P 0 ;1
L 0.8075 3.2575 0.8075 3.2575 27 P 0 ;1
L 0.8075 3.3075 0.8075 3.3075 27 P 0 ;1
L 0.8075 3.3575 0.8075 3.3575 27 P 0 ;1
L 0.8075 3.4075 0.8075 3.4075 27 P 0 ;1
L 0.8075 3.4575 0.8075 3.4575 27 P 0 ;1
L 0.8075 3.5075 0.8075 3.5075 27 P 0 ;1
L 0.8075 3.5575 0.8075 3.5575 27 P 0 ;1
L 0.8075 3.6075 0.8075 3.6075 27 P 0 ;1
L 0.8075 3.6575 0.8075 3.6575 27 P 0 ;1
L 0.8075 3.7075 0.8075 3.7075 27 P 0 ;1
L 0.8075 3.7575 0.8075 3.7575 27 P 0 ;1
L 0.8075 3.8075 0.8075 3.8075 27 P 0 ;1
L 0.8075 3.8575 0.8075 3.8575 27 P 0 ;1
L 0.8075 3.9075 0.8075 3.9075 27 P 0 ;1
L 0.8075 3.9575 0.8075 3.9575 27 P 0 ;1
L 0.8075 4.0075 0.8075 4.0075 27 P 0 ;1
L 0.8075 4.4075 0.8075 4.4075 27 P 0 ;1
L 0.8075 4.4575 0.8075 4.4575 27 P 0 ;1
L 0.8075 4.5075 0.8075 4.5075 27 P 0 ;1
L 0.8075 4.5575 0.8075 4.5575 27 P 0 ;1
L 0.8075 4.6075 0.8075 4.6075 27 P 0 ;1
L 0.8075 4.6575 0.8075 4.6575 27 P 0 ;1
L 0.8075 4.7075 0.8075 4.7075 27 P 0 ;1
L 0.8075 4.7575 0.8075 4.7575 27 P 0 ;1
L 0.8075 4.8075 0.8075 4.8075 27 P 0 ;1
L 0.8075 4.8575 0.8075 4.8575 27 P 0 ;1
L 0.8575 0.4575 0.8575 0.4575 27 P 0 ;1
L 0.8575 0.5075 0.8575 0.5075 27 P 0 ;1
L 0.8575 0.5575 0.8575 0.5575 27 P 0 ;1
L 0.8575 0.6075 0.8575 0.6075 27 P 0 ;1
L 0.8575 0.6575 0.8575 0.6575 27 P 0 ;1
L 0.8575 0.7075 0.8575 0.7075 27 P 0 ;1
L 0.8575 0.7575 0.8575 0.7575 27 P 0 ;1
L 0.8575 0.8075 0.8575 0.8075 27 P 0 ;1
L 0.8575 0.8575 0.8575 0.8575 27 P 0 ;1
L 0.8575 0.9075 0.8575 0.9075 27 P 0 ;1
L 0.8575 0.9575 0.8575 0.9575 27 P 0 ;1
L 0.8575 1.0075 0.8575 1.0075 27 P 0 ;1
L 0.8575 1.0575 0.8575 1.0575 27 P 0 ;1
L 0.8575 1.1075 0.8575 1.1075 27 P 0 ;1
L 0.8575 1.1575 0.8575 1.1575 27 P 0 ;1
L 0.8575 1.2075 0.8575 1.2075 27 P 0 ;1
L 0.8575 1.2575 0.8575 1.2575 27 P 0 ;1
L 0.8575 1.3075 0.8575 1.3075 27 P 0 ;1
L 0.8575 1.7575 0.8575 1.7575 27 P 0 ;1
L 0.8575 1.8075 0.8575 1.8075 27 P 0 ;1
L 0.8575 1.8575 0.8575 1.8575 27 P 0 ;1
L 0.8575 1.9075 0.8575 1.9075 27 P 0 ;1
L 0.8575 1.9575 0.8575 1.9575 27 P 0 ;1
L 0.8575 2.0075 0.8575 2.0075 27 P 0 ;1
L 0.8575 2.0575 0.8575 2.0575 27 P 0 ;1
L 0.8575 2.1075 0.8575 2.1075 27 P 0 ;1
L 0.8575 2.1575 0.8575 2.1575 27 P 0 ;1
L 0.8575 2.2075 0.8575 2.2075 27 P 0 ;1
L 0.8575 2.2575 0.8575 2.2575 27 P 0 ;1
L 0.8575 2.3075 0.8575 2.3075 27 P 0 ;1
L 0.8575 2.3575 0.8575 2.3575 27 P 0 ;1
L 0.8575 2.4075 0.8575 2.4075 27 P 0 ;1
L 0.8575 2.4575 0.8575 2.4575 27 P 0 ;1
L 0.8575 2.5075 0.8575 2.5075 27 P 0 ;1
L 0.8575 2.5575 0.8575 2.5575 27 P 0 ;1
L 0.8575 2.6075 0.8575 2.6075 27 P 0 ;1
L 0.8575 2.6575 0.8575 2.6575 27 P 0 ;1
L 0.8575 2.7075 0.8575 2.7075 27 P 0 ;1
L 0.8575 2.7575 0.8575 2.7575 27 P 0 ;1
L 0.8575 2.8075 0.8575 2.8075 27 P 0 ;1
L 0.8575 2.8575 0.8575 2.8575 27 P 0 ;1
L 0.8575 2.9075 0.8575 2.9075 27 P 0 ;1
L 0.8575 2.9575 0.8575 2.9575 27 P 0 ;1
L 0.8575 3.0075 0.8575 3.0075 27 P 0 ;1
L 0.8575 3.0575 0.8575 3.0575 27 P 0 ;1
L 0.8575 3.1075 0.8575 3.1075 27 P 0 ;1
L 0.8575 3.1575 0.8575 3.1575 27 P 0 ;1
L 0.8575 3.2075 0.8575 3.2075 27 P 0 ;1
L 0.8575 3.2575 0.8575 3.2575 27 P 0 ;1
L 0.8575 3.3075 0.8575 3.3075 27 P 0 ;1
L 0.8575 3.3575 0.8575 3.3575 27 P 0 ;1
L 0.8575 3.4075 0.8575 3.4075 27 P 0 ;1
L 0.8575 3.4575 0.8575 3.4575 27 P 0 ;1
L 0.8575 3.5075 0.8575 3.5075 27 P 0 ;1
L 0.8575 3.5575 0.8575 3.5575 27 P 0 ;1
L 0.8575 3.6075 0.8575 3.6075 27 P 0 ;1
L 0.8575 3.6575 0.8575 3.6575 27 P 0 ;1
L 0.8575 3.7075 0.8575 3.7075 27 P 0 ;1
L 0.8575 3.7575 0.8575 3.7575 27 P 0 ;1
L 0.8575 3.8075 0.8575 3.8075 27 P 0 ;1
L 0.8575 3.8575 0.8575 3.8575 27 P 0 ;1
L 0.8575 3.9075 0.8575 3.9075 27 P 0 ;1
L 0.8575 3.9575 0.8575 3.9575 27 P 0 ;1
L 0.8575 4.4575 0.8575 4.4575 27 P 0 ;1
L 0.8575 4.5075 0.8575 4.5075 27 P 0 ;1
L 0.8575 4.5575 0.8575 4.5575 27 P 0 ;1
L 0.8575 4.6075 0.8575 4.6075 27 P 0 ;1
L 0.8575 4.6575 0.8575 4.6575 27 P 0 ;1
L 0.8575 4.7075 0.8575 4.7075 27 P 0 ;1
L 0.8575 4.7575 0.8575 4.7575 27 P 0 ;1
L 0.8575 4.8075 0.8575 4.8075 27 P 0 ;1
L 0.8575 4.8575 0.8575 4.8575 27 P 0 ;1
L 0.9075 0.4575 0.9075 0.4575 27 P 0 ;1
L 0.9075 0.5075 0.9075 0.5075 27 P 0 ;1
L 0.9075 0.5575 0.9075 0.5575 27 P 0 ;1
L 0.9075 0.6075 0.9075 0.6075 27 P 0 ;1
L 0.9075 0.6575 0.9075 0.6575 27 P 0 ;1
L 0.9075 0.7075 0.9075 0.7075 27 P 0 ;1
L 0.9075 0.7575 0.9075 0.7575 27 P 0 ;1
L 0.9075 0.8075 0.9075 0.8075 27 P 0 ;1
L 0.9075 0.8575 0.9075 0.8575 27 P 0 ;1
L 0.9075 0.9075 0.9075 0.9075 27 P 0 ;1
L 0.9075 0.9575 0.9075 0.9575 27 P 0 ;1
L 0.9075 1.0075 0.9075 1.0075 27 P 0 ;1
L 0.9075 1.0575 0.9075 1.0575 27 P 0 ;1
L 0.9075 1.1075 0.9075 1.1075 27 P 0 ;1
L 0.9075 1.1575 0.9075 1.1575 27 P 0 ;1
L 0.9075 1.2075 0.9075 1.2075 27 P 0 ;1
L 0.9075 1.2575 0.9075 1.2575 27 P 0 ;1
L 0.9075 1.8075 0.9075 1.8075 27 P 0 ;1
L 0.9075 1.8575 0.9075 1.8575 27 P 0 ;1
L 0.9075 1.9075 0.9075 1.9075 27 P 0 ;1
L 0.9075 1.9575 0.9075 1.9575 27 P 0 ;1
L 0.9075 2.0075 0.9075 2.0075 27 P 0 ;1
L 0.9075 2.0575 0.9075 2.0575 27 P 0 ;1
L 0.9075 2.1075 0.9075 2.1075 27 P 0 ;1
L 0.9075 2.1575 0.9075 2.1575 27 P 0 ;1
L 0.9075 2.2075 0.9075 2.2075 27 P 0 ;1
L 0.9075 2.2575 0.9075 2.2575 27 P 0 ;1
L 0.9075 2.3075 0.9075 2.3075 27 P 0 ;1
L 0.9075 2.3575 0.9075 2.3575 27 P 0 ;1
L 0.9075 2.4075 0.9075 2.4075 27 P 0 ;1
L 0.9075 2.4575 0.9075 2.4575 27 P 0 ;1
L 0.9075 2.7075 0.9075 2.7075 27 P 0 ;1
L 0.9075 2.7575 0.9075 2.7575 27 P 0 ;1
L 0.9075 2.8075 0.9075 2.8075 27 P 0 ;1
L 0.9075 2.8575 0.9075 2.8575 27 P 0 ;1
L 0.9075 2.9075 0.9075 2.9075 27 P 0 ;1
L 0.9075 2.9575 0.9075 2.9575 27 P 0 ;1
L 0.9075 3.0075 0.9075 3.0075 27 P 0 ;1
L 0.9075 3.0575 0.9075 3.0575 27 P 0 ;1
L 0.9075 3.1075 0.9075 3.1075 27 P 0 ;1
L 0.9075 3.1575 0.9075 3.1575 27 P 0 ;1
L 0.9075 3.2075 0.9075 3.2075 27 P 0 ;1
L 0.9075 3.2575 0.9075 3.2575 27 P 0 ;1
L 0.9075 3.3075 0.9075 3.3075 27 P 0 ;1
L 0.9075 3.3575 0.9075 3.3575 27 P 0 ;1
L 0.9075 3.4075 0.9075 3.4075 27 P 0 ;1
L 0.9075 3.4575 0.9075 3.4575 27 P 0 ;1
L 0.9075 3.5075 0.9075 3.5075 27 P 0 ;1
L 0.9075 3.5575 0.9075 3.5575 27 P 0 ;1
L 0.9075 3.6075 0.9075 3.6075 27 P 0 ;1
L 0.9075 3.6575 0.9075 3.6575 27 P 0 ;1
L 0.9075 3.7075 0.9075 3.7075 27 P 0 ;1
L 0.9075 3.7575 0.9075 3.7575 27 P 0 ;1
L 0.9075 3.8075 0.9075 3.8075 27 P 0 ;1
L 0.9075 3.8575 0.9075 3.8575 27 P 0 ;1
L 0.9075 3.9075 0.9075 3.9075 27 P 0 ;1
L 0.9075 3.9575 0.9075 3.9575 27 P 0 ;1
L 0.9075 4.4575 0.9075 4.4575 27 P 0 ;1
L 0.9075 4.5075 0.9075 4.5075 27 P 0 ;1
L 0.9075 4.5575 0.9075 4.5575 27 P 0 ;1
L 0.9075 4.6075 0.9075 4.6075 27 P 0 ;1
L 0.9075 4.6575 0.9075 4.6575 27 P 0 ;1
L 0.9075 4.7075 0.9075 4.7075 27 P 0 ;1
L 0.9075 4.7575 0.9075 4.7575 27 P 0 ;1
L 0.9075 4.8075 0.9075 4.8075 27 P 0 ;1
L 0.9075 4.8575 0.9075 4.8575 27 P 0 ;1
L 0.9575 0.4575 0.9575 0.4575 27 P 0 ;1
L 0.9575 0.5075 0.9575 0.5075 27 P 0 ;1
L 0.9575 0.5575 0.9575 0.5575 27 P 0 ;1
L 0.9575 0.6075 0.9575 0.6075 27 P 0 ;1
L 0.9575 0.6575 0.9575 0.6575 27 P 0 ;1
L 0.9575 0.7075 0.9575 0.7075 27 P 0 ;1
L 0.9575 0.7575 0.9575 0.7575 27 P 0 ;1
L 0.9575 0.8075 0.9575 0.8075 27 P 0 ;1
L 0.9575 0.8575 0.9575 0.8575 27 P 0 ;1
L 0.9575 0.9075 0.9575 0.9075 27 P 0 ;1
L 0.9575 0.9575 0.9575 0.9575 27 P 0 ;1
L 0.9575 1.0075 0.9575 1.0075 27 P 0 ;1
L 0.9575 1.0575 0.9575 1.0575 27 P 0 ;1
L 0.9575 1.1075 0.9575 1.1075 27 P 0 ;1
L 0.9575 1.1575 0.9575 1.1575 27 P 0 ;1
L 0.9575 1.2075 0.9575 1.2075 27 P 0 ;1
L 0.9575 1.2575 0.9575 1.2575 27 P 0 ;1
L 0.9575 1.8075 0.9575 1.8075 27 P 0 ;1
L 0.9575 1.8575 0.9575 1.8575 27 P 0 ;1
L 0.9575 1.9075 0.9575 1.9075 27 P 0 ;1
L 0.9575 1.9575 0.9575 1.9575 27 P 0 ;1
L 0.9575 2.0075 0.9575 2.0075 27 P 0 ;1
L 0.9575 2.0575 0.9575 2.0575 27 P 0 ;1
L 0.9575 2.1075 0.9575 2.1075 27 P 0 ;1
L 0.9575 2.1575 0.9575 2.1575 27 P 0 ;1
L 0.9575 2.2075 0.9575 2.2075 27 P 0 ;1
L 0.9575 2.2575 0.9575 2.2575 27 P 0 ;1
L 0.9575 2.3075 0.9575 2.3075 27 P 0 ;1
L 0.9575 2.3575 0.9575 2.3575 27 P 0 ;1
L 0.9575 2.4075 0.9575 2.4075 27 P 0 ;1
L 0.9575 2.7575 0.9575 2.7575 27 P 0 ;1
L 0.9575 2.8075 0.9575 2.8075 27 P 0 ;1
L 0.9575 2.8575 0.9575 2.8575 27 P 0 ;1
L 0.9575 2.9075 0.9575 2.9075 27 P 0 ;1
L 0.9575 2.9575 0.9575 2.9575 27 P 0 ;1
L 0.9575 3.0075 0.9575 3.0075 27 P 0 ;1
L 0.9575 3.0575 0.9575 3.0575 27 P 0 ;1
L 0.9575 3.1075 0.9575 3.1075 27 P 0 ;1
L 0.9575 3.1575 0.9575 3.1575 27 P 0 ;1
L 0.9575 3.2075 0.9575 3.2075 27 P 0 ;1
L 0.9575 3.2575 0.9575 3.2575 27 P 0 ;1
L 0.9575 3.3075 0.9575 3.3075 27 P 0 ;1
L 0.9575 3.3575 0.9575 3.3575 27 P 0 ;1
L 0.9575 3.4075 0.9575 3.4075 27 P 0 ;1
L 0.9575 3.4575 0.9575 3.4575 27 P 0 ;1
L 0.9575 3.5075 0.9575 3.5075 27 P 0 ;1
L 0.9575 3.5575 0.9575 3.5575 27 P 0 ;1
L 0.9575 3.6075 0.9575 3.6075 27 P 0 ;1
L 0.9575 3.6575 0.9575 3.6575 27 P 0 ;1
L 0.9575 3.7075 0.9575 3.7075 27 P 0 ;1
L 0.9575 3.7575 0.9575 3.7575 27 P 0 ;1
L 0.9575 3.8075 0.9575 3.8075 27 P 0 ;1
L 0.9575 3.8575 0.9575 3.8575 27 P 0 ;1
L 0.9575 3.9075 0.9575 3.9075 27 P 0 ;1
L 0.9575 3.9575 0.9575 3.9575 27 P 0 ;1
L 0.9575 4.4575 0.9575 4.4575 27 P 0 ;1
L 0.9575 4.5075 0.9575 4.5075 27 P 0 ;1
L 0.9575 4.5575 0.9575 4.5575 27 P 0 ;1
L 0.9575 4.6075 0.9575 4.6075 27 P 0 ;1
L 0.9575 4.6575 0.9575 4.6575 27 P 0 ;1
L 0.9575 4.7075 0.9575 4.7075 27 P 0 ;1
L 0.9575 4.7575 0.9575 4.7575 27 P 0 ;1
L 0.9575 4.8075 0.9575 4.8075 27 P 0 ;1
L 0.9575 4.8575 0.9575 4.8575 27 P 0 ;1
L 1.0075 0.4575 1.0075 0.4575 27 P 0 ;1
L 1.0075 0.5075 1.0075 0.5075 27 P 0 ;1
L 1.0075 0.5575 1.0075 0.5575 27 P 0 ;1
L 1.0075 0.6075 1.0075 0.6075 27 P 0 ;1
L 1.0075 0.6575 1.0075 0.6575 27 P 0 ;1
L 1.0075 0.7075 1.0075 0.7075 27 P 0 ;1
L 1.0075 0.7575 1.0075 0.7575 27 P 0 ;1
L 1.0075 0.8075 1.0075 0.8075 27 P 0 ;1
L 1.0075 0.8575 1.0075 0.8575 27 P 0 ;1
L 1.0075 0.9075 1.0075 0.9075 27 P 0 ;1
L 1.0075 0.9575 1.0075 0.9575 27 P 0 ;1
L 1.0075 1.0075 1.0075 1.0075 27 P 0 ;1
L 1.0075 1.0575 1.0075 1.0575 27 P 0 ;1
L 1.0075 1.1075 1.0075 1.1075 27 P 0 ;1
L 1.0075 1.1575 1.0075 1.1575 27 P 0 ;1
L 1.0075 1.2075 1.0075 1.2075 27 P 0 ;1
L 1.0075 1.2575 1.0075 1.2575 27 P 0 ;1
L 1.0075 1.8075 1.0075 1.8075 27 P 0 ;1
L 1.0075 1.8575 1.0075 1.8575 27 P 0 ;1
L 1.0075 1.9075 1.0075 1.9075 27 P 0 ;1
L 1.0075 1.9575 1.0075 1.9575 27 P 0 ;1
L 1.0075 2.0075 1.0075 2.0075 27 P 0 ;1
L 1.0075 2.0575 1.0075 2.0575 27 P 0 ;1
L 1.0075 2.1075 1.0075 2.1075 27 P 0 ;1
L 1.0075 2.1575 1.0075 2.1575 27 P 0 ;1
L 1.0075 2.2075 1.0075 2.2075 27 P 0 ;1
L 1.0075 2.2575 1.0075 2.2575 27 P 0 ;1
L 1.0075 2.3075 1.0075 2.3075 27 P 0 ;1
L 1.0075 2.3575 1.0075 2.3575 27 P 0 ;1
L 1.0075 2.4075 1.0075 2.4075 27 P 0 ;1
L 1.0075 2.7575 1.0075 2.7575 27 P 0 ;1
L 1.0075 2.8075 1.0075 2.8075 27 P 0 ;1
L 1.0075 2.8575 1.0075 2.8575 27 P 0 ;1
L 1.0075 2.9075 1.0075 2.9075 27 P 0 ;1
L 1.0075 2.9575 1.0075 2.9575 27 P 0 ;1
L 1.0075 3.0075 1.0075 3.0075 27 P 0 ;1
L 1.0075 3.0575 1.0075 3.0575 27 P 0 ;1
L 1.0075 3.1075 1.0075 3.1075 27 P 0 ;1
L 1.0075 3.1575 1.0075 3.1575 27 P 0 ;1
L 1.0075 3.2075 1.0075 3.2075 27 P 0 ;1
L 1.0075 3.2575 1.0075 3.2575 27 P 0 ;1
L 1.0075 3.3075 1.0075 3.3075 27 P 0 ;1
L 1.0075 3.3575 1.0075 3.3575 27 P 0 ;1
L 1.0075 3.4075 1.0075 3.4075 27 P 0 ;1
L 1.0075 3.4575 1.0075 3.4575 27 P 0 ;1
L 1.0075 3.5075 1.0075 3.5075 27 P 0 ;1
L 1.0075 3.5575 1.0075 3.5575 27 P 0 ;1
L 1.0075 3.6075 1.0075 3.6075 27 P 0 ;1
L 1.0075 3.6575 1.0075 3.6575 27 P 0 ;1
L 1.0075 3.7075 1.0075 3.7075 27 P 0 ;1
L 1.0075 3.7575 1.0075 3.7575 27 P 0 ;1
L 1.0075 3.8075 1.0075 3.8075 27 P 0 ;1
L 1.0075 3.8575 1.0075 3.8575 27 P 0 ;1
L 1.0075 3.9075 1.0075 3.9075 27 P 0 ;1
L 1.0075 3.9575 1.0075 3.9575 27 P 0 ;1
L 1.0075 4.4575 1.0075 4.4575 27 P 0 ;1
L 1.0075 4.5075 1.0075 4.5075 27 P 0 ;1
L 1.0075 4.5575 1.0075 4.5575 27 P 0 ;1
L 1.0075 4.6075 1.0075 4.6075 27 P 0 ;1
L 1.0075 4.6575 1.0075 4.6575 27 P 0 ;1
L 1.0075 4.7075 1.0075 4.7075 27 P 0 ;1
L 1.0075 4.7575 1.0075 4.7575 27 P 0 ;1
L 1.0075 4.8075 1.0075 4.8075 27 P 0 ;1
L 1.0075 4.8575 1.0075 4.8575 27 P 0 ;1
L 1.0575 0.1575 1.0575 0.1575 27 P 0 ;1
L 1.0575 0.4075 1.0575 0.4075 27 P 0 ;1
L 1.0575 0.4575 1.0575 0.4575 27 P 0 ;1
L 1.0575 0.5075 1.0575 0.5075 27 P 0 ;1
L 1.0575 0.5575 1.0575 0.5575 27 P 0 ;1
L 1.0575 0.6075 1.0575 0.6075 27 P 0 ;1
L 1.0575 0.6575 1.0575 0.6575 27 P 0 ;1
L 1.0575 0.7075 1.0575 0.7075 27 P 0 ;1
L 1.0575 0.7575 1.0575 0.7575 27 P 0 ;1
L 1.0575 0.8075 1.0575 0.8075 27 P 0 ;1
L 1.0575 0.8575 1.0575 0.8575 27 P 0 ;1
L 1.0575 0.9075 1.0575 0.9075 27 P 0 ;1
L 1.0575 0.9575 1.0575 0.9575 27 P 0 ;1
L 1.0575 1.0075 1.0575 1.0075 27 P 0 ;1
L 1.0575 1.0575 1.0575 1.0575 27 P 0 ;1
L 1.0575 1.1075 1.0575 1.1075 27 P 0 ;1
L 1.0575 1.1575 1.0575 1.1575 27 P 0 ;1
L 1.0575 1.2075 1.0575 1.2075 27 P 0 ;1
L 1.0575 1.2575 1.0575 1.2575 27 P 0 ;1
L 1.0575 1.7575 1.0575 1.7575 27 P 0 ;1
L 1.0575 1.8075 1.0575 1.8075 27 P 0 ;1
L 1.0575 1.8575 1.0575 1.8575 27 P 0 ;1
L 1.0575 1.9075 1.0575 1.9075 27 P 0 ;1
L 1.0575 1.9575 1.0575 1.9575 27 P 0 ;1
L 1.0575 2.0075 1.0575 2.0075 27 P 0 ;1
L 1.0575 2.0575 1.0575 2.0575 27 P 0 ;1
L 1.0575 2.1075 1.0575 2.1075 27 P 0 ;1
L 1.0575 2.1575 1.0575 2.1575 27 P 0 ;1
L 1.0575 2.2075 1.0575 2.2075 27 P 0 ;1
L 1.0575 2.2575 1.0575 2.2575 27 P 0 ;1
L 1.0575 2.3075 1.0575 2.3075 27 P 0 ;1
L 1.0575 2.3575 1.0575 2.3575 27 P 0 ;1
L 1.0575 2.4075 1.0575 2.4075 27 P 0 ;1
L 1.0575 2.7575 1.0575 2.7575 27 P 0 ;1
L 1.0575 2.8075 1.0575 2.8075 27 P 0 ;1
L 1.0575 2.8575 1.0575 2.8575 27 P 0 ;1
L 1.0575 2.9075 1.0575 2.9075 27 P 0 ;1
L 1.0575 2.9575 1.0575 2.9575 27 P 0 ;1
L 1.0575 3.0075 1.0575 3.0075 27 P 0 ;1
L 1.0575 3.0575 1.0575 3.0575 27 P 0 ;1
L 1.0575 3.1075 1.0575 3.1075 27 P 0 ;1
L 1.0575 3.1575 1.0575 3.1575 27 P 0 ;1
L 1.0575 3.2075 1.0575 3.2075 27 P 0 ;1
L 1.0575 3.2575 1.0575 3.2575 27 P 0 ;1
L 1.0575 3.3075 1.0575 3.3075 27 P 0 ;1
L 1.0575 3.3575 1.0575 3.3575 27 P 0 ;1
L 1.0575 3.4075 1.0575 3.4075 27 P 0 ;1
L 1.0575 3.4575 1.0575 3.4575 27 P 0 ;1
L 1.0575 3.5075 1.0575 3.5075 27 P 0 ;1
L 1.0575 3.5575 1.0575 3.5575 27 P 0 ;1
L 1.0575 3.6075 1.0575 3.6075 27 P 0 ;1
L 1.0575 3.6575 1.0575 3.6575 27 P 0 ;1
L 1.0575 3.7075 1.0575 3.7075 27 P 0 ;1
L 1.0575 3.7575 1.0575 3.7575 27 P 0 ;1
L 1.0575 3.8075 1.0575 3.8075 27 P 0 ;1
L 1.0575 3.8575 1.0575 3.8575 27 P 0 ;1
L 1.0575 3.9075 1.0575 3.9075 27 P 0 ;1
L 1.0575 3.9575 1.0575 3.9575 27 P 0 ;1
L 1.0575 4.4575 1.0575 4.4575 27 P 0 ;1
L 1.0575 4.5075 1.0575 4.5075 27 P 0 ;1
L 1.0575 4.5575 1.0575 4.5575 27 P 0 ;1
L 1.0575 4.6075 1.0575 4.6075 27 P 0 ;1
L 1.0575 4.6575 1.0575 4.6575 27 P 0 ;1
L 1.0575 4.7075 1.0575 4.7075 27 P 0 ;1
L 1.0575 4.7575 1.0575 4.7575 27 P 0 ;1
L 1.0575 4.8075 1.0575 4.8075 27 P 0 ;1
L 1.0575 4.8575 1.0575 4.8575 27 P 0 ;1
L 1.1075 0.1575 1.1075 0.1575 27 P 0 ;1
L 1.1075 0.2075 1.1075 0.2075 27 P 0 ;1
L 1.1075 0.2575 1.1075 0.2575 27 P 0 ;1
L 1.1075 0.3075 1.1075 0.3075 27 P 0 ;1
L 1.1075 0.3575 1.1075 0.3575 27 P 0 ;1
L 1.1075 0.4075 1.1075 0.4075 27 P 0 ;1
L 1.1075 0.4575 1.1075 0.4575 27 P 0 ;1
L 1.1075 0.5075 1.1075 0.5075 27 P 0 ;1
L 1.1075 0.5575 1.1075 0.5575 27 P 0 ;1
L 1.1075 0.6075 1.1075 0.6075 27 P 0 ;1
L 1.1075 0.6575 1.1075 0.6575 27 P 0 ;1
L 1.1075 0.7075 1.1075 0.7075 27 P 0 ;1
L 1.1075 0.7575 1.1075 0.7575 27 P 0 ;1
L 1.1075 0.8075 1.1075 0.8075 27 P 0 ;1
L 1.1075 0.8575 1.1075 0.8575 27 P 0 ;1
L 1.1075 0.9075 1.1075 0.9075 27 P 0 ;1
L 1.1075 0.9575 1.1075 0.9575 27 P 0 ;1
L 1.1075 1.0075 1.1075 1.0075 27 P 0 ;1
L 1.1075 1.0575 1.1075 1.0575 27 P 0 ;1
L 1.1075 1.1075 1.1075 1.1075 27 P 0 ;1
L 1.1075 1.1575 1.1075 1.1575 27 P 0 ;1
L 1.1075 1.2075 1.1075 1.2075 27 P 0 ;1
L 1.1075 1.2575 1.1075 1.2575 27 P 0 ;1
L 1.1075 1.3075 1.1075 1.3075 27 P 0 ;1
L 1.1075 1.7575 1.1075 1.7575 27 P 0 ;1
L 1.1075 1.8075 1.1075 1.8075 27 P 0 ;1
L 1.1075 1.8575 1.1075 1.8575 27 P 0 ;1
L 1.1075 1.9075 1.1075 1.9075 27 P 0 ;1
L 1.1075 1.9575 1.1075 1.9575 27 P 0 ;1
L 1.1075 2.0075 1.1075 2.0075 27 P 0 ;1
L 1.1075 2.0575 1.1075 2.0575 27 P 0 ;1
L 1.1075 2.1075 1.1075 2.1075 27 P 0 ;1
L 1.1075 2.1575 1.1075 2.1575 27 P 0 ;1
L 1.1075 2.2075 1.1075 2.2075 27 P 0 ;1
L 1.1075 2.2575 1.1075 2.2575 27 P 0 ;1
L 1.1075 2.3075 1.1075 2.3075 27 P 0 ;1
L 1.1075 2.3575 1.1075 2.3575 27 P 0 ;1
L 1.1075 2.4075 1.1075 2.4075 27 P 0 ;1
L 1.1075 2.7575 1.1075 2.7575 27 P 0 ;1
L 1.1075 2.8075 1.1075 2.8075 27 P 0 ;1
L 1.1075 2.8575 1.1075 2.8575 27 P 0 ;1
L 1.1075 2.9075 1.1075 2.9075 27 P 0 ;1
L 1.1075 2.9575 1.1075 2.9575 27 P 0 ;1
L 1.1075 3.0075 1.1075 3.0075 27 P 0 ;1
L 1.1075 3.0575 1.1075 3.0575 27 P 0 ;1
L 1.1075 3.1075 1.1075 3.1075 27 P 0 ;1
L 1.1075 3.1575 1.1075 3.1575 27 P 0 ;1
L 1.1075 3.2075 1.1075 3.2075 27 P 0 ;1
L 1.1075 3.2575 1.1075 3.2575 27 P 0 ;1
L 1.1075 3.3075 1.1075 3.3075 27 P 0 ;1
L 1.1075 3.3575 1.1075 3.3575 27 P 0 ;1
L 1.1075 3.4075 1.1075 3.4075 27 P 0 ;1
L 1.1075 3.4575 1.1075 3.4575 27 P 0 ;1
L 1.1075 3.5075 1.1075 3.5075 27 P 0 ;1
L 1.1075 3.5575 1.1075 3.5575 27 P 0 ;1
L 1.1075 3.6075 1.1075 3.6075 27 P 0 ;1
L 1.1075 3.6575 1.1075 3.6575 27 P 0 ;1
L 1.1075 3.7075 1.1075 3.7075 27 P 0 ;1
L 1.1075 3.7575 1.1075 3.7575 27 P 0 ;1
L 1.1075 3.8075 1.1075 3.8075 27 P 0 ;1
L 1.1075 3.8575 1.1075 3.8575 27 P 0 ;1
L 1.1075 3.9075 1.1075 3.9075 27 P 0 ;1
L 1.1075 3.9575 1.1075 3.9575 27 P 0 ;1
L 1.1075 4.0075 1.1075 4.0075 27 P 0 ;1
L 1.1075 4.4075 1.1075 4.4075 27 P 0 ;1
L 1.1075 4.4575 1.1075 4.4575 27 P 0 ;1
L 1.1075 4.5075 1.1075 4.5075 27 P 0 ;1
L 1.1075 4.5575 1.1075 4.5575 27 P 0 ;1
L 1.1075 4.6075 1.1075 4.6075 27 P 0 ;1
L 1.1075 4.6575 1.1075 4.6575 27 P 0 ;1
L 1.1075 4.7075 1.1075 4.7075 27 P 0 ;1
L 1.1075 4.7575 1.1075 4.7575 27 P 0 ;1
L 1.1075 4.8075 1.1075 4.8075 27 P 0 ;1
L 1.1075 4.8575 1.1075 4.8575 27 P 0 ;1
L 1.1575 0.1575 1.1575 0.1575 27 P 0 ;1
L 1.1575 0.2075 1.1575 0.2075 27 P 0 ;1
L 1.1575 0.2575 1.1575 0.2575 27 P 0 ;1
L 1.1575 0.3075 1.1575 0.3075 27 P 0 ;1
L 1.1575 0.3575 1.1575 0.3575 27 P 0 ;1
L 1.1575 0.4075 1.1575 0.4075 27 P 0 ;1
L 1.1575 0.4575 1.1575 0.4575 27 P 0 ;1
L 1.1575 0.5075 1.1575 0.5075 27 P 0 ;1
L 1.1575 0.5575 1.1575 0.5575 27 P 0 ;1
L 1.1575 0.6075 1.1575 0.6075 27 P 0 ;1
L 1.1575 0.6575 1.1575 0.6575 27 P 0 ;1
L 1.1575 0.7075 1.1575 0.7075 27 P 0 ;1
L 1.1575 0.7575 1.1575 0.7575 27 P 0 ;1
L 1.1575 0.8075 1.1575 0.8075 27 P 0 ;1
L 1.1575 0.8575 1.1575 0.8575 27 P 0 ;1
L 1.1575 0.9075 1.1575 0.9075 27 P 0 ;1
L 1.1575 0.9575 1.1575 0.9575 27 P 0 ;1
L 1.1575 1.0075 1.1575 1.0075 27 P 0 ;1
L 1.1575 1.0575 1.1575 1.0575 27 P 0 ;1
L 1.1575 1.1075 1.1575 1.1075 27 P 0 ;1
L 1.1575 1.1575 1.1575 1.1575 27 P 0 ;1
L 1.1575 1.2075 1.1575 1.2075 27 P 0 ;1
L 1.1575 1.2575 1.1575 1.2575 27 P 0 ;1
L 1.1575 1.3075 1.1575 1.3075 27 P 0 ;1
L 1.1575 1.3575 1.1575 1.3575 27 P 0 ;1
L 1.1575 1.7075 1.1575 1.7075 27 P 0 ;1
L 1.1575 1.7575 1.1575 1.7575 27 P 0 ;1
L 1.1575 1.8075 1.1575 1.8075 27 P 0 ;1
L 1.1575 1.8575 1.1575 1.8575 27 P 0 ;1
L 1.1575 1.9075 1.1575 1.9075 27 P 0 ;1
L 1.1575 1.9575 1.1575 1.9575 27 P 0 ;1
L 1.1575 2.0075 1.1575 2.0075 27 P 0 ;1
L 1.1575 2.0575 1.1575 2.0575 27 P 0 ;1
L 1.1575 2.1075 1.1575 2.1075 27 P 0 ;1
L 1.1575 2.1575 1.1575 2.1575 27 P 0 ;1
L 1.1575 2.2075 1.1575 2.2075 27 P 0 ;1
L 1.1575 2.2575 1.1575 2.2575 27 P 0 ;1
L 1.1575 2.3075 1.1575 2.3075 27 P 0 ;1
L 1.1575 2.3575 1.1575 2.3575 27 P 0 ;1
L 1.1575 2.4075 1.1575 2.4075 27 P 0 ;1
L 1.1575 2.7575 1.1575 2.7575 27 P 0 ;1
L 1.1575 2.8075 1.1575 2.8075 27 P 0 ;1
L 1.1575 2.8575 1.1575 2.8575 27 P 0 ;1
L 1.1575 2.9075 1.1575 2.9075 27 P 0 ;1
L 1.1575 2.9575 1.1575 2.9575 27 P 0 ;1
L 1.1575 3.0075 1.1575 3.0075 27 P 0 ;1
L 1.1575 3.0575 1.1575 3.0575 27 P 0 ;1
L 1.1575 3.1075 1.1575 3.1075 27 P 0 ;1
L 1.1575 3.1575 1.1575 3.1575 27 P 0 ;1
L 1.1575 3.2075 1.1575 3.2075 27 P 0 ;1
L 1.1575 3.2575 1.1575 3.2575 27 P 0 ;1
L 1.1575 3.3075 1.1575 3.3075 27 P 0 ;1
L 1.1575 3.3575 1.1575 3.3575 27 P 0 ;1
L 1.1575 3.4075 1.1575 3.4075 27 P 0 ;1
L 1.1575 3.4575 1.1575 3.4575 27 P 0 ;1
L 1.1575 3.5075 1.1575 3.5075 27 P 0 ;1
L 1.1575 3.5575 1.1575 3.5575 27 P 0 ;1
L 1.1575 3.6075 1.1575 3.6075 27 P 0 ;1
L 1.1575 3.6575 1.1575 3.6575 27 P 0 ;1
L 1.1575 3.7075 1.1575 3.7075 27 P 0 ;1
L 1.1575 3.7575 1.1575 3.7575 27 P 0 ;1
L 1.1575 3.8075 1.1575 3.8075 27 P 0 ;1
L 1.1575 3.8575 1.1575 3.8575 27 P 0 ;1
L 1.1575 3.9075 1.1575 3.9075 27 P 0 ;1
L 1.1575 3.9575 1.1575 3.9575 27 P 0 ;1
L 1.1575 4.0075 1.1575 4.0075 27 P 0 ;1
L 1.1575 4.0575 1.1575 4.0575 27 P 0 ;1
L 1.1575 4.3575 1.1575 4.3575 27 P 0 ;1
L 1.1575 4.4075 1.1575 4.4075 27 P 0 ;1
L 1.1575 4.4575 1.1575 4.4575 27 P 0 ;1
L 1.1575 4.5075 1.1575 4.5075 27 P 0 ;1
L 1.1575 4.8075 1.1575 4.8075 27 P 0 ;1
L 1.1575 4.8575 1.1575 4.8575 27 P 0 ;1
L 1.1575 5.2575 1.1575 5.2575 27 P 0 ;1
L 1.2075 0.1575 1.2075 0.1575 27 P 0 ;1
L 1.2075 0.2075 1.2075 0.2075 27 P 0 ;1
L 1.2075 0.2575 1.2075 0.2575 27 P 0 ;1
L 1.2075 0.3075 1.2075 0.3075 27 P 0 ;1
L 1.2075 0.3575 1.2075 0.3575 27 P 0 ;1
L 1.2075 0.4075 1.2075 0.4075 27 P 0 ;1
L 1.2075 0.4575 1.2075 0.4575 27 P 0 ;1
L 1.2075 0.5075 1.2075 0.5075 27 P 0 ;1
L 1.2075 0.5575 1.2075 0.5575 27 P 0 ;1
L 1.2075 0.6075 1.2075 0.6075 27 P 0 ;1
L 1.2075 0.6575 1.2075 0.6575 27 P 0 ;1
L 1.2075 0.7075 1.2075 0.7075 27 P 0 ;1
L 1.2075 0.7575 1.2075 0.7575 27 P 0 ;1
L 1.2075 0.8075 1.2075 0.8075 27 P 0 ;1
L 1.2075 0.8575 1.2075 0.8575 27 P 0 ;1
L 1.2075 0.9075 1.2075 0.9075 27 P 0 ;1
L 1.2075 0.9575 1.2075 0.9575 27 P 0 ;1
L 1.2075 1.0075 1.2075 1.0075 27 P 0 ;1
L 1.2075 1.0575 1.2075 1.0575 27 P 0 ;1
L 1.2075 1.1075 1.2075 1.1075 27 P 0 ;1
L 1.2075 1.1575 1.2075 1.1575 27 P 0 ;1
L 1.2075 1.2075 1.2075 1.2075 27 P 0 ;1
L 1.2075 1.2575 1.2075 1.2575 27 P 0 ;1
L 1.2075 1.3075 1.2075 1.3075 27 P 0 ;1
L 1.2075 1.3575 1.2075 1.3575 27 P 0 ;1
L 1.2075 1.4075 1.2075 1.4075 27 P 0 ;1
L 1.2075 1.4575 1.2075 1.4575 27 P 0 ;1
L 1.2075 1.5075 1.2075 1.5075 27 P 0 ;1
L 1.2075 1.5575 1.2075 1.5575 27 P 0 ;1
L 1.2075 1.6075 1.2075 1.6075 27 P 0 ;1
L 1.2075 1.6575 1.2075 1.6575 27 P 0 ;1
L 1.2075 1.7075 1.2075 1.7075 27 P 0 ;1
L 1.2075 1.7575 1.2075 1.7575 27 P 0 ;1
L 1.2075 1.8075 1.2075 1.8075 27 P 0 ;1
L 1.2075 1.8575 1.2075 1.8575 27 P 0 ;1
L 1.2075 1.9075 1.2075 1.9075 27 P 0 ;1
L 1.2075 1.9575 1.2075 1.9575 27 P 0 ;1
L 1.2075 2.0075 1.2075 2.0075 27 P 0 ;1
L 1.2075 2.0575 1.2075 2.0575 27 P 0 ;1
L 1.2075 2.1075 1.2075 2.1075 27 P 0 ;1
L 1.2075 2.1575 1.2075 2.1575 27 P 0 ;1
L 1.2075 2.2075 1.2075 2.2075 27 P 0 ;1
L 1.2075 2.2575 1.2075 2.2575 27 P 0 ;1
L 1.2075 2.3075 1.2075 2.3075 27 P 0 ;1
L 1.2075 2.3575 1.2075 2.3575 27 P 0 ;1
L 1.2075 2.4075 1.2075 2.4075 27 P 0 ;1
L 1.2075 2.4575 1.2075 2.4575 27 P 0 ;1
L 1.2075 2.7075 1.2075 2.7075 27 P 0 ;1
L 1.2075 2.7575 1.2075 2.7575 27 P 0 ;1
L 1.2075 2.8075 1.2075 2.8075 27 P 0 ;1
L 1.2075 2.8575 1.2075 2.8575 27 P 0 ;1
L 1.2075 2.9075 1.2075 2.9075 27 P 0 ;1
L 1.2075 2.9575 1.2075 2.9575 27 P 0 ;1
L 1.2075 3.0075 1.2075 3.0075 27 P 0 ;1
L 1.2075 3.0575 1.2075 3.0575 27 P 0 ;1
L 1.2075 3.1075 1.2075 3.1075 27 P 0 ;1
L 1.2075 3.1575 1.2075 3.1575 27 P 0 ;1
L 1.2075 3.2075 1.2075 3.2075 27 P 0 ;1
L 1.2075 3.2575 1.2075 3.2575 27 P 0 ;1
L 1.2075 3.3075 1.2075 3.3075 27 P 0 ;1
L 1.2075 3.3575 1.2075 3.3575 27 P 0 ;1
L 1.2075 3.4075 1.2075 3.4075 27 P 0 ;1
L 1.2075 3.4575 1.2075 3.4575 27 P 0 ;1
L 1.2075 3.5075 1.2075 3.5075 27 P 0 ;1
L 1.2075 3.5575 1.2075 3.5575 27 P 0 ;1
L 1.2075 3.6075 1.2075 3.6075 27 P 0 ;1
L 1.2075 3.6575 1.2075 3.6575 27 P 0 ;1
L 1.2075 3.7075 1.2075 3.7075 27 P 0 ;1
L 1.2075 3.7575 1.2075 3.7575 27 P 0 ;1
L 1.2075 3.8075 1.2075 3.8075 27 P 0 ;1
L 1.2075 3.8575 1.2075 3.8575 27 P 0 ;1
L 1.2075 3.9075 1.2075 3.9075 27 P 0 ;1
L 1.2075 3.9575 1.2075 3.9575 27 P 0 ;1
L 1.2075 4.0075 1.2075 4.0075 27 P 0 ;1
L 1.2075 4.0575 1.2075 4.0575 27 P 0 ;1
L 1.2075 4.1075 1.2075 4.1075 27 P 0 ;1
L 1.2075 4.1575 1.2075 4.1575 27 P 0 ;1
L 1.2075 4.2075 1.2075 4.2075 27 P 0 ;1
L 1.2075 4.2575 1.2075 4.2575 27 P 0 ;1
L 1.2075 4.3075 1.2075 4.3075 27 P 0 ;1
L 1.2075 4.3575 1.2075 4.3575 27 P 0 ;1
L 1.2075 4.4075 1.2075 4.4075 27 P 0 ;1
L 1.2075 4.4575 1.2075 4.4575 27 P 0 ;1
L 1.2075 4.5075 1.2075 4.5075 27 P 0 ;1
L 1.2075 5.2575 1.2075 5.2575 27 P 0 ;1
L 1.2075 5.3075 1.2075 5.3075 27 P 0 ;1
L 1.2075 5.3575 1.2075 5.3575 27 P 0 ;1
L 1.2575 0.1575 1.2575 0.1575 27 P 0 ;1
L 1.2575 0.2075 1.2575 0.2075 27 P 0 ;1
L 1.2575 0.2575 1.2575 0.2575 27 P 0 ;1
L 1.2575 0.3075 1.2575 0.3075 27 P 0 ;1
L 1.2575 0.3575 1.2575 0.3575 27 P 0 ;1
L 1.2575 0.4075 1.2575 0.4075 27 P 0 ;1
L 1.2575 0.4575 1.2575 0.4575 27 P 0 ;1
L 1.2575 0.5075 1.2575 0.5075 27 P 0 ;1
L 1.2575 0.5575 1.2575 0.5575 27 P 0 ;1
L 1.2575 0.6075 1.2575 0.6075 27 P 0 ;1
L 1.2575 0.6575 1.2575 0.6575 27 P 0 ;1
L 1.2575 0.7075 1.2575 0.7075 27 P 0 ;1
L 1.2575 0.7575 1.2575 0.7575 27 P 0 ;1
L 1.2575 0.8075 1.2575 0.8075 27 P 0 ;1
L 1.2575 0.8575 1.2575 0.8575 27 P 0 ;1
L 1.2575 0.9075 1.2575 0.9075 27 P 0 ;1
L 1.2575 0.9575 1.2575 0.9575 27 P 0 ;1
L 1.2575 1.0075 1.2575 1.0075 27 P 0 ;1
L 1.2575 1.0575 1.2575 1.0575 27 P 0 ;1
L 1.2575 1.1075 1.2575 1.1075 27 P 0 ;1
L 1.2575 1.1575 1.2575 1.1575 27 P 0 ;1
L 1.2575 1.2075 1.2575 1.2075 27 P 0 ;1
L 1.2575 1.2575 1.2575 1.2575 27 P 0 ;1
L 1.2575 1.3075 1.2575 1.3075 27 P 0 ;1
L 1.2575 1.3575 1.2575 1.3575 27 P 0 ;1
L 1.2575 1.4075 1.2575 1.4075 27 P 0 ;1
L 1.2575 1.4575 1.2575 1.4575 27 P 0 ;1
L 1.2575 1.5075 1.2575 1.5075 27 P 0 ;1
L 1.2575 1.5575 1.2575 1.5575 27 P 0 ;1
L 1.2575 1.6075 1.2575 1.6075 27 P 0 ;1
L 1.2575 1.6575 1.2575 1.6575 27 P 0 ;1
L 1.2575 1.7075 1.2575 1.7075 27 P 0 ;1
L 1.2575 1.7575 1.2575 1.7575 27 P 0 ;1
L 1.2575 1.8075 1.2575 1.8075 27 P 0 ;1
L 1.2575 1.8575 1.2575 1.8575 27 P 0 ;1
L 1.2575 1.9075 1.2575 1.9075 27 P 0 ;1
L 1.2575 1.9575 1.2575 1.9575 27 P 0 ;1
L 1.2575 2.0075 1.2575 2.0075 27 P 0 ;1
L 1.2575 2.0575 1.2575 2.0575 27 P 0 ;1
L 1.2575 2.1075 1.2575 2.1075 27 P 0 ;1
L 1.2575 2.1575 1.2575 2.1575 27 P 0 ;1
L 1.2575 2.2075 1.2575 2.2075 27 P 0 ;1
L 1.2575 2.2575 1.2575 2.2575 27 P 0 ;1
L 1.2575 2.3075 1.2575 2.3075 27 P 0 ;1
L 1.2575 2.3575 1.2575 2.3575 27 P 0 ;1
L 1.2575 2.4075 1.2575 2.4075 27 P 0 ;1
L 1.2575 2.4575 1.2575 2.4575 27 P 0 ;1
L 1.2575 2.5075 1.2575 2.5075 27 P 0 ;1
L 1.2575 2.5575 1.2575 2.5575 27 P 0 ;1
L 1.2575 2.6075 1.2575 2.6075 27 P 0 ;1
L 1.2575 2.6575 1.2575 2.6575 27 P 0 ;1
L 1.2575 2.7075 1.2575 2.7075 27 P 0 ;1
L 1.2575 2.7575 1.2575 2.7575 27 P 0 ;1
L 1.2575 2.8075 1.2575 2.8075 27 P 0 ;1
L 1.2575 2.8575 1.2575 2.8575 27 P 0 ;1
L 1.2575 2.9075 1.2575 2.9075 27 P 0 ;1
L 1.2575 2.9575 1.2575 2.9575 27 P 0 ;1
L 1.2575 3.0075 1.2575 3.0075 27 P 0 ;1
L 1.2575 3.0575 1.2575 3.0575 27 P 0 ;1
L 1.2575 3.1075 1.2575 3.1075 27 P 0 ;1
L 1.2575 3.1575 1.2575 3.1575 27 P 0 ;1
L 1.2575 3.2075 1.2575 3.2075 27 P 0 ;1
L 1.2575 3.2575 1.2575 3.2575 27 P 0 ;1
L 1.2575 3.3075 1.2575 3.3075 27 P 0 ;1
L 1.2575 3.3575 1.2575 3.3575 27 P 0 ;1
L 1.2575 3.4075 1.2575 3.4075 27 P 0 ;1
L 1.2575 3.4575 1.2575 3.4575 27 P 0 ;1
L 1.2575 3.5075 1.2575 3.5075 27 P 0 ;1
L 1.2575 3.5575 1.2575 3.5575 27 P 0 ;1
L 1.2575 3.6075 1.2575 3.6075 27 P 0 ;1
L 1.2575 3.6575 1.2575 3.6575 27 P 0 ;1
L 1.2575 3.7075 1.2575 3.7075 27 P 0 ;1
L 1.2575 3.7575 1.2575 3.7575 27 P 0 ;1
L 1.2575 3.8075 1.2575 3.8075 27 P 0 ;1
L 1.2575 3.8575 1.2575 3.8575 27 P 0 ;1
L 1.2575 3.9075 1.2575 3.9075 27 P 0 ;1
L 1.2575 3.9575 1.2575 3.9575 27 P 0 ;1
L 1.2575 4.0075 1.2575 4.0075 27 P 0 ;1
L 1.2575 4.0575 1.2575 4.0575 27 P 0 ;1
L 1.2575 4.1075 1.2575 4.1075 27 P 0 ;1
L 1.2575 4.1575 1.2575 4.1575 27 P 0 ;1
L 1.2575 4.2075 1.2575 4.2075 27 P 0 ;1
L 1.2575 4.2575 1.2575 4.2575 27 P 0 ;1
L 1.2575 4.3075 1.2575 4.3075 27 P 0 ;1
L 1.2575 4.3575 1.2575 4.3575 27 P 0 ;1
L 1.2575 4.4075 1.2575 4.4075 27 P 0 ;1
L 1.2575 4.4575 1.2575 4.4575 27 P 0 ;1
L 1.2575 4.5075 1.2575 4.5075 27 P 0 ;1
L 1.2575 5.2575 1.2575 5.2575 27 P 0 ;1
L 1.3075 0.1575 1.3075 0.1575 27 P 0 ;1
L 1.3075 0.2075 1.3075 0.2075 27 P 0 ;1
L 1.3075 0.2575 1.3075 0.2575 27 P 0 ;1
L 1.3075 0.3075 1.3075 0.3075 27 P 0 ;1
L 1.3075 0.3575 1.3075 0.3575 27 P 0 ;1
L 1.3075 0.4075 1.3075 0.4075 27 P 0 ;1
L 1.3075 0.4575 1.3075 0.4575 27 P 0 ;1
L 1.3075 0.5075 1.3075 0.5075 27 P 0 ;1
L 1.3075 0.5575 1.3075 0.5575 27 P 0 ;1
L 1.3075 0.6075 1.3075 0.6075 27 P 0 ;1
L 1.3075 0.6575 1.3075 0.6575 27 P 0 ;1
L 1.3075 0.7075 1.3075 0.7075 27 P 0 ;1
L 1.3075 0.7575 1.3075 0.7575 27 P 0 ;1
L 1.3075 0.8075 1.3075 0.8075 27 P 0 ;1
L 1.3075 0.8575 1.3075 0.8575 27 P 0 ;1
L 1.3075 0.9075 1.3075 0.9075 27 P 0 ;1
L 1.3075 0.9575 1.3075 0.9575 27 P 0 ;1
L 1.3075 1.0075 1.3075 1.0075 27 P 0 ;1
L 1.3075 1.0575 1.3075 1.0575 27 P 0 ;1
L 1.3075 1.1075 1.3075 1.1075 27 P 0 ;1
L 1.3075 1.1575 1.3075 1.1575 27 P 0 ;1
L 1.3075 1.2075 1.3075 1.2075 27 P 0 ;1
L 1.3075 1.2575 1.3075 1.2575 27 P 0 ;1
L 1.3075 1.3075 1.3075 1.3075 27 P 0 ;1
L 1.3075 1.3575 1.3075 1.3575 27 P 0 ;1
L 1.3075 1.4075 1.3075 1.4075 27 P 0 ;1
L 1.3075 1.4575 1.3075 1.4575 27 P 0 ;1
L 1.3075 1.5075 1.3075 1.5075 27 P 0 ;1
L 1.3075 1.5575 1.3075 1.5575 27 P 0 ;1
L 1.3075 1.6075 1.3075 1.6075 27 P 0 ;1
L 1.3075 1.6575 1.3075 1.6575 27 P 0 ;1
L 1.3075 1.7075 1.3075 1.7075 27 P 0 ;1
L 1.3075 1.7575 1.3075 1.7575 27 P 0 ;1
L 1.3075 1.8075 1.3075 1.8075 27 P 0 ;1
L 1.3075 1.8575 1.3075 1.8575 27 P 0 ;1
L 1.3075 1.9075 1.3075 1.9075 27 P 0 ;1
L 1.3075 1.9575 1.3075 1.9575 27 P 0 ;1
L 1.3075 2.0075 1.3075 2.0075 27 P 0 ;1
L 1.3075 2.0575 1.3075 2.0575 27 P 0 ;1
L 1.3075 2.1075 1.3075 2.1075 27 P 0 ;1
L 1.3075 2.1575 1.3075 2.1575 27 P 0 ;1
L 1.3075 2.2075 1.3075 2.2075 27 P 0 ;1
L 1.3075 2.2575 1.3075 2.2575 27 P 0 ;1
L 1.3075 2.3075 1.3075 2.3075 27 P 0 ;1
L 1.3075 2.3575 1.3075 2.3575 27 P 0 ;1
L 1.3075 2.4075 1.3075 2.4075 27 P 0 ;1
L 1.3075 2.4575 1.3075 2.4575 27 P 0 ;1
L 1.3075 2.5075 1.3075 2.5075 27 P 0 ;1
L 1.3075 2.5575 1.3075 2.5575 27 P 0 ;1
L 1.3075 2.6075 1.3075 2.6075 27 P 0 ;1
L 1.3075 2.6575 1.3075 2.6575 27 P 0 ;1
L 1.3075 2.7075 1.3075 2.7075 27 P 0 ;1
L 1.3075 2.7575 1.3075 2.7575 27 P 0 ;1
L 1.3075 2.8075 1.3075 2.8075 27 P 0 ;1
L 1.3075 2.8575 1.3075 2.8575 27 P 0 ;1
L 1.3075 2.9075 1.3075 2.9075 27 P 0 ;1
L 1.3075 2.9575 1.3075 2.9575 27 P 0 ;1
L 1.3075 3.0075 1.3075 3.0075 27 P 0 ;1
L 1.3075 3.0575 1.3075 3.0575 27 P 0 ;1
L 1.3075 3.1075 1.3075 3.1075 27 P 0 ;1
L 1.3075 3.1575 1.3075 3.1575 27 P 0 ;1
L 1.3075 3.2075 1.3075 3.2075 27 P 0 ;1
L 1.3075 3.2575 1.3075 3.2575 27 P 0 ;1
L 1.3075 3.3075 1.3075 3.3075 27 P 0 ;1
L 1.3075 3.3575 1.3075 3.3575 27 P 0 ;1
L 1.3075 3.4075 1.3075 3.4075 27 P 0 ;1
L 1.3075 3.4575 1.3075 3.4575 27 P 0 ;1
L 1.3075 3.5075 1.3075 3.5075 27 P 0 ;1
L 1.3075 3.5575 1.3075 3.5575 27 P 0 ;1
L 1.3075 3.6075 1.3075 3.6075 27 P 0 ;1
L 1.3075 3.6575 1.3075 3.6575 27 P 0 ;1
L 1.3075 3.7075 1.3075 3.7075 27 P 0 ;1
L 1.3075 3.7575 1.3075 3.7575 27 P 0 ;1
L 1.3075 3.8075 1.3075 3.8075 27 P 0 ;1
L 1.3075 3.8575 1.3075 3.8575 27 P 0 ;1
L 1.3075 3.9075 1.3075 3.9075 27 P 0 ;1
L 1.3075 3.9575 1.3075 3.9575 27 P 0 ;1
L 1.3075 4.0075 1.3075 4.0075 27 P 0 ;1
L 1.3075 4.0575 1.3075 4.0575 27 P 0 ;1
L 1.3075 4.1075 1.3075 4.1075 27 P 0 ;1
L 1.3075 4.1575 1.3075 4.1575 27 P 0 ;1
L 1.3075 4.2075 1.3075 4.2075 27 P 0 ;1
L 1.3075 4.2575 1.3075 4.2575 27 P 0 ;1
L 1.3075 4.3075 1.3075 4.3075 27 P 0 ;1
L 1.3075 4.3575 1.3075 4.3575 27 P 0 ;1
L 1.3075 4.4075 1.3075 4.4075 27 P 0 ;1
L 1.3075 4.4575 1.3075 4.4575 27 P 0 ;1
L 1.3075 4.5075 1.3075 4.5075 27 P 0 ;1
L 1.3075 5.2575 1.3075 5.2575 27 P 0 ;1
L 1.3575 0.1575 1.3575 0.1575 27 P 0 ;1
L 1.3575 0.2075 1.3575 0.2075 27 P 0 ;1
L 1.3575 0.2575 1.3575 0.2575 27 P 0 ;1
L 1.3575 0.3075 1.3575 0.3075 27 P 0 ;1
L 1.3575 0.3575 1.3575 0.3575 27 P 0 ;1
L 1.3575 0.4075 1.3575 0.4075 27 P 0 ;1
L 1.3575 0.4575 1.3575 0.4575 27 P 0 ;1
L 1.3575 0.5075 1.3575 0.5075 27 P 0 ;1
L 1.3575 0.5575 1.3575 0.5575 27 P 0 ;1
L 1.3575 0.6075 1.3575 0.6075 27 P 0 ;1
L 1.3575 0.6575 1.3575 0.6575 27 P 0 ;1
L 1.3575 0.7075 1.3575 0.7075 27 P 0 ;1
L 1.3575 0.7575 1.3575 0.7575 27 P 0 ;1
L 1.3575 0.8075 1.3575 0.8075 27 P 0 ;1
L 1.3575 0.8575 1.3575 0.8575 27 P 0 ;1
L 1.3575 0.9075 1.3575 0.9075 27 P 0 ;1
L 1.3575 0.9575 1.3575 0.9575 27 P 0 ;1
L 1.3575 1.0075 1.3575 1.0075 27 P 0 ;1
L 1.3575 1.0575 1.3575 1.0575 27 P 0 ;1
L 1.3575 1.1075 1.3575 1.1075 27 P 0 ;1
L 1.3575 1.1575 1.3575 1.1575 27 P 0 ;1
L 1.3575 1.2075 1.3575 1.2075 27 P 0 ;1
L 1.3575 1.2575 1.3575 1.2575 27 P 0 ;1
L 1.3575 1.3075 1.3575 1.3075 27 P 0 ;1
L 1.3575 1.3575 1.3575 1.3575 27 P 0 ;1
L 1.3575 1.4075 1.3575 1.4075 27 P 0 ;1
L 1.3575 1.4575 1.3575 1.4575 27 P 0 ;1
L 1.3575 1.5075 1.3575 1.5075 27 P 0 ;1
L 1.3575 1.5575 1.3575 1.5575 27 P 0 ;1
L 1.3575 1.6075 1.3575 1.6075 27 P 0 ;1
L 1.3575 1.6575 1.3575 1.6575 27 P 0 ;1
L 1.3575 1.7075 1.3575 1.7075 27 P 0 ;1
L 1.3575 1.7575 1.3575 1.7575 27 P 0 ;1
L 1.3575 1.8075 1.3575 1.8075 27 P 0 ;1
L 1.3575 1.8575 1.3575 1.8575 27 P 0 ;1
L 1.3575 1.9075 1.3575 1.9075 27 P 0 ;1
L 1.3575 1.9575 1.3575 1.9575 27 P 0 ;1
L 1.3575 2.0075 1.3575 2.0075 27 P 0 ;1
L 1.3575 2.0575 1.3575 2.0575 27 P 0 ;1
L 1.3575 2.1075 1.3575 2.1075 27 P 0 ;1
L 1.3575 2.1575 1.3575 2.1575 27 P 0 ;1
L 1.3575 2.2075 1.3575 2.2075 27 P 0 ;1
L 1.3575 2.2575 1.3575 2.2575 27 P 0 ;1
L 1.3575 2.3075 1.3575 2.3075 27 P 0 ;1
L 1.3575 2.3575 1.3575 2.3575 27 P 0 ;1
L 1.3575 2.4075 1.3575 2.4075 27 P 0 ;1
L 1.3575 2.4575 1.3575 2.4575 27 P 0 ;1
L 1.3575 2.5075 1.3575 2.5075 27 P 0 ;1
L 1.3575 2.5575 1.3575 2.5575 27 P 0 ;1
L 1.3575 2.6075 1.3575 2.6075 27 P 0 ;1
L 1.3575 2.6575 1.3575 2.6575 27 P 0 ;1
L 1.3575 2.7075 1.3575 2.7075 27 P 0 ;1
L 1.3575 2.7575 1.3575 2.7575 27 P 0 ;1
L 1.3575 2.8075 1.3575 2.8075 27 P 0 ;1
L 1.3575 2.8575 1.3575 2.8575 27 P 0 ;1
L 1.3575 2.9075 1.3575 2.9075 27 P 0 ;1
L 1.3575 2.9575 1.3575 2.9575 27 P 0 ;1
L 1.3575 3.0075 1.3575 3.0075 27 P 0 ;1
L 1.3575 3.0575 1.3575 3.0575 27 P 0 ;1
L 1.3575 3.1075 1.3575 3.1075 27 P 0 ;1
L 1.3575 3.1575 1.3575 3.1575 27 P 0 ;1
L 1.3575 3.2075 1.3575 3.2075 27 P 0 ;1
L 1.3575 3.2575 1.3575 3.2575 27 P 0 ;1
L 1.3575 3.3075 1.3575 3.3075 27 P 0 ;1
L 1.3575 3.3575 1.3575 3.3575 27 P 0 ;1
L 1.3575 3.4075 1.3575 3.4075 27 P 0 ;1
L 1.3575 3.4575 1.3575 3.4575 27 P 0 ;1
L 1.3575 3.5075 1.3575 3.5075 27 P 0 ;1
L 1.3575 3.5575 1.3575 3.5575 27 P 0 ;1
L 1.3575 3.6075 1.3575 3.6075 27 P 0 ;1
L 1.3575 3.6575 1.3575 3.6575 27 P 0 ;1
L 1.3575 3.7075 1.3575 3.7075 27 P 0 ;1
L 1.3575 3.7575 1.3575 3.7575 27 P 0 ;1
L 1.3575 3.8075 1.3575 3.8075 27 P 0 ;1
L 1.3575 3.8575 1.3575 3.8575 27 P 0 ;1
L 1.3575 3.9075 1.3575 3.9075 27 P 0 ;1
L 1.3575 3.9575 1.3575 3.9575 27 P 0 ;1
L 1.3575 4.0075 1.3575 4.0075 27 P 0 ;1
L 1.3575 4.0575 1.3575 4.0575 27 P 0 ;1
L 1.3575 4.1075 1.3575 4.1075 27 P 0 ;1
L 1.3575 4.1575 1.3575 4.1575 27 P 0 ;1
L 1.3575 4.2075 1.3575 4.2075 27 P 0 ;1
L 1.3575 4.2575 1.3575 4.2575 27 P 0 ;1
L 1.3575 4.3075 1.3575 4.3075 27 P 0 ;1
L 1.3575 4.3575 1.3575 4.3575 27 P 0 ;1
L 1.3575 4.4075 1.3575 4.4075 27 P 0 ;1
L 1.3575 4.4575 1.3575 4.4575 27 P 0 ;1
L 1.3575 4.5075 1.3575 4.5075 27 P 0 ;1
L 1.3575 5.2575 1.3575 5.2575 27 P 0 ;1
L 1.4075 0.1575 1.4075 0.1575 27 P 0 ;1
L 1.4075 0.2075 1.4075 0.2075 27 P 0 ;1
L 1.4075 0.2575 1.4075 0.2575 27 P 0 ;1
L 1.4075 0.3075 1.4075 0.3075 27 P 0 ;1
L 1.4075 0.3575 1.4075 0.3575 27 P 0 ;1
L 1.4075 0.4075 1.4075 0.4075 27 P 0 ;1
L 1.4075 0.4575 1.4075 0.4575 27 P 0 ;1
L 1.4075 0.5075 1.4075 0.5075 27 P 0 ;1
L 1.4075 0.5575 1.4075 0.5575 27 P 0 ;1
L 1.4075 0.6075 1.4075 0.6075 27 P 0 ;1
L 1.4075 0.6575 1.4075 0.6575 27 P 0 ;1
L 1.4075 0.7075 1.4075 0.7075 27 P 0 ;1
L 1.4075 0.7575 1.4075 0.7575 27 P 0 ;1
L 1.4075 0.8075 1.4075 0.8075 27 P 0 ;1
L 1.4075 0.8575 1.4075 0.8575 27 P 0 ;1
L 1.4075 0.9075 1.4075 0.9075 27 P 0 ;1
L 1.4075 0.9575 1.4075 0.9575 27 P 0 ;1
L 1.4075 1.0075 1.4075 1.0075 27 P 0 ;1
L 1.4075 1.0575 1.4075 1.0575 27 P 0 ;1
L 1.4075 1.1075 1.4075 1.1075 27 P 0 ;1
L 1.4075 1.1575 1.4075 1.1575 27 P 0 ;1
L 1.4075 1.2075 1.4075 1.2075 27 P 0 ;1
L 1.4075 1.2575 1.4075 1.2575 27 P 0 ;1
L 1.4075 1.3075 1.4075 1.3075 27 P 0 ;1
L 1.4075 1.3575 1.4075 1.3575 27 P 0 ;1
L 1.4075 1.4075 1.4075 1.4075 27 P 0 ;1
L 1.4075 1.4575 1.4075 1.4575 27 P 0 ;1
L 1.4075 1.5075 1.4075 1.5075 27 P 0 ;1
L 1.4075 1.5575 1.4075 1.5575 27 P 0 ;1
L 1.4075 1.6075 1.4075 1.6075 27 P 0 ;1
L 1.4075 1.6575 1.4075 1.6575 27 P 0 ;1
L 1.4075 1.7075 1.4075 1.7075 27 P 0 ;1
L 1.4075 1.7575 1.4075 1.7575 27 P 0 ;1
L 1.4075 1.8075 1.4075 1.8075 27 P 0 ;1
L 1.4075 1.8575 1.4075 1.8575 27 P 0 ;1
L 1.4075 1.9075 1.4075 1.9075 27 P 0 ;1
L 1.4075 1.9575 1.4075 1.9575 27 P 0 ;1
L 1.4075 2.0075 1.4075 2.0075 27 P 0 ;1
L 1.4075 2.0575 1.4075 2.0575 27 P 0 ;1
L 1.4075 2.1075 1.4075 2.1075 27 P 0 ;1
L 1.4075 2.1575 1.4075 2.1575 27 P 0 ;1
L 1.4075 2.2075 1.4075 2.2075 27 P 0 ;1
L 1.4075 2.2575 1.4075 2.2575 27 P 0 ;1
L 1.4075 2.3075 1.4075 2.3075 27 P 0 ;1
L 1.4075 2.3575 1.4075 2.3575 27 P 0 ;1
L 1.4075 2.4075 1.4075 2.4075 27 P 0 ;1
L 1.4075 2.4575 1.4075 2.4575 27 P 0 ;1
L 1.4075 2.5075 1.4075 2.5075 27 P 0 ;1
L 1.4075 2.5575 1.4075 2.5575 27 P 0 ;1
L 1.4075 2.6075 1.4075 2.6075 27 P 0 ;1
L 1.4075 2.6575 1.4075 2.6575 27 P 0 ;1
L 1.4075 2.7075 1.4075 2.7075 27 P 0 ;1
L 1.4075 2.7575 1.4075 2.7575 27 P 0 ;1
L 1.4075 2.8075 1.4075 2.8075 27 P 0 ;1
L 1.4075 2.8575 1.4075 2.8575 27 P 0 ;1
L 1.4075 2.9075 1.4075 2.9075 27 P 0 ;1
L 1.4075 2.9575 1.4075 2.9575 27 P 0 ;1
L 1.4075 3.0075 1.4075 3.0075 27 P 0 ;1
L 1.4075 3.0575 1.4075 3.0575 27 P 0 ;1
L 1.4075 3.1075 1.4075 3.1075 27 P 0 ;1
L 1.4075 3.1575 1.4075 3.1575 27 P 0 ;1
L 1.4075 3.2075 1.4075 3.2075 27 P 0 ;1
L 1.4075 3.2575 1.4075 3.2575 27 P 0 ;1
L 1.4075 3.3075 1.4075 3.3075 27 P 0 ;1
L 1.4075 3.3575 1.4075 3.3575 27 P 0 ;1
L 1.4075 3.4075 1.4075 3.4075 27 P 0 ;1
L 1.4075 3.4575 1.4075 3.4575 27 P 0 ;1
L 1.4075 3.5075 1.4075 3.5075 27 P 0 ;1
L 1.4075 3.5575 1.4075 3.5575 27 P 0 ;1
L 1.4075 3.6075 1.4075 3.6075 27 P 0 ;1
L 1.4075 3.6575 1.4075 3.6575 27 P 0 ;1
L 1.4075 3.7075 1.4075 3.7075 27 P 0 ;1
L 1.4075 3.7575 1.4075 3.7575 27 P 0 ;1
L 1.4075 3.8075 1.4075 3.8075 27 P 0 ;1
L 1.4075 3.8575 1.4075 3.8575 27 P 0 ;1
L 1.4075 3.9075 1.4075 3.9075 27 P 0 ;1
L 1.4075 3.9575 1.4075 3.9575 27 P 0 ;1
L 1.4075 4.0075 1.4075 4.0075 27 P 0 ;1
L 1.4075 4.0575 1.4075 4.0575 27 P 0 ;1
L 1.4075 4.1075 1.4075 4.1075 27 P 0 ;1
L 1.4075 4.1575 1.4075 4.1575 27 P 0 ;1
L 1.4075 4.2075 1.4075 4.2075 27 P 0 ;1
L 1.4075 4.2575 1.4075 4.2575 27 P 0 ;1
L 1.4075 4.3075 1.4075 4.3075 27 P 0 ;1
L 1.4075 4.3575 1.4075 4.3575 27 P 0 ;1
L 1.4075 4.4075 1.4075 4.4075 27 P 0 ;1
L 1.4075 4.4575 1.4075 4.4575 27 P 0 ;1
L 1.4075 4.5075 1.4075 4.5075 27 P 0 ;1
L 1.4075 5.2575 1.4075 5.2575 27 P 0 ;1
L 1.4575 0.1575 1.4575 0.1575 27 P 0 ;1
L 1.4575 0.2075 1.4575 0.2075 27 P 0 ;1
L 1.4575 0.2575 1.4575 0.2575 27 P 0 ;1
L 1.4575 0.3075 1.4575 0.3075 27 P 0 ;1
L 1.4575 0.3575 1.4575 0.3575 27 P 0 ;1
L 1.4575 0.4075 1.4575 0.4075 27 P 0 ;1
L 1.4575 0.4575 1.4575 0.4575 27 P 0 ;1
L 1.4575 0.5075 1.4575 0.5075 27 P 0 ;1
L 1.4575 0.5575 1.4575 0.5575 27 P 0 ;1
L 1.4575 0.6075 1.4575 0.6075 27 P 0 ;1
L 1.4575 0.6575 1.4575 0.6575 27 P 0 ;1
L 1.4575 0.7075 1.4575 0.7075 27 P 0 ;1
L 1.4575 0.7575 1.4575 0.7575 27 P 0 ;1
L 1.4575 0.8075 1.4575 0.8075 27 P 0 ;1
L 1.4575 0.8575 1.4575 0.8575 27 P 0 ;1
L 1.4575 0.9075 1.4575 0.9075 27 P 0 ;1
L 1.4575 0.9575 1.4575 0.9575 27 P 0 ;1
L 1.4575 1.0075 1.4575 1.0075 27 P 0 ;1
L 1.4575 1.0575 1.4575 1.0575 27 P 0 ;1
L 1.4575 1.1075 1.4575 1.1075 27 P 0 ;1
L 1.4575 1.1575 1.4575 1.1575 27 P 0 ;1
L 1.4575 1.2075 1.4575 1.2075 27 P 0 ;1
L 1.4575 1.2575 1.4575 1.2575 27 P 0 ;1
L 1.4575 1.3075 1.4575 1.3075 27 P 0 ;1
L 1.4575 1.3575 1.4575 1.3575 27 P 0 ;1
L 1.4575 1.4075 1.4575 1.4075 27 P 0 ;1
L 1.4575 1.4575 1.4575 1.4575 27 P 0 ;1
L 1.4575 1.5075 1.4575 1.5075 27 P 0 ;1
L 1.4575 1.5575 1.4575 1.5575 27 P 0 ;1
L 1.4575 1.6075 1.4575 1.6075 27 P 0 ;1
L 1.4575 1.6575 1.4575 1.6575 27 P 0 ;1
L 1.4575 1.7075 1.4575 1.7075 27 P 0 ;1
L 1.4575 1.7575 1.4575 1.7575 27 P 0 ;1
L 1.4575 1.8075 1.4575 1.8075 27 P 0 ;1
L 1.4575 1.8575 1.4575 1.8575 27 P 0 ;1
L 1.4575 1.9075 1.4575 1.9075 27 P 0 ;1
L 1.4575 1.9575 1.4575 1.9575 27 P 0 ;1
L 1.4575 2.0075 1.4575 2.0075 27 P 0 ;1
L 1.4575 2.0575 1.4575 2.0575 27 P 0 ;1
L 1.4575 2.1075 1.4575 2.1075 27 P 0 ;1
L 1.4575 2.1575 1.4575 2.1575 27 P 0 ;1
L 1.4575 2.2075 1.4575 2.2075 27 P 0 ;1
L 1.4575 2.2575 1.4575 2.2575 27 P 0 ;1
L 1.4575 2.3075 1.4575 2.3075 27 P 0 ;1
L 1.4575 2.3575 1.4575 2.3575 27 P 0 ;1
L 1.4575 2.4075 1.4575 2.4075 27 P 0 ;1
L 1.4575 2.4575 1.4575 2.4575 27 P 0 ;1
L 1.4575 2.5075 1.4575 2.5075 27 P 0 ;1
L 1.4575 2.5575 1.4575 2.5575 27 P 0 ;1
L 1.4575 2.6075 1.4575 2.6075 27 P 0 ;1
L 1.4575 2.6575 1.4575 2.6575 27 P 0 ;1
L 1.4575 2.7075 1.4575 2.7075 27 P 0 ;1
L 1.4575 2.7575 1.4575 2.7575 27 P 0 ;1
L 1.4575 2.8075 1.4575 2.8075 27 P 0 ;1
L 1.4575 2.8575 1.4575 2.8575 27 P 0 ;1
L 1.4575 2.9075 1.4575 2.9075 27 P 0 ;1
L 1.4575 2.9575 1.4575 2.9575 27 P 0 ;1
L 1.4575 3.0075 1.4575 3.0075 27 P 0 ;1
L 1.4575 3.0575 1.4575 3.0575 27 P 0 ;1
L 1.4575 3.1075 1.4575 3.1075 27 P 0 ;1
L 1.4575 3.1575 1.4575 3.1575 27 P 0 ;1
L 1.4575 3.2075 1.4575 3.2075 27 P 0 ;1
L 1.4575 3.2575 1.4575 3.2575 27 P 0 ;1
L 1.4575 3.3075 1.4575 3.3075 27 P 0 ;1
L 1.4575 3.3575 1.4575 3.3575 27 P 0 ;1
L 1.4575 3.4075 1.4575 3.4075 27 P 0 ;1
L 1.4575 3.4575 1.4575 3.4575 27 P 0 ;1
L 1.4575 3.5075 1.4575 3.5075 27 P 0 ;1
L 1.4575 3.5575 1.4575 3.5575 27 P 0 ;1
L 1.4575 3.6075 1.4575 3.6075 27 P 0 ;1
L 1.4575 3.6575 1.4575 3.6575 27 P 0 ;1
L 1.4575 3.7075 1.4575 3.7075 27 P 0 ;1
L 1.4575 3.7575 1.4575 3.7575 27 P 0 ;1
L 1.4575 3.8075 1.4575 3.8075 27 P 0 ;1
L 1.4575 3.8575 1.4575 3.8575 27 P 0 ;1
L 1.4575 3.9075 1.4575 3.9075 27 P 0 ;1
L 1.4575 3.9575 1.4575 3.9575 27 P 0 ;1
L 1.4575 4.0075 1.4575 4.0075 27 P 0 ;1
L 1.4575 4.0575 1.4575 4.0575 27 P 0 ;1
L 1.4575 4.1075 1.4575 4.1075 27 P 0 ;1
L 1.4575 4.1575 1.4575 4.1575 27 P 0 ;1
L 1.4575 4.2075 1.4575 4.2075 27 P 0 ;1
L 1.4575 4.2575 1.4575 4.2575 27 P 0 ;1
L 1.4575 4.3075 1.4575 4.3075 27 P 0 ;1
L 1.4575 4.3575 1.4575 4.3575 27 P 0 ;1
L 1.4575 4.4075 1.4575 4.4075 27 P 0 ;1
L 1.4575 4.4575 1.4575 4.4575 27 P 0 ;1
L 1.4575 4.5075 1.4575 4.5075 27 P 0 ;1
L 1.4575 4.5575 1.4575 4.5575 27 P 0 ;1
L 1.4575 4.6075 1.4575 4.6075 27 P 0 ;1
L 1.4575 4.6575 1.4575 4.6575 27 P 0 ;1
L 1.4575 5.2575 1.4575 5.2575 27 P 0 ;1
L 1.5075 0.1575 1.5075 0.1575 27 P 0 ;1
L 1.5075 0.2075 1.5075 0.2075 27 P 0 ;1
L 1.5075 0.2575 1.5075 0.2575 27 P 0 ;1
L 1.5075 0.3075 1.5075 0.3075 27 P 0 ;1
L 1.5075 0.3575 1.5075 0.3575 27 P 0 ;1
L 1.5075 0.4075 1.5075 0.4075 27 P 0 ;1
L 1.5075 0.4575 1.5075 0.4575 27 P 0 ;1
L 1.5075 0.5075 1.5075 0.5075 27 P 0 ;1
L 1.5075 0.5575 1.5075 0.5575 27 P 0 ;1
L 1.5075 0.6075 1.5075 0.6075 27 P 0 ;1
L 1.5075 0.6575 1.5075 0.6575 27 P 0 ;1
L 1.5075 0.7075 1.5075 0.7075 27 P 0 ;1
L 1.5075 0.7575 1.5075 0.7575 27 P 0 ;1
L 1.5075 0.8075 1.5075 0.8075 27 P 0 ;1
L 1.5075 0.8575 1.5075 0.8575 27 P 0 ;1
L 1.5075 0.9075 1.5075 0.9075 27 P 0 ;1
L 1.5075 0.9575 1.5075 0.9575 27 P 0 ;1
L 1.5075 1.0075 1.5075 1.0075 27 P 0 ;1
L 1.5075 1.0575 1.5075 1.0575 27 P 0 ;1
L 1.5075 1.1075 1.5075 1.1075 27 P 0 ;1
L 1.5075 1.1575 1.5075 1.1575 27 P 0 ;1
L 1.5075 1.2075 1.5075 1.2075 27 P 0 ;1
L 1.5075 1.2575 1.5075 1.2575 27 P 0 ;1
L 1.5075 1.3075 1.5075 1.3075 27 P 0 ;1
L 1.5075 1.3575 1.5075 1.3575 27 P 0 ;1
L 1.5075 1.4075 1.5075 1.4075 27 P 0 ;1
L 1.5075 1.4575 1.5075 1.4575 27 P 0 ;1
L 1.5075 1.5075 1.5075 1.5075 27 P 0 ;1
L 1.5075 1.5575 1.5075 1.5575 27 P 0 ;1
L 1.5075 1.6075 1.5075 1.6075 27 P 0 ;1
L 1.5075 1.6575 1.5075 1.6575 27 P 0 ;1
L 1.5075 1.7075 1.5075 1.7075 27 P 0 ;1
L 1.5075 1.7575 1.5075 1.7575 27 P 0 ;1
L 1.5075 1.8075 1.5075 1.8075 27 P 0 ;1
L 1.5075 1.8575 1.5075 1.8575 27 P 0 ;1
L 1.5075 1.9075 1.5075 1.9075 27 P 0 ;1
L 1.5075 1.9575 1.5075 1.9575 27 P 0 ;1
L 1.5075 2.0075 1.5075 2.0075 27 P 0 ;1
L 1.5075 2.0575 1.5075 2.0575 27 P 0 ;1
L 1.5075 2.1075 1.5075 2.1075 27 P 0 ;1
L 1.5075 2.1575 1.5075 2.1575 27 P 0 ;1
L 1.5075 2.2075 1.5075 2.2075 27 P 0 ;1
L 1.5075 2.2575 1.5075 2.2575 27 P 0 ;1
L 1.5075 2.3075 1.5075 2.3075 27 P 0 ;1
L 1.5075 2.3575 1.5075 2.3575 27 P 0 ;1
L 1.5075 2.4075 1.5075 2.4075 27 P 0 ;1
L 1.5075 2.4575 1.5075 2.4575 27 P 0 ;1
L 1.5075 2.5075 1.5075 2.5075 27 P 0 ;1
L 1.5075 2.5575 1.5075 2.5575 27 P 0 ;1
L 1.5075 2.6075 1.5075 2.6075 27 P 0 ;1
L 1.5075 2.6575 1.5075 2.6575 27 P 0 ;1
L 1.5075 2.7075 1.5075 2.7075 27 P 0 ;1
L 1.5075 2.7575 1.5075 2.7575 27 P 0 ;1
L 1.5075 2.8075 1.5075 2.8075 27 P 0 ;1
L 1.5075 2.8575 1.5075 2.8575 27 P 0 ;1
L 1.5075 2.9075 1.5075 2.9075 27 P 0 ;1
L 1.5075 2.9575 1.5075 2.9575 27 P 0 ;1
L 1.5075 3.0075 1.5075 3.0075 27 P 0 ;1
L 1.5075 3.0575 1.5075 3.0575 27 P 0 ;1
L 1.5075 3.1075 1.5075 3.1075 27 P 0 ;1
L 1.5075 3.1575 1.5075 3.1575 27 P 0 ;1
L 1.5075 3.2075 1.5075 3.2075 27 P 0 ;1
L 1.5075 3.2575 1.5075 3.2575 27 P 0 ;1
L 1.5075 3.3075 1.5075 3.3075 27 P 0 ;1
L 1.5075 3.3575 1.5075 3.3575 27 P 0 ;1
L 1.5075 3.4075 1.5075 3.4075 27 P 0 ;1
L 1.5075 3.4575 1.5075 3.4575 27 P 0 ;1
L 1.5075 3.5075 1.5075 3.5075 27 P 0 ;1
L 1.5075 3.5575 1.5075 3.5575 27 P 0 ;1
L 1.5075 3.6075 1.5075 3.6075 27 P 0 ;1
L 1.5075 3.6575 1.5075 3.6575 27 P 0 ;1
L 1.5075 3.7075 1.5075 3.7075 27 P 0 ;1
L 1.5075 3.7575 1.5075 3.7575 27 P 0 ;1
L 1.5075 3.8075 1.5075 3.8075 27 P 0 ;1
L 1.5075 3.8575 1.5075 3.8575 27 P 0 ;1
L 1.5075 3.9075 1.5075 3.9075 27 P 0 ;1
L 1.5075 3.9575 1.5075 3.9575 27 P 0 ;1
L 1.5075 4.0075 1.5075 4.0075 27 P 0 ;1
L 1.5075 4.0575 1.5075 4.0575 27 P 0 ;1
L 1.5075 4.1075 1.5075 4.1075 27 P 0 ;1
L 1.5075 4.1575 1.5075 4.1575 27 P 0 ;1
L 1.5075 4.2075 1.5075 4.2075 27 P 0 ;1
L 1.5075 4.2575 1.5075 4.2575 27 P 0 ;1
L 1.5075 4.3075 1.5075 4.3075 27 P 0 ;1
L 1.5075 4.3575 1.5075 4.3575 27 P 0 ;1
L 1.5075 4.4075 1.5075 4.4075 27 P 0 ;1
L 1.5075 4.4575 1.5075 4.4575 27 P 0 ;1
L 1.5075 4.5075 1.5075 4.5075 27 P 0 ;1
L 1.5075 4.5575 1.5075 4.5575 27 P 0 ;1
L 1.5075 5.2575 1.5075 5.2575 27 P 0 ;1
L 1.5575 0.1575 1.5575 0.1575 27 P 0 ;1
L 1.5575 0.2075 1.5575 0.2075 27 P 0 ;1
L 1.5575 0.2575 1.5575 0.2575 27 P 0 ;1
L 1.5575 0.3075 1.5575 0.3075 27 P 0 ;1
L 1.5575 0.3575 1.5575 0.3575 27 P 0 ;1
L 1.5575 0.4075 1.5575 0.4075 27 P 0 ;1
L 1.5575 0.4575 1.5575 0.4575 27 P 0 ;1
L 1.5575 0.5075 1.5575 0.5075 27 P 0 ;1
L 1.5575 0.5575 1.5575 0.5575 27 P 0 ;1
L 1.5575 0.6075 1.5575 0.6075 27 P 0 ;1
L 1.5575 0.6575 1.5575 0.6575 27 P 0 ;1
L 1.5575 0.7075 1.5575 0.7075 27 P 0 ;1
L 1.5575 0.7575 1.5575 0.7575 27 P 0 ;1
L 1.5575 0.8075 1.5575 0.8075 27 P 0 ;1
L 1.5575 0.8575 1.5575 0.8575 27 P 0 ;1
L 1.5575 0.9075 1.5575 0.9075 27 P 0 ;1
L 1.5575 0.9575 1.5575 0.9575 27 P 0 ;1
L 1.5575 1.0075 1.5575 1.0075 27 P 0 ;1
L 1.5575 1.0575 1.5575 1.0575 27 P 0 ;1
L 1.5575 1.1075 1.5575 1.1075 27 P 0 ;1
L 1.5575 1.1575 1.5575 1.1575 27 P 0 ;1
L 1.5575 1.2075 1.5575 1.2075 27 P 0 ;1
L 1.5575 1.2575 1.5575 1.2575 27 P 0 ;1
L 1.5575 1.3075 1.5575 1.3075 27 P 0 ;1
L 1.5575 1.3575 1.5575 1.3575 27 P 0 ;1
L 1.5575 1.4075 1.5575 1.4075 27 P 0 ;1
L 1.5575 1.4575 1.5575 1.4575 27 P 0 ;1
L 1.5575 1.5075 1.5575 1.5075 27 P 0 ;1
L 1.5575 1.5575 1.5575 1.5575 27 P 0 ;1
L 1.5575 1.6075 1.5575 1.6075 27 P 0 ;1
L 1.5575 1.6575 1.5575 1.6575 27 P 0 ;1
L 1.5575 1.7075 1.5575 1.7075 27 P 0 ;1
L 1.5575 1.7575 1.5575 1.7575 27 P 0 ;1
L 1.5575 1.8075 1.5575 1.8075 27 P 0 ;1
L 1.5575 1.8575 1.5575 1.8575 27 P 0 ;1
L 1.5575 1.9075 1.5575 1.9075 27 P 0 ;1
L 1.5575 1.9575 1.5575 1.9575 27 P 0 ;1
L 1.5575 2.0075 1.5575 2.0075 27 P 0 ;1
L 1.5575 2.0575 1.5575 2.0575 27 P 0 ;1
L 1.5575 2.1075 1.5575 2.1075 27 P 0 ;1
L 1.5575 2.1575 1.5575 2.1575 27 P 0 ;1
L 1.5575 2.2075 1.5575 2.2075 27 P 0 ;1
L 1.5575 2.2575 1.5575 2.2575 27 P 0 ;1
L 1.5575 2.3075 1.5575 2.3075 27 P 0 ;1
L 1.5575 2.3575 1.5575 2.3575 27 P 0 ;1
L 1.5575 2.4075 1.5575 2.4075 27 P 0 ;1
L 1.5575 2.4575 1.5575 2.4575 27 P 0 ;1
L 1.5575 2.5075 1.5575 2.5075 27 P 0 ;1
L 1.5575 2.5575 1.5575 2.5575 27 P 0 ;1
L 1.5575 2.6075 1.5575 2.6075 27 P 0 ;1
L 1.5575 2.6575 1.5575 2.6575 27 P 0 ;1
L 1.5575 2.7075 1.5575 2.7075 27 P 0 ;1
L 1.5575 2.7575 1.5575 2.7575 27 P 0 ;1
L 1.5575 2.8075 1.5575 2.8075 27 P 0 ;1
L 1.5575 2.8575 1.5575 2.8575 27 P 0 ;1
L 1.5575 2.9075 1.5575 2.9075 27 P 0 ;1
L 1.5575 2.9575 1.5575 2.9575 27 P 0 ;1
L 1.5575 3.0075 1.5575 3.0075 27 P 0 ;1
L 1.5575 3.0575 1.5575 3.0575 27 P 0 ;1
L 1.5575 3.1075 1.5575 3.1075 27 P 0 ;1
L 1.5575 3.1575 1.5575 3.1575 27 P 0 ;1
L 1.5575 3.2075 1.5575 3.2075 27 P 0 ;1
L 1.5575 3.2575 1.5575 3.2575 27 P 0 ;1
L 1.5575 3.3075 1.5575 3.3075 27 P 0 ;1
L 1.5575 3.3575 1.5575 3.3575 27 P 0 ;1
L 1.5575 3.4075 1.5575 3.4075 27 P 0 ;1
L 1.5575 3.4575 1.5575 3.4575 27 P 0 ;1
L 1.5575 3.5075 1.5575 3.5075 27 P 0 ;1
L 1.5575 3.5575 1.5575 3.5575 27 P 0 ;1
L 1.5575 3.6075 1.5575 3.6075 27 P 0 ;1
L 1.5575 3.6575 1.5575 3.6575 27 P 0 ;1
L 1.5575 3.7075 1.5575 3.7075 27 P 0 ;1
L 1.5575 3.7575 1.5575 3.7575 27 P 0 ;1
L 1.5575 3.8075 1.5575 3.8075 27 P 0 ;1
L 1.5575 3.8575 1.5575 3.8575 27 P 0 ;1
L 1.5575 3.9075 1.5575 3.9075 27 P 0 ;1
L 1.5575 3.9575 1.5575 3.9575 27 P 0 ;1
L 1.5575 4.0075 1.5575 4.0075 27 P 0 ;1
L 1.5575 4.0575 1.5575 4.0575 27 P 0 ;1
L 1.5575 4.1075 1.5575 4.1075 27 P 0 ;1
L 1.5575 4.1575 1.5575 4.1575 27 P 0 ;1
L 1.5575 4.2075 1.5575 4.2075 27 P 0 ;1
L 1.5575 4.2575 1.5575 4.2575 27 P 0 ;1
L 1.5575 4.3075 1.5575 4.3075 27 P 0 ;1
L 1.5575 4.3575 1.5575 4.3575 27 P 0 ;1
L 1.5575 4.4075 1.5575 4.4075 27 P 0 ;1
L 1.5575 4.4575 1.5575 4.4575 27 P 0 ;1
L 1.5575 4.5075 1.5575 4.5075 27 P 0 ;1
L 1.5575 4.5575 1.5575 4.5575 27 P 0 ;1
L 1.5575 5.3075 1.5575 5.3075 27 P 0 ;1
L 1.5575 5.3575 1.5575 5.3575 27 P 0 ;1
L 1.6075 0.1575 1.6075 0.1575 27 P 0 ;1
L 1.6075 0.2075 1.6075 0.2075 27 P 0 ;1
L 1.6075 0.2575 1.6075 0.2575 27 P 0 ;1
L 1.6075 0.3075 1.6075 0.3075 27 P 0 ;1
L 1.6075 0.3575 1.6075 0.3575 27 P 0 ;1
L 1.6075 0.4075 1.6075 0.4075 27 P 0 ;1
L 1.6075 0.4575 1.6075 0.4575 27 P 0 ;1
L 1.6075 0.5075 1.6075 0.5075 27 P 0 ;1
L 1.6075 0.5575 1.6075 0.5575 27 P 0 ;1
L 1.6075 0.6075 1.6075 0.6075 27 P 0 ;1
L 1.6075 0.6575 1.6075 0.6575 27 P 0 ;1
L 1.6075 0.7075 1.6075 0.7075 27 P 0 ;1
L 1.6075 0.7575 1.6075 0.7575 27 P 0 ;1
L 1.6075 0.8075 1.6075 0.8075 27 P 0 ;1
L 1.6075 0.8575 1.6075 0.8575 27 P 0 ;1
L 1.6075 0.9075 1.6075 0.9075 27 P 0 ;1
L 1.6075 0.9575 1.6075 0.9575 27 P 0 ;1
L 1.6075 1.0075 1.6075 1.0075 27 P 0 ;1
L 1.6075 1.0575 1.6075 1.0575 27 P 0 ;1
L 1.6075 1.1075 1.6075 1.1075 27 P 0 ;1
L 1.6075 1.1575 1.6075 1.1575 27 P 0 ;1
L 1.6075 1.2075 1.6075 1.2075 27 P 0 ;1
L 1.6075 1.2575 1.6075 1.2575 27 P 0 ;1
L 1.6075 1.3075 1.6075 1.3075 27 P 0 ;1
L 1.6075 1.3575 1.6075 1.3575 27 P 0 ;1
L 1.6075 1.4075 1.6075 1.4075 27 P 0 ;1
L 1.6075 1.4575 1.6075 1.4575 27 P 0 ;1
L 1.6075 1.5075 1.6075 1.5075 27 P 0 ;1
L 1.6075 1.5575 1.6075 1.5575 27 P 0 ;1
L 1.6075 1.6075 1.6075 1.6075 27 P 0 ;1
L 1.6075 1.6575 1.6075 1.6575 27 P 0 ;1
L 1.6075 1.7075 1.6075 1.7075 27 P 0 ;1
L 1.6075 1.7575 1.6075 1.7575 27 P 0 ;1
L 1.6075 1.8075 1.6075 1.8075 27 P 0 ;1
L 1.6075 1.8575 1.6075 1.8575 27 P 0 ;1
L 1.6075 1.9075 1.6075 1.9075 27 P 0 ;1
L 1.6075 1.9575 1.6075 1.9575 27 P 0 ;1
L 1.6075 2.0075 1.6075 2.0075 27 P 0 ;1
L 1.6075 2.0575 1.6075 2.0575 27 P 0 ;1
L 1.6075 2.1075 1.6075 2.1075 27 P 0 ;1
L 1.6075 2.1575 1.6075 2.1575 27 P 0 ;1
L 1.6075 2.2075 1.6075 2.2075 27 P 0 ;1
L 1.6075 2.2575 1.6075 2.2575 27 P 0 ;1
L 1.6075 2.3075 1.6075 2.3075 27 P 0 ;1
L 1.6075 2.3575 1.6075 2.3575 27 P 0 ;1
L 1.6075 2.4075 1.6075 2.4075 27 P 0 ;1
L 1.6075 2.4575 1.6075 2.4575 27 P 0 ;1
L 1.6075 2.5075 1.6075 2.5075 27 P 0 ;1
L 1.6075 2.5575 1.6075 2.5575 27 P 0 ;1
L 1.6075 2.6075 1.6075 2.6075 27 P 0 ;1
L 1.6075 2.6575 1.6075 2.6575 27 P 0 ;1
L 1.6075 2.7075 1.6075 2.7075 27 P 0 ;1
L 1.6075 2.7575 1.6075 2.7575 27 P 0 ;1
L 1.6075 2.8075 1.6075 2.8075 27 P 0 ;1
L 1.6075 2.8575 1.6075 2.8575 27 P 0 ;1
L 1.6075 2.9075 1.6075 2.9075 27 P 0 ;1
L 1.6075 2.9575 1.6075 2.9575 27 P 0 ;1
L 1.6075 3.0075 1.6075 3.0075 27 P 0 ;1
L 1.6075 3.0575 1.6075 3.0575 27 P 0 ;1
L 1.6075 3.1075 1.6075 3.1075 27 P 0 ;1
L 1.6075 3.1575 1.6075 3.1575 27 P 0 ;1
L 1.6075 3.2075 1.6075 3.2075 27 P 0 ;1
L 1.6075 3.2575 1.6075 3.2575 27 P 0 ;1
L 1.6075 3.3075 1.6075 3.3075 27 P 0 ;1
L 1.6075 3.3575 1.6075 3.3575 27 P 0 ;1
L 1.6075 3.4075 1.6075 3.4075 27 P 0 ;1
L 1.6075 3.4575 1.6075 3.4575 27 P 0 ;1
L 1.6075 3.5075 1.6075 3.5075 27 P 0 ;1
L 1.6075 3.5575 1.6075 3.5575 27 P 0 ;1
L 1.6075 3.6075 1.6075 3.6075 27 P 0 ;1
L 1.6075 3.6575 1.6075 3.6575 27 P 0 ;1
L 1.6075 3.7075 1.6075 3.7075 27 P 0 ;1
L 1.6075 3.7575 1.6075 3.7575 27 P 0 ;1
L 1.6075 3.8075 1.6075 3.8075 27 P 0 ;1
L 1.6075 3.8575 1.6075 3.8575 27 P 0 ;1
L 1.6075 3.9075 1.6075 3.9075 27 P 0 ;1
L 1.6075 3.9575 1.6075 3.9575 27 P 0 ;1
L 1.6075 4.0075 1.6075 4.0075 27 P 0 ;1
L 1.6075 4.0575 1.6075 4.0575 27 P 0 ;1
L 1.6075 4.1075 1.6075 4.1075 27 P 0 ;1
L 1.6075 4.1575 1.6075 4.1575 27 P 0 ;1
L 1.6075 4.2075 1.6075 4.2075 27 P 0 ;1
L 1.6075 4.2575 1.6075 4.2575 27 P 0 ;1
L 1.6075 4.3075 1.6075 4.3075 27 P 0 ;1
L 1.6075 4.3575 1.6075 4.3575 27 P 0 ;1
L 1.6075 4.4075 1.6075 4.4075 27 P 0 ;1
L 1.6075 4.4575 1.6075 4.4575 27 P 0 ;1
L 1.6075 4.5075 1.6075 4.5075 27 P 0 ;1
L 1.6075 4.5575 1.6075 4.5575 27 P 0 ;1
L 1.6075 5.3075 1.6075 5.3075 27 P 0 ;1
L 1.6075 5.3575 1.6075 5.3575 27 P 0 ;1
L 1.6075 5.4075 1.6075 5.4075 27 P 0 ;1
L 1.6075 5.8075 1.6075 5.8075 27 P 0 ;1
L 1.6075 5.8575 1.6075 5.8575 27 P 0 ;1
L 1.6575 0.1575 1.6575 0.1575 27 P 0 ;1
L 1.6575 0.2075 1.6575 0.2075 27 P 0 ;1
L 1.6575 0.2575 1.6575 0.2575 27 P 0 ;1
L 1.6575 0.3075 1.6575 0.3075 27 P 0 ;1
L 1.6575 0.3575 1.6575 0.3575 27 P 0 ;1
L 1.6575 0.4075 1.6575 0.4075 27 P 0 ;1
L 1.6575 0.4575 1.6575 0.4575 27 P 0 ;1
L 1.6575 0.5075 1.6575 0.5075 27 P 0 ;1
L 1.6575 0.5575 1.6575 0.5575 27 P 0 ;1
L 1.6575 0.6075 1.6575 0.6075 27 P 0 ;1
L 1.6575 0.6575 1.6575 0.6575 27 P 0 ;1
L 1.6575 0.7075 1.6575 0.7075 27 P 0 ;1
L 1.6575 0.7575 1.6575 0.7575 27 P 0 ;1
L 1.6575 0.8075 1.6575 0.8075 27 P 0 ;1
L 1.6575 0.8575 1.6575 0.8575 27 P 0 ;1
L 1.6575 0.9075 1.6575 0.9075 27 P 0 ;1
L 1.6575 0.9575 1.6575 0.9575 27 P 0 ;1
L 1.6575 1.0075 1.6575 1.0075 27 P 0 ;1
L 1.6575 1.0575 1.6575 1.0575 27 P 0 ;1
L 1.6575 1.1075 1.6575 1.1075 27 P 0 ;1
L 1.6575 1.1575 1.6575 1.1575 27 P 0 ;1
L 1.6575 1.2075 1.6575 1.2075 27 P 0 ;1
L 1.6575 1.2575 1.6575 1.2575 27 P 0 ;1
L 1.6575 1.3075 1.6575 1.3075 27 P 0 ;1
L 1.6575 1.3575 1.6575 1.3575 27 P 0 ;1
L 1.6575 1.4075 1.6575 1.4075 27 P 0 ;1
L 1.6575 1.4575 1.6575 1.4575 27 P 0 ;1
L 1.6575 1.5075 1.6575 1.5075 27 P 0 ;1
L 1.6575 1.5575 1.6575 1.5575 27 P 0 ;1
L 1.6575 1.6075 1.6575 1.6075 27 P 0 ;1
L 1.6575 1.6575 1.6575 1.6575 27 P 0 ;1
L 1.6575 1.7075 1.6575 1.7075 27 P 0 ;1
L 1.6575 1.7575 1.6575 1.7575 27 P 0 ;1
L 1.6575 1.8075 1.6575 1.8075 27 P 0 ;1
L 1.6575 1.8575 1.6575 1.8575 27 P 0 ;1
L 1.6575 1.9075 1.6575 1.9075 27 P 0 ;1
L 1.6575 1.9575 1.6575 1.9575 27 P 0 ;1
L 1.6575 2.0075 1.6575 2.0075 27 P 0 ;1
L 1.6575 2.0575 1.6575 2.0575 27 P 0 ;1
L 1.6575 2.1075 1.6575 2.1075 27 P 0 ;1
L 1.6575 2.1575 1.6575 2.1575 27 P 0 ;1
L 1.6575 2.2075 1.6575 2.2075 27 P 0 ;1
L 1.6575 2.2575 1.6575 2.2575 27 P 0 ;1
L 1.6575 2.3075 1.6575 2.3075 27 P 0 ;1
L 1.6575 2.3575 1.6575 2.3575 27 P 0 ;1
L 1.6575 2.4075 1.6575 2.4075 27 P 0 ;1
L 1.6575 2.4575 1.6575 2.4575 27 P 0 ;1
L 1.6575 2.5075 1.6575 2.5075 27 P 0 ;1
L 1.6575 2.5575 1.6575 2.5575 27 P 0 ;1
L 1.6575 2.6075 1.6575 2.6075 27 P 0 ;1
L 1.6575 2.6575 1.6575 2.6575 27 P 0 ;1
L 1.6575 2.7075 1.6575 2.7075 27 P 0 ;1
L 1.6575 2.7575 1.6575 2.7575 27 P 0 ;1
L 1.6575 2.8075 1.6575 2.8075 27 P 0 ;1
L 1.6575 2.8575 1.6575 2.8575 27 P 0 ;1
L 1.6575 2.9075 1.6575 2.9075 27 P 0 ;1
L 1.6575 2.9575 1.6575 2.9575 27 P 0 ;1
L 1.6575 3.0075 1.6575 3.0075 27 P 0 ;1
L 1.6575 3.0575 1.6575 3.0575 27 P 0 ;1
L 1.6575 3.1075 1.6575 3.1075 27 P 0 ;1
L 1.6575 3.1575 1.6575 3.1575 27 P 0 ;1
L 1.6575 3.2075 1.6575 3.2075 27 P 0 ;1
L 1.6575 3.2575 1.6575 3.2575 27 P 0 ;1
L 1.6575 3.3075 1.6575 3.3075 27 P 0 ;1
L 1.6575 3.3575 1.6575 3.3575 27 P 0 ;1
L 1.6575 3.4075 1.6575 3.4075 27 P 0 ;1
L 1.6575 3.4575 1.6575 3.4575 27 P 0 ;1
L 1.6575 3.5075 1.6575 3.5075 27 P 0 ;1
L 1.6575 3.5575 1.6575 3.5575 27 P 0 ;1
L 1.6575 3.6075 1.6575 3.6075 27 P 0 ;1
L 1.6575 3.6575 1.6575 3.6575 27 P 0 ;1
L 1.6575 3.7075 1.6575 3.7075 27 P 0 ;1
L 1.6575 3.7575 1.6575 3.7575 27 P 0 ;1
L 1.6575 3.8075 1.6575 3.8075 27 P 0 ;1
L 1.6575 3.8575 1.6575 3.8575 27 P 0 ;1
L 1.6575 3.9075 1.6575 3.9075 27 P 0 ;1
L 1.6575 3.9575 1.6575 3.9575 27 P 0 ;1
L 1.6575 4.0075 1.6575 4.0075 27 P 0 ;1
L 1.6575 4.0575 1.6575 4.0575 27 P 0 ;1
L 1.6575 4.1075 1.6575 4.1075 27 P 0 ;1
L 1.6575 4.1575 1.6575 4.1575 27 P 0 ;1
L 1.6575 4.2075 1.6575 4.2075 27 P 0 ;1
L 1.6575 4.2575 1.6575 4.2575 27 P 0 ;1
L 1.6575 4.3075 1.6575 4.3075 27 P 0 ;1
L 1.6575 4.3575 1.6575 4.3575 27 P 0 ;1
L 1.6575 4.4075 1.6575 4.4075 27 P 0 ;1
L 1.6575 4.4575 1.6575 4.4575 27 P 0 ;1
L 1.6575 4.5075 1.6575 4.5075 27 P 0 ;1
L 1.6575 4.5575 1.6575 4.5575 27 P 0 ;1
L 1.6575 5.2575 1.6575 5.2575 27 P 0 ;1
L 1.6575 5.3075 1.6575 5.3075 27 P 0 ;1
L 1.6575 5.3575 1.6575 5.3575 27 P 0 ;1
L 1.6575 5.4075 1.6575 5.4075 27 P 0 ;1
L 1.6575 5.4575 1.6575 5.4575 27 P 0 ;1
L 1.6575 5.5075 1.6575 5.5075 27 P 0 ;1
L 1.6575 5.5575 1.6575 5.5575 27 P 0 ;1
L 1.6575 5.6075 1.6575 5.6075 27 P 0 ;1
L 1.6575 5.6575 1.6575 5.6575 27 P 0 ;1
L 1.6575 5.7075 1.6575 5.7075 27 P 0 ;1
L 1.6575 5.7575 1.6575 5.7575 27 P 0 ;1
L 1.6575 5.8075 1.6575 5.8075 27 P 0 ;1
L 1.6575 5.8575 1.6575 5.8575 27 P 0 ;1
L 1.7075 0.1575 1.7075 0.1575 27 P 0 ;1
L 1.7075 0.2075 1.7075 0.2075 27 P 0 ;1
L 1.7075 0.2575 1.7075 0.2575 27 P 0 ;1
L 1.7075 0.3075 1.7075 0.3075 27 P 0 ;1
L 1.7075 0.3575 1.7075 0.3575 27 P 0 ;1
L 1.7075 0.4075 1.7075 0.4075 27 P 0 ;1
L 1.7075 0.4575 1.7075 0.4575 27 P 0 ;1
L 1.7075 0.5075 1.7075 0.5075 27 P 0 ;1
L 1.7075 0.5575 1.7075 0.5575 27 P 0 ;1
L 1.7075 0.6075 1.7075 0.6075 27 P 0 ;1
L 1.7075 0.6575 1.7075 0.6575 27 P 0 ;1
L 1.7075 0.7075 1.7075 0.7075 27 P 0 ;1
L 1.7075 0.7575 1.7075 0.7575 27 P 0 ;1
L 1.7075 0.8075 1.7075 0.8075 27 P 0 ;1
L 1.7075 0.8575 1.7075 0.8575 27 P 0 ;1
L 1.7075 0.9075 1.7075 0.9075 27 P 0 ;1
L 1.7075 0.9575 1.7075 0.9575 27 P 0 ;1
L 1.7075 1.0075 1.7075 1.0075 27 P 0 ;1
L 1.7075 1.0575 1.7075 1.0575 27 P 0 ;1
L 1.7075 1.1075 1.7075 1.1075 27 P 0 ;1
L 1.7075 1.1575 1.7075 1.1575 27 P 0 ;1
L 1.7075 1.2075 1.7075 1.2075 27 P 0 ;1
L 1.7075 1.2575 1.7075 1.2575 27 P 0 ;1
L 1.7075 1.3075 1.7075 1.3075 27 P 0 ;1
L 1.7075 1.3575 1.7075 1.3575 27 P 0 ;1
L 1.7075 1.4075 1.7075 1.4075 27 P 0 ;1
L 1.7075 1.4575 1.7075 1.4575 27 P 0 ;1
L 1.7075 1.5075 1.7075 1.5075 27 P 0 ;1
L 1.7075 1.5575 1.7075 1.5575 27 P 0 ;1
L 1.7075 1.6075 1.7075 1.6075 27 P 0 ;1
L 1.7075 1.6575 1.7075 1.6575 27 P 0 ;1
L 1.7075 1.7075 1.7075 1.7075 27 P 0 ;1
L 1.7075 1.7575 1.7075 1.7575 27 P 0 ;1
L 1.7075 1.8075 1.7075 1.8075 27 P 0 ;1
L 1.7075 1.8575 1.7075 1.8575 27 P 0 ;1
L 1.7075 1.9075 1.7075 1.9075 27 P 0 ;1
L 1.7075 1.9575 1.7075 1.9575 27 P 0 ;1
L 1.7075 2.0075 1.7075 2.0075 27 P 0 ;1
L 1.7075 2.0575 1.7075 2.0575 27 P 0 ;1
L 1.7075 2.1075 1.7075 2.1075 27 P 0 ;1
L 1.7075 2.1575 1.7075 2.1575 27 P 0 ;1
L 1.7075 2.2075 1.7075 2.2075 27 P 0 ;1
L 1.7075 2.2575 1.7075 2.2575 27 P 0 ;1
L 1.7075 2.3075 1.7075 2.3075 27 P 0 ;1
L 1.7075 2.3575 1.7075 2.3575 27 P 0 ;1
L 1.7075 2.4075 1.7075 2.4075 27 P 0 ;1
L 1.7075 2.5575 1.7075 2.5575 27 P 0 ;1
L 1.7075 2.6075 1.7075 2.6075 27 P 0 ;1
L 1.7075 2.6575 1.7075 2.6575 27 P 0 ;1
L 1.7075 2.7075 1.7075 2.7075 27 P 0 ;1
L 1.7075 2.7575 1.7075 2.7575 27 P 0 ;1
L 1.7075 2.8075 1.7075 2.8075 27 P 0 ;1
L 1.7075 2.8575 1.7075 2.8575 27 P 0 ;1
L 1.7075 2.9075 1.7075 2.9075 27 P 0 ;1
L 1.7075 2.9575 1.7075 2.9575 27 P 0 ;1
L 1.7075 3.0075 1.7075 3.0075 27 P 0 ;1
L 1.7075 3.0575 1.7075 3.0575 27 P 0 ;1
L 1.7075 3.1075 1.7075 3.1075 27 P 0 ;1
L 1.7075 3.1575 1.7075 3.1575 27 P 0 ;1
L 1.7075 3.2075 1.7075 3.2075 27 P 0 ;1
L 1.7075 3.2575 1.7075 3.2575 27 P 0 ;1
L 1.7075 3.3075 1.7075 3.3075 27 P 0 ;1
L 1.7075 3.3575 1.7075 3.3575 27 P 0 ;1
L 1.7075 3.4075 1.7075 3.4075 27 P 0 ;1
L 1.7075 3.4575 1.7075 3.4575 27 P 0 ;1
L 1.7075 3.5075 1.7075 3.5075 27 P 0 ;1
L 1.7075 3.5575 1.7075 3.5575 27 P 0 ;1
L 1.7075 3.6075 1.7075 3.6075 27 P 0 ;1
L 1.7075 3.6575 1.7075 3.6575 27 P 0 ;1
L 1.7075 3.7075 1.7075 3.7075 27 P 0 ;1
L 1.7075 3.7575 1.7075 3.7575 27 P 0 ;1
L 1.7075 3.8075 1.7075 3.8075 27 P 0 ;1
L 1.7075 3.8575 1.7075 3.8575 27 P 0 ;1
L 1.7075 3.9075 1.7075 3.9075 27 P 0 ;1
L 1.7075 3.9575 1.7075 3.9575 27 P 0 ;1
L 1.7075 4.0075 1.7075 4.0075 27 P 0 ;1
L 1.7075 4.0575 1.7075 4.0575 27 P 0 ;1
L 1.7075 4.1075 1.7075 4.1075 27 P 0 ;1
L 1.7075 4.1575 1.7075 4.1575 27 P 0 ;1
L 1.7075 4.2075 1.7075 4.2075 27 P 0 ;1
L 1.7075 4.2575 1.7075 4.2575 27 P 0 ;1
L 1.7075 4.3075 1.7075 4.3075 27 P 0 ;1
L 1.7075 4.3575 1.7075 4.3575 27 P 0 ;1
L 1.7075 4.4075 1.7075 4.4075 27 P 0 ;1
L 1.7075 4.4575 1.7075 4.4575 27 P 0 ;1
L 1.7075 4.5075 1.7075 4.5075 27 P 0 ;1
L 1.7075 4.5575 1.7075 4.5575 27 P 0 ;1
L 1.7075 4.6075 1.7075 4.6075 27 P 0 ;1
L 1.7075 5.2075 1.7075 5.2075 27 P 0 ;1
L 1.7075 5.2575 1.7075 5.2575 27 P 0 ;1
L 1.7075 5.3075 1.7075 5.3075 27 P 0 ;1
L 1.7075 5.3575 1.7075 5.3575 27 P 0 ;1
L 1.7075 5.4075 1.7075 5.4075 27 P 0 ;1
L 1.7075 5.4575 1.7075 5.4575 27 P 0 ;1
L 1.7075 5.5075 1.7075 5.5075 27 P 0 ;1
L 1.7075 5.5575 1.7075 5.5575 27 P 0 ;1
L 1.7075 5.6075 1.7075 5.6075 27 P 0 ;1
L 1.7075 5.6575 1.7075 5.6575 27 P 0 ;1
L 1.7075 5.7075 1.7075 5.7075 27 P 0 ;1
L 1.7075 5.7575 1.7075 5.7575 27 P 0 ;1
L 1.7075 5.8075 1.7075 5.8075 27 P 0 ;1
L 1.7075 5.8575 1.7075 5.8575 27 P 0 ;1
L 1.7575 0.1575 1.7575 0.1575 27 P 0 ;1
L 1.7575 0.2075 1.7575 0.2075 27 P 0 ;1
L 1.7575 0.2575 1.7575 0.2575 27 P 0 ;1
L 1.7575 0.3075 1.7575 0.3075 27 P 0 ;1
L 1.7575 0.3575 1.7575 0.3575 27 P 0 ;1
L 1.7575 0.4075 1.7575 0.4075 27 P 0 ;1
L 1.7575 0.4575 1.7575 0.4575 27 P 0 ;1
L 1.7575 0.5075 1.7575 0.5075 27 P 0 ;1
L 1.7575 0.5575 1.7575 0.5575 27 P 0 ;1
L 1.7575 0.6075 1.7575 0.6075 27 P 0 ;1
L 1.7575 0.6575 1.7575 0.6575 27 P 0 ;1
L 1.7575 0.7075 1.7575 0.7075 27 P 0 ;1
L 1.7575 0.7575 1.7575 0.7575 27 P 0 ;1
L 1.7575 0.8075 1.7575 0.8075 27 P 0 ;1
L 1.7575 0.8575 1.7575 0.8575 27 P 0 ;1
L 1.7575 0.9075 1.7575 0.9075 27 P 0 ;1
L 1.7575 0.9575 1.7575 0.9575 27 P 0 ;1
L 1.7575 1.0075 1.7575 1.0075 27 P 0 ;1
L 1.7575 1.0575 1.7575 1.0575 27 P 0 ;1
L 1.7575 1.1075 1.7575 1.1075 27 P 0 ;1
L 1.7575 1.1575 1.7575 1.1575 27 P 0 ;1
L 1.7575 1.2075 1.7575 1.2075 27 P 0 ;1
L 1.7575 1.2575 1.7575 1.2575 27 P 0 ;1
L 1.7575 1.3075 1.7575 1.3075 27 P 0 ;1
L 1.7575 1.3575 1.7575 1.3575 27 P 0 ;1
L 1.7575 1.4075 1.7575 1.4075 27 P 0 ;1
L 1.7575 1.4575 1.7575 1.4575 27 P 0 ;1
L 1.7575 1.5075 1.7575 1.5075 27 P 0 ;1
L 1.7575 1.5575 1.7575 1.5575 27 P 0 ;1
L 1.7575 1.6075 1.7575 1.6075 27 P 0 ;1
L 1.7575 1.6575 1.7575 1.6575 27 P 0 ;1
L 1.7575 1.7075 1.7575 1.7075 27 P 0 ;1
L 1.7575 1.7575 1.7575 1.7575 27 P 0 ;1
L 1.7575 1.8075 1.7575 1.8075 27 P 0 ;1
L 1.7575 1.8575 1.7575 1.8575 27 P 0 ;1
L 1.7575 1.9075 1.7575 1.9075 27 P 0 ;1
L 1.7575 1.9575 1.7575 1.9575 27 P 0 ;1
L 1.7575 2.0075 1.7575 2.0075 27 P 0 ;1
L 1.7575 2.0575 1.7575 2.0575 27 P 0 ;1
L 1.7575 2.1075 1.7575 2.1075 27 P 0 ;1
L 1.7575 2.1575 1.7575 2.1575 27 P 0 ;1
L 1.7575 2.2075 1.7575 2.2075 27 P 0 ;1
L 1.7575 2.2575 1.7575 2.2575 27 P 0 ;1
L 1.7575 2.3075 1.7575 2.3075 27 P 0 ;1
L 1.7575 2.3575 1.7575 2.3575 27 P 0 ;1
L 1.7575 2.6075 1.7575 2.6075 27 P 0 ;1
L 1.7575 2.6575 1.7575 2.6575 27 P 0 ;1
L 1.7575 2.7075 1.7575 2.7075 27 P 0 ;1
L 1.7575 2.7575 1.7575 2.7575 27 P 0 ;1
L 1.7575 2.8075 1.7575 2.8075 27 P 0 ;1
L 1.7575 2.8575 1.7575 2.8575 27 P 0 ;1
L 1.7575 2.9075 1.7575 2.9075 27 P 0 ;1
L 1.7575 2.9575 1.7575 2.9575 27 P 0 ;1
L 1.7575 3.0075 1.7575 3.0075 27 P 0 ;1
L 1.7575 3.0575 1.7575 3.0575 27 P 0 ;1
L 1.7575 3.1075 1.7575 3.1075 27 P 0 ;1
L 1.7575 3.1575 1.7575 3.1575 27 P 0 ;1
L 1.7575 3.2075 1.7575 3.2075 27 P 0 ;1
L 1.7575 3.2575 1.7575 3.2575 27 P 0 ;1
L 1.7575 3.3075 1.7575 3.3075 27 P 0 ;1
L 1.7575 3.3575 1.7575 3.3575 27 P 0 ;1
L 1.7575 3.4075 1.7575 3.4075 27 P 0 ;1
L 1.7575 3.4575 1.7575 3.4575 27 P 0 ;1
L 1.7575 3.5075 1.7575 3.5075 27 P 0 ;1
L 1.7575 3.5575 1.7575 3.5575 27 P 0 ;1
L 1.7575 3.6075 1.7575 3.6075 27 P 0 ;1
L 1.7575 3.6575 1.7575 3.6575 27 P 0 ;1
L 1.7575 3.7075 1.7575 3.7075 27 P 0 ;1
L 1.7575 3.7575 1.7575 3.7575 27 P 0 ;1
L 1.7575 3.8075 1.7575 3.8075 27 P 0 ;1
L 1.7575 3.8575 1.7575 3.8575 27 P 0 ;1
L 1.7575 3.9075 1.7575 3.9075 27 P 0 ;1
L 1.7575 3.9575 1.7575 3.9575 27 P 0 ;1
L 1.7575 4.0075 1.7575 4.0075 27 P 0 ;1
L 1.7575 4.0575 1.7575 4.0575 27 P 0 ;1
L 1.7575 4.1075 1.7575 4.1075 27 P 0 ;1
L 1.7575 4.1575 1.7575 4.1575 27 P 0 ;1
L 1.7575 4.2075 1.7575 4.2075 27 P 0 ;1
L 1.7575 4.2575 1.7575 4.2575 27 P 0 ;1
L 1.7575 4.3075 1.7575 4.3075 27 P 0 ;1
L 1.7575 4.3575 1.7575 4.3575 27 P 0 ;1
L 1.7575 4.6075 1.7575 4.6075 27 P 0 ;1
L 1.7575 5.2075 1.7575 5.2075 27 P 0 ;1
L 1.7575 5.2575 1.7575 5.2575 27 P 0 ;1
L 1.7575 5.3075 1.7575 5.3075 27 P 0 ;1
L 1.7575 5.3575 1.7575 5.3575 27 P 0 ;1
L 1.7575 5.4075 1.7575 5.4075 27 P 0 ;1
L 1.7575 5.4575 1.7575 5.4575 27 P 0 ;1
L 1.7575 5.5075 1.7575 5.5075 27 P 0 ;1
L 1.7575 5.5575 1.7575 5.5575 27 P 0 ;1
L 1.7575 5.6075 1.7575 5.6075 27 P 0 ;1
L 1.7575 5.6575 1.7575 5.6575 27 P 0 ;1
L 1.7575 5.7075 1.7575 5.7075 27 P 0 ;1
L 1.7575 5.7575 1.7575 5.7575 27 P 0 ;1
L 1.7575 5.8075 1.7575 5.8075 27 P 0 ;1
L 1.7575 5.8575 1.7575 5.8575 27 P 0 ;1
L 1.8075 0.1575 1.8075 0.1575 27 P 0 ;1
L 1.8075 0.2075 1.8075 0.2075 27 P 0 ;1
L 1.8075 0.2575 1.8075 0.2575 27 P 0 ;1
L 1.8075 0.3075 1.8075 0.3075 27 P 0 ;1
L 1.8075 0.3575 1.8075 0.3575 27 P 0 ;1
L 1.8075 0.4075 1.8075 0.4075 27 P 0 ;1
L 1.8075 0.4575 1.8075 0.4575 27 P 0 ;1
L 1.8075 0.5075 1.8075 0.5075 27 P 0 ;1
L 1.8075 0.5575 1.8075 0.5575 27 P 0 ;1
L 1.8075 0.6075 1.8075 0.6075 27 P 0 ;1
L 1.8075 0.6575 1.8075 0.6575 27 P 0 ;1
L 1.8075 0.7075 1.8075 0.7075 27 P 0 ;1
L 1.8075 0.7575 1.8075 0.7575 27 P 0 ;1
L 1.8075 0.8075 1.8075 0.8075 27 P 0 ;1
L 1.8075 0.8575 1.8075 0.8575 27 P 0 ;1
L 1.8075 0.9075 1.8075 0.9075 27 P 0 ;1
L 1.8075 0.9575 1.8075 0.9575 27 P 0 ;1
L 1.8075 1.0075 1.8075 1.0075 27 P 0 ;1
L 1.8075 1.0575 1.8075 1.0575 27 P 0 ;1
L 1.8075 1.1075 1.8075 1.1075 27 P 0 ;1
L 1.8075 1.1575 1.8075 1.1575 27 P 0 ;1
L 1.8075 1.2075 1.8075 1.2075 27 P 0 ;1
L 1.8075 1.2575 1.8075 1.2575 27 P 0 ;1
L 1.8075 1.3075 1.8075 1.3075 27 P 0 ;1
L 1.8075 1.3575 1.8075 1.3575 27 P 0 ;1
L 1.8075 1.4075 1.8075 1.4075 27 P 0 ;1
L 1.8075 1.4575 1.8075 1.4575 27 P 0 ;1
L 1.8075 1.5075 1.8075 1.5075 27 P 0 ;1
L 1.8075 1.5575 1.8075 1.5575 27 P 0 ;1
L 1.8075 1.6075 1.8075 1.6075 27 P 0 ;1
L 1.8075 1.6575 1.8075 1.6575 27 P 0 ;1
L 1.8075 1.7075 1.8075 1.7075 27 P 0 ;1
L 1.8075 1.7575 1.8075 1.7575 27 P 0 ;1
L 1.8075 1.8075 1.8075 1.8075 27 P 0 ;1
L 1.8075 1.8575 1.8075 1.8575 27 P 0 ;1
L 1.8075 1.9075 1.8075 1.9075 27 P 0 ;1
L 1.8075 1.9575 1.8075 1.9575 27 P 0 ;1
L 1.8075 2.0075 1.8075 2.0075 27 P 0 ;1
L 1.8075 2.0575 1.8075 2.0575 27 P 0 ;1
L 1.8075 2.1075 1.8075 2.1075 27 P 0 ;1
L 1.8075 2.1575 1.8075 2.1575 27 P 0 ;1
L 1.8075 2.2075 1.8075 2.2075 27 P 0 ;1
L 1.8075 2.2575 1.8075 2.2575 27 P 0 ;1
L 1.8075 2.3075 1.8075 2.3075 27 P 0 ;1
L 1.8075 2.3575 1.8075 2.3575 27 P 0 ;1
L 1.8075 2.6075 1.8075 2.6075 27 P 0 ;1
L 1.8075 2.6575 1.8075 2.6575 27 P 0 ;1
L 1.8075 2.7075 1.8075 2.7075 27 P 0 ;1
L 1.8075 2.7575 1.8075 2.7575 27 P 0 ;1
L 1.8075 2.8075 1.8075 2.8075 27 P 0 ;1
L 1.8075 2.8575 1.8075 2.8575 27 P 0 ;1
L 1.8075 2.9075 1.8075 2.9075 27 P 0 ;1
L 1.8075 2.9575 1.8075 2.9575 27 P 0 ;1
L 1.8075 3.0075 1.8075 3.0075 27 P 0 ;1
L 1.8075 3.0575 1.8075 3.0575 27 P 0 ;1
L 1.8075 3.1075 1.8075 3.1075 27 P 0 ;1
L 1.8075 3.1575 1.8075 3.1575 27 P 0 ;1
L 1.8075 3.2075 1.8075 3.2075 27 P 0 ;1
L 1.8075 3.2575 1.8075 3.2575 27 P 0 ;1
L 1.8075 3.3075 1.8075 3.3075 27 P 0 ;1
L 1.8075 3.3575 1.8075 3.3575 27 P 0 ;1
L 1.8075 3.4075 1.8075 3.4075 27 P 0 ;1
L 1.8075 3.4575 1.8075 3.4575 27 P 0 ;1
L 1.8075 3.5075 1.8075 3.5075 27 P 0 ;1
L 1.8075 3.5575 1.8075 3.5575 27 P 0 ;1
L 1.8075 3.6075 1.8075 3.6075 27 P 0 ;1
L 1.8075 3.6575 1.8075 3.6575 27 P 0 ;1
L 1.8075 3.7075 1.8075 3.7075 27 P 0 ;1
L 1.8075 3.7575 1.8075 3.7575 27 P 0 ;1
L 1.8075 3.8075 1.8075 3.8075 27 P 0 ;1
L 1.8075 3.8575 1.8075 3.8575 27 P 0 ;1
L 1.8075 3.9075 1.8075 3.9075 27 P 0 ;1
L 1.8075 3.9575 1.8075 3.9575 27 P 0 ;1
L 1.8075 4.0075 1.8075 4.0075 27 P 0 ;1
L 1.8075 4.0575 1.8075 4.0575 27 P 0 ;1
L 1.8075 4.1075 1.8075 4.1075 27 P 0 ;1
L 1.8075 4.1575 1.8075 4.1575 27 P 0 ;1
L 1.8075 4.2075 1.8075 4.2075 27 P 0 ;1
L 1.8075 4.2575 1.8075 4.2575 27 P 0 ;1
L 1.8075 4.3075 1.8075 4.3075 27 P 0 ;1
L 1.8075 4.3575 1.8075 4.3575 27 P 0 ;1
L 1.8075 5.2575 1.8075 5.2575 27 P 0 ;1
L 1.8075 5.3075 1.8075 5.3075 27 P 0 ;1
L 1.8075 5.3575 1.8075 5.3575 27 P 0 ;1
L 1.8075 5.4075 1.8075 5.4075 27 P 0 ;1
L 1.8075 5.4575 1.8075 5.4575 27 P 0 ;1
L 1.8075 5.5075 1.8075 5.5075 27 P 0 ;1
L 1.8075 5.5575 1.8075 5.5575 27 P 0 ;1
L 1.8075 5.6075 1.8075 5.6075 27 P 0 ;1
L 1.8075 5.6575 1.8075 5.6575 27 P 0 ;1
L 1.8075 5.7075 1.8075 5.7075 27 P 0 ;1
L 1.8075 5.7575 1.8075 5.7575 27 P 0 ;1
L 1.8075 5.8075 1.8075 5.8075 27 P 0 ;1
L 1.8075 5.8575 1.8075 5.8575 27 P 0 ;1
L 1.8575 0.1575 1.8575 0.1575 27 P 0 ;1
L 1.8575 0.2075 1.8575 0.2075 27 P 0 ;1
L 1.8575 0.2575 1.8575 0.2575 27 P 0 ;1
L 1.8575 0.3075 1.8575 0.3075 27 P 0 ;1
L 1.8575 0.3575 1.8575 0.3575 27 P 0 ;1
L 1.8575 0.4075 1.8575 0.4075 27 P 0 ;1
L 1.8575 0.4575 1.8575 0.4575 27 P 0 ;1
L 1.8575 0.5075 1.8575 0.5075 27 P 0 ;1
L 1.8575 0.5575 1.8575 0.5575 27 P 0 ;1
L 1.8575 0.6075 1.8575 0.6075 27 P 0 ;1
L 1.8575 0.6575 1.8575 0.6575 27 P 0 ;1
L 1.8575 0.7075 1.8575 0.7075 27 P 0 ;1
L 1.8575 0.7575 1.8575 0.7575 27 P 0 ;1
L 1.8575 0.8075 1.8575 0.8075 27 P 0 ;1
L 1.8575 0.8575 1.8575 0.8575 27 P 0 ;1
L 1.8575 0.9075 1.8575 0.9075 27 P 0 ;1
L 1.8575 0.9575 1.8575 0.9575 27 P 0 ;1
L 1.8575 1.0075 1.8575 1.0075 27 P 0 ;1
L 1.8575 1.0575 1.8575 1.0575 27 P 0 ;1
L 1.8575 1.1075 1.8575 1.1075 27 P 0 ;1
L 1.8575 1.1575 1.8575 1.1575 27 P 0 ;1
L 1.8575 1.2075 1.8575 1.2075 27 P 0 ;1
L 1.8575 1.2575 1.8575 1.2575 27 P 0 ;1
L 1.8575 1.3075 1.8575 1.3075 27 P 0 ;1
L 1.8575 1.3575 1.8575 1.3575 27 P 0 ;1
L 1.8575 1.4075 1.8575 1.4075 27 P 0 ;1
L 1.8575 1.4575 1.8575 1.4575 27 P 0 ;1
L 1.8575 1.5075 1.8575 1.5075 27 P 0 ;1
L 1.8575 1.5575 1.8575 1.5575 27 P 0 ;1
L 1.8575 1.6075 1.8575 1.6075 27 P 0 ;1
L 1.8575 1.6575 1.8575 1.6575 27 P 0 ;1
L 1.8575 1.7075 1.8575 1.7075 27 P 0 ;1
L 1.8575 1.7575 1.8575 1.7575 27 P 0 ;1
L 1.8575 1.8075 1.8575 1.8075 27 P 0 ;1
L 1.8575 1.8575 1.8575 1.8575 27 P 0 ;1
L 1.8575 1.9075 1.8575 1.9075 27 P 0 ;1
L 1.8575 1.9575 1.8575 1.9575 27 P 0 ;1
L 1.8575 2.0075 1.8575 2.0075 27 P 0 ;1
L 1.8575 2.0575 1.8575 2.0575 27 P 0 ;1
L 1.8575 2.1075 1.8575 2.1075 27 P 0 ;1
L 1.8575 2.1575 1.8575 2.1575 27 P 0 ;1
L 1.8575 2.2075 1.8575 2.2075 27 P 0 ;1
L 1.8575 2.2575 1.8575 2.2575 27 P 0 ;1
L 1.8575 2.3075 1.8575 2.3075 27 P 0 ;1
L 1.8575 2.3575 1.8575 2.3575 27 P 0 ;1
L 1.8575 2.4075 1.8575 2.4075 27 P 0 ;1
L 1.8575 2.5575 1.8575 2.5575 27 P 0 ;1
L 1.8575 2.6075 1.8575 2.6075 27 P 0 ;1
L 1.8575 2.6575 1.8575 2.6575 27 P 0 ;1
L 1.8575 2.7075 1.8575 2.7075 27 P 0 ;1
L 1.8575 2.7575 1.8575 2.7575 27 P 0 ;1
L 1.8575 2.8075 1.8575 2.8075 27 P 0 ;1
L 1.8575 2.8575 1.8575 2.8575 27 P 0 ;1
L 1.8575 2.9075 1.8575 2.9075 27 P 0 ;1
L 1.8575 2.9575 1.8575 2.9575 27 P 0 ;1
L 1.8575 3.0075 1.8575 3.0075 27 P 0 ;1
L 1.8575 3.0575 1.8575 3.0575 27 P 0 ;1
L 1.8575 3.1075 1.8575 3.1075 27 P 0 ;1
L 1.8575 3.1575 1.8575 3.1575 27 P 0 ;1
L 1.8575 3.2075 1.8575 3.2075 27 P 0 ;1
L 1.8575 3.2575 1.8575 3.2575 27 P 0 ;1
L 1.8575 3.3075 1.8575 3.3075 27 P 0 ;1
L 1.8575 3.3575 1.8575 3.3575 27 P 0 ;1
L 1.8575 3.4075 1.8575 3.4075 27 P 0 ;1
L 1.8575 3.4575 1.8575 3.4575 27 P 0 ;1
L 1.8575 3.5075 1.8575 3.5075 27 P 0 ;1
L 1.8575 3.5575 1.8575 3.5575 27 P 0 ;1
L 1.8575 3.6075 1.8575 3.6075 27 P 0 ;1
L 1.8575 3.6575 1.8575 3.6575 27 P 0 ;1
L 1.8575 3.7075 1.8575 3.7075 27 P 0 ;1
L 1.8575 3.7575 1.8575 3.7575 27 P 0 ;1
L 1.8575 3.8075 1.8575 3.8075 27 P 0 ;1
L 1.8575 3.8575 1.8575 3.8575 27 P 0 ;1
L 1.8575 3.9075 1.8575 3.9075 27 P 0 ;1
L 1.8575 3.9575 1.8575 3.9575 27 P 0 ;1
L 1.8575 4.0075 1.8575 4.0075 27 P 0 ;1
L 1.8575 4.0575 1.8575 4.0575 27 P 0 ;1
L 1.8575 4.1075 1.8575 4.1075 27 P 0 ;1
L 1.8575 4.1575 1.8575 4.1575 27 P 0 ;1
L 1.8575 4.2075 1.8575 4.2075 27 P 0 ;1
L 1.8575 4.2575 1.8575 4.2575 27 P 0 ;1
L 1.8575 4.3075 1.8575 4.3075 27 P 0 ;1
L 1.8575 4.3575 1.8575 4.3575 27 P 0 ;1
L 1.8575 5.3075 1.8575 5.3075 27 P 0 ;1
L 1.8575 5.4575 1.8575 5.4575 27 P 0 ;1
L 1.8575 5.5075 1.8575 5.5075 27 P 0 ;1
L 1.8575 5.5575 1.8575 5.5575 27 P 0 ;1
L 1.8575 5.6075 1.8575 5.6075 27 P 0 ;1
L 1.8575 5.6575 1.8575 5.6575 27 P 0 ;1
L 1.8575 5.7075 1.8575 5.7075 27 P 0 ;1
L 1.8575 5.7575 1.8575 5.7575 27 P 0 ;1
L 1.8575 5.8075 1.8575 5.8075 27 P 0 ;1
L 1.8575 5.8575 1.8575 5.8575 27 P 0 ;1
L 1.9075 0.1575 1.9075 0.1575 27 P 0 ;1
L 1.9075 0.2075 1.9075 0.2075 27 P 0 ;1
L 1.9075 0.2575 1.9075 0.2575 27 P 0 ;1
L 1.9075 0.3075 1.9075 0.3075 27 P 0 ;1
L 1.9075 0.3575 1.9075 0.3575 27 P 0 ;1
L 1.9075 0.4075 1.9075 0.4075 27 P 0 ;1
L 1.9075 0.4575 1.9075 0.4575 27 P 0 ;1
L 1.9075 0.5075 1.9075 0.5075 27 P 0 ;1
L 1.9075 0.5575 1.9075 0.5575 27 P 0 ;1
L 1.9075 0.6075 1.9075 0.6075 27 P 0 ;1
L 1.9075 0.6575 1.9075 0.6575 27 P 0 ;1
L 1.9075 0.7075 1.9075 0.7075 27 P 0 ;1
L 1.9075 0.7575 1.9075 0.7575 27 P 0 ;1
L 1.9075 0.8075 1.9075 0.8075 27 P 0 ;1
L 1.9075 0.8575 1.9075 0.8575 27 P 0 ;1
L 1.9075 0.9075 1.9075 0.9075 27 P 0 ;1
L 1.9075 0.9575 1.9075 0.9575 27 P 0 ;1
L 1.9075 1.0075 1.9075 1.0075 27 P 0 ;1
L 1.9075 1.0575 1.9075 1.0575 27 P 0 ;1
L 1.9075 1.1075 1.9075 1.1075 27 P 0 ;1
L 1.9075 1.1575 1.9075 1.1575 27 P 0 ;1
L 1.9075 1.2075 1.9075 1.2075 27 P 0 ;1
L 1.9075 1.2575 1.9075 1.2575 27 P 0 ;1
L 1.9075 1.3075 1.9075 1.3075 27 P 0 ;1
L 1.9075 1.3575 1.9075 1.3575 27 P 0 ;1
L 1.9075 1.4075 1.9075 1.4075 27 P 0 ;1
L 1.9075 1.4575 1.9075 1.4575 27 P 0 ;1
L 1.9075 1.5075 1.9075 1.5075 27 P 0 ;1
L 1.9075 1.5575 1.9075 1.5575 27 P 0 ;1
L 1.9075 1.6075 1.9075 1.6075 27 P 0 ;1
L 1.9075 1.6575 1.9075 1.6575 27 P 0 ;1
L 1.9075 1.7075 1.9075 1.7075 27 P 0 ;1
L 1.9075 1.7575 1.9075 1.7575 27 P 0 ;1
L 1.9075 1.8075 1.9075 1.8075 27 P 0 ;1
L 1.9075 1.8575 1.9075 1.8575 27 P 0 ;1
L 1.9075 1.9075 1.9075 1.9075 27 P 0 ;1
L 1.9075 1.9575 1.9075 1.9575 27 P 0 ;1
L 1.9075 2.0075 1.9075 2.0075 27 P 0 ;1
L 1.9075 2.0575 1.9075 2.0575 27 P 0 ;1
L 1.9075 2.1075 1.9075 2.1075 27 P 0 ;1
L 1.9075 2.1575 1.9075 2.1575 27 P 0 ;1
L 1.9075 2.2075 1.9075 2.2075 27 P 0 ;1
L 1.9075 2.2575 1.9075 2.2575 27 P 0 ;1
L 1.9075 2.3075 1.9075 2.3075 27 P 0 ;1
L 1.9075 2.3575 1.9075 2.3575 27 P 0 ;1
L 1.9075 2.4075 1.9075 2.4075 27 P 0 ;1
L 1.9075 2.4575 1.9075 2.4575 27 P 0 ;1
L 1.9075 2.5075 1.9075 2.5075 27 P 0 ;1
L 1.9075 2.5575 1.9075 2.5575 27 P 0 ;1
L 1.9075 2.6075 1.9075 2.6075 27 P 0 ;1
L 1.9075 2.6575 1.9075 2.6575 27 P 0 ;1
L 1.9075 2.9075 1.9075 2.9075 27 P 0 ;1
L 1.9075 2.9575 1.9075 2.9575 27 P 0 ;1
L 1.9075 3.0075 1.9075 3.0075 27 P 0 ;1
L 1.9075 3.0575 1.9075 3.0575 27 P 0 ;1
L 1.9075 3.1075 1.9075 3.1075 27 P 0 ;1
L 1.9075 3.1575 1.9075 3.1575 27 P 0 ;1
L 1.9075 3.2075 1.9075 3.2075 27 P 0 ;1
L 1.9075 3.2575 1.9075 3.2575 27 P 0 ;1
L 1.9075 3.3075 1.9075 3.3075 27 P 0 ;1
L 1.9075 3.3575 1.9075 3.3575 27 P 0 ;1
L 1.9075 3.6075 1.9075 3.6075 27 P 0 ;1
L 1.9075 3.6575 1.9075 3.6575 27 P 0 ;1
L 1.9075 3.7075 1.9075 3.7075 27 P 0 ;1
L 1.9075 3.7575 1.9075 3.7575 27 P 0 ;1
L 1.9075 3.8075 1.9075 3.8075 27 P 0 ;1
L 1.9075 3.8575 1.9075 3.8575 27 P 0 ;1
L 1.9075 3.9075 1.9075 3.9075 27 P 0 ;1
L 1.9075 3.9575 1.9075 3.9575 27 P 0 ;1
L 1.9075 4.0075 1.9075 4.0075 27 P 0 ;1
L 1.9075 4.0575 1.9075 4.0575 27 P 0 ;1
L 1.9075 4.1075 1.9075 4.1075 27 P 0 ;1
L 1.9075 4.1575 1.9075 4.1575 27 P 0 ;1
L 1.9075 4.2075 1.9075 4.2075 27 P 0 ;1
L 1.9075 4.2575 1.9075 4.2575 27 P 0 ;1
L 1.9075 4.3075 1.9075 4.3075 27 P 0 ;1
L 1.9075 4.3575 1.9075 4.3575 27 P 0 ;1
L 1.9075 5.5075 1.9075 5.5075 27 P 0 ;1
L 1.9075 5.5575 1.9075 5.5575 27 P 0 ;1
L 1.9075 5.6075 1.9075 5.6075 27 P 0 ;1
L 1.9075 5.6575 1.9075 5.6575 27 P 0 ;1
L 1.9075 5.7075 1.9075 5.7075 27 P 0 ;1
L 1.9075 5.7575 1.9075 5.7575 27 P 0 ;1
L 1.9075 5.8075 1.9075 5.8075 27 P 0 ;1
L 1.9075 5.8575 1.9075 5.8575 27 P 0 ;1
L 1.9575 0.1575 1.9575 0.1575 27 P 0 ;1
L 1.9575 0.2075 1.9575 0.2075 27 P 0 ;1
L 1.9575 0.2575 1.9575 0.2575 27 P 0 ;1
L 1.9575 0.3075 1.9575 0.3075 27 P 0 ;1
L 1.9575 0.3575 1.9575 0.3575 27 P 0 ;1
L 1.9575 0.4075 1.9575 0.4075 27 P 0 ;1
L 1.9575 0.4575 1.9575 0.4575 27 P 0 ;1
L 1.9575 0.5075 1.9575 0.5075 27 P 0 ;1
L 1.9575 0.5575 1.9575 0.5575 27 P 0 ;1
L 1.9575 0.6075 1.9575 0.6075 27 P 0 ;1
L 1.9575 0.6575 1.9575 0.6575 27 P 0 ;1
L 1.9575 0.7075 1.9575 0.7075 27 P 0 ;1
L 1.9575 0.7575 1.9575 0.7575 27 P 0 ;1
L 1.9575 0.8075 1.9575 0.8075 27 P 0 ;1
L 1.9575 0.8575 1.9575 0.8575 27 P 0 ;1
L 1.9575 0.9075 1.9575 0.9075 27 P 0 ;1
L 1.9575 0.9575 1.9575 0.9575 27 P 0 ;1
L 1.9575 1.0075 1.9575 1.0075 27 P 0 ;1
L 1.9575 1.0575 1.9575 1.0575 27 P 0 ;1
L 1.9575 1.1075 1.9575 1.1075 27 P 0 ;1
L 1.9575 1.1575 1.9575 1.1575 27 P 0 ;1
L 1.9575 1.2075 1.9575 1.2075 27 P 0 ;1
L 1.9575 1.2575 1.9575 1.2575 27 P 0 ;1
L 1.9575 1.3075 1.9575 1.3075 27 P 0 ;1
L 1.9575 1.3575 1.9575 1.3575 27 P 0 ;1
L 1.9575 1.4075 1.9575 1.4075 27 P 0 ;1
L 1.9575 1.4575 1.9575 1.4575 27 P 0 ;1
L 1.9575 1.5075 1.9575 1.5075 27 P 0 ;1
L 1.9575 1.5575 1.9575 1.5575 27 P 0 ;1
L 1.9575 1.6075 1.9575 1.6075 27 P 0 ;1
L 1.9575 1.6575 1.9575 1.6575 27 P 0 ;1
L 1.9575 1.7075 1.9575 1.7075 27 P 0 ;1
L 1.9575 1.7575 1.9575 1.7575 27 P 0 ;1
L 1.9575 1.8075 1.9575 1.8075 27 P 0 ;1
L 1.9575 3.9575 1.9575 3.9575 27 P 0 ;1
L 1.9575 4.0075 1.9575 4.0075 27 P 0 ;1
L 1.9575 4.0575 1.9575 4.0575 27 P 0 ;1
L 1.9575 4.1075 1.9575 4.1075 27 P 0 ;1
L 1.9575 4.1575 1.9575 4.1575 27 P 0 ;1
L 1.9575 4.2075 1.9575 4.2075 27 P 0 ;1
L 1.9575 4.2575 1.9575 4.2575 27 P 0 ;1
L 1.9575 4.3075 1.9575 4.3075 27 P 0 ;1
L 1.9575 4.3575 1.9575 4.3575 27 P 0 ;1
L 1.9575 5.5075 1.9575 5.5075 27 P 0 ;1
L 1.9575 5.5575 1.9575 5.5575 27 P 0 ;1
L 1.9575 5.6075 1.9575 5.6075 27 P 0 ;1
L 1.9575 5.6575 1.9575 5.6575 27 P 0 ;1
L 1.9575 5.7075 1.9575 5.7075 27 P 0 ;1
L 1.9575 5.7575 1.9575 5.7575 27 P 0 ;1
L 1.9575 5.8075 1.9575 5.8075 27 P 0 ;1
L 1.9575 5.8575 1.9575 5.8575 27 P 0 ;1
L 2.0075 0.1575 2.0075 0.1575 27 P 0 ;1
L 2.0075 0.2075 2.0075 0.2075 27 P 0 ;1
L 2.0075 0.2575 2.0075 0.2575 27 P 0 ;1
L 2.0075 0.3075 2.0075 0.3075 27 P 0 ;1
L 2.0075 0.3575 2.0075 0.3575 27 P 0 ;1
L 2.0075 0.4075 2.0075 0.4075 27 P 0 ;1
L 2.0075 0.4575 2.0075 0.4575 27 P 0 ;1
L 2.0075 0.5075 2.0075 0.5075 27 P 0 ;1
L 2.0075 0.5575 2.0075 0.5575 27 P 0 ;1
L 2.0075 0.6075 2.0075 0.6075 27 P 0 ;1
L 2.0075 0.6575 2.0075 0.6575 27 P 0 ;1
L 2.0075 0.7075 2.0075 0.7075 27 P 0 ;1
L 2.0075 0.7575 2.0075 0.7575 27 P 0 ;1
L 2.0075 0.8075 2.0075 0.8075 27 P 0 ;1
L 2.0075 0.8575 2.0075 0.8575 27 P 0 ;1
L 2.0075 0.9075 2.0075 0.9075 27 P 0 ;1
L 2.0075 0.9575 2.0075 0.9575 27 P 0 ;1
L 2.0075 1.0075 2.0075 1.0075 27 P 0 ;1
L 2.0075 1.0575 2.0075 1.0575 27 P 0 ;1
L 2.0075 1.1075 2.0075 1.1075 27 P 0 ;1
L 2.0075 1.1575 2.0075 1.1575 27 P 0 ;1
L 2.0075 1.2075 2.0075 1.2075 27 P 0 ;1
L 2.0075 1.2575 2.0075 1.2575 27 P 0 ;1
L 2.0075 1.3075 2.0075 1.3075 27 P 0 ;1
L 2.0075 1.3575 2.0075 1.3575 27 P 0 ;1
L 2.0075 1.4075 2.0075 1.4075 27 P 0 ;1
L 2.0075 1.4575 2.0075 1.4575 27 P 0 ;1
L 2.0075 1.5575 2.0075 1.5575 27 P 0 ;1
L 2.0075 1.6075 2.0075 1.6075 27 P 0 ;1
L 2.0075 1.6575 2.0075 1.6575 27 P 0 ;1
L 2.0075 1.7075 2.0075 1.7075 27 P 0 ;1
L 2.0075 1.7575 2.0075 1.7575 27 P 0 ;1
L 2.0075 3.9575 2.0075 3.9575 27 P 0 ;1
L 2.0075 4.0075 2.0075 4.0075 27 P 0 ;1
L 2.0075 4.0575 2.0075 4.0575 27 P 0 ;1
L 2.0075 4.1075 2.0075 4.1075 27 P 0 ;1
L 2.0075 4.1575 2.0075 4.1575 27 P 0 ;1
L 2.0075 4.3075 2.0075 4.3075 27 P 0 ;1
L 2.0075 4.3575 2.0075 4.3575 27 P 0 ;1
L 2.0075 4.4075 2.0075 4.4075 27 P 0 ;1
L 2.0075 5.4575 2.0075 5.4575 27 P 0 ;1
L 2.0075 5.5075 2.0075 5.5075 27 P 0 ;1
L 2.0075 5.5575 2.0075 5.5575 27 P 0 ;1
L 2.0075 5.6075 2.0075 5.6075 27 P 0 ;1
L 2.0075 5.6575 2.0075 5.6575 27 P 0 ;1
L 2.0075 5.7075 2.0075 5.7075 27 P 0 ;1
L 2.0075 5.7575 2.0075 5.7575 27 P 0 ;1
L 2.0075 5.8075 2.0075 5.8075 27 P 0 ;1
L 2.0075 5.8575 2.0075 5.8575 27 P 0 ;1
L 2.0575 0.1575 2.0575 0.1575 27 P 0 ;1
L 2.0575 0.2075 2.0575 0.2075 27 P 0 ;1
L 2.0575 0.2575 2.0575 0.2575 27 P 0 ;1
L 2.0575 0.3075 2.0575 0.3075 27 P 0 ;1
L 2.0575 0.3575 2.0575 0.3575 27 P 0 ;1
L 2.0575 0.4075 2.0575 0.4075 27 P 0 ;1
L 2.0575 0.4575 2.0575 0.4575 27 P 0 ;1
L 2.0575 0.5075 2.0575 0.5075 27 P 0 ;1
L 2.0575 0.5575 2.0575 0.5575 27 P 0 ;1
L 2.0575 0.6075 2.0575 0.6075 27 P 0 ;1
L 2.0575 0.6575 2.0575 0.6575 27 P 0 ;1
L 2.0575 0.7075 2.0575 0.7075 27 P 0 ;1
L 2.0575 0.7575 2.0575 0.7575 27 P 0 ;1
L 2.0575 0.8075 2.0575 0.8075 27 P 0 ;1
L 2.0575 0.8575 2.0575 0.8575 27 P 0 ;1
L 2.0575 0.9075 2.0575 0.9075 27 P 0 ;1
L 2.0575 0.9575 2.0575 0.9575 27 P 0 ;1
L 2.0575 1.0075 2.0575 1.0075 27 P 0 ;1
L 2.0575 1.0575 2.0575 1.0575 27 P 0 ;1
L 2.0575 1.1075 2.0575 1.1075 27 P 0 ;1
L 2.0575 1.1575 2.0575 1.1575 27 P 0 ;1
L 2.0575 1.2075 2.0575 1.2075 27 P 0 ;1
L 2.0575 1.2575 2.0575 1.2575 27 P 0 ;1
L 2.0575 1.3075 2.0575 1.3075 27 P 0 ;1
L 2.0575 1.7075 2.0575 1.7075 27 P 0 ;1
L 2.0575 1.7575 2.0575 1.7575 27 P 0 ;1
L 2.0575 4.0075 2.0575 4.0075 27 P 0 ;1
L 2.0575 4.0575 2.0575 4.0575 27 P 0 ;1
L 2.0575 4.4075 2.0575 4.4075 27 P 0 ;1
L 2.0575 4.4575 2.0575 4.4575 27 P 0 ;1
L 2.0575 4.5075 2.0575 4.5075 27 P 0 ;1
L 2.0575 5.4575 2.0575 5.4575 27 P 0 ;1
L 2.0575 5.5075 2.0575 5.5075 27 P 0 ;1
L 2.0575 5.5575 2.0575 5.5575 27 P 0 ;1
L 2.0575 5.6075 2.0575 5.6075 27 P 0 ;1
L 2.0575 5.6575 2.0575 5.6575 27 P 0 ;1
L 2.0575 5.7075 2.0575 5.7075 27 P 0 ;1
L 2.0575 5.7575 2.0575 5.7575 27 P 0 ;1
L 2.0575 5.8075 2.0575 5.8075 27 P 0 ;1
L 2.0575 5.8575 2.0575 5.8575 27 P 0 ;1
L 2.1075 0.1575 2.1075 0.1575 27 P 0 ;1
L 2.1075 0.2075 2.1075 0.2075 27 P 0 ;1
L 2.1075 0.2575 2.1075 0.2575 27 P 0 ;1
L 2.1075 0.3075 2.1075 0.3075 27 P 0 ;1
L 2.1075 0.3575 2.1075 0.3575 27 P 0 ;1
L 2.1075 0.4075 2.1075 0.4075 27 P 0 ;1
L 2.1075 0.4575 2.1075 0.4575 27 P 0 ;1
L 2.1075 0.5075 2.1075 0.5075 27 P 0 ;1
L 2.1075 0.5575 2.1075 0.5575 27 P 0 ;1
L 2.1075 0.6075 2.1075 0.6075 27 P 0 ;1
L 2.1075 0.6575 2.1075 0.6575 27 P 0 ;1
L 2.1075 0.7075 2.1075 0.7075 27 P 0 ;1
L 2.1075 0.7575 2.1075 0.7575 27 P 0 ;1
L 2.1075 0.8075 2.1075 0.8075 27 P 0 ;1
L 2.1075 0.8575 2.1075 0.8575 27 P 0 ;1
L 2.1075 0.9075 2.1075 0.9075 27 P 0 ;1
L 2.1075 0.9575 2.1075 0.9575 27 P 0 ;1
L 2.1075 1.0075 2.1075 1.0075 27 P 0 ;1
L 2.1075 1.0575 2.1075 1.0575 27 P 0 ;1
L 2.1075 1.1075 2.1075 1.1075 27 P 0 ;1
L 2.1075 1.1575 2.1075 1.1575 27 P 0 ;1
L 2.1075 1.2075 2.1075 1.2075 27 P 0 ;1
L 2.1075 1.2575 2.1075 1.2575 27 P 0 ;1
L 2.1075 1.3075 2.1075 1.3075 27 P 0 ;1
L 2.1075 1.7075 2.1075 1.7075 27 P 0 ;1
L 2.1075 1.7575 2.1075 1.7575 27 P 0 ;1
L 2.1075 3.9575 2.1075 3.9575 27 P 0 ;1
L 2.1075 4.0075 2.1075 4.0075 27 P 0 ;1
L 2.1075 4.4575 2.1075 4.4575 27 P 0 ;1
L 2.1075 4.5075 2.1075 4.5075 27 P 0 ;1
L 2.1075 5.5075 2.1075 5.5075 27 P 0 ;1
L 2.1075 5.5575 2.1075 5.5575 27 P 0 ;1
L 2.1075 5.6075 2.1075 5.6075 27 P 0 ;1
L 2.1075 5.6575 2.1075 5.6575 27 P 0 ;1
L 2.1075 5.7075 2.1075 5.7075 27 P 0 ;1
L 2.1075 5.7575 2.1075 5.7575 27 P 0 ;1
L 2.1075 5.8075 2.1075 5.8075 27 P 0 ;1
L 2.1075 5.8575 2.1075 5.8575 27 P 0 ;1
L 2.1575 0.1575 2.1575 0.1575 27 P 0 ;1
L 2.1575 0.2075 2.1575 0.2075 27 P 0 ;1
L 2.1575 0.2575 2.1575 0.2575 27 P 0 ;1
L 2.1575 0.3075 2.1575 0.3075 27 P 0 ;1
L 2.1575 0.3575 2.1575 0.3575 27 P 0 ;1
L 2.1575 0.4075 2.1575 0.4075 27 P 0 ;1
L 2.1575 0.4575 2.1575 0.4575 27 P 0 ;1
L 2.1575 0.5075 2.1575 0.5075 27 P 0 ;1
L 2.1575 0.5575 2.1575 0.5575 27 P 0 ;1
L 2.1575 0.6075 2.1575 0.6075 27 P 0 ;1
L 2.1575 0.6575 2.1575 0.6575 27 P 0 ;1
L 2.1575 0.7075 2.1575 0.7075 27 P 0 ;1
L 2.1575 0.7575 2.1575 0.7575 27 P 0 ;1
L 2.1575 0.8075 2.1575 0.8075 27 P 0 ;1
L 2.1575 0.8575 2.1575 0.8575 27 P 0 ;1
L 2.1575 0.9075 2.1575 0.9075 27 P 0 ;1
L 2.1575 0.9575 2.1575 0.9575 27 P 0 ;1
L 2.1575 1.0075 2.1575 1.0075 27 P 0 ;1
L 2.1575 1.0575 2.1575 1.0575 27 P 0 ;1
L 2.1575 1.1075 2.1575 1.1075 27 P 0 ;1
L 2.1575 1.1575 2.1575 1.1575 27 P 0 ;1
L 2.1575 1.2075 2.1575 1.2075 27 P 0 ;1
L 2.1575 1.2575 2.1575 1.2575 27 P 0 ;1
L 2.1575 1.7575 2.1575 1.7575 27 P 0 ;1
L 2.1575 4.4575 2.1575 4.4575 27 P 0 ;1
L 2.1575 4.5075 2.1575 4.5075 27 P 0 ;1
L 2.1575 5.2575 2.1575 5.2575 27 P 0 ;1
L 2.1575 5.5075 2.1575 5.5075 27 P 0 ;1
L 2.1575 5.5575 2.1575 5.5575 27 P 0 ;1
L 2.1575 5.6075 2.1575 5.6075 27 P 0 ;1
L 2.1575 5.6575 2.1575 5.6575 27 P 0 ;1
L 2.1575 5.7075 2.1575 5.7075 27 P 0 ;1
L 2.1575 5.7575 2.1575 5.7575 27 P 0 ;1
L 2.1575 5.8075 2.1575 5.8075 27 P 0 ;1
L 2.1575 5.8575 2.1575 5.8575 27 P 0 ;1
L 2.2075 0.1575 2.2075 0.1575 27 P 0 ;1
L 2.2075 0.2075 2.2075 0.2075 27 P 0 ;1
L 2.2075 0.2575 2.2075 0.2575 27 P 0 ;1
L 2.2075 0.3075 2.2075 0.3075 27 P 0 ;1
L 2.2075 0.3575 2.2075 0.3575 27 P 0 ;1
L 2.2075 0.4075 2.2075 0.4075 27 P 0 ;1
L 2.2075 0.4575 2.2075 0.4575 27 P 0 ;1
L 2.2075 0.5075 2.2075 0.5075 27 P 0 ;1
L 2.2075 0.5575 2.2075 0.5575 27 P 0 ;1
L 2.2075 0.6075 2.2075 0.6075 27 P 0 ;1
L 2.2075 0.6575 2.2075 0.6575 27 P 0 ;1
L 2.2075 0.7075 2.2075 0.7075 27 P 0 ;1
L 2.2075 0.7575 2.2075 0.7575 27 P 0 ;1
L 2.2075 0.8075 2.2075 0.8075 27 P 0 ;1
L 2.2075 0.8575 2.2075 0.8575 27 P 0 ;1
L 2.2075 0.9075 2.2075 0.9075 27 P 0 ;1
L 2.2075 0.9575 2.2075 0.9575 27 P 0 ;1
L 2.2075 1.0075 2.2075 1.0075 27 P 0 ;1
L 2.2075 1.0575 2.2075 1.0575 27 P 0 ;1
L 2.2075 1.1075 2.2075 1.1075 27 P 0 ;1
L 2.2075 1.1575 2.2075 1.1575 27 P 0 ;1
L 2.2075 1.2075 2.2075 1.2075 27 P 0 ;1
L 2.2075 1.2575 2.2075 1.2575 27 P 0 ;1
L 2.2075 1.7575 2.2075 1.7575 27 P 0 ;1
L 2.2075 3.9575 2.2075 3.9575 27 P 0 ;1
L 2.2075 4.5075 2.2075 4.5075 27 P 0 ;1
L 2.2075 5.2075 2.2075 5.2075 27 P 0 ;1
L 2.2075 5.2575 2.2075 5.2575 27 P 0 ;1
L 2.2075 5.4575 2.2075 5.4575 27 P 0 ;1
L 2.2075 5.5075 2.2075 5.5075 27 P 0 ;1
L 2.2075 5.5575 2.2075 5.5575 27 P 0 ;1
L 2.2075 5.6075 2.2075 5.6075 27 P 0 ;1
L 2.2075 5.6575 2.2075 5.6575 27 P 0 ;1
L 2.2075 5.7075 2.2075 5.7075 27 P 0 ;1
L 2.2075 5.7575 2.2075 5.7575 27 P 0 ;1
L 2.2075 5.8075 2.2075 5.8075 27 P 0 ;1
L 2.2075 5.8575 2.2075 5.8575 27 P 0 ;1
L 2.2575 0.1575 2.2575 0.1575 27 P 0 ;1
L 2.2575 0.2075 2.2575 0.2075 27 P 0 ;1
L 2.2575 0.2575 2.2575 0.2575 27 P 0 ;1
L 2.2575 0.3075 2.2575 0.3075 27 P 0 ;1
L 2.2575 0.3575 2.2575 0.3575 27 P 0 ;1
L 2.2575 0.4075 2.2575 0.4075 27 P 0 ;1
L 2.2575 0.4575 2.2575 0.4575 27 P 0 ;1
L 2.2575 0.5075 2.2575 0.5075 27 P 0 ;1
L 2.2575 0.5575 2.2575 0.5575 27 P 0 ;1
L 2.2575 0.6075 2.2575 0.6075 27 P 0 ;1
L 2.2575 0.6575 2.2575 0.6575 27 P 0 ;1
L 2.2575 0.7075 2.2575 0.7075 27 P 0 ;1
L 2.2575 0.7575 2.2575 0.7575 27 P 0 ;1
L 2.2575 0.8075 2.2575 0.8075 27 P 0 ;1
L 2.2575 0.8575 2.2575 0.8575 27 P 0 ;1
L 2.2575 0.9075 2.2575 0.9075 27 P 0 ;1
L 2.2575 0.9575 2.2575 0.9575 27 P 0 ;1
L 2.2575 1.0075 2.2575 1.0075 27 P 0 ;1
L 2.2575 1.0575 2.2575 1.0575 27 P 0 ;1
L 2.2575 1.1075 2.2575 1.1075 27 P 0 ;1
L 2.2575 1.1575 2.2575 1.1575 27 P 0 ;1
L 2.2575 1.2075 2.2575 1.2075 27 P 0 ;1
L 2.2575 1.2575 2.2575 1.2575 27 P 0 ;1
L 2.2575 1.7575 2.2575 1.7575 27 P 0 ;1
L 2.2575 4.5075 2.2575 4.5075 27 P 0 ;1
L 2.2575 5.2075 2.2575 5.2075 27 P 0 ;1
L 2.2575 5.2575 2.2575 5.2575 27 P 0 ;1
L 2.2575 5.3075 2.2575 5.3075 27 P 0 ;1
L 2.2575 5.3575 2.2575 5.3575 27 P 0 ;1
L 2.2575 5.4075 2.2575 5.4075 27 P 0 ;1
L 2.2575 5.4575 2.2575 5.4575 27 P 0 ;1
L 2.2575 5.5075 2.2575 5.5075 27 P 0 ;1
L 2.2575 5.5575 2.2575 5.5575 27 P 0 ;1
L 2.2575 5.6075 2.2575 5.6075 27 P 0 ;1
L 2.2575 5.6575 2.2575 5.6575 27 P 0 ;1
L 2.2575 5.7075 2.2575 5.7075 27 P 0 ;1
L 2.2575 5.7575 2.2575 5.7575 27 P 0 ;1
L 2.2575 5.8075 2.2575 5.8075 27 P 0 ;1
L 2.2575 5.8575 2.2575 5.8575 27 P 0 ;1
L 2.3075 0.1575 2.3075 0.1575 27 P 0 ;1
L 2.3075 0.2075 2.3075 0.2075 27 P 0 ;1
L 2.3075 0.2575 2.3075 0.2575 27 P 0 ;1
L 2.3075 0.3075 2.3075 0.3075 27 P 0 ;1
L 2.3075 0.3575 2.3075 0.3575 27 P 0 ;1
L 2.3075 0.4075 2.3075 0.4075 27 P 0 ;1
L 2.3075 0.4575 2.3075 0.4575 27 P 0 ;1
L 2.3075 0.5075 2.3075 0.5075 27 P 0 ;1
L 2.3075 0.5575 2.3075 0.5575 27 P 0 ;1
L 2.3075 0.6075 2.3075 0.6075 27 P 0 ;1
L 2.3075 0.6575 2.3075 0.6575 27 P 0 ;1
L 2.3075 0.7075 2.3075 0.7075 27 P 0 ;1
L 2.3075 0.7575 2.3075 0.7575 27 P 0 ;1
L 2.3075 0.8075 2.3075 0.8075 27 P 0 ;1
L 2.3075 0.8575 2.3075 0.8575 27 P 0 ;1
L 2.3075 0.9075 2.3075 0.9075 27 P 0 ;1
L 2.3075 0.9575 2.3075 0.9575 27 P 0 ;1
L 2.3075 1.0075 2.3075 1.0075 27 P 0 ;1
L 2.3075 1.0575 2.3075 1.0575 27 P 0 ;1
L 2.3075 1.1075 2.3075 1.1075 27 P 0 ;1
L 2.3075 1.1575 2.3075 1.1575 27 P 0 ;1
L 2.3075 1.2075 2.3075 1.2075 27 P 0 ;1
L 2.3075 1.2575 2.3075 1.2575 27 P 0 ;1
L 2.3075 1.7575 2.3075 1.7575 27 P 0 ;1
L 2.3075 4.5075 2.3075 4.5075 27 P 0 ;1
L 2.3075 5.2575 2.3075 5.2575 27 P 0 ;1
L 2.3075 5.3075 2.3075 5.3075 27 P 0 ;1
L 2.3075 5.3575 2.3075 5.3575 27 P 0 ;1
L 2.3075 5.4075 2.3075 5.4075 27 P 0 ;1
L 2.3075 5.4575 2.3075 5.4575 27 P 0 ;1
L 2.3075 5.5075 2.3075 5.5075 27 P 0 ;1
L 2.3075 5.5575 2.3075 5.5575 27 P 0 ;1
L 2.3075 5.6075 2.3075 5.6075 27 P 0 ;1
L 2.3075 5.6575 2.3075 5.6575 27 P 0 ;1
L 2.3075 5.7075 2.3075 5.7075 27 P 0 ;1
L 2.3075 5.7575 2.3075 5.7575 27 P 0 ;1
L 2.3075 5.8075 2.3075 5.8075 27 P 0 ;1
L 2.3075 5.8575 2.3075 5.8575 27 P 0 ;1
L 2.3575 0.1575 2.3575 0.1575 27 P 0 ;1
L 2.3575 0.2075 2.3575 0.2075 27 P 0 ;1
L 2.3575 0.2575 2.3575 0.2575 27 P 0 ;1
L 2.3575 0.3075 2.3575 0.3075 27 P 0 ;1
L 2.3575 0.3575 2.3575 0.3575 27 P 0 ;1
L 2.3575 0.4075 2.3575 0.4075 27 P 0 ;1
L 2.3575 0.4575 2.3575 0.4575 27 P 0 ;1
L 2.3575 0.5075 2.3575 0.5075 27 P 0 ;1
L 2.3575 0.5575 2.3575 0.5575 27 P 0 ;1
L 2.3575 0.6075 2.3575 0.6075 27 P 0 ;1
L 2.3575 0.6575 2.3575 0.6575 27 P 0 ;1
L 2.3575 0.7075 2.3575 0.7075 27 P 0 ;1
L 2.3575 0.7575 2.3575 0.7575 27 P 0 ;1
L 2.3575 0.8075 2.3575 0.8075 27 P 0 ;1
L 2.3575 0.8575 2.3575 0.8575 27 P 0 ;1
L 2.3575 0.9075 2.3575 0.9075 27 P 0 ;1
L 2.3575 0.9575 2.3575 0.9575 27 P 0 ;1
L 2.3575 1.0075 2.3575 1.0075 27 P 0 ;1
L 2.3575 1.0575 2.3575 1.0575 27 P 0 ;1
L 2.3575 1.1075 2.3575 1.1075 27 P 0 ;1
L 2.3575 1.1575 2.3575 1.1575 27 P 0 ;1
L 2.3575 1.2075 2.3575 1.2075 27 P 0 ;1
L 2.3575 1.2575 2.3575 1.2575 27 P 0 ;1
L 2.3575 1.7575 2.3575 1.7575 27 P 0 ;1
L 2.3575 3.9575 2.3575 3.9575 27 P 0 ;1
L 2.3575 4.0075 2.3575 4.0075 27 P 0 ;1
L 2.3575 4.4575 2.3575 4.4575 27 P 0 ;1
L 2.3575 4.5075 2.3575 4.5075 27 P 0 ;1
L 2.3575 4.5575 2.3575 4.5575 27 P 0 ;1
L 2.3575 5.2575 2.3575 5.2575 27 P 0 ;1
L 2.3575 5.3075 2.3575 5.3075 27 P 0 ;1
L 2.3575 5.3575 2.3575 5.3575 27 P 0 ;1
L 2.3575 5.4075 2.3575 5.4075 27 P 0 ;1
L 2.3575 5.4575 2.3575 5.4575 27 P 0 ;1
L 2.3575 5.5075 2.3575 5.5075 27 P 0 ;1
L 2.3575 5.5575 2.3575 5.5575 27 P 0 ;1
L 2.3575 5.6075 2.3575 5.6075 27 P 0 ;1
L 2.3575 5.6575 2.3575 5.6575 27 P 0 ;1
L 2.3575 5.7075 2.3575 5.7075 27 P 0 ;1
L 2.3575 5.7575 2.3575 5.7575 27 P 0 ;1
L 2.3575 5.8075 2.3575 5.8075 27 P 0 ;1
L 2.3575 5.8575 2.3575 5.8575 27 P 0 ;1
L 2.4075 0.1575 2.4075 0.1575 27 P 0 ;1
L 2.4075 0.2075 2.4075 0.2075 27 P 0 ;1
L 2.4075 0.2575 2.4075 0.2575 27 P 0 ;1
L 2.4075 0.3075 2.4075 0.3075 27 P 0 ;1
L 2.4075 0.3575 2.4075 0.3575 27 P 0 ;1
L 2.4075 0.4075 2.4075 0.4075 27 P 0 ;1
L 2.4075 0.4575 2.4075 0.4575 27 P 0 ;1
L 2.4075 0.5075 2.4075 0.5075 27 P 0 ;1
L 2.4075 0.5575 2.4075 0.5575 27 P 0 ;1
L 2.4075 0.6075 2.4075 0.6075 27 P 0 ;1
L 2.4075 0.6575 2.4075 0.6575 27 P 0 ;1
L 2.4075 0.7075 2.4075 0.7075 27 P 0 ;1
L 2.4075 0.7575 2.4075 0.7575 27 P 0 ;1
L 2.4075 0.8075 2.4075 0.8075 27 P 0 ;1
L 2.4075 0.8575 2.4075 0.8575 27 P 0 ;1
L 2.4075 0.9075 2.4075 0.9075 27 P 0 ;1
L 2.4075 0.9575 2.4075 0.9575 27 P 0 ;1
L 2.4075 1.0075 2.4075 1.0075 27 P 0 ;1
L 2.4075 1.0575 2.4075 1.0575 27 P 0 ;1
L 2.4075 1.1075 2.4075 1.1075 27 P 0 ;1
L 2.4075 1.1575 2.4075 1.1575 27 P 0 ;1
L 2.4075 1.2075 2.4075 1.2075 27 P 0 ;1
L 2.4075 1.2575 2.4075 1.2575 27 P 0 ;1
L 2.4075 1.3075 2.4075 1.3075 27 P 0 ;1
L 2.4075 1.7075 2.4075 1.7075 27 P 0 ;1
L 2.4075 1.7575 2.4075 1.7575 27 P 0 ;1
L 2.4075 4.0075 2.4075 4.0075 27 P 0 ;1
L 2.4075 4.4075 2.4075 4.4075 27 P 0 ;1
L 2.4075 4.4575 2.4075 4.4575 27 P 0 ;1
L 2.4075 4.5075 2.4075 4.5075 27 P 0 ;1
L 2.4075 4.5575 2.4075 4.5575 27 P 0 ;1
L 2.4075 4.6075 2.4075 4.6075 27 P 0 ;1
L 2.4075 5.2575 2.4075 5.2575 27 P 0 ;1
L 2.4075 5.3075 2.4075 5.3075 27 P 0 ;1
L 2.4075 5.3575 2.4075 5.3575 27 P 0 ;1
L 2.4075 5.4075 2.4075 5.4075 27 P 0 ;1
L 2.4075 5.4575 2.4075 5.4575 27 P 0 ;1
L 2.4075 5.5075 2.4075 5.5075 27 P 0 ;1
L 2.4075 5.5575 2.4075 5.5575 27 P 0 ;1
L 2.4075 5.6075 2.4075 5.6075 27 P 0 ;1
L 2.4075 5.6575 2.4075 5.6575 27 P 0 ;1
L 2.4075 5.7075 2.4075 5.7075 27 P 0 ;1
L 2.4075 5.7575 2.4075 5.7575 27 P 0 ;1
L 2.4075 5.8075 2.4075 5.8075 27 P 0 ;1
L 2.4075 5.8575 2.4075 5.8575 27 P 0 ;1
L 2.4575 0.1575 2.4575 0.1575 27 P 0 ;1
L 2.4575 0.2075 2.4575 0.2075 27 P 0 ;1
L 2.4575 0.2575 2.4575 0.2575 27 P 0 ;1
L 2.4575 0.3075 2.4575 0.3075 27 P 0 ;1
L 2.4575 0.3575 2.4575 0.3575 27 P 0 ;1
L 2.4575 0.4075 2.4575 0.4075 27 P 0 ;1
L 2.4575 0.4575 2.4575 0.4575 27 P 0 ;1
L 2.4575 0.5075 2.4575 0.5075 27 P 0 ;1
L 2.4575 0.5575 2.4575 0.5575 27 P 0 ;1
L 2.4575 0.6075 2.4575 0.6075 27 P 0 ;1
L 2.4575 0.6575 2.4575 0.6575 27 P 0 ;1
L 2.4575 0.7075 2.4575 0.7075 27 P 0 ;1
L 2.4575 0.7575 2.4575 0.7575 27 P 0 ;1
L 2.4575 0.8075 2.4575 0.8075 27 P 0 ;1
L 2.4575 0.8575 2.4575 0.8575 27 P 0 ;1
L 2.4575 0.9075 2.4575 0.9075 27 P 0 ;1
L 2.4575 0.9575 2.4575 0.9575 27 P 0 ;1
L 2.4575 1.0075 2.4575 1.0075 27 P 0 ;1
L 2.4575 1.0575 2.4575 1.0575 27 P 0 ;1
L 2.4575 1.1075 2.4575 1.1075 27 P 0 ;1
L 2.4575 1.1575 2.4575 1.1575 27 P 0 ;1
L 2.4575 1.2075 2.4575 1.2075 27 P 0 ;1
L 2.4575 1.2575 2.4575 1.2575 27 P 0 ;1
L 2.4575 1.3075 2.4575 1.3075 27 P 0 ;1
L 2.4575 1.3575 2.4575 1.3575 27 P 0 ;1
L 2.4575 1.6575 2.4575 1.6575 27 P 0 ;1
L 2.4575 1.7075 2.4575 1.7075 27 P 0 ;1
L 2.4575 1.7575 2.4575 1.7575 27 P 0 ;1
L 2.4575 3.9575 2.4575 3.9575 27 P 0 ;1
L 2.4575 4.0075 2.4575 4.0075 27 P 0 ;1
L 2.4575 4.0575 2.4575 4.0575 27 P 0 ;1
L 2.4575 4.3575 2.4575 4.3575 27 P 0 ;1
L 2.4575 4.4075 2.4575 4.4075 27 P 0 ;1
L 2.4575 4.4575 2.4575 4.4575 27 P 0 ;1
L 2.4575 4.5075 2.4575 4.5075 27 P 0 ;1
L 2.4575 4.5575 2.4575 4.5575 27 P 0 ;1
L 2.4575 4.6075 2.4575 4.6075 27 P 0 ;1
L 2.4575 5.2575 2.4575 5.2575 27 P 0 ;1
L 2.4575 5.3075 2.4575 5.3075 27 P 0 ;1
L 2.4575 5.3575 2.4575 5.3575 27 P 0 ;1
L 2.4575 5.4075 2.4575 5.4075 27 P 0 ;1
L 2.4575 5.4575 2.4575 5.4575 27 P 0 ;1
L 2.4575 5.5075 2.4575 5.5075 27 P 0 ;1
L 2.4575 5.5575 2.4575 5.5575 27 P 0 ;1
L 2.4575 5.6075 2.4575 5.6075 27 P 0 ;1
L 2.4575 5.6575 2.4575 5.6575 27 P 0 ;1
L 2.4575 5.7075 2.4575 5.7075 27 P 0 ;1
L 2.4575 5.7575 2.4575 5.7575 27 P 0 ;1
L 2.4575 5.8075 2.4575 5.8075 27 P 0 ;1
L 2.4575 5.8575 2.4575 5.8575 27 P 0 ;1
L 2.5075 0.1575 2.5075 0.1575 27 P 0 ;1
L 2.5075 0.2075 2.5075 0.2075 27 P 0 ;1
L 2.5075 0.2575 2.5075 0.2575 27 P 0 ;1
L 2.5075 0.3075 2.5075 0.3075 27 P 0 ;1
L 2.5075 0.3575 2.5075 0.3575 27 P 0 ;1
L 2.5075 0.4075 2.5075 0.4075 27 P 0 ;1
L 2.5075 0.4575 2.5075 0.4575 27 P 0 ;1
L 2.5075 0.5075 2.5075 0.5075 27 P 0 ;1
L 2.5075 0.5575 2.5075 0.5575 27 P 0 ;1
L 2.5075 0.6075 2.5075 0.6075 27 P 0 ;1
L 2.5075 0.6575 2.5075 0.6575 27 P 0 ;1
L 2.5075 0.7075 2.5075 0.7075 27 P 0 ;1
L 2.5075 0.7575 2.5075 0.7575 27 P 0 ;1
L 2.5075 0.8075 2.5075 0.8075 27 P 0 ;1
L 2.5075 0.8575 2.5075 0.8575 27 P 0 ;1
L 2.5075 0.9075 2.5075 0.9075 27 P 0 ;1
L 2.5075 0.9575 2.5075 0.9575 27 P 0 ;1
L 2.5075 1.0075 2.5075 1.0075 27 P 0 ;1
L 2.5075 1.0575 2.5075 1.0575 27 P 0 ;1
L 2.5075 1.1075 2.5075 1.1075 27 P 0 ;1
L 2.5075 1.1575 2.5075 1.1575 27 P 0 ;1
L 2.5075 1.2075 2.5075 1.2075 27 P 0 ;1
L 2.5075 1.2575 2.5075 1.2575 27 P 0 ;1
L 2.5075 1.3075 2.5075 1.3075 27 P 0 ;1
L 2.5075 1.3575 2.5075 1.3575 27 P 0 ;1
L 2.5075 1.4075 2.5075 1.4075 27 P 0 ;1
L 2.5075 1.4575 2.5075 1.4575 27 P 0 ;1
L 2.5075 1.5075 2.5075 1.5075 27 P 0 ;1
L 2.5075 1.5575 2.5075 1.5575 27 P 0 ;1
L 2.5075 1.6075 2.5075 1.6075 27 P 0 ;1
L 2.5075 1.6575 2.5075 1.6575 27 P 0 ;1
L 2.5075 1.7075 2.5075 1.7075 27 P 0 ;1
L 2.5075 1.7575 2.5075 1.7575 27 P 0 ;1
L 2.5075 4.0075 2.5075 4.0075 27 P 0 ;1
L 2.5075 4.0575 2.5075 4.0575 27 P 0 ;1
L 2.5075 4.1075 2.5075 4.1075 27 P 0 ;1
L 2.5075 4.1575 2.5075 4.1575 27 P 0 ;1
L 2.5075 4.2075 2.5075 4.2075 27 P 0 ;1
L 2.5075 4.2575 2.5075 4.2575 27 P 0 ;1
L 2.5075 4.3075 2.5075 4.3075 27 P 0 ;1
L 2.5075 4.3575 2.5075 4.3575 27 P 0 ;1
L 2.5075 4.4075 2.5075 4.4075 27 P 0 ;1
L 2.5075 4.4575 2.5075 4.4575 27 P 0 ;1
L 2.5075 4.5075 2.5075 4.5075 27 P 0 ;1
L 2.5075 4.5575 2.5075 4.5575 27 P 0 ;1
L 2.5075 4.6075 2.5075 4.6075 27 P 0 ;1
L 2.5075 4.6575 2.5075 4.6575 27 P 0 ;1
L 2.5075 5.1575 2.5075 5.1575 27 P 0 ;1
L 2.5075 5.2075 2.5075 5.2075 27 P 0 ;1
L 2.5075 5.2575 2.5075 5.2575 27 P 0 ;1
L 2.5075 5.3075 2.5075 5.3075 27 P 0 ;1
L 2.5075 5.3575 2.5075 5.3575 27 P 0 ;1
L 2.5075 5.4075 2.5075 5.4075 27 P 0 ;1
L 2.5075 5.4575 2.5075 5.4575 27 P 0 ;1
L 2.5075 5.5075 2.5075 5.5075 27 P 0 ;1
L 2.5075 5.5575 2.5075 5.5575 27 P 0 ;1
L 2.5075 5.6075 2.5075 5.6075 27 P 0 ;1
L 2.5075 5.6575 2.5075 5.6575 27 P 0 ;1
L 2.5075 5.7075 2.5075 5.7075 27 P 0 ;1
L 2.5075 5.7575 2.5075 5.7575 27 P 0 ;1
L 2.5075 5.8075 2.5075 5.8075 27 P 0 ;1
L 2.5075 5.8575 2.5075 5.8575 27 P 0 ;1
L 2.5575 0.1575 2.5575 0.1575 27 P 0 ;1
L 2.5575 0.2075 2.5575 0.2075 27 P 0 ;1
L 2.5575 0.2575 2.5575 0.2575 27 P 0 ;1
L 2.5575 0.3075 2.5575 0.3075 27 P 0 ;1
L 2.5575 0.3575 2.5575 0.3575 27 P 0 ;1
L 2.5575 0.4075 2.5575 0.4075 27 P 0 ;1
L 2.5575 0.4575 2.5575 0.4575 27 P 0 ;1
L 2.5575 0.5075 2.5575 0.5075 27 P 0 ;1
L 2.5575 0.5575 2.5575 0.5575 27 P 0 ;1
L 2.5575 0.6075 2.5575 0.6075 27 P 0 ;1
L 2.5575 0.6575 2.5575 0.6575 27 P 0 ;1
L 2.5575 0.7075 2.5575 0.7075 27 P 0 ;1
L 2.5575 0.7575 2.5575 0.7575 27 P 0 ;1
L 2.5575 0.8075 2.5575 0.8075 27 P 0 ;1
L 2.5575 0.8575 2.5575 0.8575 27 P 0 ;1
L 2.5575 0.9075 2.5575 0.9075 27 P 0 ;1
L 2.5575 0.9575 2.5575 0.9575 27 P 0 ;1
L 2.5575 1.0075 2.5575 1.0075 27 P 0 ;1
L 2.5575 1.0575 2.5575 1.0575 27 P 0 ;1
L 2.5575 1.1075 2.5575 1.1075 27 P 0 ;1
L 2.5575 1.1575 2.5575 1.1575 27 P 0 ;1
L 2.5575 1.2075 2.5575 1.2075 27 P 0 ;1
L 2.5575 1.2575 2.5575 1.2575 27 P 0 ;1
L 2.5575 1.3075 2.5575 1.3075 27 P 0 ;1
L 2.5575 1.3575 2.5575 1.3575 27 P 0 ;1
L 2.5575 1.4075 2.5575 1.4075 27 P 0 ;1
L 2.5575 1.4575 2.5575 1.4575 27 P 0 ;1
L 2.5575 1.5075 2.5575 1.5075 27 P 0 ;1
L 2.5575 1.5575 2.5575 1.5575 27 P 0 ;1
L 2.5575 1.6075 2.5575 1.6075 27 P 0 ;1
L 2.5575 1.6575 2.5575 1.6575 27 P 0 ;1
L 2.5575 1.7075 2.5575 1.7075 27 P 0 ;1
L 2.5575 1.7575 2.5575 1.7575 27 P 0 ;1
L 2.5575 3.9575 2.5575 3.9575 27 P 0 ;1
L 2.5575 4.0075 2.5575 4.0075 27 P 0 ;1
L 2.5575 4.0575 2.5575 4.0575 27 P 0 ;1
L 2.5575 4.1075 2.5575 4.1075 27 P 0 ;1
L 2.5575 4.1575 2.5575 4.1575 27 P 0 ;1
L 2.5575 4.2075 2.5575 4.2075 27 P 0 ;1
L 2.5575 4.2575 2.5575 4.2575 27 P 0 ;1
L 2.5575 4.3075 2.5575 4.3075 27 P 0 ;1
L 2.5575 4.3575 2.5575 4.3575 27 P 0 ;1
L 2.5575 4.4075 2.5575 4.4075 27 P 0 ;1
L 2.5575 4.4575 2.5575 4.4575 27 P 0 ;1
L 2.5575 4.5075 2.5575 4.5075 27 P 0 ;1
L 2.5575 4.5575 2.5575 4.5575 27 P 0 ;1
L 2.5575 4.6075 2.5575 4.6075 27 P 0 ;1
L 2.5575 4.6575 2.5575 4.6575 27 P 0 ;1
L 2.5575 4.7075 2.5575 4.7075 27 P 0 ;1
L 2.5575 4.8575 2.5575 4.8575 27 P 0 ;1
L 2.5575 4.9075 2.5575 4.9075 27 P 0 ;1
L 2.5575 4.9575 2.5575 4.9575 27 P 0 ;1
L 2.5575 5.0075 2.5575 5.0075 27 P 0 ;1
L 2.5575 5.0575 2.5575 5.0575 27 P 0 ;1
L 2.5575 5.1075 2.5575 5.1075 27 P 0 ;1
L 2.5575 5.1575 2.5575 5.1575 27 P 0 ;1
L 2.5575 5.2075 2.5575 5.2075 27 P 0 ;1
L 2.5575 5.2575 2.5575 5.2575 27 P 0 ;1
L 2.5575 5.3075 2.5575 5.3075 27 P 0 ;1
L 2.5575 5.3575 2.5575 5.3575 27 P 0 ;1
L 2.5575 5.4075 2.5575 5.4075 27 P 0 ;1
L 2.5575 5.4575 2.5575 5.4575 27 P 0 ;1
L 2.5575 5.5075 2.5575 5.5075 27 P 0 ;1
L 2.5575 5.5575 2.5575 5.5575 27 P 0 ;1
L 2.5575 5.6075 2.5575 5.6075 27 P 0 ;1
L 2.5575 5.6575 2.5575 5.6575 27 P 0 ;1
L 2.5575 5.7075 2.5575 5.7075 27 P 0 ;1
L 2.5575 5.7575 2.5575 5.7575 27 P 0 ;1
L 2.5575 5.8075 2.5575 5.8075 27 P 0 ;1
L 2.5575 5.8575 2.5575 5.8575 27 P 0 ;1
L 2.6075 0.1575 2.6075 0.1575 27 P 0 ;1
L 2.6075 0.2075 2.6075 0.2075 27 P 0 ;1
L 2.6075 0.2575 2.6075 0.2575 27 P 0 ;1
L 2.6075 0.3075 2.6075 0.3075 27 P 0 ;1
L 2.6075 0.3575 2.6075 0.3575 27 P 0 ;1
L 2.6075 0.4075 2.6075 0.4075 27 P 0 ;1
L 2.6075 0.4575 2.6075 0.4575 27 P 0 ;1
L 2.6075 0.5075 2.6075 0.5075 27 P 0 ;1
L 2.6075 0.5575 2.6075 0.5575 27 P 0 ;1
L 2.6075 0.6075 2.6075 0.6075 27 P 0 ;1
L 2.6075 0.6575 2.6075 0.6575 27 P 0 ;1
L 2.6075 0.7075 2.6075 0.7075 27 P 0 ;1
L 2.6075 0.7575 2.6075 0.7575 27 P 0 ;1
L 2.6075 0.8075 2.6075 0.8075 27 P 0 ;1
L 2.6075 0.8575 2.6075 0.8575 27 P 0 ;1
L 2.6075 0.9075 2.6075 0.9075 27 P 0 ;1
L 2.6075 0.9575 2.6075 0.9575 27 P 0 ;1
L 2.6075 1.0075 2.6075 1.0075 27 P 0 ;1
L 2.6075 1.0575 2.6075 1.0575 27 P 0 ;1
L 2.6075 1.1075 2.6075 1.1075 27 P 0 ;1
L 2.6075 1.1575 2.6075 1.1575 27 P 0 ;1
L 2.6075 1.2075 2.6075 1.2075 27 P 0 ;1
L 2.6075 1.2575 2.6075 1.2575 27 P 0 ;1
L 2.6075 1.3075 2.6075 1.3075 27 P 0 ;1
L 2.6075 1.3575 2.6075 1.3575 27 P 0 ;1
L 2.6075 1.4075 2.6075 1.4075 27 P 0 ;1
L 2.6075 1.4575 2.6075 1.4575 27 P 0 ;1
L 2.6075 1.5075 2.6075 1.5075 27 P 0 ;1
L 2.6075 1.5575 2.6075 1.5575 27 P 0 ;1
L 2.6075 1.6075 2.6075 1.6075 27 P 0 ;1
L 2.6075 1.6575 2.6075 1.6575 27 P 0 ;1
L 2.6075 1.7075 2.6075 1.7075 27 P 0 ;1
L 2.6075 1.7575 2.6075 1.7575 27 P 0 ;1
L 2.6075 1.8075 2.6075 1.8075 27 P 0 ;1
L 2.6075 1.8575 2.6075 1.8575 27 P 0 ;1
L 2.6075 1.9075 2.6075 1.9075 27 P 0 ;1
L 2.6075 1.9575 2.6075 1.9575 27 P 0 ;1
L 2.6075 3.7575 2.6075 3.7575 27 P 0 ;1
L 2.6075 3.8075 2.6075 3.8075 27 P 0 ;1
L 2.6075 3.8575 2.6075 3.8575 27 P 0 ;1
L 2.6075 3.9075 2.6075 3.9075 27 P 0 ;1
L 2.6075 3.9575 2.6075 3.9575 27 P 0 ;1
L 2.6075 4.0075 2.6075 4.0075 27 P 0 ;1
L 2.6075 4.0575 2.6075 4.0575 27 P 0 ;1
L 2.6075 4.1075 2.6075 4.1075 27 P 0 ;1
L 2.6075 4.1575 2.6075 4.1575 27 P 0 ;1
L 2.6075 4.2075 2.6075 4.2075 27 P 0 ;1
L 2.6075 4.2575 2.6075 4.2575 27 P 0 ;1
L 2.6075 4.3075 2.6075 4.3075 27 P 0 ;1
L 2.6075 4.3575 2.6075 4.3575 27 P 0 ;1
L 2.6075 4.4075 2.6075 4.4075 27 P 0 ;1
L 2.6075 4.4575 2.6075 4.4575 27 P 0 ;1
L 2.6075 4.5075 2.6075 4.5075 27 P 0 ;1
L 2.6075 4.5575 2.6075 4.5575 27 P 0 ;1
L 2.6075 4.6075 2.6075 4.6075 27 P 0 ;1
L 2.6075 4.6575 2.6075 4.6575 27 P 0 ;1
L 2.6075 4.9075 2.6075 4.9075 27 P 0 ;1
L 2.6075 4.9575 2.6075 4.9575 27 P 0 ;1
L 2.6075 5.1575 2.6075 5.1575 27 P 0 ;1
L 2.6075 5.2075 2.6075 5.2075 27 P 0 ;1
L 2.6075 5.2575 2.6075 5.2575 27 P 0 ;1
L 2.6075 5.3075 2.6075 5.3075 27 P 0 ;1
L 2.6075 5.3575 2.6075 5.3575 27 P 0 ;1
L 2.6075 5.4075 2.6075 5.4075 27 P 0 ;1
L 2.6075 5.4575 2.6075 5.4575 27 P 0 ;1
L 2.6075 5.5075 2.6075 5.5075 27 P 0 ;1
L 2.6075 5.5575 2.6075 5.5575 27 P 0 ;1
L 2.6075 5.6075 2.6075 5.6075 27 P 0 ;1
L 2.6075 5.6575 2.6075 5.6575 27 P 0 ;1
L 2.6075 5.7075 2.6075 5.7075 27 P 0 ;1
L 2.6075 5.7575 2.6075 5.7575 27 P 0 ;1
L 2.6075 5.8075 2.6075 5.8075 27 P 0 ;1
L 2.6075 5.8575 2.6075 5.8575 27 P 0 ;1
L 2.6575 0.1575 2.6575 0.1575 27 P 0 ;1
L 2.6575 0.2075 2.6575 0.2075 27 P 0 ;1
L 2.6575 0.2575 2.6575 0.2575 27 P 0 ;1
L 2.6575 0.3075 2.6575 0.3075 27 P 0 ;1
L 2.6575 0.3575 2.6575 0.3575 27 P 0 ;1
L 2.6575 0.4075 2.6575 0.4075 27 P 0 ;1
L 2.6575 0.4575 2.6575 0.4575 27 P 0 ;1
L 2.6575 0.5075 2.6575 0.5075 27 P 0 ;1
L 2.6575 0.5575 2.6575 0.5575 27 P 0 ;1
L 2.6575 0.6075 2.6575 0.6075 27 P 0 ;1
L 2.6575 0.6575 2.6575 0.6575 27 P 0 ;1
L 2.6575 0.7075 2.6575 0.7075 27 P 0 ;1
L 2.6575 0.7575 2.6575 0.7575 27 P 0 ;1
L 2.6575 0.8075 2.6575 0.8075 27 P 0 ;1
L 2.6575 0.8575 2.6575 0.8575 27 P 0 ;1
L 2.6575 0.9075 2.6575 0.9075 27 P 0 ;1
L 2.6575 0.9575 2.6575 0.9575 27 P 0 ;1
L 2.6575 1.0075 2.6575 1.0075 27 P 0 ;1
L 2.6575 1.0575 2.6575 1.0575 27 P 0 ;1
L 2.6575 1.1075 2.6575 1.1075 27 P 0 ;1
L 2.6575 1.1575 2.6575 1.1575 27 P 0 ;1
L 2.6575 1.2075 2.6575 1.2075 27 P 0 ;1
L 2.6575 1.2575 2.6575 1.2575 27 P 0 ;1
L 2.6575 1.3075 2.6575 1.3075 27 P 0 ;1
L 2.6575 1.3575 2.6575 1.3575 27 P 0 ;1
L 2.6575 1.4075 2.6575 1.4075 27 P 0 ;1
L 2.6575 1.4575 2.6575 1.4575 27 P 0 ;1
L 2.6575 1.5075 2.6575 1.5075 27 P 0 ;1
L 2.6575 1.5575 2.6575 1.5575 27 P 0 ;1
L 2.6575 1.6075 2.6575 1.6075 27 P 0 ;1
L 2.6575 1.6575 2.6575 1.6575 27 P 0 ;1
L 2.6575 1.7075 2.6575 1.7075 27 P 0 ;1
L 2.6575 1.7575 2.6575 1.7575 27 P 0 ;1
L 2.6575 1.8075 2.6575 1.8075 27 P 0 ;1
L 2.6575 1.8575 2.6575 1.8575 27 P 0 ;1
L 2.6575 1.9075 2.6575 1.9075 27 P 0 ;1
L 2.6575 1.9575 2.6575 1.9575 27 P 0 ;1
L 2.6575 3.7575 2.6575 3.7575 27 P 0 ;1
L 2.6575 3.8075 2.6575 3.8075 27 P 0 ;1
L 2.6575 3.8575 2.6575 3.8575 27 P 0 ;1
L 2.6575 3.9075 2.6575 3.9075 27 P 0 ;1
L 2.6575 3.9575 2.6575 3.9575 27 P 0 ;1
L 2.6575 4.0075 2.6575 4.0075 27 P 0 ;1
L 2.6575 4.0575 2.6575 4.0575 27 P 0 ;1
L 2.6575 4.1075 2.6575 4.1075 27 P 0 ;1
L 2.6575 4.1575 2.6575 4.1575 27 P 0 ;1
L 2.6575 4.2075 2.6575 4.2075 27 P 0 ;1
L 2.6575 4.2575 2.6575 4.2575 27 P 0 ;1
L 2.6575 4.3075 2.6575 4.3075 27 P 0 ;1
L 2.6575 4.3575 2.6575 4.3575 27 P 0 ;1
L 2.6575 4.4075 2.6575 4.4075 27 P 0 ;1
L 2.6575 4.4575 2.6575 4.4575 27 P 0 ;1
L 2.6575 4.5075 2.6575 4.5075 27 P 0 ;1
L 2.6575 4.5575 2.6575 4.5575 27 P 0 ;1
L 2.6575 4.6075 2.6575 4.6075 27 P 0 ;1
L 2.6575 5.2575 2.6575 5.2575 27 P 0 ;1
L 2.6575 5.3075 2.6575 5.3075 27 P 0 ;1
L 2.6575 5.3575 2.6575 5.3575 27 P 0 ;1
L 2.6575 5.4075 2.6575 5.4075 27 P 0 ;1
L 2.6575 5.4575 2.6575 5.4575 27 P 0 ;1
L 2.6575 5.5075 2.6575 5.5075 27 P 0 ;1
L 2.6575 5.5575 2.6575 5.5575 27 P 0 ;1
L 2.6575 5.6075 2.6575 5.6075 27 P 0 ;1
L 2.6575 5.6575 2.6575 5.6575 27 P 0 ;1
L 2.6575 5.7075 2.6575 5.7075 27 P 0 ;1
L 2.6575 5.7575 2.6575 5.7575 27 P 0 ;1
L 2.6575 5.8075 2.6575 5.8075 27 P 0 ;1
L 2.6575 5.8575 2.6575 5.8575 27 P 0 ;1
L 2.7075 0.1575 2.7075 0.1575 27 P 0 ;1
L 2.7075 0.2075 2.7075 0.2075 27 P 0 ;1
L 2.7075 0.2575 2.7075 0.2575 27 P 0 ;1
L 2.7075 0.3075 2.7075 0.3075 27 P 0 ;1
L 2.7075 0.3575 2.7075 0.3575 27 P 0 ;1
L 2.7075 0.4075 2.7075 0.4075 27 P 0 ;1
L 2.7075 0.4575 2.7075 0.4575 27 P 0 ;1
L 2.7075 0.5075 2.7075 0.5075 27 P 0 ;1
L 2.7075 0.5575 2.7075 0.5575 27 P 0 ;1
L 2.7075 0.6075 2.7075 0.6075 27 P 0 ;1
L 2.7075 0.6575 2.7075 0.6575 27 P 0 ;1
L 2.7075 0.7075 2.7075 0.7075 27 P 0 ;1
L 2.7075 0.7575 2.7075 0.7575 27 P 0 ;1
L 2.7075 0.8075 2.7075 0.8075 27 P 0 ;1
L 2.7075 0.8575 2.7075 0.8575 27 P 0 ;1
L 2.7075 0.9075 2.7075 0.9075 27 P 0 ;1
L 2.7075 0.9575 2.7075 0.9575 27 P 0 ;1
L 2.7075 1.0075 2.7075 1.0075 27 P 0 ;1
L 2.7075 1.0575 2.7075 1.0575 27 P 0 ;1
L 2.7075 1.1075 2.7075 1.1075 27 P 0 ;1
L 2.7075 1.1575 2.7075 1.1575 27 P 0 ;1
L 2.7075 1.2075 2.7075 1.2075 27 P 0 ;1
L 2.7075 1.2575 2.7075 1.2575 27 P 0 ;1
L 2.7075 1.3075 2.7075 1.3075 27 P 0 ;1
L 2.7075 1.3575 2.7075 1.3575 27 P 0 ;1
L 2.7075 1.4075 2.7075 1.4075 27 P 0 ;1
L 2.7075 1.4575 2.7075 1.4575 27 P 0 ;1
L 2.7075 1.5075 2.7075 1.5075 27 P 0 ;1
L 2.7075 1.5575 2.7075 1.5575 27 P 0 ;1
L 2.7075 1.6075 2.7075 1.6075 27 P 0 ;1
L 2.7075 1.6575 2.7075 1.6575 27 P 0 ;1
L 2.7075 1.7075 2.7075 1.7075 27 P 0 ;1
L 2.7075 1.7575 2.7075 1.7575 27 P 0 ;1
L 2.7075 1.8075 2.7075 1.8075 27 P 0 ;1
L 2.7075 1.8575 2.7075 1.8575 27 P 0 ;1
L 2.7075 1.9075 2.7075 1.9075 27 P 0 ;1
L 2.7075 1.9575 2.7075 1.9575 27 P 0 ;1
L 2.7075 3.7575 2.7075 3.7575 27 P 0 ;1
L 2.7075 3.8075 2.7075 3.8075 27 P 0 ;1
L 2.7075 3.8575 2.7075 3.8575 27 P 0 ;1
L 2.7075 3.9075 2.7075 3.9075 27 P 0 ;1
L 2.7075 3.9575 2.7075 3.9575 27 P 0 ;1
L 2.7075 4.0075 2.7075 4.0075 27 P 0 ;1
L 2.7075 4.0575 2.7075 4.0575 27 P 0 ;1
L 2.7075 4.1075 2.7075 4.1075 27 P 0 ;1
L 2.7075 4.1575 2.7075 4.1575 27 P 0 ;1
L 2.7075 4.2075 2.7075 4.2075 27 P 0 ;1
L 2.7075 4.2575 2.7075 4.2575 27 P 0 ;1
L 2.7075 4.3075 2.7075 4.3075 27 P 0 ;1
L 2.7075 4.3575 2.7075 4.3575 27 P 0 ;1
L 2.7075 4.4075 2.7075 4.4075 27 P 0 ;1
L 2.7075 4.4575 2.7075 4.4575 27 P 0 ;1
L 2.7075 4.5075 2.7075 4.5075 27 P 0 ;1
L 2.7075 4.5575 2.7075 4.5575 27 P 0 ;1
L 2.7075 5.3075 2.7075 5.3075 27 P 0 ;1
L 2.7075 5.3575 2.7075 5.3575 27 P 0 ;1
L 2.7075 5.4075 2.7075 5.4075 27 P 0 ;1
L 2.7075 5.4575 2.7075 5.4575 27 P 0 ;1
L 2.7075 5.5075 2.7075 5.5075 27 P 0 ;1
L 2.7075 5.5575 2.7075 5.5575 27 P 0 ;1
L 2.7075 5.6075 2.7075 5.6075 27 P 0 ;1
L 2.7075 5.6575 2.7075 5.6575 27 P 0 ;1
L 2.7075 5.7075 2.7075 5.7075 27 P 0 ;1
L 2.7075 5.7575 2.7075 5.7575 27 P 0 ;1
L 2.7075 5.8075 2.7075 5.8075 27 P 0 ;1
L 2.7075 5.8575 2.7075 5.8575 27 P 0 ;1
L 2.7575 0.1575 2.7575 0.1575 27 P 0 ;1
L 2.7575 0.2075 2.7575 0.2075 27 P 0 ;1
L 2.7575 0.2575 2.7575 0.2575 27 P 0 ;1
L 2.7575 0.3075 2.7575 0.3075 27 P 0 ;1
L 2.7575 0.3575 2.7575 0.3575 27 P 0 ;1
L 2.7575 0.4075 2.7575 0.4075 27 P 0 ;1
L 2.7575 0.4575 2.7575 0.4575 27 P 0 ;1
L 2.7575 0.5075 2.7575 0.5075 27 P 0 ;1
L 2.7575 0.5575 2.7575 0.5575 27 P 0 ;1
L 2.7575 0.6075 2.7575 0.6075 27 P 0 ;1
L 2.7575 0.6575 2.7575 0.6575 27 P 0 ;1
L 2.7575 0.7075 2.7575 0.7075 27 P 0 ;1
L 2.7575 0.7575 2.7575 0.7575 27 P 0 ;1
L 2.7575 0.8075 2.7575 0.8075 27 P 0 ;1
L 2.7575 0.8575 2.7575 0.8575 27 P 0 ;1
L 2.7575 0.9075 2.7575 0.9075 27 P 0 ;1
L 2.7575 0.9575 2.7575 0.9575 27 P 0 ;1
L 2.7575 1.0075 2.7575 1.0075 27 P 0 ;1
L 2.7575 1.0575 2.7575 1.0575 27 P 0 ;1
L 2.7575 1.1075 2.7575 1.1075 27 P 0 ;1
L 2.7575 1.1575 2.7575 1.1575 27 P 0 ;1
L 2.7575 1.2075 2.7575 1.2075 27 P 0 ;1
L 2.7575 1.2575 2.7575 1.2575 27 P 0 ;1
L 2.7575 1.3075 2.7575 1.3075 27 P 0 ;1
L 2.7575 1.3575 2.7575 1.3575 27 P 0 ;1
L 2.7575 1.4075 2.7575 1.4075 27 P 0 ;1
L 2.7575 1.4575 2.7575 1.4575 27 P 0 ;1
L 2.7575 1.5075 2.7575 1.5075 27 P 0 ;1
L 2.7575 1.5575 2.7575 1.5575 27 P 0 ;1
L 2.7575 1.6075 2.7575 1.6075 27 P 0 ;1
L 2.7575 1.6575 2.7575 1.6575 27 P 0 ;1
L 2.7575 1.7075 2.7575 1.7075 27 P 0 ;1
L 2.7575 1.7575 2.7575 1.7575 27 P 0 ;1
L 2.7575 1.8075 2.7575 1.8075 27 P 0 ;1
L 2.7575 1.8575 2.7575 1.8575 27 P 0 ;1
L 2.7575 1.9075 2.7575 1.9075 27 P 0 ;1
L 2.7575 1.9575 2.7575 1.9575 27 P 0 ;1
L 2.7575 3.7575 2.7575 3.7575 27 P 0 ;1
L 2.7575 3.8075 2.7575 3.8075 27 P 0 ;1
L 2.7575 3.8575 2.7575 3.8575 27 P 0 ;1
L 2.7575 3.9075 2.7575 3.9075 27 P 0 ;1
L 2.7575 3.9575 2.7575 3.9575 27 P 0 ;1
L 2.7575 4.0075 2.7575 4.0075 27 P 0 ;1
L 2.7575 4.0575 2.7575 4.0575 27 P 0 ;1
L 2.7575 4.1075 2.7575 4.1075 27 P 0 ;1
L 2.7575 4.1575 2.7575 4.1575 27 P 0 ;1
L 2.7575 4.2075 2.7575 4.2075 27 P 0 ;1
L 2.7575 4.2575 2.7575 4.2575 27 P 0 ;1
L 2.7575 4.3075 2.7575 4.3075 27 P 0 ;1
L 2.7575 4.3575 2.7575 4.3575 27 P 0 ;1
L 2.7575 4.4075 2.7575 4.4075 27 P 0 ;1
L 2.7575 4.4575 2.7575 4.4575 27 P 0 ;1
L 2.7575 4.5075 2.7575 4.5075 27 P 0 ;1
L 2.7575 4.5575 2.7575 4.5575 27 P 0 ;1
L 2.7575 5.3075 2.7575 5.3075 27 P 0 ;1
L 2.7575 5.3575 2.7575 5.3575 27 P 0 ;1
L 2.7575 5.4075 2.7575 5.4075 27 P 0 ;1
L 2.7575 5.4575 2.7575 5.4575 27 P 0 ;1
L 2.7575 5.5075 2.7575 5.5075 27 P 0 ;1
L 2.7575 5.5575 2.7575 5.5575 27 P 0 ;1
L 2.7575 5.6075 2.7575 5.6075 27 P 0 ;1
L 2.7575 5.6575 2.7575 5.6575 27 P 0 ;1
L 2.7575 5.7075 2.7575 5.7075 27 P 0 ;1
L 2.7575 5.7575 2.7575 5.7575 27 P 0 ;1
L 2.7575 5.8075 2.7575 5.8075 27 P 0 ;1
L 2.7575 5.8575 2.7575 5.8575 27 P 0 ;1
L 2.8075 0.1575 2.8075 0.1575 27 P 0 ;1
L 2.8075 0.2075 2.8075 0.2075 27 P 0 ;1
L 2.8075 0.2575 2.8075 0.2575 27 P 0 ;1
L 2.8075 0.3075 2.8075 0.3075 27 P 0 ;1
L 2.8075 0.3575 2.8075 0.3575 27 P 0 ;1
L 2.8075 0.4075 2.8075 0.4075 27 P 0 ;1
L 2.8075 0.4575 2.8075 0.4575 27 P 0 ;1
L 2.8075 0.5075 2.8075 0.5075 27 P 0 ;1
L 2.8075 0.5575 2.8075 0.5575 27 P 0 ;1
L 2.8075 0.6075 2.8075 0.6075 27 P 0 ;1
L 2.8075 0.6575 2.8075 0.6575 27 P 0 ;1
L 2.8075 0.7075 2.8075 0.7075 27 P 0 ;1
L 2.8075 0.7575 2.8075 0.7575 27 P 0 ;1
L 2.8075 0.8075 2.8075 0.8075 27 P 0 ;1
L 2.8075 0.8575 2.8075 0.8575 27 P 0 ;1
L 2.8075 0.9075 2.8075 0.9075 27 P 0 ;1
L 2.8075 0.9575 2.8075 0.9575 27 P 0 ;1
L 2.8075 1.0075 2.8075 1.0075 27 P 0 ;1
L 2.8075 1.0575 2.8075 1.0575 27 P 0 ;1
L 2.8075 1.1075 2.8075 1.1075 27 P 0 ;1
L 2.8075 1.1575 2.8075 1.1575 27 P 0 ;1
L 2.8075 1.2075 2.8075 1.2075 27 P 0 ;1
L 2.8075 1.2575 2.8075 1.2575 27 P 0 ;1
L 2.8075 1.3075 2.8075 1.3075 27 P 0 ;1
L 2.8075 1.3575 2.8075 1.3575 27 P 0 ;1
L 2.8075 1.4075 2.8075 1.4075 27 P 0 ;1
L 2.8075 1.4575 2.8075 1.4575 27 P 0 ;1
L 2.8075 1.5075 2.8075 1.5075 27 P 0 ;1
L 2.8075 1.5575 2.8075 1.5575 27 P 0 ;1
L 2.8075 1.6075 2.8075 1.6075 27 P 0 ;1
L 2.8075 1.6575 2.8075 1.6575 27 P 0 ;1
L 2.8075 1.7075 2.8075 1.7075 27 P 0 ;1
L 2.8075 1.7575 2.8075 1.7575 27 P 0 ;1
L 2.8075 1.8075 2.8075 1.8075 27 P 0 ;1
L 2.8075 1.8575 2.8075 1.8575 27 P 0 ;1
L 2.8075 1.9075 2.8075 1.9075 27 P 0 ;1
L 2.8075 1.9575 2.8075 1.9575 27 P 0 ;1
L 2.8075 3.7575 2.8075 3.7575 27 P 0 ;1
L 2.8075 3.8075 2.8075 3.8075 27 P 0 ;1
L 2.8075 3.8575 2.8075 3.8575 27 P 0 ;1
L 2.8075 3.9075 2.8075 3.9075 27 P 0 ;1
L 2.8075 3.9575 2.8075 3.9575 27 P 0 ;1
L 2.8075 4.0075 2.8075 4.0075 27 P 0 ;1
L 2.8075 4.0575 2.8075 4.0575 27 P 0 ;1
L 2.8075 4.1075 2.8075 4.1075 27 P 0 ;1
L 2.8075 4.1575 2.8075 4.1575 27 P 0 ;1
L 2.8075 4.2075 2.8075 4.2075 27 P 0 ;1
L 2.8075 4.2575 2.8075 4.2575 27 P 0 ;1
L 2.8075 4.3075 2.8075 4.3075 27 P 0 ;1
L 2.8075 4.3575 2.8075 4.3575 27 P 0 ;1
L 2.8075 4.4075 2.8075 4.4075 27 P 0 ;1
L 2.8075 4.4575 2.8075 4.4575 27 P 0 ;1
L 2.8075 4.5075 2.8075 4.5075 27 P 0 ;1
L 2.8075 4.5575 2.8075 4.5575 27 P 0 ;1
L 2.8075 5.3075 2.8075 5.3075 27 P 0 ;1
L 2.8075 5.3575 2.8075 5.3575 27 P 0 ;1
L 2.8075 5.4075 2.8075 5.4075 27 P 0 ;1
L 2.8075 5.4575 2.8075 5.4575 27 P 0 ;1
L 2.8075 5.5075 2.8075 5.5075 27 P 0 ;1
L 2.8075 5.5575 2.8075 5.5575 27 P 0 ;1
L 2.8075 5.6075 2.8075 5.6075 27 P 0 ;1
L 2.8075 5.6575 2.8075 5.6575 27 P 0 ;1
L 2.8075 5.7075 2.8075 5.7075 27 P 0 ;1
L 2.8075 5.7575 2.8075 5.7575 27 P 0 ;1
L 2.8075 5.8075 2.8075 5.8075 27 P 0 ;1
L 2.8075 5.8575 2.8075 5.8575 27 P 0 ;1
L 2.8575 0.1575 2.8575 0.1575 27 P 0 ;1
L 2.8575 0.2075 2.8575 0.2075 27 P 0 ;1
L 2.8575 0.2575 2.8575 0.2575 27 P 0 ;1
L 2.8575 0.3075 2.8575 0.3075 27 P 0 ;1
L 2.8575 0.3575 2.8575 0.3575 27 P 0 ;1
L 2.8575 0.4075 2.8575 0.4075 27 P 0 ;1
L 2.8575 0.4575 2.8575 0.4575 27 P 0 ;1
L 2.8575 0.5075 2.8575 0.5075 27 P 0 ;1
L 2.8575 0.5575 2.8575 0.5575 27 P 0 ;1
L 2.8575 0.6075 2.8575 0.6075 27 P 0 ;1
L 2.8575 0.6575 2.8575 0.6575 27 P 0 ;1
L 2.8575 0.7075 2.8575 0.7075 27 P 0 ;1
L 2.8575 0.7575 2.8575 0.7575 27 P 0 ;1
L 2.8575 0.8075 2.8575 0.8075 27 P 0 ;1
L 2.8575 0.8575 2.8575 0.8575 27 P 0 ;1
L 2.8575 0.9075 2.8575 0.9075 27 P 0 ;1
L 2.8575 0.9575 2.8575 0.9575 27 P 0 ;1
L 2.8575 1.0075 2.8575 1.0075 27 P 0 ;1
L 2.8575 1.0575 2.8575 1.0575 27 P 0 ;1
L 2.8575 1.1075 2.8575 1.1075 27 P 0 ;1
L 2.8575 1.1575 2.8575 1.1575 27 P 0 ;1
L 2.8575 1.2075 2.8575 1.2075 27 P 0 ;1
L 2.8575 1.2575 2.8575 1.2575 27 P 0 ;1
L 2.8575 1.3075 2.8575 1.3075 27 P 0 ;1
L 2.8575 1.3575 2.8575 1.3575 27 P 0 ;1
L 2.8575 1.4075 2.8575 1.4075 27 P 0 ;1
L 2.8575 1.4575 2.8575 1.4575 27 P 0 ;1
L 2.8575 1.5075 2.8575 1.5075 27 P 0 ;1
L 2.8575 1.5575 2.8575 1.5575 27 P 0 ;1
L 2.8575 1.6075 2.8575 1.6075 27 P 0 ;1
L 2.8575 1.6575 2.8575 1.6575 27 P 0 ;1
L 2.8575 1.7075 2.8575 1.7075 27 P 0 ;1
L 2.8575 1.7575 2.8575 1.7575 27 P 0 ;1
L 2.8575 1.8075 2.8575 1.8075 27 P 0 ;1
L 2.8575 1.8575 2.8575 1.8575 27 P 0 ;1
L 2.8575 1.9075 2.8575 1.9075 27 P 0 ;1
L 2.8575 1.9575 2.8575 1.9575 27 P 0 ;1
L 2.8575 3.7575 2.8575 3.7575 27 P 0 ;1
L 2.8575 3.8075 2.8575 3.8075 27 P 0 ;1
L 2.8575 3.8575 2.8575 3.8575 27 P 0 ;1
L 2.8575 3.9075 2.8575 3.9075 27 P 0 ;1
L 2.8575 3.9575 2.8575 3.9575 27 P 0 ;1
L 2.8575 4.0075 2.8575 4.0075 27 P 0 ;1
L 2.8575 4.0575 2.8575 4.0575 27 P 0 ;1
L 2.8575 4.1075 2.8575 4.1075 27 P 0 ;1
L 2.8575 4.1575 2.8575 4.1575 27 P 0 ;1
L 2.8575 4.2075 2.8575 4.2075 27 P 0 ;1
L 2.8575 4.2575 2.8575 4.2575 27 P 0 ;1
L 2.8575 4.3075 2.8575 4.3075 27 P 0 ;1
L 2.8575 4.3575 2.8575 4.3575 27 P 0 ;1
L 2.8575 4.4075 2.8575 4.4075 27 P 0 ;1
L 2.8575 4.4575 2.8575 4.4575 27 P 0 ;1
L 2.8575 4.5075 2.8575 4.5075 27 P 0 ;1
L 2.8575 4.5575 2.8575 4.5575 27 P 0 ;1
L 2.8575 5.3075 2.8575 5.3075 27 P 0 ;1
L 2.8575 5.3575 2.8575 5.3575 27 P 0 ;1
L 2.8575 5.4075 2.8575 5.4075 27 P 0 ;1
L 2.8575 5.4575 2.8575 5.4575 27 P 0 ;1
L 2.8575 5.5075 2.8575 5.5075 27 P 0 ;1
L 2.8575 5.5575 2.8575 5.5575 27 P 0 ;1
L 2.8575 5.6075 2.8575 5.6075 27 P 0 ;1
L 2.8575 5.6575 2.8575 5.6575 27 P 0 ;1
L 2.8575 5.7075 2.8575 5.7075 27 P 0 ;1
L 2.8575 5.7575 2.8575 5.7575 27 P 0 ;1
L 2.8575 5.8075 2.8575 5.8075 27 P 0 ;1
L 2.8575 5.8575 2.8575 5.8575 27 P 0 ;1
L 2.9075 0.1575 2.9075 0.1575 27 P 0 ;1
L 2.9075 0.2075 2.9075 0.2075 27 P 0 ;1
L 2.9075 0.2575 2.9075 0.2575 27 P 0 ;1
L 2.9075 0.3075 2.9075 0.3075 27 P 0 ;1
L 2.9075 0.3575 2.9075 0.3575 27 P 0 ;1
L 2.9075 0.4075 2.9075 0.4075 27 P 0 ;1
L 2.9075 0.4575 2.9075 0.4575 27 P 0 ;1
L 2.9075 0.5075 2.9075 0.5075 27 P 0 ;1
L 2.9075 0.5575 2.9075 0.5575 27 P 0 ;1
L 2.9075 0.6075 2.9075 0.6075 27 P 0 ;1
L 2.9075 0.6575 2.9075 0.6575 27 P 0 ;1
L 2.9075 0.7075 2.9075 0.7075 27 P 0 ;1
L 2.9075 0.7575 2.9075 0.7575 27 P 0 ;1
L 2.9075 0.8075 2.9075 0.8075 27 P 0 ;1
L 2.9075 0.8575 2.9075 0.8575 27 P 0 ;1
L 2.9075 0.9075 2.9075 0.9075 27 P 0 ;1
L 2.9075 0.9575 2.9075 0.9575 27 P 0 ;1
L 2.9075 1.0075 2.9075 1.0075 27 P 0 ;1
L 2.9075 1.0575 2.9075 1.0575 27 P 0 ;1
L 2.9075 1.1075 2.9075 1.1075 27 P 0 ;1
L 2.9075 1.1575 2.9075 1.1575 27 P 0 ;1
L 2.9075 1.2075 2.9075 1.2075 27 P 0 ;1
L 2.9075 1.2575 2.9075 1.2575 27 P 0 ;1
L 2.9075 1.3075 2.9075 1.3075 27 P 0 ;1
L 2.9075 1.3575 2.9075 1.3575 27 P 0 ;1
L 2.9075 1.4075 2.9075 1.4075 27 P 0 ;1
L 2.9075 1.4575 2.9075 1.4575 27 P 0 ;1
L 2.9075 1.5075 2.9075 1.5075 27 P 0 ;1
L 2.9075 1.5575 2.9075 1.5575 27 P 0 ;1
L 2.9075 1.6075 2.9075 1.6075 27 P 0 ;1
L 2.9075 1.6575 2.9075 1.6575 27 P 0 ;1
L 2.9075 1.7075 2.9075 1.7075 27 P 0 ;1
L 2.9075 1.7575 2.9075 1.7575 27 P 0 ;1
L 2.9075 1.8075 2.9075 1.8075 27 P 0 ;1
L 2.9075 1.8575 2.9075 1.8575 27 P 0 ;1
L 2.9075 1.9075 2.9075 1.9075 27 P 0 ;1
L 2.9075 1.9575 2.9075 1.9575 27 P 0 ;1
L 2.9075 3.7575 2.9075 3.7575 27 P 0 ;1
L 2.9075 3.8075 2.9075 3.8075 27 P 0 ;1
L 2.9075 3.8575 2.9075 3.8575 27 P 0 ;1
L 2.9075 3.9075 2.9075 3.9075 27 P 0 ;1
L 2.9075 3.9575 2.9075 3.9575 27 P 0 ;1
L 2.9075 4.0075 2.9075 4.0075 27 P 0 ;1
L 2.9075 4.0575 2.9075 4.0575 27 P 0 ;1
L 2.9075 4.1075 2.9075 4.1075 27 P 0 ;1
L 2.9075 4.1575 2.9075 4.1575 27 P 0 ;1
L 2.9075 4.2075 2.9075 4.2075 27 P 0 ;1
L 2.9075 4.2575 2.9075 4.2575 27 P 0 ;1
L 2.9075 4.3075 2.9075 4.3075 27 P 0 ;1
L 2.9075 4.3575 2.9075 4.3575 27 P 0 ;1
L 2.9075 4.4075 2.9075 4.4075 27 P 0 ;1
L 2.9075 4.4575 2.9075 4.4575 27 P 0 ;1
L 2.9075 4.5075 2.9075 4.5075 27 P 0 ;1
L 2.9075 4.5575 2.9075 4.5575 27 P 0 ;1
L 2.9075 5.3075 2.9075 5.3075 27 P 0 ;1
L 2.9075 5.3575 2.9075 5.3575 27 P 0 ;1
L 2.9075 5.4075 2.9075 5.4075 27 P 0 ;1
L 2.9075 5.4575 2.9075 5.4575 27 P 0 ;1
L 2.9075 5.5075 2.9075 5.5075 27 P 0 ;1
L 2.9075 5.5575 2.9075 5.5575 27 P 0 ;1
L 2.9075 5.6075 2.9075 5.6075 27 P 0 ;1
L 2.9075 5.6575 2.9075 5.6575 27 P 0 ;1
L 2.9075 5.7075 2.9075 5.7075 27 P 0 ;1
L 2.9075 5.7575 2.9075 5.7575 27 P 0 ;1
L 2.9075 5.8075 2.9075 5.8075 27 P 0 ;1
L 2.9075 5.8575 2.9075 5.8575 27 P 0 ;1
L 2.9575 0.1575 2.9575 0.1575 27 P 0 ;1
L 2.9575 0.2075 2.9575 0.2075 27 P 0 ;1
L 2.9575 0.2575 2.9575 0.2575 27 P 0 ;1
L 2.9575 0.3075 2.9575 0.3075 27 P 0 ;1
L 2.9575 0.3575 2.9575 0.3575 27 P 0 ;1
L 2.9575 0.4075 2.9575 0.4075 27 P 0 ;1
L 2.9575 0.4575 2.9575 0.4575 27 P 0 ;1
L 2.9575 0.5075 2.9575 0.5075 27 P 0 ;1
L 2.9575 0.5575 2.9575 0.5575 27 P 0 ;1
L 2.9575 0.6075 2.9575 0.6075 27 P 0 ;1
L 2.9575 0.6575 2.9575 0.6575 27 P 0 ;1
L 2.9575 0.7075 2.9575 0.7075 27 P 0 ;1
L 2.9575 0.7575 2.9575 0.7575 27 P 0 ;1
L 2.9575 0.8075 2.9575 0.8075 27 P 0 ;1
L 2.9575 0.8575 2.9575 0.8575 27 P 0 ;1
L 2.9575 0.9075 2.9575 0.9075 27 P 0 ;1
L 2.9575 0.9575 2.9575 0.9575 27 P 0 ;1
L 2.9575 1.0075 2.9575 1.0075 27 P 0 ;1
L 2.9575 1.0575 2.9575 1.0575 27 P 0 ;1
L 2.9575 1.1075 2.9575 1.1075 27 P 0 ;1
L 2.9575 1.1575 2.9575 1.1575 27 P 0 ;1
L 2.9575 1.2075 2.9575 1.2075 27 P 0 ;1
L 2.9575 1.2575 2.9575 1.2575 27 P 0 ;1
L 2.9575 1.3075 2.9575 1.3075 27 P 0 ;1
L 2.9575 1.3575 2.9575 1.3575 27 P 0 ;1
L 2.9575 1.4075 2.9575 1.4075 27 P 0 ;1
L 2.9575 1.4575 2.9575 1.4575 27 P 0 ;1
L 2.9575 1.5075 2.9575 1.5075 27 P 0 ;1
L 2.9575 1.5575 2.9575 1.5575 27 P 0 ;1
L 2.9575 1.6075 2.9575 1.6075 27 P 0 ;1
L 2.9575 1.6575 2.9575 1.6575 27 P 0 ;1
L 2.9575 1.7075 2.9575 1.7075 27 P 0 ;1
L 2.9575 1.7575 2.9575 1.7575 27 P 0 ;1
L 2.9575 1.8075 2.9575 1.8075 27 P 0 ;1
L 2.9575 1.8575 2.9575 1.8575 27 P 0 ;1
L 2.9575 1.9075 2.9575 1.9075 27 P 0 ;1
L 2.9575 1.9575 2.9575 1.9575 27 P 0 ;1
L 2.9575 3.7575 2.9575 3.7575 27 P 0 ;1
L 2.9575 3.8075 2.9575 3.8075 27 P 0 ;1
L 2.9575 3.8575 2.9575 3.8575 27 P 0 ;1
L 2.9575 3.9075 2.9575 3.9075 27 P 0 ;1
L 2.9575 3.9575 2.9575 3.9575 27 P 0 ;1
L 2.9575 4.0075 2.9575 4.0075 27 P 0 ;1
L 2.9575 4.0575 2.9575 4.0575 27 P 0 ;1
L 2.9575 4.1075 2.9575 4.1075 27 P 0 ;1
L 2.9575 4.1575 2.9575 4.1575 27 P 0 ;1
L 2.9575 4.2075 2.9575 4.2075 27 P 0 ;1
L 2.9575 4.2575 2.9575 4.2575 27 P 0 ;1
L 2.9575 4.3075 2.9575 4.3075 27 P 0 ;1
L 2.9575 4.3575 2.9575 4.3575 27 P 0 ;1
L 2.9575 4.4075 2.9575 4.4075 27 P 0 ;1
L 2.9575 4.4575 2.9575 4.4575 27 P 0 ;1
L 2.9575 4.5075 2.9575 4.5075 27 P 0 ;1
L 2.9575 4.5575 2.9575 4.5575 27 P 0 ;1
L 2.9575 5.3075 2.9575 5.3075 27 P 0 ;1
L 2.9575 5.3575 2.9575 5.3575 27 P 0 ;1
L 2.9575 5.4075 2.9575 5.4075 27 P 0 ;1
L 2.9575 5.4575 2.9575 5.4575 27 P 0 ;1
L 2.9575 5.5075 2.9575 5.5075 27 P 0 ;1
L 2.9575 5.5575 2.9575 5.5575 27 P 0 ;1
L 2.9575 5.6075 2.9575 5.6075 27 P 0 ;1
L 2.9575 5.6575 2.9575 5.6575 27 P 0 ;1
L 2.9575 5.7075 2.9575 5.7075 27 P 0 ;1
L 2.9575 5.7575 2.9575 5.7575 27 P 0 ;1
L 2.9575 5.8075 2.9575 5.8075 27 P 0 ;1
L 2.9575 5.8575 2.9575 5.8575 27 P 0 ;1
L 3.0075 0.1575 3.0075 0.1575 27 P 0 ;1
L 3.0075 0.2075 3.0075 0.2075 27 P 0 ;1
L 3.0075 0.2575 3.0075 0.2575 27 P 0 ;1
L 3.0075 0.3075 3.0075 0.3075 27 P 0 ;1
L 3.0075 0.3575 3.0075 0.3575 27 P 0 ;1
L 3.0075 0.4075 3.0075 0.4075 27 P 0 ;1
L 3.0075 0.4575 3.0075 0.4575 27 P 0 ;1
L 3.0075 0.5075 3.0075 0.5075 27 P 0 ;1
L 3.0075 0.5575 3.0075 0.5575 27 P 0 ;1
L 3.0075 0.6075 3.0075 0.6075 27 P 0 ;1
L 3.0075 0.6575 3.0075 0.6575 27 P 0 ;1
L 3.0075 0.7075 3.0075 0.7075 27 P 0 ;1
L 3.0075 0.7575 3.0075 0.7575 27 P 0 ;1
L 3.0075 0.8075 3.0075 0.8075 27 P 0 ;1
L 3.0075 0.8575 3.0075 0.8575 27 P 0 ;1
L 3.0075 0.9075 3.0075 0.9075 27 P 0 ;1
L 3.0075 0.9575 3.0075 0.9575 27 P 0 ;1
L 3.0075 1.0075 3.0075 1.0075 27 P 0 ;1
L 3.0075 1.0575 3.0075 1.0575 27 P 0 ;1
L 3.0075 1.1075 3.0075 1.1075 27 P 0 ;1
L 3.0075 1.1575 3.0075 1.1575 27 P 0 ;1
L 3.0075 1.2075 3.0075 1.2075 27 P 0 ;1
L 3.0075 1.2575 3.0075 1.2575 27 P 0 ;1
L 3.0075 1.3075 3.0075 1.3075 27 P 0 ;1
L 3.0075 1.3575 3.0075 1.3575 27 P 0 ;1
L 3.0075 1.4075 3.0075 1.4075 27 P 0 ;1
L 3.0075 1.4575 3.0075 1.4575 27 P 0 ;1
L 3.0075 1.5075 3.0075 1.5075 27 P 0 ;1
L 3.0075 1.5575 3.0075 1.5575 27 P 0 ;1
L 3.0075 1.6075 3.0075 1.6075 27 P 0 ;1
L 3.0075 1.6575 3.0075 1.6575 27 P 0 ;1
L 3.0075 1.7075 3.0075 1.7075 27 P 0 ;1
L 3.0075 1.7575 3.0075 1.7575 27 P 0 ;1
L 3.0075 1.8075 3.0075 1.8075 27 P 0 ;1
L 3.0075 1.8575 3.0075 1.8575 27 P 0 ;1
L 3.0075 1.9075 3.0075 1.9075 27 P 0 ;1
L 3.0075 1.9575 3.0075 1.9575 27 P 0 ;1
L 3.0075 2.0075 3.0075 2.0075 27 P 0 ;1
L 3.0075 2.0575 3.0075 2.0575 27 P 0 ;1
L 3.0075 2.1075 3.0075 2.1075 27 P 0 ;1
L 3.0075 2.1575 3.0075 2.1575 27 P 0 ;1
L 3.0075 2.2075 3.0075 2.2075 27 P 0 ;1
L 3.0075 2.2575 3.0075 2.2575 27 P 0 ;1
L 3.0075 2.3075 3.0075 2.3075 27 P 0 ;1
L 3.0075 2.3575 3.0075 2.3575 27 P 0 ;1
L 3.0075 2.4075 3.0075 2.4075 27 P 0 ;1
L 3.0075 2.4575 3.0075 2.4575 27 P 0 ;1
L 3.0075 2.5075 3.0075 2.5075 27 P 0 ;1
L 3.0075 2.5575 3.0075 2.5575 27 P 0 ;1
L 3.0075 2.6075 3.0075 2.6075 27 P 0 ;1
L 3.0075 2.6575 3.0075 2.6575 27 P 0 ;1
L 3.0075 3.0075 3.0075 3.0075 27 P 0 ;1
L 3.0075 3.0575 3.0075 3.0575 27 P 0 ;1
L 3.0075 3.1075 3.0075 3.1075 27 P 0 ;1
L 3.0075 3.1575 3.0075 3.1575 27 P 0 ;1
L 3.0075 3.2075 3.0075 3.2075 27 P 0 ;1
L 3.0075 3.2575 3.0075 3.2575 27 P 0 ;1
L 3.0075 3.3075 3.0075 3.3075 27 P 0 ;1
L 3.0075 3.3575 3.0075 3.3575 27 P 0 ;1
L 3.0075 3.4075 3.0075 3.4075 27 P 0 ;1
L 3.0075 3.4575 3.0075 3.4575 27 P 0 ;1
L 3.0075 3.5075 3.0075 3.5075 27 P 0 ;1
L 3.0075 3.5575 3.0075 3.5575 27 P 0 ;1
L 3.0075 3.6075 3.0075 3.6075 27 P 0 ;1
L 3.0075 3.6575 3.0075 3.6575 27 P 0 ;1
L 3.0075 3.7075 3.0075 3.7075 27 P 0 ;1
L 3.0075 3.7575 3.0075 3.7575 27 P 0 ;1
L 3.0075 3.8075 3.0075 3.8075 27 P 0 ;1
L 3.0075 3.8575 3.0075 3.8575 27 P 0 ;1
L 3.0075 3.9075 3.0075 3.9075 27 P 0 ;1
L 3.0075 3.9575 3.0075 3.9575 27 P 0 ;1
L 3.0075 4.0075 3.0075 4.0075 27 P 0 ;1
L 3.0075 4.0575 3.0075 4.0575 27 P 0 ;1
L 3.0075 4.1075 3.0075 4.1075 27 P 0 ;1
L 3.0075 4.1575 3.0075 4.1575 27 P 0 ;1
L 3.0075 4.2075 3.0075 4.2075 27 P 0 ;1
L 3.0075 4.2575 3.0075 4.2575 27 P 0 ;1
L 3.0075 4.3075 3.0075 4.3075 27 P 0 ;1
L 3.0075 5.4075 3.0075 5.4075 27 P 0 ;1
L 3.0075 5.4575 3.0075 5.4575 27 P 0 ;1
L 3.0075 5.5075 3.0075 5.5075 27 P 0 ;1
L 3.0075 5.5575 3.0075 5.5575 27 P 0 ;1
L 3.0075 5.6075 3.0075 5.6075 27 P 0 ;1
L 3.0075 5.6575 3.0075 5.6575 27 P 0 ;1
L 3.0075 5.7075 3.0075 5.7075 27 P 0 ;1
L 3.0075 5.7575 3.0075 5.7575 27 P 0 ;1
L 3.0075 5.8075 3.0075 5.8075 27 P 0 ;1
L 3.0075 5.8575 3.0075 5.8575 27 P 0 ;1
L 3.0575 0.1575 3.0575 0.1575 27 P 0 ;1
L 3.0575 0.2075 3.0575 0.2075 27 P 0 ;1
L 3.0575 0.2575 3.0575 0.2575 27 P 0 ;1
L 3.0575 0.3075 3.0575 0.3075 27 P 0 ;1
L 3.0575 0.3575 3.0575 0.3575 27 P 0 ;1
L 3.0575 0.4075 3.0575 0.4075 27 P 0 ;1
L 3.0575 0.4575 3.0575 0.4575 27 P 0 ;1
L 3.0575 0.5075 3.0575 0.5075 27 P 0 ;1
L 3.0575 0.5575 3.0575 0.5575 27 P 0 ;1
L 3.0575 0.6075 3.0575 0.6075 27 P 0 ;1
L 3.0575 0.6575 3.0575 0.6575 27 P 0 ;1
L 3.0575 0.7075 3.0575 0.7075 27 P 0 ;1
L 3.0575 0.7575 3.0575 0.7575 27 P 0 ;1
L 3.0575 0.8075 3.0575 0.8075 27 P 0 ;1
L 3.0575 0.8575 3.0575 0.8575 27 P 0 ;1
L 3.0575 0.9075 3.0575 0.9075 27 P 0 ;1
L 3.0575 0.9575 3.0575 0.9575 27 P 0 ;1
L 3.0575 1.0075 3.0575 1.0075 27 P 0 ;1
L 3.0575 1.0575 3.0575 1.0575 27 P 0 ;1
L 3.0575 1.1075 3.0575 1.1075 27 P 0 ;1
L 3.0575 1.1575 3.0575 1.1575 27 P 0 ;1
L 3.0575 1.2075 3.0575 1.2075 27 P 0 ;1
L 3.0575 1.2575 3.0575 1.2575 27 P 0 ;1
L 3.0575 1.3075 3.0575 1.3075 27 P 0 ;1
L 3.0575 1.3575 3.0575 1.3575 27 P 0 ;1
L 3.0575 1.4075 3.0575 1.4075 27 P 0 ;1
L 3.0575 1.4575 3.0575 1.4575 27 P 0 ;1
L 3.0575 1.5075 3.0575 1.5075 27 P 0 ;1
L 3.0575 1.5575 3.0575 1.5575 27 P 0 ;1
L 3.0575 1.6075 3.0575 1.6075 27 P 0 ;1
L 3.0575 1.6575 3.0575 1.6575 27 P 0 ;1
L 3.0575 1.7075 3.0575 1.7075 27 P 0 ;1
L 3.0575 1.7575 3.0575 1.7575 27 P 0 ;1
L 3.0575 1.8075 3.0575 1.8075 27 P 0 ;1
L 3.0575 1.8575 3.0575 1.8575 27 P 0 ;1
L 3.0575 1.9075 3.0575 1.9075 27 P 0 ;1
L 3.0575 1.9575 3.0575 1.9575 27 P 0 ;1
L 3.0575 2.0075 3.0575 2.0075 27 P 0 ;1
L 3.0575 2.0575 3.0575 2.0575 27 P 0 ;1
L 3.0575 2.1075 3.0575 2.1075 27 P 0 ;1
L 3.0575 2.1575 3.0575 2.1575 27 P 0 ;1
L 3.0575 2.2075 3.0575 2.2075 27 P 0 ;1
L 3.0575 2.2575 3.0575 2.2575 27 P 0 ;1
L 3.0575 2.3075 3.0575 2.3075 27 P 0 ;1
L 3.0575 2.3575 3.0575 2.3575 27 P 0 ;1
L 3.0575 2.4075 3.0575 2.4075 27 P 0 ;1
L 3.0575 2.4575 3.0575 2.4575 27 P 0 ;1
L 3.0575 2.5075 3.0575 2.5075 27 P 0 ;1
L 3.0575 2.5575 3.0575 2.5575 27 P 0 ;1
L 3.0575 2.6075 3.0575 2.6075 27 P 0 ;1
L 3.0575 2.6575 3.0575 2.6575 27 P 0 ;1
L 3.0575 2.7075 3.0575 2.7075 27 P 0 ;1
L 3.0575 2.9575 3.0575 2.9575 27 P 0 ;1
L 3.0575 3.0075 3.0575 3.0075 27 P 0 ;1
L 3.0575 3.0575 3.0575 3.0575 27 P 0 ;1
L 3.0575 3.1075 3.0575 3.1075 27 P 0 ;1
L 3.0575 3.1575 3.0575 3.1575 27 P 0 ;1
L 3.0575 3.2075 3.0575 3.2075 27 P 0 ;1
L 3.0575 3.2575 3.0575 3.2575 27 P 0 ;1
L 3.0575 3.3075 3.0575 3.3075 27 P 0 ;1
L 3.0575 3.3575 3.0575 3.3575 27 P 0 ;1
L 3.0575 3.4075 3.0575 3.4075 27 P 0 ;1
L 3.0575 3.4575 3.0575 3.4575 27 P 0 ;1
L 3.0575 3.5075 3.0575 3.5075 27 P 0 ;1
L 3.0575 3.5575 3.0575 3.5575 27 P 0 ;1
L 3.0575 3.6075 3.0575 3.6075 27 P 0 ;1
L 3.0575 3.6575 3.0575 3.6575 27 P 0 ;1
L 3.0575 3.7075 3.0575 3.7075 27 P 0 ;1
L 3.0575 3.7575 3.0575 3.7575 27 P 0 ;1
L 3.0575 3.8075 3.0575 3.8075 27 P 0 ;1
L 3.0575 3.8575 3.0575 3.8575 27 P 0 ;1
L 3.0575 3.9075 3.0575 3.9075 27 P 0 ;1
L 3.0575 3.9575 3.0575 3.9575 27 P 0 ;1
L 3.0575 4.0075 3.0575 4.0075 27 P 0 ;1
L 3.0575 4.0575 3.0575 4.0575 27 P 0 ;1
L 3.0575 4.1075 3.0575 4.1075 27 P 0 ;1
L 3.0575 4.1575 3.0575 4.1575 27 P 0 ;1
L 3.0575 4.2075 3.0575 4.2075 27 P 0 ;1
L 3.0575 4.2575 3.0575 4.2575 27 P 0 ;1
L 3.0575 4.3075 3.0575 4.3075 27 P 0 ;1
L 3.0575 5.4575 3.0575 5.4575 27 P 0 ;1
L 3.0575 5.5075 3.0575 5.5075 27 P 0 ;1
L 3.0575 5.5575 3.0575 5.5575 27 P 0 ;1
L 3.0575 5.6075 3.0575 5.6075 27 P 0 ;1
L 3.0575 5.6575 3.0575 5.6575 27 P 0 ;1
L 3.0575 5.7075 3.0575 5.7075 27 P 0 ;1
L 3.0575 5.7575 3.0575 5.7575 27 P 0 ;1
L 3.0575 5.8075 3.0575 5.8075 27 P 0 ;1
L 3.0575 5.8575 3.0575 5.8575 27 P 0 ;1
L 3.1075 0.1575 3.1075 0.1575 27 P 0 ;1
L 3.1075 0.2075 3.1075 0.2075 27 P 0 ;1
L 3.1075 0.2575 3.1075 0.2575 27 P 0 ;1
L 3.1075 0.3075 3.1075 0.3075 27 P 0 ;1
L 3.1075 0.3575 3.1075 0.3575 27 P 0 ;1
L 3.1075 0.4075 3.1075 0.4075 27 P 0 ;1
L 3.1075 0.4575 3.1075 0.4575 27 P 0 ;1
L 3.1075 0.5075 3.1075 0.5075 27 P 0 ;1
L 3.1075 0.5575 3.1075 0.5575 27 P 0 ;1
L 3.1075 0.6075 3.1075 0.6075 27 P 0 ;1
L 3.1075 0.6575 3.1075 0.6575 27 P 0 ;1
L 3.1075 0.7075 3.1075 0.7075 27 P 0 ;1
L 3.1075 0.7575 3.1075 0.7575 27 P 0 ;1
L 3.1075 0.8075 3.1075 0.8075 27 P 0 ;1
L 3.1075 0.8575 3.1075 0.8575 27 P 0 ;1
L 3.1075 0.9075 3.1075 0.9075 27 P 0 ;1
L 3.1075 0.9575 3.1075 0.9575 27 P 0 ;1
L 3.1075 1.0075 3.1075 1.0075 27 P 0 ;1
L 3.1075 1.0575 3.1075 1.0575 27 P 0 ;1
L 3.1075 1.1075 3.1075 1.1075 27 P 0 ;1
L 3.1075 1.1575 3.1075 1.1575 27 P 0 ;1
L 3.1075 1.2075 3.1075 1.2075 27 P 0 ;1
L 3.1075 1.2575 3.1075 1.2575 27 P 0 ;1
L 3.1075 1.3075 3.1075 1.3075 27 P 0 ;1
L 3.1075 1.3575 3.1075 1.3575 27 P 0 ;1
L 3.1075 1.4075 3.1075 1.4075 27 P 0 ;1
L 3.1075 1.4575 3.1075 1.4575 27 P 0 ;1
L 3.1075 1.5075 3.1075 1.5075 27 P 0 ;1
L 3.1075 1.5575 3.1075 1.5575 27 P 0 ;1
L 3.1075 1.6075 3.1075 1.6075 27 P 0 ;1
L 3.1075 1.6575 3.1075 1.6575 27 P 0 ;1
L 3.1075 1.7075 3.1075 1.7075 27 P 0 ;1
L 3.1075 1.7575 3.1075 1.7575 27 P 0 ;1
L 3.1075 1.8075 3.1075 1.8075 27 P 0 ;1
L 3.1075 1.8575 3.1075 1.8575 27 P 0 ;1
L 3.1075 1.9075 3.1075 1.9075 27 P 0 ;1
L 3.1075 1.9575 3.1075 1.9575 27 P 0 ;1
L 3.1075 2.0075 3.1075 2.0075 27 P 0 ;1
L 3.1075 2.0575 3.1075 2.0575 27 P 0 ;1
L 3.1075 2.1075 3.1075 2.1075 27 P 0 ;1
L 3.1075 2.1575 3.1075 2.1575 27 P 0 ;1
L 3.1075 2.2075 3.1075 2.2075 27 P 0 ;1
L 3.1075 2.2575 3.1075 2.2575 27 P 0 ;1
L 3.1075 2.3075 3.1075 2.3075 27 P 0 ;1
L 3.1075 2.3575 3.1075 2.3575 27 P 0 ;1
L 3.1075 2.4075 3.1075 2.4075 27 P 0 ;1
L 3.1075 2.4575 3.1075 2.4575 27 P 0 ;1
L 3.1075 2.5075 3.1075 2.5075 27 P 0 ;1
L 3.1075 2.5575 3.1075 2.5575 27 P 0 ;1
L 3.1075 2.6075 3.1075 2.6075 27 P 0 ;1
L 3.1075 2.6575 3.1075 2.6575 27 P 0 ;1
L 3.1075 2.7075 3.1075 2.7075 27 P 0 ;1
L 3.1075 2.7575 3.1075 2.7575 27 P 0 ;1
L 3.1075 2.8075 3.1075 2.8075 27 P 0 ;1
L 3.1075 2.8575 3.1075 2.8575 27 P 0 ;1
L 3.1075 2.9075 3.1075 2.9075 27 P 0 ;1
L 3.1075 2.9575 3.1075 2.9575 27 P 0 ;1
L 3.1075 3.0075 3.1075 3.0075 27 P 0 ;1
L 3.1075 3.0575 3.1075 3.0575 27 P 0 ;1
L 3.1075 3.1075 3.1075 3.1075 27 P 0 ;1
L 3.1075 3.1575 3.1075 3.1575 27 P 0 ;1
L 3.1075 3.2075 3.1075 3.2075 27 P 0 ;1
L 3.1075 3.2575 3.1075 3.2575 27 P 0 ;1
L 3.1075 3.3075 3.1075 3.3075 27 P 0 ;1
L 3.1075 3.3575 3.1075 3.3575 27 P 0 ;1
L 3.1075 3.4075 3.1075 3.4075 27 P 0 ;1
L 3.1075 3.4575 3.1075 3.4575 27 P 0 ;1
L 3.1075 3.5075 3.1075 3.5075 27 P 0 ;1
L 3.1075 3.5575 3.1075 3.5575 27 P 0 ;1
L 3.1075 3.6075 3.1075 3.6075 27 P 0 ;1
L 3.1075 3.6575 3.1075 3.6575 27 P 0 ;1
L 3.1075 3.7075 3.1075 3.7075 27 P 0 ;1
L 3.1075 3.7575 3.1075 3.7575 27 P 0 ;1
L 3.1075 3.8075 3.1075 3.8075 27 P 0 ;1
L 3.1075 3.8575 3.1075 3.8575 27 P 0 ;1
L 3.1075 3.9075 3.1075 3.9075 27 P 0 ;1
L 3.1075 3.9575 3.1075 3.9575 27 P 0 ;1
L 3.1075 4.0075 3.1075 4.0075 27 P 0 ;1
L 3.1075 4.0575 3.1075 4.0575 27 P 0 ;1
L 3.1075 4.1075 3.1075 4.1075 27 P 0 ;1
L 3.1075 4.1575 3.1075 4.1575 27 P 0 ;1
L 3.1075 4.2075 3.1075 4.2075 27 P 0 ;1
L 3.1075 4.2575 3.1075 4.2575 27 P 0 ;1
L 3.1075 4.3075 3.1075 4.3075 27 P 0 ;1
L 3.1075 5.4575 3.1075 5.4575 27 P 0 ;1
L 3.1075 5.5075 3.1075 5.5075 27 P 0 ;1
L 3.1075 5.5575 3.1075 5.5575 27 P 0 ;1
L 3.1075 5.6075 3.1075 5.6075 27 P 0 ;1
L 3.1075 5.6575 3.1075 5.6575 27 P 0 ;1
L 3.1075 5.7075 3.1075 5.7075 27 P 0 ;1
L 3.1075 5.7575 3.1075 5.7575 27 P 0 ;1
L 3.1075 5.8075 3.1075 5.8075 27 P 0 ;1
L 3.1075 5.8575 3.1075 5.8575 27 P 0 ;1
L 3.1575 0.1575 3.1575 0.1575 27 P 0 ;1
L 3.1575 0.2075 3.1575 0.2075 27 P 0 ;1
L 3.1575 0.2575 3.1575 0.2575 27 P 0 ;1
L 3.1575 0.3075 3.1575 0.3075 27 P 0 ;1
L 3.1575 0.3575 3.1575 0.3575 27 P 0 ;1
L 3.1575 0.4075 3.1575 0.4075 27 P 0 ;1
L 3.1575 0.4575 3.1575 0.4575 27 P 0 ;1
L 3.1575 0.5075 3.1575 0.5075 27 P 0 ;1
L 3.1575 0.5575 3.1575 0.5575 27 P 0 ;1
L 3.1575 0.6075 3.1575 0.6075 27 P 0 ;1
L 3.1575 0.6575 3.1575 0.6575 27 P 0 ;1
L 3.1575 0.7075 3.1575 0.7075 27 P 0 ;1
L 3.1575 0.7575 3.1575 0.7575 27 P 0 ;1
L 3.1575 0.8075 3.1575 0.8075 27 P 0 ;1
L 3.1575 0.8575 3.1575 0.8575 27 P 0 ;1
L 3.1575 0.9075 3.1575 0.9075 27 P 0 ;1
L 3.1575 0.9575 3.1575 0.9575 27 P 0 ;1
L 3.1575 1.0075 3.1575 1.0075 27 P 0 ;1
L 3.1575 1.0575 3.1575 1.0575 27 P 0 ;1
L 3.1575 1.1075 3.1575 1.1075 27 P 0 ;1
L 3.1575 1.1575 3.1575 1.1575 27 P 0 ;1
L 3.1575 1.2075 3.1575 1.2075 27 P 0 ;1
L 3.1575 1.2575 3.1575 1.2575 27 P 0 ;1
L 3.1575 1.3075 3.1575 1.3075 27 P 0 ;1
L 3.1575 1.3575 3.1575 1.3575 27 P 0 ;1
L 3.1575 1.4075 3.1575 1.4075 27 P 0 ;1
L 3.1575 1.4575 3.1575 1.4575 27 P 0 ;1
L 3.1575 1.5075 3.1575 1.5075 27 P 0 ;1
L 3.1575 1.5575 3.1575 1.5575 27 P 0 ;1
L 3.1575 1.6075 3.1575 1.6075 27 P 0 ;1
L 3.1575 1.6575 3.1575 1.6575 27 P 0 ;1
L 3.1575 1.7075 3.1575 1.7075 27 P 0 ;1
L 3.1575 1.7575 3.1575 1.7575 27 P 0 ;1
L 3.1575 1.8075 3.1575 1.8075 27 P 0 ;1
L 3.1575 1.8575 3.1575 1.8575 27 P 0 ;1
L 3.1575 1.9075 3.1575 1.9075 27 P 0 ;1
L 3.1575 1.9575 3.1575 1.9575 27 P 0 ;1
L 3.1575 2.0075 3.1575 2.0075 27 P 0 ;1
L 3.1575 2.0575 3.1575 2.0575 27 P 0 ;1
L 3.1575 2.1075 3.1575 2.1075 27 P 0 ;1
L 3.1575 2.1575 3.1575 2.1575 27 P 0 ;1
L 3.1575 2.2075 3.1575 2.2075 27 P 0 ;1
L 3.1575 2.2575 3.1575 2.2575 27 P 0 ;1
L 3.1575 2.3075 3.1575 2.3075 27 P 0 ;1
L 3.1575 2.3575 3.1575 2.3575 27 P 0 ;1
L 3.1575 2.4075 3.1575 2.4075 27 P 0 ;1
L 3.1575 2.4575 3.1575 2.4575 27 P 0 ;1
L 3.1575 2.5075 3.1575 2.5075 27 P 0 ;1
L 3.1575 2.5575 3.1575 2.5575 27 P 0 ;1
L 3.1575 2.6075 3.1575 2.6075 27 P 0 ;1
L 3.1575 2.6575 3.1575 2.6575 27 P 0 ;1
L 3.1575 2.7075 3.1575 2.7075 27 P 0 ;1
L 3.1575 2.7575 3.1575 2.7575 27 P 0 ;1
L 3.1575 2.8075 3.1575 2.8075 27 P 0 ;1
L 3.1575 2.8575 3.1575 2.8575 27 P 0 ;1
L 3.1575 2.9075 3.1575 2.9075 27 P 0 ;1
L 3.1575 2.9575 3.1575 2.9575 27 P 0 ;1
L 3.1575 3.0075 3.1575 3.0075 27 P 0 ;1
L 3.1575 3.0575 3.1575 3.0575 27 P 0 ;1
L 3.1575 3.1075 3.1575 3.1075 27 P 0 ;1
L 3.1575 3.1575 3.1575 3.1575 27 P 0 ;1
L 3.1575 3.2075 3.1575 3.2075 27 P 0 ;1
L 3.1575 3.2575 3.1575 3.2575 27 P 0 ;1
L 3.1575 3.3075 3.1575 3.3075 27 P 0 ;1
L 3.1575 3.3575 3.1575 3.3575 27 P 0 ;1
L 3.1575 3.4075 3.1575 3.4075 27 P 0 ;1
L 3.1575 3.4575 3.1575 3.4575 27 P 0 ;1
L 3.1575 3.5075 3.1575 3.5075 27 P 0 ;1
L 3.1575 3.5575 3.1575 3.5575 27 P 0 ;1
L 3.1575 3.6075 3.1575 3.6075 27 P 0 ;1
L 3.1575 3.6575 3.1575 3.6575 27 P 0 ;1
L 3.1575 3.7075 3.1575 3.7075 27 P 0 ;1
L 3.1575 3.7575 3.1575 3.7575 27 P 0 ;1
L 3.1575 3.8075 3.1575 3.8075 27 P 0 ;1
L 3.1575 3.8575 3.1575 3.8575 27 P 0 ;1
L 3.1575 3.9075 3.1575 3.9075 27 P 0 ;1
L 3.1575 3.9575 3.1575 3.9575 27 P 0 ;1
L 3.1575 4.0075 3.1575 4.0075 27 P 0 ;1
L 3.1575 4.0575 3.1575 4.0575 27 P 0 ;1
L 3.1575 4.1075 3.1575 4.1075 27 P 0 ;1
L 3.1575 4.1575 3.1575 4.1575 27 P 0 ;1
L 3.1575 4.2075 3.1575 4.2075 27 P 0 ;1
L 3.1575 4.2575 3.1575 4.2575 27 P 0 ;1
L 3.1575 4.3075 3.1575 4.3075 27 P 0 ;1
L 3.1575 4.3575 3.1575 4.3575 27 P 0 ;1
L 3.1575 5.4075 3.1575 5.4075 27 P 0 ;1
L 3.1575 5.4575 3.1575 5.4575 27 P 0 ;1
L 3.1575 5.5075 3.1575 5.5075 27 P 0 ;1
L 3.1575 5.5575 3.1575 5.5575 27 P 0 ;1
L 3.1575 5.6075 3.1575 5.6075 27 P 0 ;1
L 3.1575 5.6575 3.1575 5.6575 27 P 0 ;1
L 3.1575 5.7075 3.1575 5.7075 27 P 0 ;1
L 3.1575 5.7575 3.1575 5.7575 27 P 0 ;1
L 3.1575 5.8075 3.1575 5.8075 27 P 0 ;1
L 3.1575 5.8575 3.1575 5.8575 27 P 0 ;1
L 3.2075 0.1575 3.2075 0.1575 27 P 0 ;1
L 3.2075 0.2075 3.2075 0.2075 27 P 0 ;1
L 3.2075 0.2575 3.2075 0.2575 27 P 0 ;1
L 3.2075 0.3075 3.2075 0.3075 27 P 0 ;1
L 3.2075 0.3575 3.2075 0.3575 27 P 0 ;1
L 3.2075 0.4075 3.2075 0.4075 27 P 0 ;1
L 3.2075 0.4575 3.2075 0.4575 27 P 0 ;1
L 3.2075 0.5075 3.2075 0.5075 27 P 0 ;1
L 3.2075 0.5575 3.2075 0.5575 27 P 0 ;1
L 3.2075 0.6075 3.2075 0.6075 27 P 0 ;1
L 3.2075 0.6575 3.2075 0.6575 27 P 0 ;1
L 3.2075 0.7075 3.2075 0.7075 27 P 0 ;1
L 3.2075 0.7575 3.2075 0.7575 27 P 0 ;1
L 3.2075 0.8075 3.2075 0.8075 27 P 0 ;1
L 3.2075 0.8575 3.2075 0.8575 27 P 0 ;1
L 3.2075 0.9075 3.2075 0.9075 27 P 0 ;1
L 3.2075 0.9575 3.2075 0.9575 27 P 0 ;1
L 3.2075 1.0075 3.2075 1.0075 27 P 0 ;1
L 3.2075 1.0575 3.2075 1.0575 27 P 0 ;1
L 3.2075 1.1075 3.2075 1.1075 27 P 0 ;1
L 3.2075 1.1575 3.2075 1.1575 27 P 0 ;1
L 3.2075 1.2075 3.2075 1.2075 27 P 0 ;1
L 3.2075 1.2575 3.2075 1.2575 27 P 0 ;1
L 3.2075 1.3075 3.2075 1.3075 27 P 0 ;1
L 3.2075 1.3575 3.2075 1.3575 27 P 0 ;1
L 3.2075 1.4075 3.2075 1.4075 27 P 0 ;1
L 3.2075 1.4575 3.2075 1.4575 27 P 0 ;1
L 3.2075 1.5075 3.2075 1.5075 27 P 0 ;1
L 3.2075 1.5575 3.2075 1.5575 27 P 0 ;1
L 3.2075 1.6075 3.2075 1.6075 27 P 0 ;1
L 3.2075 1.6575 3.2075 1.6575 27 P 0 ;1
L 3.2075 1.7075 3.2075 1.7075 27 P 0 ;1
L 3.2075 1.7575 3.2075 1.7575 27 P 0 ;1
L 3.2075 1.8075 3.2075 1.8075 27 P 0 ;1
L 3.2075 1.8575 3.2075 1.8575 27 P 0 ;1
L 3.2075 1.9075 3.2075 1.9075 27 P 0 ;1
L 3.2075 1.9575 3.2075 1.9575 27 P 0 ;1
L 3.2075 2.0075 3.2075 2.0075 27 P 0 ;1
L 3.2075 2.0575 3.2075 2.0575 27 P 0 ;1
L 3.2075 2.1075 3.2075 2.1075 27 P 0 ;1
L 3.2075 2.1575 3.2075 2.1575 27 P 0 ;1
L 3.2075 2.2075 3.2075 2.2075 27 P 0 ;1
L 3.2075 2.2575 3.2075 2.2575 27 P 0 ;1
L 3.2075 2.3075 3.2075 2.3075 27 P 0 ;1
L 3.2075 2.3575 3.2075 2.3575 27 P 0 ;1
L 3.2075 2.4075 3.2075 2.4075 27 P 0 ;1
L 3.2075 2.4575 3.2075 2.4575 27 P 0 ;1
L 3.2075 2.5075 3.2075 2.5075 27 P 0 ;1
L 3.2075 2.5575 3.2075 2.5575 27 P 0 ;1
L 3.2075 2.6075 3.2075 2.6075 27 P 0 ;1
L 3.2075 2.6575 3.2075 2.6575 27 P 0 ;1
L 3.2075 2.7075 3.2075 2.7075 27 P 0 ;1
L 3.2075 2.7575 3.2075 2.7575 27 P 0 ;1
L 3.2075 2.8075 3.2075 2.8075 27 P 0 ;1
L 3.2075 2.8575 3.2075 2.8575 27 P 0 ;1
L 3.2075 2.9075 3.2075 2.9075 27 P 0 ;1
L 3.2075 2.9575 3.2075 2.9575 27 P 0 ;1
L 3.2075 3.0075 3.2075 3.0075 27 P 0 ;1
L 3.2075 3.0575 3.2075 3.0575 27 P 0 ;1
L 3.2075 3.1075 3.2075 3.1075 27 P 0 ;1
L 3.2075 3.1575 3.2075 3.1575 27 P 0 ;1
L 3.2075 3.2075 3.2075 3.2075 27 P 0 ;1
L 3.2075 3.2575 3.2075 3.2575 27 P 0 ;1
L 3.2075 3.3075 3.2075 3.3075 27 P 0 ;1
L 3.2075 3.3575 3.2075 3.3575 27 P 0 ;1
L 3.2075 3.4075 3.2075 3.4075 27 P 0 ;1
L 3.2075 3.4575 3.2075 3.4575 27 P 0 ;1
L 3.2075 3.5075 3.2075 3.5075 27 P 0 ;1
L 3.2075 3.5575 3.2075 3.5575 27 P 0 ;1
L 3.2075 3.6075 3.2075 3.6075 27 P 0 ;1
L 3.2075 3.6575 3.2075 3.6575 27 P 0 ;1
L 3.2075 3.7075 3.2075 3.7075 27 P 0 ;1
L 3.2075 3.7575 3.2075 3.7575 27 P 0 ;1
L 3.2075 3.8075 3.2075 3.8075 27 P 0 ;1
L 3.2075 3.8575 3.2075 3.8575 27 P 0 ;1
L 3.2075 3.9075 3.2075 3.9075 27 P 0 ;1
L 3.2075 3.9575 3.2075 3.9575 27 P 0 ;1
L 3.2075 4.0075 3.2075 4.0075 27 P 0 ;1
L 3.2075 4.0575 3.2075 4.0575 27 P 0 ;1
L 3.2075 4.1075 3.2075 4.1075 27 P 0 ;1
L 3.2075 4.1575 3.2075 4.1575 27 P 0 ;1
L 3.2075 4.2075 3.2075 4.2075 27 P 0 ;1
L 3.2075 4.2575 3.2075 4.2575 27 P 0 ;1
L 3.2075 4.3075 3.2075 4.3075 27 P 0 ;1
L 3.2075 4.3575 3.2075 4.3575 27 P 0 ;1
L 3.2075 4.4075 3.2075 4.4075 27 P 0 ;1
L 3.2075 4.4575 3.2075 4.4575 27 P 0 ;1
L 3.2075 5.4575 3.2075 5.4575 27 P 0 ;1
L 3.2075 5.5075 3.2075 5.5075 27 P 0 ;1
L 3.2075 5.5575 3.2075 5.5575 27 P 0 ;1
L 3.2075 5.6075 3.2075 5.6075 27 P 0 ;1
L 3.2075 5.6575 3.2075 5.6575 27 P 0 ;1
L 3.2075 5.7075 3.2075 5.7075 27 P 0 ;1
L 3.2075 5.7575 3.2075 5.7575 27 P 0 ;1
L 3.2075 5.8075 3.2075 5.8075 27 P 0 ;1
L 3.2075 5.8575 3.2075 5.8575 27 P 0 ;1
L 3.2575 0.1575 3.2575 0.1575 27 P 0 ;1
L 3.2575 0.2075 3.2575 0.2075 27 P 0 ;1
L 3.2575 0.2575 3.2575 0.2575 27 P 0 ;1
L 3.2575 0.3075 3.2575 0.3075 27 P 0 ;1
L 3.2575 0.3575 3.2575 0.3575 27 P 0 ;1
L 3.2575 0.4075 3.2575 0.4075 27 P 0 ;1
L 3.2575 0.4575 3.2575 0.4575 27 P 0 ;1
L 3.2575 0.5075 3.2575 0.5075 27 P 0 ;1
L 3.2575 0.5575 3.2575 0.5575 27 P 0 ;1
L 3.2575 0.6075 3.2575 0.6075 27 P 0 ;1
L 3.2575 0.6575 3.2575 0.6575 27 P 0 ;1
L 3.2575 0.7075 3.2575 0.7075 27 P 0 ;1
L 3.2575 0.7575 3.2575 0.7575 27 P 0 ;1
L 3.2575 0.8075 3.2575 0.8075 27 P 0 ;1
L 3.2575 0.8575 3.2575 0.8575 27 P 0 ;1
L 3.2575 0.9075 3.2575 0.9075 27 P 0 ;1
L 3.2575 0.9575 3.2575 0.9575 27 P 0 ;1
L 3.2575 1.0075 3.2575 1.0075 27 P 0 ;1
L 3.2575 1.0575 3.2575 1.0575 27 P 0 ;1
L 3.2575 1.1075 3.2575 1.1075 27 P 0 ;1
L 3.2575 1.1575 3.2575 1.1575 27 P 0 ;1
L 3.2575 1.2075 3.2575 1.2075 27 P 0 ;1
L 3.2575 1.2575 3.2575 1.2575 27 P 0 ;1
L 3.2575 1.3075 3.2575 1.3075 27 P 0 ;1
L 3.2575 1.3575 3.2575 1.3575 27 P 0 ;1
L 3.2575 1.4075 3.2575 1.4075 27 P 0 ;1
L 3.2575 1.4575 3.2575 1.4575 27 P 0 ;1
L 3.2575 1.5075 3.2575 1.5075 27 P 0 ;1
L 3.2575 1.5575 3.2575 1.5575 27 P 0 ;1
L 3.2575 1.6075 3.2575 1.6075 27 P 0 ;1
L 3.2575 1.6575 3.2575 1.6575 27 P 0 ;1
L 3.2575 1.7075 3.2575 1.7075 27 P 0 ;1
L 3.2575 1.7575 3.2575 1.7575 27 P 0 ;1
L 3.2575 1.8075 3.2575 1.8075 27 P 0 ;1
L 3.2575 1.8575 3.2575 1.8575 27 P 0 ;1
L 3.2575 1.9075 3.2575 1.9075 27 P 0 ;1
L 3.2575 1.9575 3.2575 1.9575 27 P 0 ;1
L 3.2575 2.0075 3.2575 2.0075 27 P 0 ;1
L 3.2575 2.0575 3.2575 2.0575 27 P 0 ;1
L 3.2575 2.1075 3.2575 2.1075 27 P 0 ;1
L 3.2575 2.1575 3.2575 2.1575 27 P 0 ;1
L 3.2575 2.2075 3.2575 2.2075 27 P 0 ;1
L 3.2575 2.2575 3.2575 2.2575 27 P 0 ;1
L 3.2575 2.3075 3.2575 2.3075 27 P 0 ;1
L 3.2575 2.3575 3.2575 2.3575 27 P 0 ;1
L 3.2575 2.4075 3.2575 2.4075 27 P 0 ;1
L 3.2575 2.4575 3.2575 2.4575 27 P 0 ;1
L 3.2575 2.5075 3.2575 2.5075 27 P 0 ;1
L 3.2575 2.5575 3.2575 2.5575 27 P 0 ;1
L 3.2575 2.6075 3.2575 2.6075 27 P 0 ;1
L 3.2575 2.6575 3.2575 2.6575 27 P 0 ;1
L 3.2575 2.7075 3.2575 2.7075 27 P 0 ;1
L 3.2575 2.7575 3.2575 2.7575 27 P 0 ;1
L 3.2575 2.8075 3.2575 2.8075 27 P 0 ;1
L 3.2575 2.8575 3.2575 2.8575 27 P 0 ;1
L 3.2575 2.9075 3.2575 2.9075 27 P 0 ;1
L 3.2575 2.9575 3.2575 2.9575 27 P 0 ;1
L 3.2575 3.0075 3.2575 3.0075 27 P 0 ;1
L 3.2575 3.0575 3.2575 3.0575 27 P 0 ;1
L 3.2575 3.1075 3.2575 3.1075 27 P 0 ;1
L 3.2575 3.1575 3.2575 3.1575 27 P 0 ;1
L 3.2575 3.2075 3.2575 3.2075 27 P 0 ;1
L 3.2575 3.2575 3.2575 3.2575 27 P 0 ;1
L 3.2575 3.3075 3.2575 3.3075 27 P 0 ;1
L 3.2575 3.3575 3.2575 3.3575 27 P 0 ;1
L 3.2575 3.4075 3.2575 3.4075 27 P 0 ;1
L 3.2575 3.4575 3.2575 3.4575 27 P 0 ;1
L 3.2575 3.5075 3.2575 3.5075 27 P 0 ;1
L 3.2575 3.5575 3.2575 3.5575 27 P 0 ;1
L 3.2575 3.6075 3.2575 3.6075 27 P 0 ;1
L 3.2575 3.6575 3.2575 3.6575 27 P 0 ;1
L 3.2575 3.7075 3.2575 3.7075 27 P 0 ;1
L 3.2575 3.7575 3.2575 3.7575 27 P 0 ;1
L 3.2575 3.8075 3.2575 3.8075 27 P 0 ;1
L 3.2575 3.8575 3.2575 3.8575 27 P 0 ;1
L 3.2575 3.9075 3.2575 3.9075 27 P 0 ;1
L 3.2575 3.9575 3.2575 3.9575 27 P 0 ;1
L 3.2575 4.0075 3.2575 4.0075 27 P 0 ;1
L 3.2575 4.0575 3.2575 4.0575 27 P 0 ;1
L 3.2575 4.1075 3.2575 4.1075 27 P 0 ;1
L 3.2575 4.1575 3.2575 4.1575 27 P 0 ;1
L 3.2575 4.2075 3.2575 4.2075 27 P 0 ;1
L 3.2575 4.2575 3.2575 4.2575 27 P 0 ;1
L 3.2575 4.3075 3.2575 4.3075 27 P 0 ;1
L 3.2575 4.3575 3.2575 4.3575 27 P 0 ;1
L 3.2575 4.4075 3.2575 4.4075 27 P 0 ;1
L 3.2575 4.4575 3.2575 4.4575 27 P 0 ;1
L 3.2575 4.5075 3.2575 4.5075 27 P 0 ;1
L 3.2575 5.4575 3.2575 5.4575 27 P 0 ;1
L 3.2575 5.5075 3.2575 5.5075 27 P 0 ;1
L 3.2575 5.5575 3.2575 5.5575 27 P 0 ;1
L 3.2575 5.6075 3.2575 5.6075 27 P 0 ;1
L 3.2575 5.6575 3.2575 5.6575 27 P 0 ;1
L 3.2575 5.7075 3.2575 5.7075 27 P 0 ;1
L 3.2575 5.7575 3.2575 5.7575 27 P 0 ;1
L 3.2575 5.8075 3.2575 5.8075 27 P 0 ;1
L 3.2575 5.8575 3.2575 5.8575 27 P 0 ;1
L 3.3075 0.1575 3.3075 0.1575 27 P 0 ;1
L 3.3075 0.2075 3.3075 0.2075 27 P 0 ;1
L 3.3075 0.2575 3.3075 0.2575 27 P 0 ;1
L 3.3075 0.3075 3.3075 0.3075 27 P 0 ;1
L 3.3075 0.3575 3.3075 0.3575 27 P 0 ;1
L 3.3075 0.4075 3.3075 0.4075 27 P 0 ;1
L 3.3075 0.4575 3.3075 0.4575 27 P 0 ;1
L 3.3075 0.5075 3.3075 0.5075 27 P 0 ;1
L 3.3075 0.5575 3.3075 0.5575 27 P 0 ;1
L 3.3075 0.6075 3.3075 0.6075 27 P 0 ;1
L 3.3075 0.6575 3.3075 0.6575 27 P 0 ;1
L 3.3075 0.7075 3.3075 0.7075 27 P 0 ;1
L 3.3075 0.7575 3.3075 0.7575 27 P 0 ;1
L 3.3075 0.8075 3.3075 0.8075 27 P 0 ;1
L 3.3075 0.8575 3.3075 0.8575 27 P 0 ;1
L 3.3075 0.9075 3.3075 0.9075 27 P 0 ;1
L 3.3075 0.9575 3.3075 0.9575 27 P 0 ;1
L 3.3075 1.0075 3.3075 1.0075 27 P 0 ;1
L 3.3075 1.0575 3.3075 1.0575 27 P 0 ;1
L 3.3075 1.1075 3.3075 1.1075 27 P 0 ;1
L 3.3075 1.1575 3.3075 1.1575 27 P 0 ;1
L 3.3075 1.2075 3.3075 1.2075 27 P 0 ;1
L 3.3075 1.2575 3.3075 1.2575 27 P 0 ;1
L 3.3075 1.3075 3.3075 1.3075 27 P 0 ;1
L 3.3075 1.3575 3.3075 1.3575 27 P 0 ;1
L 3.3075 1.4075 3.3075 1.4075 27 P 0 ;1
L 3.3075 1.4575 3.3075 1.4575 27 P 0 ;1
L 3.3075 1.5075 3.3075 1.5075 27 P 0 ;1
L 3.3075 1.5575 3.3075 1.5575 27 P 0 ;1
L 3.3075 1.6075 3.3075 1.6075 27 P 0 ;1
L 3.3075 1.6575 3.3075 1.6575 27 P 0 ;1
L 3.3075 1.7075 3.3075 1.7075 27 P 0 ;1
L 3.3075 1.7575 3.3075 1.7575 27 P 0 ;1
L 3.3075 1.8075 3.3075 1.8075 27 P 0 ;1
L 3.3075 1.8575 3.3075 1.8575 27 P 0 ;1
L 3.3075 1.9075 3.3075 1.9075 27 P 0 ;1
L 3.3075 1.9575 3.3075 1.9575 27 P 0 ;1
L 3.3075 2.0075 3.3075 2.0075 27 P 0 ;1
L 3.3075 2.0575 3.3075 2.0575 27 P 0 ;1
L 3.3075 2.1075 3.3075 2.1075 27 P 0 ;1
L 3.3075 2.1575 3.3075 2.1575 27 P 0 ;1
L 3.3075 2.2075 3.3075 2.2075 27 P 0 ;1
L 3.3075 2.2575 3.3075 2.2575 27 P 0 ;1
L 3.3075 2.3075 3.3075 2.3075 27 P 0 ;1
L 3.3075 2.3575 3.3075 2.3575 27 P 0 ;1
L 3.3075 2.4075 3.3075 2.4075 27 P 0 ;1
L 3.3075 2.4575 3.3075 2.4575 27 P 0 ;1
L 3.3075 2.5075 3.3075 2.5075 27 P 0 ;1
L 3.3075 2.5575 3.3075 2.5575 27 P 0 ;1
L 3.3075 2.6075 3.3075 2.6075 27 P 0 ;1
L 3.3075 2.6575 3.3075 2.6575 27 P 0 ;1
L 3.3075 2.7075 3.3075 2.7075 27 P 0 ;1
L 3.3075 2.7575 3.3075 2.7575 27 P 0 ;1
L 3.3075 2.8075 3.3075 2.8075 27 P 0 ;1
L 3.3075 2.8575 3.3075 2.8575 27 P 0 ;1
L 3.3075 2.9075 3.3075 2.9075 27 P 0 ;1
L 3.3075 2.9575 3.3075 2.9575 27 P 0 ;1
L 3.3075 3.0075 3.3075 3.0075 27 P 0 ;1
L 3.3075 3.0575 3.3075 3.0575 27 P 0 ;1
L 3.3075 3.1075 3.3075 3.1075 27 P 0 ;1
L 3.3075 3.1575 3.3075 3.1575 27 P 0 ;1
L 3.3075 3.2075 3.3075 3.2075 27 P 0 ;1
L 3.3075 3.2575 3.3075 3.2575 27 P 0 ;1
L 3.3075 3.3075 3.3075 3.3075 27 P 0 ;1
L 3.3075 3.3575 3.3075 3.3575 27 P 0 ;1
L 3.3075 3.4075 3.3075 3.4075 27 P 0 ;1
L 3.3075 3.4575 3.3075 3.4575 27 P 0 ;1
L 3.3075 3.5075 3.3075 3.5075 27 P 0 ;1
L 3.3075 3.5575 3.3075 3.5575 27 P 0 ;1
L 3.3075 3.6075 3.3075 3.6075 27 P 0 ;1
L 3.3075 3.6575 3.3075 3.6575 27 P 0 ;1
L 3.3075 3.7075 3.3075 3.7075 27 P 0 ;1
L 3.3075 3.7575 3.3075 3.7575 27 P 0 ;1
L 3.3075 3.8075 3.3075 3.8075 27 P 0 ;1
L 3.3075 3.8575 3.3075 3.8575 27 P 0 ;1
L 3.3075 3.9075 3.3075 3.9075 27 P 0 ;1
L 3.3075 3.9575 3.3075 3.9575 27 P 0 ;1
L 3.3075 4.0075 3.3075 4.0075 27 P 0 ;1
L 3.3075 4.0575 3.3075 4.0575 27 P 0 ;1
L 3.3075 4.1075 3.3075 4.1075 27 P 0 ;1
L 3.3075 4.1575 3.3075 4.1575 27 P 0 ;1
L 3.3075 4.2075 3.3075 4.2075 27 P 0 ;1
L 3.3075 4.2575 3.3075 4.2575 27 P 0 ;1
L 3.3075 4.3075 3.3075 4.3075 27 P 0 ;1
L 3.3075 4.3575 3.3075 4.3575 27 P 0 ;1
L 3.3075 4.4075 3.3075 4.4075 27 P 0 ;1
L 3.3075 4.4575 3.3075 4.4575 27 P 0 ;1
L 3.3075 4.5075 3.3075 4.5075 27 P 0 ;1
L 3.3075 5.4575 3.3075 5.4575 27 P 0 ;1
L 3.3075 5.5075 3.3075 5.5075 27 P 0 ;1
L 3.3075 5.5575 3.3075 5.5575 27 P 0 ;1
L 3.3075 5.6075 3.3075 5.6075 27 P 0 ;1
L 3.3075 5.6575 3.3075 5.6575 27 P 0 ;1
L 3.3075 5.7075 3.3075 5.7075 27 P 0 ;1
L 3.3075 5.7575 3.3075 5.7575 27 P 0 ;1
L 3.3075 5.8075 3.3075 5.8075 27 P 0 ;1
L 3.3075 5.8575 3.3075 5.8575 27 P 0 ;1
L 3.3575 0.1575 3.3575 0.1575 27 P 0 ;1
L 3.3575 0.2075 3.3575 0.2075 27 P 0 ;1
L 3.3575 0.2575 3.3575 0.2575 27 P 0 ;1
L 3.3575 0.3075 3.3575 0.3075 27 P 0 ;1
L 3.3575 0.3575 3.3575 0.3575 27 P 0 ;1
L 3.3575 0.4075 3.3575 0.4075 27 P 0 ;1
L 3.3575 0.4575 3.3575 0.4575 27 P 0 ;1
L 3.3575 0.5075 3.3575 0.5075 27 P 0 ;1
L 3.3575 0.5575 3.3575 0.5575 27 P 0 ;1
L 3.3575 0.6075 3.3575 0.6075 27 P 0 ;1
L 3.3575 0.6575 3.3575 0.6575 27 P 0 ;1
L 3.3575 0.7075 3.3575 0.7075 27 P 0 ;1
L 3.3575 0.7575 3.3575 0.7575 27 P 0 ;1
L 3.3575 0.8075 3.3575 0.8075 27 P 0 ;1
L 3.3575 0.8575 3.3575 0.8575 27 P 0 ;1
L 3.3575 0.9075 3.3575 0.9075 27 P 0 ;1
L 3.3575 0.9575 3.3575 0.9575 27 P 0 ;1
L 3.3575 1.0075 3.3575 1.0075 27 P 0 ;1
L 3.3575 1.0575 3.3575 1.0575 27 P 0 ;1
L 3.3575 1.1075 3.3575 1.1075 27 P 0 ;1
L 3.3575 1.1575 3.3575 1.1575 27 P 0 ;1
L 3.3575 1.2075 3.3575 1.2075 27 P 0 ;1
L 3.3575 1.2575 3.3575 1.2575 27 P 0 ;1
L 3.3575 1.3075 3.3575 1.3075 27 P 0 ;1
L 3.3575 1.3575 3.3575 1.3575 27 P 0 ;1
L 3.3575 1.4075 3.3575 1.4075 27 P 0 ;1
L 3.3575 1.4575 3.3575 1.4575 27 P 0 ;1
L 3.3575 1.5075 3.3575 1.5075 27 P 0 ;1
L 3.3575 1.5575 3.3575 1.5575 27 P 0 ;1
L 3.3575 1.6075 3.3575 1.6075 27 P 0 ;1
L 3.3575 1.6575 3.3575 1.6575 27 P 0 ;1
L 3.3575 1.7075 3.3575 1.7075 27 P 0 ;1
L 3.3575 1.7575 3.3575 1.7575 27 P 0 ;1
L 3.3575 1.8075 3.3575 1.8075 27 P 0 ;1
L 3.3575 1.8575 3.3575 1.8575 27 P 0 ;1
L 3.3575 1.9075 3.3575 1.9075 27 P 0 ;1
L 3.3575 1.9575 3.3575 1.9575 27 P 0 ;1
L 3.3575 2.0075 3.3575 2.0075 27 P 0 ;1
L 3.3575 2.0575 3.3575 2.0575 27 P 0 ;1
L 3.3575 2.1075 3.3575 2.1075 27 P 0 ;1
L 3.3575 2.1575 3.3575 2.1575 27 P 0 ;1
L 3.3575 2.2075 3.3575 2.2075 27 P 0 ;1
L 3.3575 2.2575 3.3575 2.2575 27 P 0 ;1
L 3.3575 2.3075 3.3575 2.3075 27 P 0 ;1
L 3.3575 2.3575 3.3575 2.3575 27 P 0 ;1
L 3.3575 2.4075 3.3575 2.4075 27 P 0 ;1
L 3.3575 2.4575 3.3575 2.4575 27 P 0 ;1
L 3.3575 2.5075 3.3575 2.5075 27 P 0 ;1
L 3.3575 2.5575 3.3575 2.5575 27 P 0 ;1
L 3.3575 2.6075 3.3575 2.6075 27 P 0 ;1
L 3.3575 2.6575 3.3575 2.6575 27 P 0 ;1
L 3.3575 2.7075 3.3575 2.7075 27 P 0 ;1
L 3.3575 2.7575 3.3575 2.7575 27 P 0 ;1
L 3.3575 2.8075 3.3575 2.8075 27 P 0 ;1
L 3.3575 2.8575 3.3575 2.8575 27 P 0 ;1
L 3.3575 2.9075 3.3575 2.9075 27 P 0 ;1
L 3.3575 2.9575 3.3575 2.9575 27 P 0 ;1
L 3.3575 3.0075 3.3575 3.0075 27 P 0 ;1
L 3.3575 3.0575 3.3575 3.0575 27 P 0 ;1
L 3.3575 3.1075 3.3575 3.1075 27 P 0 ;1
L 3.3575 3.1575 3.3575 3.1575 27 P 0 ;1
L 3.3575 3.2075 3.3575 3.2075 27 P 0 ;1
L 3.3575 3.2575 3.3575 3.2575 27 P 0 ;1
L 3.3575 3.3075 3.3575 3.3075 27 P 0 ;1
L 3.3575 3.3575 3.3575 3.3575 27 P 0 ;1
L 3.3575 3.4075 3.3575 3.4075 27 P 0 ;1
L 3.3575 3.4575 3.3575 3.4575 27 P 0 ;1
L 3.3575 3.5075 3.3575 3.5075 27 P 0 ;1
L 3.3575 3.5575 3.3575 3.5575 27 P 0 ;1
L 3.3575 3.6075 3.3575 3.6075 27 P 0 ;1
L 3.3575 3.6575 3.3575 3.6575 27 P 0 ;1
L 3.3575 3.7075 3.3575 3.7075 27 P 0 ;1
L 3.3575 3.7575 3.3575 3.7575 27 P 0 ;1
L 3.3575 3.8075 3.3575 3.8075 27 P 0 ;1
L 3.3575 3.8575 3.3575 3.8575 27 P 0 ;1
L 3.3575 3.9075 3.3575 3.9075 27 P 0 ;1
L 3.3575 3.9575 3.3575 3.9575 27 P 0 ;1
L 3.3575 4.0075 3.3575 4.0075 27 P 0 ;1
L 3.3575 4.0575 3.3575 4.0575 27 P 0 ;1
L 3.3575 4.1075 3.3575 4.1075 27 P 0 ;1
L 3.3575 4.1575 3.3575 4.1575 27 P 0 ;1
L 3.3575 4.2075 3.3575 4.2075 27 P 0 ;1
L 3.3575 4.2575 3.3575 4.2575 27 P 0 ;1
L 3.3575 4.3075 3.3575 4.3075 27 P 0 ;1
L 3.3575 4.3575 3.3575 4.3575 27 P 0 ;1
L 3.3575 4.4075 3.3575 4.4075 27 P 0 ;1
L 3.3575 4.4575 3.3575 4.4575 27 P 0 ;1
L 3.3575 4.5075 3.3575 4.5075 27 P 0 ;1
L 3.3575 4.5575 3.3575 4.5575 27 P 0 ;1
L 3.3575 5.4575 3.3575 5.4575 27 P 0 ;1
L 3.3575 5.5075 3.3575 5.5075 27 P 0 ;1
L 3.3575 5.5575 3.3575 5.5575 27 P 0 ;1
L 3.3575 5.6075 3.3575 5.6075 27 P 0 ;1
L 3.3575 5.6575 3.3575 5.6575 27 P 0 ;1
L 3.3575 5.7075 3.3575 5.7075 27 P 0 ;1
L 3.3575 5.7575 3.3575 5.7575 27 P 0 ;1
L 3.3575 5.8075 3.3575 5.8075 27 P 0 ;1
L 3.3575 5.8575 3.3575 5.8575 27 P 0 ;1
L 3.4075 0.1575 3.4075 0.1575 27 P 0 ;1
L 3.4075 0.2075 3.4075 0.2075 27 P 0 ;1
L 3.4075 0.2575 3.4075 0.2575 27 P 0 ;1
L 3.4075 0.3075 3.4075 0.3075 27 P 0 ;1
L 3.4075 0.3575 3.4075 0.3575 27 P 0 ;1
L 3.4075 0.4075 3.4075 0.4075 27 P 0 ;1
L 3.4075 0.4575 3.4075 0.4575 27 P 0 ;1
L 3.4075 0.5075 3.4075 0.5075 27 P 0 ;1
L 3.4075 0.5575 3.4075 0.5575 27 P 0 ;1
L 3.4075 0.6075 3.4075 0.6075 27 P 0 ;1
L 3.4075 0.6575 3.4075 0.6575 27 P 0 ;1
L 3.4075 0.7075 3.4075 0.7075 27 P 0 ;1
L 3.4075 0.7575 3.4075 0.7575 27 P 0 ;1
L 3.4075 0.8075 3.4075 0.8075 27 P 0 ;1
L 3.4075 0.8575 3.4075 0.8575 27 P 0 ;1
L 3.4075 0.9075 3.4075 0.9075 27 P 0 ;1
L 3.4075 0.9575 3.4075 0.9575 27 P 0 ;1
L 3.4075 1.0075 3.4075 1.0075 27 P 0 ;1
L 3.4075 1.0575 3.4075 1.0575 27 P 0 ;1
L 3.4075 1.1075 3.4075 1.1075 27 P 0 ;1
L 3.4075 1.1575 3.4075 1.1575 27 P 0 ;1
L 3.4075 1.2075 3.4075 1.2075 27 P 0 ;1
L 3.4075 1.2575 3.4075 1.2575 27 P 0 ;1
L 3.4075 1.3075 3.4075 1.3075 27 P 0 ;1
L 3.4075 1.3575 3.4075 1.3575 27 P 0 ;1
L 3.4075 1.4075 3.4075 1.4075 27 P 0 ;1
L 3.4075 1.4575 3.4075 1.4575 27 P 0 ;1
L 3.4075 1.5075 3.4075 1.5075 27 P 0 ;1
L 3.4075 1.5575 3.4075 1.5575 27 P 0 ;1
L 3.4075 1.6075 3.4075 1.6075 27 P 0 ;1
L 3.4075 1.6575 3.4075 1.6575 27 P 0 ;1
L 3.4075 1.7075 3.4075 1.7075 27 P 0 ;1
L 3.4075 1.7575 3.4075 1.7575 27 P 0 ;1
L 3.4075 1.8075 3.4075 1.8075 27 P 0 ;1
L 3.4075 1.8575 3.4075 1.8575 27 P 0 ;1
L 3.4075 1.9075 3.4075 1.9075 27 P 0 ;1
L 3.4075 1.9575 3.4075 1.9575 27 P 0 ;1
L 3.4075 2.0075 3.4075 2.0075 27 P 0 ;1
L 3.4075 2.0575 3.4075 2.0575 27 P 0 ;1
L 3.4075 2.1075 3.4075 2.1075 27 P 0 ;1
L 3.4075 2.1575 3.4075 2.1575 27 P 0 ;1
L 3.4075 2.2075 3.4075 2.2075 27 P 0 ;1
L 3.4075 2.2575 3.4075 2.2575 27 P 0 ;1
L 3.4075 2.3075 3.4075 2.3075 27 P 0 ;1
L 3.4075 2.3575 3.4075 2.3575 27 P 0 ;1
L 3.4075 2.4075 3.4075 2.4075 27 P 0 ;1
L 3.4075 2.4575 3.4075 2.4575 27 P 0 ;1
L 3.4075 2.5075 3.4075 2.5075 27 P 0 ;1
L 3.4075 2.5575 3.4075 2.5575 27 P 0 ;1
L 3.4075 2.6075 3.4075 2.6075 27 P 0 ;1
L 3.4075 2.6575 3.4075 2.6575 27 P 0 ;1
L 3.4075 2.7075 3.4075 2.7075 27 P 0 ;1
L 3.4075 2.7575 3.4075 2.7575 27 P 0 ;1
L 3.4075 2.8075 3.4075 2.8075 27 P 0 ;1
L 3.4075 2.8575 3.4075 2.8575 27 P 0 ;1
L 3.4075 2.9075 3.4075 2.9075 27 P 0 ;1
L 3.4075 2.9575 3.4075 2.9575 27 P 0 ;1
L 3.4075 3.0075 3.4075 3.0075 27 P 0 ;1
L 3.4075 3.0575 3.4075 3.0575 27 P 0 ;1
L 3.4075 3.1075 3.4075 3.1075 27 P 0 ;1
L 3.4075 3.1575 3.4075 3.1575 27 P 0 ;1
L 3.4075 3.2075 3.4075 3.2075 27 P 0 ;1
L 3.4075 3.2575 3.4075 3.2575 27 P 0 ;1
L 3.4075 3.3075 3.4075 3.3075 27 P 0 ;1
L 3.4075 3.3575 3.4075 3.3575 27 P 0 ;1
L 3.4075 3.4075 3.4075 3.4075 27 P 0 ;1
L 3.4075 3.4575 3.4075 3.4575 27 P 0 ;1
L 3.4075 3.5075 3.4075 3.5075 27 P 0 ;1
L 3.4075 3.5575 3.4075 3.5575 27 P 0 ;1
L 3.4075 3.6075 3.4075 3.6075 27 P 0 ;1
L 3.4075 3.6575 3.4075 3.6575 27 P 0 ;1
L 3.4075 3.7075 3.4075 3.7075 27 P 0 ;1
L 3.4075 3.7575 3.4075 3.7575 27 P 0 ;1
L 3.4075 3.8075 3.4075 3.8075 27 P 0 ;1
L 3.4075 3.8575 3.4075 3.8575 27 P 0 ;1
L 3.4075 3.9075 3.4075 3.9075 27 P 0 ;1
L 3.4075 3.9575 3.4075 3.9575 27 P 0 ;1
L 3.4075 4.0075 3.4075 4.0075 27 P 0 ;1
L 3.4075 4.0575 3.4075 4.0575 27 P 0 ;1
L 3.4075 4.1075 3.4075 4.1075 27 P 0 ;1
L 3.4075 4.1575 3.4075 4.1575 27 P 0 ;1
L 3.4075 4.2075 3.4075 4.2075 27 P 0 ;1
L 3.4075 4.2575 3.4075 4.2575 27 P 0 ;1
L 3.4075 4.3075 3.4075 4.3075 27 P 0 ;1
L 3.4075 4.3575 3.4075 4.3575 27 P 0 ;1
L 3.4075 4.4075 3.4075 4.4075 27 P 0 ;1
L 3.4075 4.4575 3.4075 4.4575 27 P 0 ;1
L 3.4075 5.4575 3.4075 5.4575 27 P 0 ;1
L 3.4075 5.5075 3.4075 5.5075 27 P 0 ;1
L 3.4075 5.5575 3.4075 5.5575 27 P 0 ;1
L 3.4075 5.6075 3.4075 5.6075 27 P 0 ;1
L 3.4075 5.6575 3.4075 5.6575 27 P 0 ;1
L 3.4075 5.7075 3.4075 5.7075 27 P 0 ;1
L 3.4075 5.7575 3.4075 5.7575 27 P 0 ;1
L 3.4075 5.8075 3.4075 5.8075 27 P 0 ;1
L 3.4075 5.8575 3.4075 5.8575 27 P 0 ;1
L 3.4575 0.1575 3.4575 0.1575 27 P 0 ;1
L 3.4575 0.2075 3.4575 0.2075 27 P 0 ;1
L 3.4575 0.2575 3.4575 0.2575 27 P 0 ;1
L 3.4575 0.3075 3.4575 0.3075 27 P 0 ;1
L 3.4575 0.3575 3.4575 0.3575 27 P 0 ;1
L 3.4575 0.4075 3.4575 0.4075 27 P 0 ;1
L 3.4575 0.4575 3.4575 0.4575 27 P 0 ;1
L 3.4575 0.5075 3.4575 0.5075 27 P 0 ;1
L 3.4575 0.5575 3.4575 0.5575 27 P 0 ;1
L 3.4575 0.6075 3.4575 0.6075 27 P 0 ;1
L 3.4575 0.6575 3.4575 0.6575 27 P 0 ;1
L 3.4575 0.7075 3.4575 0.7075 27 P 0 ;1
L 3.4575 0.7575 3.4575 0.7575 27 P 0 ;1
L 3.4575 0.8075 3.4575 0.8075 27 P 0 ;1
L 3.4575 0.8575 3.4575 0.8575 27 P 0 ;1
L 3.4575 0.9075 3.4575 0.9075 27 P 0 ;1
L 3.4575 0.9575 3.4575 0.9575 27 P 0 ;1
L 3.4575 1.0075 3.4575 1.0075 27 P 0 ;1
L 3.4575 1.0575 3.4575 1.0575 27 P 0 ;1
L 3.4575 1.1075 3.4575 1.1075 27 P 0 ;1
L 3.4575 1.1575 3.4575 1.1575 27 P 0 ;1
L 3.4575 1.2075 3.4575 1.2075 27 P 0 ;1
L 3.4575 1.2575 3.4575 1.2575 27 P 0 ;1
L 3.4575 1.3075 3.4575 1.3075 27 P 0 ;1
L 3.4575 1.3575 3.4575 1.3575 27 P 0 ;1
L 3.4575 1.4075 3.4575 1.4075 27 P 0 ;1
L 3.4575 1.4575 3.4575 1.4575 27 P 0 ;1
L 3.4575 1.5075 3.4575 1.5075 27 P 0 ;1
L 3.4575 1.5575 3.4575 1.5575 27 P 0 ;1
L 3.4575 1.6075 3.4575 1.6075 27 P 0 ;1
L 3.4575 1.6575 3.4575 1.6575 27 P 0 ;1
L 3.4575 1.7075 3.4575 1.7075 27 P 0 ;1
L 3.4575 1.7575 3.4575 1.7575 27 P 0 ;1
L 3.4575 1.8075 3.4575 1.8075 27 P 0 ;1
L 3.4575 1.8575 3.4575 1.8575 27 P 0 ;1
L 3.4575 1.9075 3.4575 1.9075 27 P 0 ;1
L 3.4575 1.9575 3.4575 1.9575 27 P 0 ;1
L 3.4575 2.0075 3.4575 2.0075 27 P 0 ;1
L 3.4575 2.0575 3.4575 2.0575 27 P 0 ;1
L 3.4575 2.1075 3.4575 2.1075 27 P 0 ;1
L 3.4575 2.1575 3.4575 2.1575 27 P 0 ;1
L 3.4575 2.2075 3.4575 2.2075 27 P 0 ;1
L 3.4575 2.2575 3.4575 2.2575 27 P 0 ;1
L 3.4575 2.3075 3.4575 2.3075 27 P 0 ;1
L 3.4575 2.3575 3.4575 2.3575 27 P 0 ;1
L 3.4575 2.4075 3.4575 2.4075 27 P 0 ;1
L 3.4575 2.4575 3.4575 2.4575 27 P 0 ;1
L 3.4575 2.5075 3.4575 2.5075 27 P 0 ;1
L 3.4575 2.5575 3.4575 2.5575 27 P 0 ;1
L 3.4575 2.6075 3.4575 2.6075 27 P 0 ;1
L 3.4575 2.6575 3.4575 2.6575 27 P 0 ;1
L 3.4575 2.7075 3.4575 2.7075 27 P 0 ;1
L 3.4575 2.7575 3.4575 2.7575 27 P 0 ;1
L 3.4575 2.8075 3.4575 2.8075 27 P 0 ;1
L 3.4575 2.8575 3.4575 2.8575 27 P 0 ;1
L 3.4575 2.9075 3.4575 2.9075 27 P 0 ;1
L 3.4575 2.9575 3.4575 2.9575 27 P 0 ;1
L 3.4575 3.0075 3.4575 3.0075 27 P 0 ;1
L 3.4575 3.0575 3.4575 3.0575 27 P 0 ;1
L 3.4575 3.1075 3.4575 3.1075 27 P 0 ;1
L 3.4575 3.1575 3.4575 3.1575 27 P 0 ;1
L 3.4575 3.2075 3.4575 3.2075 27 P 0 ;1
L 3.4575 3.2575 3.4575 3.2575 27 P 0 ;1
L 3.4575 3.3075 3.4575 3.3075 27 P 0 ;1
L 3.4575 3.3575 3.4575 3.3575 27 P 0 ;1
L 3.4575 3.4075 3.4575 3.4075 27 P 0 ;1
L 3.4575 3.4575 3.4575 3.4575 27 P 0 ;1
L 3.4575 3.5075 3.4575 3.5075 27 P 0 ;1
L 3.4575 3.5575 3.4575 3.5575 27 P 0 ;1
L 3.4575 3.6075 3.4575 3.6075 27 P 0 ;1
L 3.4575 3.6575 3.4575 3.6575 27 P 0 ;1
L 3.4575 3.7075 3.4575 3.7075 27 P 0 ;1
L 3.4575 3.7575 3.4575 3.7575 27 P 0 ;1
L 3.4575 3.8075 3.4575 3.8075 27 P 0 ;1
L 3.4575 3.8575 3.4575 3.8575 27 P 0 ;1
L 3.4575 3.9075 3.4575 3.9075 27 P 0 ;1
L 3.4575 3.9575 3.4575 3.9575 27 P 0 ;1
L 3.4575 4.0075 3.4575 4.0075 27 P 0 ;1
L 3.4575 4.0575 3.4575 4.0575 27 P 0 ;1
L 3.4575 4.1075 3.4575 4.1075 27 P 0 ;1
L 3.4575 4.1575 3.4575 4.1575 27 P 0 ;1
L 3.4575 4.2075 3.4575 4.2075 27 P 0 ;1
L 3.4575 4.2575 3.4575 4.2575 27 P 0 ;1
L 3.4575 4.3075 3.4575 4.3075 27 P 0 ;1
L 3.4575 4.3575 3.4575 4.3575 27 P 0 ;1
L 3.4575 4.4075 3.4575 4.4075 27 P 0 ;1
L 3.4575 4.4575 3.4575 4.4575 27 P 0 ;1
L 3.4575 5.4575 3.4575 5.4575 27 P 0 ;1
L 3.4575 5.5075 3.4575 5.5075 27 P 0 ;1
L 3.4575 5.5575 3.4575 5.5575 27 P 0 ;1
L 3.4575 5.6075 3.4575 5.6075 27 P 0 ;1
L 3.4575 5.6575 3.4575 5.6575 27 P 0 ;1
L 3.4575 5.7075 3.4575 5.7075 27 P 0 ;1
L 3.4575 5.7575 3.4575 5.7575 27 P 0 ;1
L 3.4575 5.8075 3.4575 5.8075 27 P 0 ;1
L 3.4575 5.8575 3.4575 5.8575 27 P 0 ;1
L 3.5075 0.1575 3.5075 0.1575 27 P 0 ;1
L 3.5075 0.2075 3.5075 0.2075 27 P 0 ;1
L 3.5075 0.2575 3.5075 0.2575 27 P 0 ;1
L 3.5075 0.3075 3.5075 0.3075 27 P 0 ;1
L 3.5075 0.3575 3.5075 0.3575 27 P 0 ;1
L 3.5075 0.4075 3.5075 0.4075 27 P 0 ;1
L 3.5075 0.6075 3.5075 0.6075 27 P 0 ;1
L 3.5075 0.6575 3.5075 0.6575 27 P 0 ;1
L 3.5075 0.7075 3.5075 0.7075 27 P 0 ;1
L 3.5075 0.7575 3.5075 0.7575 27 P 0 ;1
L 3.5075 0.8075 3.5075 0.8075 27 P 0 ;1
L 3.5075 0.8575 3.5075 0.8575 27 P 0 ;1
L 3.5075 0.9075 3.5075 0.9075 27 P 0 ;1
L 3.5075 0.9575 3.5075 0.9575 27 P 0 ;1
L 3.5075 1.0075 3.5075 1.0075 27 P 0 ;1
L 3.5075 1.0575 3.5075 1.0575 27 P 0 ;1
L 3.5075 1.1075 3.5075 1.1075 27 P 0 ;1
L 3.5075 1.1575 3.5075 1.1575 27 P 0 ;1
L 3.5075 1.2075 3.5075 1.2075 27 P 0 ;1
L 3.5075 1.2575 3.5075 1.2575 27 P 0 ;1
L 3.5075 1.3075 3.5075 1.3075 27 P 0 ;1
L 3.5075 1.3575 3.5075 1.3575 27 P 0 ;1
L 3.5075 1.4075 3.5075 1.4075 27 P 0 ;1
L 3.5075 1.4575 3.5075 1.4575 27 P 0 ;1
L 3.5075 1.5075 3.5075 1.5075 27 P 0 ;1
L 3.5075 1.5575 3.5075 1.5575 27 P 0 ;1
L 3.5075 1.6075 3.5075 1.6075 27 P 0 ;1
L 3.5075 1.6575 3.5075 1.6575 27 P 0 ;1
L 3.5075 1.7075 3.5075 1.7075 27 P 0 ;1
L 3.5075 1.7575 3.5075 1.7575 27 P 0 ;1
L 3.5075 1.8075 3.5075 1.8075 27 P 0 ;1
L 3.5075 1.8575 3.5075 1.8575 27 P 0 ;1
L 3.5075 1.9075 3.5075 1.9075 27 P 0 ;1
L 3.5075 1.9575 3.5075 1.9575 27 P 0 ;1
L 3.5075 2.0075 3.5075 2.0075 27 P 0 ;1
L 3.5075 2.0575 3.5075 2.0575 27 P 0 ;1
L 3.5075 2.1075 3.5075 2.1075 27 P 0 ;1
L 3.5075 2.1575 3.5075 2.1575 27 P 0 ;1
L 3.5075 2.2075 3.5075 2.2075 27 P 0 ;1
L 3.5075 2.2575 3.5075 2.2575 27 P 0 ;1
L 3.5075 2.3075 3.5075 2.3075 27 P 0 ;1
L 3.5075 2.3575 3.5075 2.3575 27 P 0 ;1
L 3.5075 2.4075 3.5075 2.4075 27 P 0 ;1
L 3.5075 2.4575 3.5075 2.4575 27 P 0 ;1
L 3.5075 2.5075 3.5075 2.5075 27 P 0 ;1
L 3.5075 2.5575 3.5075 2.5575 27 P 0 ;1
L 3.5075 2.6075 3.5075 2.6075 27 P 0 ;1
L 3.5075 2.6575 3.5075 2.6575 27 P 0 ;1
L 3.5075 2.7075 3.5075 2.7075 27 P 0 ;1
L 3.5075 2.7575 3.5075 2.7575 27 P 0 ;1
L 3.5075 2.8075 3.5075 2.8075 27 P 0 ;1
L 3.5075 2.8575 3.5075 2.8575 27 P 0 ;1
L 3.5075 2.9075 3.5075 2.9075 27 P 0 ;1
L 3.5075 2.9575 3.5075 2.9575 27 P 0 ;1
L 3.5075 3.0075 3.5075 3.0075 27 P 0 ;1
L 3.5075 3.0575 3.5075 3.0575 27 P 0 ;1
L 3.5075 3.1075 3.5075 3.1075 27 P 0 ;1
L 3.5075 3.1575 3.5075 3.1575 27 P 0 ;1
L 3.5075 3.2075 3.5075 3.2075 27 P 0 ;1
L 3.5075 3.2575 3.5075 3.2575 27 P 0 ;1
L 3.5075 3.3075 3.5075 3.3075 27 P 0 ;1
L 3.5075 3.3575 3.5075 3.3575 27 P 0 ;1
L 3.5075 3.4075 3.5075 3.4075 27 P 0 ;1
L 3.5075 3.4575 3.5075 3.4575 27 P 0 ;1
L 3.5075 3.5075 3.5075 3.5075 27 P 0 ;1
L 3.5075 3.5575 3.5075 3.5575 27 P 0 ;1
L 3.5075 3.6075 3.5075 3.6075 27 P 0 ;1
L 3.5075 3.6575 3.5075 3.6575 27 P 0 ;1
L 3.5075 3.7075 3.5075 3.7075 27 P 0 ;1
L 3.5075 3.7575 3.5075 3.7575 27 P 0 ;1
L 3.5075 3.8075 3.5075 3.8075 27 P 0 ;1
L 3.5075 3.8575 3.5075 3.8575 27 P 0 ;1
L 3.5075 3.9075 3.5075 3.9075 27 P 0 ;1
L 3.5075 3.9575 3.5075 3.9575 27 P 0 ;1
L 3.5075 4.0075 3.5075 4.0075 27 P 0 ;1
L 3.5075 4.0575 3.5075 4.0575 27 P 0 ;1
L 3.5075 4.1075 3.5075 4.1075 27 P 0 ;1
L 3.5075 4.1575 3.5075 4.1575 27 P 0 ;1
L 3.5075 4.2075 3.5075 4.2075 27 P 0 ;1
L 3.5075 4.2575 3.5075 4.2575 27 P 0 ;1
L 3.5075 4.3075 3.5075 4.3075 27 P 0 ;1
L 3.5075 4.3575 3.5075 4.3575 27 P 0 ;1
L 3.5075 5.4075 3.5075 5.4075 27 P 0 ;1
L 3.5075 5.4575 3.5075 5.4575 27 P 0 ;1
L 3.5075 5.5075 3.5075 5.5075 27 P 0 ;1
L 3.5075 5.5575 3.5075 5.5575 27 P 0 ;1
L 3.5075 5.6075 3.5075 5.6075 27 P 0 ;1
L 3.5075 5.6575 3.5075 5.6575 27 P 0 ;1
L 3.5075 5.7075 3.5075 5.7075 27 P 0 ;1
L 3.5075 5.7575 3.5075 5.7575 27 P 0 ;1
L 3.5075 5.8075 3.5075 5.8075 27 P 0 ;1
L 3.5075 5.8575 3.5075 5.8575 27 P 0 ;1
L 3.5575 0.1575 3.5575 0.1575 27 P 0 ;1
L 3.5575 0.9075 3.5575 0.9075 27 P 0 ;1
L 3.5575 0.9575 3.5575 0.9575 27 P 0 ;1
L 3.5575 1.0075 3.5575 1.0075 27 P 0 ;1
L 3.5575 1.0575 3.5575 1.0575 27 P 0 ;1
L 3.5575 1.1075 3.5575 1.1075 27 P 0 ;1
L 3.5575 1.1575 3.5575 1.1575 27 P 0 ;1
L 3.5575 1.2075 3.5575 1.2075 27 P 0 ;1
L 3.5575 1.2575 3.5575 1.2575 27 P 0 ;1
L 3.5575 1.3075 3.5575 1.3075 27 P 0 ;1
L 3.5575 1.3575 3.5575 1.3575 27 P 0 ;1
L 3.5575 1.4075 3.5575 1.4075 27 P 0 ;1
L 3.5575 1.4575 3.5575 1.4575 27 P 0 ;1
L 3.5575 1.5075 3.5575 1.5075 27 P 0 ;1
L 3.5575 1.5575 3.5575 1.5575 27 P 0 ;1
L 3.5575 1.6075 3.5575 1.6075 27 P 0 ;1
L 3.5575 1.6575 3.5575 1.6575 27 P 0 ;1
L 3.5575 1.7075 3.5575 1.7075 27 P 0 ;1
L 3.5575 1.7575 3.5575 1.7575 27 P 0 ;1
L 3.5575 1.8075 3.5575 1.8075 27 P 0 ;1
L 3.5575 1.8575 3.5575 1.8575 27 P 0 ;1
L 3.5575 1.9075 3.5575 1.9075 27 P 0 ;1
L 3.5575 1.9575 3.5575 1.9575 27 P 0 ;1
L 3.5575 2.0075 3.5575 2.0075 27 P 0 ;1
L 3.5575 2.0575 3.5575 2.0575 27 P 0 ;1
L 3.5575 2.1075 3.5575 2.1075 27 P 0 ;1
L 3.5575 2.1575 3.5575 2.1575 27 P 0 ;1
L 3.5575 2.2075 3.5575 2.2075 27 P 0 ;1
L 3.5575 2.2575 3.5575 2.2575 27 P 0 ;1
L 3.5575 2.3075 3.5575 2.3075 27 P 0 ;1
L 3.5575 2.3575 3.5575 2.3575 27 P 0 ;1
L 3.5575 2.4075 3.5575 2.4075 27 P 0 ;1
L 3.5575 2.4575 3.5575 2.4575 27 P 0 ;1
L 3.5575 2.5075 3.5575 2.5075 27 P 0 ;1
L 3.5575 2.5575 3.5575 2.5575 27 P 0 ;1
L 3.5575 2.6075 3.5575 2.6075 27 P 0 ;1
L 3.5575 2.6575 3.5575 2.6575 27 P 0 ;1
L 3.5575 2.7075 3.5575 2.7075 27 P 0 ;1
L 3.5575 2.7575 3.5575 2.7575 27 P 0 ;1
L 3.5575 2.8075 3.5575 2.8075 27 P 0 ;1
L 3.5575 2.8575 3.5575 2.8575 27 P 0 ;1
L 3.5575 2.9075 3.5575 2.9075 27 P 0 ;1
L 3.5575 2.9575 3.5575 2.9575 27 P 0 ;1
L 3.5575 3.0075 3.5575 3.0075 27 P 0 ;1
L 3.5575 3.0575 3.5575 3.0575 27 P 0 ;1
L 3.5575 3.1075 3.5575 3.1075 27 P 0 ;1
L 3.5575 3.1575 3.5575 3.1575 27 P 0 ;1
L 3.5575 3.2075 3.5575 3.2075 27 P 0 ;1
L 3.5575 3.2575 3.5575 3.2575 27 P 0 ;1
L 3.5575 3.3075 3.5575 3.3075 27 P 0 ;1
L 3.5575 3.3575 3.5575 3.3575 27 P 0 ;1
L 3.5575 3.4075 3.5575 3.4075 27 P 0 ;1
L 3.5575 3.4575 3.5575 3.4575 27 P 0 ;1
L 3.5575 3.5075 3.5575 3.5075 27 P 0 ;1
L 3.5575 3.5575 3.5575 3.5575 27 P 0 ;1
L 3.5575 3.6075 3.5575 3.6075 27 P 0 ;1
L 3.5575 3.6575 3.5575 3.6575 27 P 0 ;1
L 3.5575 3.7075 3.5575 3.7075 27 P 0 ;1
L 3.5575 3.7575 3.5575 3.7575 27 P 0 ;1
L 3.5575 3.8075 3.5575 3.8075 27 P 0 ;1
L 3.5575 3.8575 3.5575 3.8575 27 P 0 ;1
L 3.5575 3.9075 3.5575 3.9075 27 P 0 ;1
L 3.5575 3.9575 3.5575 3.9575 27 P 0 ;1
L 3.5575 4.0075 3.5575 4.0075 27 P 0 ;1
L 3.5575 4.0575 3.5575 4.0575 27 P 0 ;1
L 3.5575 4.1075 3.5575 4.1075 27 P 0 ;1
L 3.5575 4.1575 3.5575 4.1575 27 P 0 ;1
L 3.5575 4.2075 3.5575 4.2075 27 P 0 ;1
L 3.5575 4.2575 3.5575 4.2575 27 P 0 ;1
L 3.5575 4.3075 3.5575 4.3075 27 P 0 ;1
L 3.5575 4.3575 3.5575 4.3575 27 P 0 ;1
L 3.5575 5.3075 3.5575 5.3075 27 P 0 ;1
L 3.5575 5.3575 3.5575 5.3575 27 P 0 ;1
L 3.5575 5.4075 3.5575 5.4075 27 P 0 ;1
L 3.5575 5.4575 3.5575 5.4575 27 P 0 ;1
L 3.5575 5.5075 3.5575 5.5075 27 P 0 ;1
L 3.5575 5.5575 3.5575 5.5575 27 P 0 ;1
L 3.5575 5.6075 3.5575 5.6075 27 P 0 ;1
L 3.5575 5.6575 3.5575 5.6575 27 P 0 ;1
L 3.5575 5.7075 3.5575 5.7075 27 P 0 ;1
L 3.5575 5.7575 3.5575 5.7575 27 P 0 ;1
L 3.5575 5.8075 3.5575 5.8075 27 P 0 ;1
L 3.5575 5.8575 3.5575 5.8575 27 P 0 ;1
L 3.6075 0.9075 3.6075 0.9075 27 P 0 ;1
L 3.6075 0.9575 3.6075 0.9575 27 P 0 ;1
L 3.6075 1.0075 3.6075 1.0075 27 P 0 ;1
L 3.6075 1.0575 3.6075 1.0575 27 P 0 ;1
L 3.6075 1.1075 3.6075 1.1075 27 P 0 ;1
L 3.6075 1.1575 3.6075 1.1575 27 P 0 ;1
L 3.6075 1.2075 3.6075 1.2075 27 P 0 ;1
L 3.6075 1.2575 3.6075 1.2575 27 P 0 ;1
L 3.6075 1.3075 3.6075 1.3075 27 P 0 ;1
L 3.6075 1.3575 3.6075 1.3575 27 P 0 ;1
L 3.6075 1.4075 3.6075 1.4075 27 P 0 ;1
L 3.6075 1.4575 3.6075 1.4575 27 P 0 ;1
L 3.6075 1.5075 3.6075 1.5075 27 P 0 ;1
L 3.6075 1.5575 3.6075 1.5575 27 P 0 ;1
L 3.6075 1.6075 3.6075 1.6075 27 P 0 ;1
L 3.6075 1.6575 3.6075 1.6575 27 P 0 ;1
L 3.6075 1.7075 3.6075 1.7075 27 P 0 ;1
L 3.6075 1.7575 3.6075 1.7575 27 P 0 ;1
L 3.6075 1.8075 3.6075 1.8075 27 P 0 ;1
L 3.6075 1.8575 3.6075 1.8575 27 P 0 ;1
L 3.6075 1.9075 3.6075 1.9075 27 P 0 ;1
L 3.6075 1.9575 3.6075 1.9575 27 P 0 ;1
L 3.6075 2.0075 3.6075 2.0075 27 P 0 ;1
L 3.6075 2.0575 3.6075 2.0575 27 P 0 ;1
L 3.6075 2.1075 3.6075 2.1075 27 P 0 ;1
L 3.6075 2.1575 3.6075 2.1575 27 P 0 ;1
L 3.6075 2.2075 3.6075 2.2075 27 P 0 ;1
L 3.6075 2.2575 3.6075 2.2575 27 P 0 ;1
L 3.6075 2.3075 3.6075 2.3075 27 P 0 ;1
L 3.6075 2.3575 3.6075 2.3575 27 P 0 ;1
L 3.6075 2.4075 3.6075 2.4075 27 P 0 ;1
L 3.6075 2.4575 3.6075 2.4575 27 P 0 ;1
L 3.6075 2.5075 3.6075 2.5075 27 P 0 ;1
L 3.6075 2.5575 3.6075 2.5575 27 P 0 ;1
L 3.6075 2.6075 3.6075 2.6075 27 P 0 ;1
L 3.6075 2.6575 3.6075 2.6575 27 P 0 ;1
L 3.6075 2.7075 3.6075 2.7075 27 P 0 ;1
L 3.6075 2.7575 3.6075 2.7575 27 P 0 ;1
L 3.6075 2.8075 3.6075 2.8075 27 P 0 ;1
L 3.6075 2.8575 3.6075 2.8575 27 P 0 ;1
L 3.6075 2.9075 3.6075 2.9075 27 P 0 ;1
L 3.6075 2.9575 3.6075 2.9575 27 P 0 ;1
L 3.6075 3.0075 3.6075 3.0075 27 P 0 ;1
L 3.6075 3.0575 3.6075 3.0575 27 P 0 ;1
L 3.6075 3.1075 3.6075 3.1075 27 P 0 ;1
L 3.6075 3.1575 3.6075 3.1575 27 P 0 ;1
L 3.6075 3.2075 3.6075 3.2075 27 P 0 ;1
L 3.6075 3.2575 3.6075 3.2575 27 P 0 ;1
L 3.6075 3.3075 3.6075 3.3075 27 P 0 ;1
L 3.6075 3.3575 3.6075 3.3575 27 P 0 ;1
L 3.6075 3.4075 3.6075 3.4075 27 P 0 ;1
L 3.6075 3.4575 3.6075 3.4575 27 P 0 ;1
L 3.6075 3.5075 3.6075 3.5075 27 P 0 ;1
L 3.6075 3.5575 3.6075 3.5575 27 P 0 ;1
L 3.6075 3.6075 3.6075 3.6075 27 P 0 ;1
L 3.6075 3.6575 3.6075 3.6575 27 P 0 ;1
L 3.6075 3.7075 3.6075 3.7075 27 P 0 ;1
L 3.6075 3.7575 3.6075 3.7575 27 P 0 ;1
L 3.6075 3.8075 3.6075 3.8075 27 P 0 ;1
L 3.6075 3.8575 3.6075 3.8575 27 P 0 ;1
L 3.6075 3.9075 3.6075 3.9075 27 P 0 ;1
L 3.6075 3.9575 3.6075 3.9575 27 P 0 ;1
L 3.6075 4.0075 3.6075 4.0075 27 P 0 ;1
L 3.6075 4.0575 3.6075 4.0575 27 P 0 ;1
L 3.6075 4.1075 3.6075 4.1075 27 P 0 ;1
L 3.6075 4.1575 3.6075 4.1575 27 P 0 ;1
L 3.6075 4.2075 3.6075 4.2075 27 P 0 ;1
L 3.6075 4.2575 3.6075 4.2575 27 P 0 ;1
L 3.6075 4.3075 3.6075 4.3075 27 P 0 ;1
L 3.6075 5.8575 3.6075 5.8575 27 P 0 ;1
L 3.6575 0.1575 3.6575 0.1575 27 P 0 ;1
L 3.6575 0.9075 3.6575 0.9075 27 P 0 ;1
L 3.6575 0.9575 3.6575 0.9575 27 P 0 ;1
L 3.6575 1.0075 3.6575 1.0075 27 P 0 ;1
L 3.6575 1.0575 3.6575 1.0575 27 P 0 ;1
L 3.6575 1.1075 3.6575 1.1075 27 P 0 ;1
L 3.6575 1.1575 3.6575 1.1575 27 P 0 ;1
L 3.6575 1.2075 3.6575 1.2075 27 P 0 ;1
L 3.6575 1.2575 3.6575 1.2575 27 P 0 ;1
L 3.6575 1.3075 3.6575 1.3075 27 P 0 ;1
L 3.6575 1.3575 3.6575 1.3575 27 P 0 ;1
L 3.6575 1.4075 3.6575 1.4075 27 P 0 ;1
L 3.6575 1.4575 3.6575 1.4575 27 P 0 ;1
L 3.6575 1.5075 3.6575 1.5075 27 P 0 ;1
L 3.6575 1.5575 3.6575 1.5575 27 P 0 ;1
L 3.6575 1.6075 3.6575 1.6075 27 P 0 ;1
L 3.6575 1.6575 3.6575 1.6575 27 P 0 ;1
L 3.6575 1.7075 3.6575 1.7075 27 P 0 ;1
L 3.6575 1.7575 3.6575 1.7575 27 P 0 ;1
L 3.6575 1.8075 3.6575 1.8075 27 P 0 ;1
L 3.6575 1.8575 3.6575 1.8575 27 P 0 ;1
L 3.6575 1.9075 3.6575 1.9075 27 P 0 ;1
L 3.6575 1.9575 3.6575 1.9575 27 P 0 ;1
L 3.6575 2.0075 3.6575 2.0075 27 P 0 ;1
L 3.6575 2.0575 3.6575 2.0575 27 P 0 ;1
L 3.6575 2.1075 3.6575 2.1075 27 P 0 ;1
L 3.6575 2.1575 3.6575 2.1575 27 P 0 ;1
L 3.6575 2.2075 3.6575 2.2075 27 P 0 ;1
L 3.6575 2.2575 3.6575 2.2575 27 P 0 ;1
L 3.6575 2.3075 3.6575 2.3075 27 P 0 ;1
L 3.6575 2.3575 3.6575 2.3575 27 P 0 ;1
L 3.6575 2.4075 3.6575 2.4075 27 P 0 ;1
L 3.6575 2.4575 3.6575 2.4575 27 P 0 ;1
L 3.6575 2.5075 3.6575 2.5075 27 P 0 ;1
L 3.6575 2.5575 3.6575 2.5575 27 P 0 ;1
L 3.6575 2.6075 3.6575 2.6075 27 P 0 ;1
L 3.6575 2.6575 3.6575 2.6575 27 P 0 ;1
L 3.6575 2.7075 3.6575 2.7075 27 P 0 ;1
L 3.6575 2.7575 3.6575 2.7575 27 P 0 ;1
L 3.6575 2.8075 3.6575 2.8075 27 P 0 ;1
L 3.6575 2.8575 3.6575 2.8575 27 P 0 ;1
L 3.6575 2.9075 3.6575 2.9075 27 P 0 ;1
L 3.6575 2.9575 3.6575 2.9575 27 P 0 ;1
L 3.6575 3.0075 3.6575 3.0075 27 P 0 ;1
L 3.6575 3.0575 3.6575 3.0575 27 P 0 ;1
L 3.6575 3.1075 3.6575 3.1075 27 P 0 ;1
L 3.6575 3.1575 3.6575 3.1575 27 P 0 ;1
L 3.6575 3.2075 3.6575 3.2075 27 P 0 ;1
L 3.6575 3.2575 3.6575 3.2575 27 P 0 ;1
L 3.6575 3.3075 3.6575 3.3075 27 P 0 ;1
L 3.6575 3.3575 3.6575 3.3575 27 P 0 ;1
L 3.6575 3.4075 3.6575 3.4075 27 P 0 ;1
L 3.6575 3.4575 3.6575 3.4575 27 P 0 ;1
L 3.6575 3.5075 3.6575 3.5075 27 P 0 ;1
L 3.6575 3.5575 3.6575 3.5575 27 P 0 ;1
L 3.6575 3.6075 3.6575 3.6075 27 P 0 ;1
L 3.6575 3.6575 3.6575 3.6575 27 P 0 ;1
L 3.6575 3.7075 3.6575 3.7075 27 P 0 ;1
L 3.6575 3.7575 3.6575 3.7575 27 P 0 ;1
L 3.6575 3.8075 3.6575 3.8075 27 P 0 ;1
L 3.6575 3.8575 3.6575 3.8575 27 P 0 ;1
L 3.6575 3.9075 3.6575 3.9075 27 P 0 ;1
L 3.6575 3.9575 3.6575 3.9575 27 P 0 ;1
L 3.6575 4.0075 3.6575 4.0075 27 P 0 ;1
L 3.6575 4.0575 3.6575 4.0575 27 P 0 ;1
L 3.6575 4.1075 3.6575 4.1075 27 P 0 ;1
L 3.6575 4.1575 3.6575 4.1575 27 P 0 ;1
L 3.6575 4.2075 3.6575 4.2075 27 P 0 ;1
L 3.6575 4.2575 3.6575 4.2575 27 P 0 ;1
L 3.6575 4.3075 3.6575 4.3075 27 P 0 ;1
L 3.7075 0.1575 3.7075 0.1575 27 P 0 ;1
L 3.7075 0.9075 3.7075 0.9075 27 P 0 ;1
L 3.7075 0.9575 3.7075 0.9575 27 P 0 ;1
L 3.7075 1.0075 3.7075 1.0075 27 P 0 ;1
L 3.7075 1.0575 3.7075 1.0575 27 P 0 ;1
L 3.7075 1.1075 3.7075 1.1075 27 P 0 ;1
L 3.7075 1.1575 3.7075 1.1575 27 P 0 ;1
L 3.7075 1.2075 3.7075 1.2075 27 P 0 ;1
L 3.7075 1.2575 3.7075 1.2575 27 P 0 ;1
L 3.7075 1.3075 3.7075 1.3075 27 P 0 ;1
L 3.7075 1.3575 3.7075 1.3575 27 P 0 ;1
L 3.7075 1.4075 3.7075 1.4075 27 P 0 ;1
L 3.7075 1.4575 3.7075 1.4575 27 P 0 ;1
L 3.7075 1.5075 3.7075 1.5075 27 P 0 ;1
L 3.7075 1.5575 3.7075 1.5575 27 P 0 ;1
L 3.7075 1.6075 3.7075 1.6075 27 P 0 ;1
L 3.7075 1.6575 3.7075 1.6575 27 P 0 ;1
L 3.7075 1.7075 3.7075 1.7075 27 P 0 ;1
L 3.7075 1.7575 3.7075 1.7575 27 P 0 ;1
L 3.7075 1.8075 3.7075 1.8075 27 P 0 ;1
L 3.7075 1.8575 3.7075 1.8575 27 P 0 ;1
L 3.7075 1.9075 3.7075 1.9075 27 P 0 ;1
L 3.7075 1.9575 3.7075 1.9575 27 P 0 ;1
L 3.7075 2.0075 3.7075 2.0075 27 P 0 ;1
L 3.7075 2.0575 3.7075 2.0575 27 P 0 ;1
L 3.7075 2.1075 3.7075 2.1075 27 P 0 ;1
L 3.7075 2.1575 3.7075 2.1575 27 P 0 ;1
L 3.7075 2.2075 3.7075 2.2075 27 P 0 ;1
L 3.7075 2.2575 3.7075 2.2575 27 P 0 ;1
L 3.7075 2.3075 3.7075 2.3075 27 P 0 ;1
L 3.7075 2.3575 3.7075 2.3575 27 P 0 ;1
L 3.7075 2.4075 3.7075 2.4075 27 P 0 ;1
L 3.7075 2.4575 3.7075 2.4575 27 P 0 ;1
L 3.7075 2.5075 3.7075 2.5075 27 P 0 ;1
L 3.7075 2.5575 3.7075 2.5575 27 P 0 ;1
L 3.7075 2.6075 3.7075 2.6075 27 P 0 ;1
L 3.7075 2.6575 3.7075 2.6575 27 P 0 ;1
L 3.7075 2.7075 3.7075 2.7075 27 P 0 ;1
L 3.7075 2.7575 3.7075 2.7575 27 P 0 ;1
L 3.7075 2.8075 3.7075 2.8075 27 P 0 ;1
L 3.7075 2.8575 3.7075 2.8575 27 P 0 ;1
L 3.7075 2.9075 3.7075 2.9075 27 P 0 ;1
L 3.7075 2.9575 3.7075 2.9575 27 P 0 ;1
L 3.7075 3.0075 3.7075 3.0075 27 P 0 ;1
L 3.7075 3.0575 3.7075 3.0575 27 P 0 ;1
L 3.7075 3.1075 3.7075 3.1075 27 P 0 ;1
L 3.7075 3.1575 3.7075 3.1575 27 P 0 ;1
L 3.7075 3.2075 3.7075 3.2075 27 P 0 ;1
L 3.7075 3.2575 3.7075 3.2575 27 P 0 ;1
L 3.7075 3.3075 3.7075 3.3075 27 P 0 ;1
L 3.7075 3.3575 3.7075 3.3575 27 P 0 ;1
L 3.7075 3.4075 3.7075 3.4075 27 P 0 ;1
L 3.7075 3.4575 3.7075 3.4575 27 P 0 ;1
L 3.7075 3.5075 3.7075 3.5075 27 P 0 ;1
L 3.7075 3.5575 3.7075 3.5575 27 P 0 ;1
L 3.7075 3.6075 3.7075 3.6075 27 P 0 ;1
L 3.7075 3.6575 3.7075 3.6575 27 P 0 ;1
L 3.7075 3.7075 3.7075 3.7075 27 P 0 ;1
L 3.7075 3.7575 3.7075 3.7575 27 P 0 ;1
L 3.7075 3.8075 3.7075 3.8075 27 P 0 ;1
L 3.7075 3.8575 3.7075 3.8575 27 P 0 ;1
L 3.7075 3.9075 3.7075 3.9075 27 P 0 ;1
L 3.7075 3.9575 3.7075 3.9575 27 P 0 ;1
L 3.7075 4.0075 3.7075 4.0075 27 P 0 ;1
L 3.7075 4.0575 3.7075 4.0575 27 P 0 ;1
L 3.7075 4.1075 3.7075 4.1075 27 P 0 ;1
L 3.7075 4.1575 3.7075 4.1575 27 P 0 ;1
L 3.7075 4.2075 3.7075 4.2075 27 P 0 ;1
L 3.7075 4.2575 3.7075 4.2575 27 P 0 ;1
L 3.7075 4.3075 3.7075 4.3075 27 P 0 ;1
L 3.7575 0.9075 3.7575 0.9075 27 P 0 ;1
L 3.7575 0.9575 3.7575 0.9575 27 P 0 ;1
L 3.7575 1.0075 3.7575 1.0075 27 P 0 ;1
L 3.7575 1.0575 3.7575 1.0575 27 P 0 ;1
L 3.7575 1.1075 3.7575 1.1075 27 P 0 ;1
L 3.7575 1.1575 3.7575 1.1575 27 P 0 ;1
L 3.7575 1.2075 3.7575 1.2075 27 P 0 ;1
L 3.7575 1.2575 3.7575 1.2575 27 P 0 ;1
L 3.7575 1.3075 3.7575 1.3075 27 P 0 ;1
L 3.7575 1.3575 3.7575 1.3575 27 P 0 ;1
L 3.7575 1.4075 3.7575 1.4075 27 P 0 ;1
L 3.7575 1.4575 3.7575 1.4575 27 P 0 ;1
L 3.7575 1.5075 3.7575 1.5075 27 P 0 ;1
L 3.7575 1.5575 3.7575 1.5575 27 P 0 ;1
L 3.7575 1.6075 3.7575 1.6075 27 P 0 ;1
L 3.7575 1.6575 3.7575 1.6575 27 P 0 ;1
L 3.7575 1.7075 3.7575 1.7075 27 P 0 ;1
L 3.7575 1.7575 3.7575 1.7575 27 P 0 ;1
L 3.7575 1.8075 3.7575 1.8075 27 P 0 ;1
L 3.7575 1.8575 3.7575 1.8575 27 P 0 ;1
L 3.7575 1.9075 3.7575 1.9075 27 P 0 ;1
L 3.7575 1.9575 3.7575 1.9575 27 P 0 ;1
L 3.7575 2.0075 3.7575 2.0075 27 P 0 ;1
L 3.7575 2.0575 3.7575 2.0575 27 P 0 ;1
L 3.7575 2.1075 3.7575 2.1075 27 P 0 ;1
L 3.7575 2.1575 3.7575 2.1575 27 P 0 ;1
L 3.7575 2.2075 3.7575 2.2075 27 P 0 ;1
L 3.7575 2.2575 3.7575 2.2575 27 P 0 ;1
L 3.7575 2.3075 3.7575 2.3075 27 P 0 ;1
L 3.7575 2.3575 3.7575 2.3575 27 P 0 ;1
L 3.7575 2.4075 3.7575 2.4075 27 P 0 ;1
L 3.7575 2.4575 3.7575 2.4575 27 P 0 ;1
L 3.7575 2.5075 3.7575 2.5075 27 P 0 ;1
L 3.7575 2.5575 3.7575 2.5575 27 P 0 ;1
L 3.7575 2.6075 3.7575 2.6075 27 P 0 ;1
L 3.7575 2.6575 3.7575 2.6575 27 P 0 ;1
L 3.7575 2.7075 3.7575 2.7075 27 P 0 ;1
L 3.7575 2.7575 3.7575 2.7575 27 P 0 ;1
L 3.7575 2.8075 3.7575 2.8075 27 P 0 ;1
L 3.7575 2.8575 3.7575 2.8575 27 P 0 ;1
L 3.7575 2.9075 3.7575 2.9075 27 P 0 ;1
L 3.7575 2.9575 3.7575 2.9575 27 P 0 ;1
L 3.7575 3.0075 3.7575 3.0075 27 P 0 ;1
L 3.7575 3.0575 3.7575 3.0575 27 P 0 ;1
L 3.7575 3.1075 3.7575 3.1075 27 P 0 ;1
L 3.7575 3.1575 3.7575 3.1575 27 P 0 ;1
L 3.7575 3.2075 3.7575 3.2075 27 P 0 ;1
L 3.7575 3.2575 3.7575 3.2575 27 P 0 ;1
L 3.7575 3.3075 3.7575 3.3075 27 P 0 ;1
L 3.7575 3.3575 3.7575 3.3575 27 P 0 ;1
L 3.7575 3.4075 3.7575 3.4075 27 P 0 ;1
L 3.7575 3.4575 3.7575 3.4575 27 P 0 ;1
L 3.7575 3.5075 3.7575 3.5075 27 P 0 ;1
L 3.7575 3.5575 3.7575 3.5575 27 P 0 ;1
L 3.7575 3.6075 3.7575 3.6075 27 P 0 ;1
L 3.7575 3.6575 3.7575 3.6575 27 P 0 ;1
L 3.7575 3.7075 3.7575 3.7075 27 P 0 ;1
L 3.7575 3.7575 3.7575 3.7575 27 P 0 ;1
L 3.7575 3.8075 3.7575 3.8075 27 P 0 ;1
L 3.7575 3.8575 3.7575 3.8575 27 P 0 ;1
L 3.7575 3.9075 3.7575 3.9075 27 P 0 ;1
L 3.7575 3.9575 3.7575 3.9575 27 P 0 ;1
L 3.7575 4.0075 3.7575 4.0075 27 P 0 ;1
L 3.7575 4.0575 3.7575 4.0575 27 P 0 ;1
L 3.7575 4.1075 3.7575 4.1075 27 P 0 ;1
L 3.7575 4.1575 3.7575 4.1575 27 P 0 ;1
L 3.7575 4.2075 3.7575 4.2075 27 P 0 ;1
L 3.7575 4.2575 3.7575 4.2575 27 P 0 ;1
L 3.7575 4.3075 3.7575 4.3075 27 P 0 ;1
L 3.8075 0.1575 3.8075 0.1575 27 P 0 ;1
L 3.8075 0.9075 3.8075 0.9075 27 P 0 ;1
L 3.8075 0.9575 3.8075 0.9575 27 P 0 ;1
L 3.8075 1.0075 3.8075 1.0075 27 P 0 ;1
L 3.8075 1.0575 3.8075 1.0575 27 P 0 ;1
L 3.8075 1.1075 3.8075 1.1075 27 P 0 ;1
L 3.8075 1.1575 3.8075 1.1575 27 P 0 ;1
L 3.8075 1.2075 3.8075 1.2075 27 P 0 ;1
L 3.8075 1.2575 3.8075 1.2575 27 P 0 ;1
L 3.8075 1.3075 3.8075 1.3075 27 P 0 ;1
L 3.8075 1.3575 3.8075 1.3575 27 P 0 ;1
L 3.8075 1.4075 3.8075 1.4075 27 P 0 ;1
L 3.8075 1.4575 3.8075 1.4575 27 P 0 ;1
L 3.8075 1.5075 3.8075 1.5075 27 P 0 ;1
L 3.8075 1.5575 3.8075 1.5575 27 P 0 ;1
L 3.8075 1.6075 3.8075 1.6075 27 P 0 ;1
L 3.8075 1.6575 3.8075 1.6575 27 P 0 ;1
L 3.8075 1.7075 3.8075 1.7075 27 P 0 ;1
L 3.8075 1.7575 3.8075 1.7575 27 P 0 ;1
L 3.8075 1.8075 3.8075 1.8075 27 P 0 ;1
L 3.8075 1.8575 3.8075 1.8575 27 P 0 ;1
L 3.8075 1.9075 3.8075 1.9075 27 P 0 ;1
L 3.8075 1.9575 3.8075 1.9575 27 P 0 ;1
L 3.8075 2.0075 3.8075 2.0075 27 P 0 ;1
L 3.8075 2.0575 3.8075 2.0575 27 P 0 ;1
L 3.8075 2.1075 3.8075 2.1075 27 P 0 ;1
L 3.8075 2.1575 3.8075 2.1575 27 P 0 ;1
L 3.8075 2.2075 3.8075 2.2075 27 P 0 ;1
L 3.8075 2.2575 3.8075 2.2575 27 P 0 ;1
L 3.8075 2.3075 3.8075 2.3075 27 P 0 ;1
L 3.8075 2.3575 3.8075 2.3575 27 P 0 ;1
L 3.8075 2.4075 3.8075 2.4075 27 P 0 ;1
L 3.8075 2.4575 3.8075 2.4575 27 P 0 ;1
L 3.8075 2.5075 3.8075 2.5075 27 P 0 ;1
L 3.8075 2.5575 3.8075 2.5575 27 P 0 ;1
L 3.8075 2.7575 3.8075 2.7575 27 P 0 ;1
L 3.8075 2.8075 3.8075 2.8075 27 P 0 ;1
L 3.8075 2.8575 3.8075 2.8575 27 P 0 ;1
L 3.8075 2.9075 3.8075 2.9075 27 P 0 ;1
L 3.8075 2.9575 3.8075 2.9575 27 P 0 ;1
L 3.8075 3.0075 3.8075 3.0075 27 P 0 ;1
L 3.8075 3.0575 3.8075 3.0575 27 P 0 ;1
L 3.8075 3.1075 3.8075 3.1075 27 P 0 ;1
L 3.8075 3.1575 3.8075 3.1575 27 P 0 ;1
L 3.8075 3.2075 3.8075 3.2075 27 P 0 ;1
L 3.8075 3.2575 3.8075 3.2575 27 P 0 ;1
L 3.8075 3.3075 3.8075 3.3075 27 P 0 ;1
L 3.8075 3.3575 3.8075 3.3575 27 P 0 ;1
L 3.8075 3.4075 3.8075 3.4075 27 P 0 ;1
L 3.8075 3.4575 3.8075 3.4575 27 P 0 ;1
L 3.8075 3.5075 3.8075 3.5075 27 P 0 ;1
L 3.8075 3.5575 3.8075 3.5575 27 P 0 ;1
L 3.8075 3.6075 3.8075 3.6075 27 P 0 ;1
L 3.8075 3.6575 3.8075 3.6575 27 P 0 ;1
L 3.8075 3.7075 3.8075 3.7075 27 P 0 ;1
L 3.8075 3.7575 3.8075 3.7575 27 P 0 ;1
L 3.8075 3.8075 3.8075 3.8075 27 P 0 ;1
L 3.8075 3.8575 3.8075 3.8575 27 P 0 ;1
L 3.8075 3.9075 3.8075 3.9075 27 P 0 ;1
L 3.8075 3.9575 3.8075 3.9575 27 P 0 ;1
L 3.8075 4.0075 3.8075 4.0075 27 P 0 ;1
L 3.8075 4.0575 3.8075 4.0575 27 P 0 ;1
L 3.8075 4.1075 3.8075 4.1075 27 P 0 ;1
L 3.8075 4.1575 3.8075 4.1575 27 P 0 ;1
L 3.8075 4.2075 3.8075 4.2075 27 P 0 ;1
L 3.8075 4.2575 3.8075 4.2575 27 P 0 ;1
L 3.8075 4.3075 3.8075 4.3075 27 P 0 ;1
L 3.8075 5.4575 3.8075 5.4575 27 P 0 ;1
L 3.8075 5.5075 3.8075 5.5075 27 P 0 ;1
L 3.8075 5.5575 3.8075 5.5575 27 P 0 ;1
L 3.8075 5.6075 3.8075 5.6075 27 P 0 ;1
L 3.8075 5.6575 3.8075 5.6575 27 P 0 ;1
L 3.8575 0.1575 3.8575 0.1575 27 P 0 ;1
L 3.8575 0.2075 3.8575 0.2075 27 P 0 ;1
L 3.8575 0.2575 3.8575 0.2575 27 P 0 ;1
L 3.8575 0.9075 3.8575 0.9075 27 P 0 ;1
L 3.8575 0.9575 3.8575 0.9575 27 P 0 ;1
L 3.8575 1.0075 3.8575 1.0075 27 P 0 ;1
L 3.8575 1.0575 3.8575 1.0575 27 P 0 ;1
L 3.8575 1.1075 3.8575 1.1075 27 P 0 ;1
L 3.8575 1.1575 3.8575 1.1575 27 P 0 ;1
L 3.8575 1.2075 3.8575 1.2075 27 P 0 ;1
L 3.8575 1.2575 3.8575 1.2575 27 P 0 ;1
L 3.8575 1.3075 3.8575 1.3075 27 P 0 ;1
L 3.8575 1.3575 3.8575 1.3575 27 P 0 ;1
L 3.8575 1.4075 3.8575 1.4075 27 P 0 ;1
L 3.8575 1.4575 3.8575 1.4575 27 P 0 ;1
L 3.8575 1.5075 3.8575 1.5075 27 P 0 ;1
L 3.8575 1.5575 3.8575 1.5575 27 P 0 ;1
L 3.8575 1.6075 3.8575 1.6075 27 P 0 ;1
L 3.8575 1.6575 3.8575 1.6575 27 P 0 ;1
L 3.8575 1.7075 3.8575 1.7075 27 P 0 ;1
L 3.8575 1.7575 3.8575 1.7575 27 P 0 ;1
L 3.8575 1.8075 3.8575 1.8075 27 P 0 ;1
L 3.8575 1.8575 3.8575 1.8575 27 P 0 ;1
L 3.8575 1.9075 3.8575 1.9075 27 P 0 ;1
L 3.8575 1.9575 3.8575 1.9575 27 P 0 ;1
L 3.8575 2.0075 3.8575 2.0075 27 P 0 ;1
L 3.8575 2.0575 3.8575 2.0575 27 P 0 ;1
L 3.8575 2.1075 3.8575 2.1075 27 P 0 ;1
L 3.8575 2.1575 3.8575 2.1575 27 P 0 ;1
L 3.8575 2.2075 3.8575 2.2075 27 P 0 ;1
L 3.8575 2.2575 3.8575 2.2575 27 P 0 ;1
L 3.8575 2.3075 3.8575 2.3075 27 P 0 ;1
L 3.8575 2.3575 3.8575 2.3575 27 P 0 ;1
L 3.8575 2.4075 3.8575 2.4075 27 P 0 ;1
L 3.8575 2.4575 3.8575 2.4575 27 P 0 ;1
L 3.8575 2.5075 3.8575 2.5075 27 P 0 ;1
L 3.8575 2.7575 3.8575 2.7575 27 P 0 ;1
L 3.8575 2.8075 3.8575 2.8075 27 P 0 ;1
L 3.8575 2.8575 3.8575 2.8575 27 P 0 ;1
L 3.8575 2.9075 3.8575 2.9075 27 P 0 ;1
L 3.8575 2.9575 3.8575 2.9575 27 P 0 ;1
L 3.8575 3.0075 3.8575 3.0075 27 P 0 ;1
L 3.8575 3.0575 3.8575 3.0575 27 P 0 ;1
L 3.8575 3.1075 3.8575 3.1075 27 P 0 ;1
L 3.8575 3.1575 3.8575 3.1575 27 P 0 ;1
L 3.8575 3.2075 3.8575 3.2075 27 P 0 ;1
L 3.8575 3.2575 3.8575 3.2575 27 P 0 ;1
L 3.8575 3.3075 3.8575 3.3075 27 P 0 ;1
L 3.8575 3.3575 3.8575 3.3575 27 P 0 ;1
L 3.8575 3.4075 3.8575 3.4075 27 P 0 ;1
L 3.8575 3.4575 3.8575 3.4575 27 P 0 ;1
L 3.8575 3.5075 3.8575 3.5075 27 P 0 ;1
L 3.8575 3.5575 3.8575 3.5575 27 P 0 ;1
L 3.8575 3.6075 3.8575 3.6075 27 P 0 ;1
L 3.8575 3.6575 3.8575 3.6575 27 P 0 ;1
L 3.8575 3.7075 3.8575 3.7075 27 P 0 ;1
L 3.8575 3.7575 3.8575 3.7575 27 P 0 ;1
L 3.8575 3.8075 3.8575 3.8075 27 P 0 ;1
L 3.8575 3.8575 3.8575 3.8575 27 P 0 ;1
L 3.8575 3.9075 3.8575 3.9075 27 P 0 ;1
L 3.8575 3.9575 3.8575 3.9575 27 P 0 ;1
L 3.8575 4.0075 3.8575 4.0075 27 P 0 ;1
L 3.8575 4.0575 3.8575 4.0575 27 P 0 ;1
L 3.8575 4.1075 3.8575 4.1075 27 P 0 ;1
L 3.8575 4.1575 3.8575 4.1575 27 P 0 ;1
L 3.8575 4.2075 3.8575 4.2075 27 P 0 ;1
L 3.8575 4.2575 3.8575 4.2575 27 P 0 ;1
L 3.8575 4.3075 3.8575 4.3075 27 P 0 ;1
L 3.8575 5.6075 3.8575 5.6075 27 P 0 ;1
L 3.8575 5.6575 3.8575 5.6575 27 P 0 ;1
L 3.9075 0.1575 3.9075 0.1575 27 P 0 ;1
L 3.9075 0.2075 3.9075 0.2075 27 P 0 ;1
L 3.9075 0.2575 3.9075 0.2575 27 P 0 ;1
L 3.9075 0.3075 3.9075 0.3075 27 P 0 ;1
L 3.9075 0.3575 3.9075 0.3575 27 P 0 ;1
L 3.9075 0.4075 3.9075 0.4075 27 P 0 ;1
L 3.9075 0.4575 3.9075 0.4575 27 P 0 ;1
L 3.9075 0.5075 3.9075 0.5075 27 P 0 ;1
L 3.9075 0.5575 3.9075 0.5575 27 P 0 ;1
L 3.9075 0.6075 3.9075 0.6075 27 P 0 ;1
L 3.9075 0.9075 3.9075 0.9075 27 P 0 ;1
L 3.9075 0.9575 3.9075 0.9575 27 P 0 ;1
L 3.9075 1.0075 3.9075 1.0075 27 P 0 ;1
L 3.9075 1.0575 3.9075 1.0575 27 P 0 ;1
L 3.9075 1.1075 3.9075 1.1075 27 P 0 ;1
L 3.9075 1.1575 3.9075 1.1575 27 P 0 ;1
L 3.9075 1.2075 3.9075 1.2075 27 P 0 ;1
L 3.9075 1.2575 3.9075 1.2575 27 P 0 ;1
L 3.9075 1.3075 3.9075 1.3075 27 P 0 ;1
L 3.9075 1.3575 3.9075 1.3575 27 P 0 ;1
L 3.9075 1.4075 3.9075 1.4075 27 P 0 ;1
L 3.9075 1.4575 3.9075 1.4575 27 P 0 ;1
L 3.9075 1.5075 3.9075 1.5075 27 P 0 ;1
L 3.9075 1.5575 3.9075 1.5575 27 P 0 ;1
L 3.9075 1.6075 3.9075 1.6075 27 P 0 ;1
L 3.9075 1.6575 3.9075 1.6575 27 P 0 ;1
L 3.9075 1.7075 3.9075 1.7075 27 P 0 ;1
L 3.9075 1.7575 3.9075 1.7575 27 P 0 ;1
L 3.9075 1.8075 3.9075 1.8075 27 P 0 ;1
L 3.9075 1.8575 3.9075 1.8575 27 P 0 ;1
L 3.9075 1.9075 3.9075 1.9075 27 P 0 ;1
L 3.9075 1.9575 3.9075 1.9575 27 P 0 ;1
L 3.9075 2.0075 3.9075 2.0075 27 P 0 ;1
L 3.9075 2.0575 3.9075 2.0575 27 P 0 ;1
L 3.9075 2.1075 3.9075 2.1075 27 P 0 ;1
L 3.9075 2.1575 3.9075 2.1575 27 P 0 ;1
L 3.9075 2.2075 3.9075 2.2075 27 P 0 ;1
L 3.9075 2.2575 3.9075 2.2575 27 P 0 ;1
L 3.9075 2.3075 3.9075 2.3075 27 P 0 ;1
L 3.9075 2.3575 3.9075 2.3575 27 P 0 ;1
L 3.9075 2.4075 3.9075 2.4075 27 P 0 ;1
L 3.9075 2.4575 3.9075 2.4575 27 P 0 ;1
L 3.9075 2.5075 3.9075 2.5075 27 P 0 ;1
L 3.9075 2.5575 3.9075 2.5575 27 P 0 ;1
L 3.9075 2.7575 3.9075 2.7575 27 P 0 ;1
L 3.9075 2.8075 3.9075 2.8075 27 P 0 ;1
L 3.9075 2.8575 3.9075 2.8575 27 P 0 ;1
L 3.9075 2.9075 3.9075 2.9075 27 P 0 ;1
L 3.9075 2.9575 3.9075 2.9575 27 P 0 ;1
L 3.9075 3.0075 3.9075 3.0075 27 P 0 ;1
L 3.9075 3.0575 3.9075 3.0575 27 P 0 ;1
L 3.9075 3.1075 3.9075 3.1075 27 P 0 ;1
L 3.9075 3.1575 3.9075 3.1575 27 P 0 ;1
L 3.9075 3.2075 3.9075 3.2075 27 P 0 ;1
L 3.9075 3.2575 3.9075 3.2575 27 P 0 ;1
L 3.9075 3.3075 3.9075 3.3075 27 P 0 ;1
L 3.9075 3.3575 3.9075 3.3575 27 P 0 ;1
L 3.9075 3.4075 3.9075 3.4075 27 P 0 ;1
L 3.9075 3.4575 3.9075 3.4575 27 P 0 ;1
L 3.9075 3.5075 3.9075 3.5075 27 P 0 ;1
L 3.9075 3.5575 3.9075 3.5575 27 P 0 ;1
L 3.9075 3.6075 3.9075 3.6075 27 P 0 ;1
L 3.9075 3.6575 3.9075 3.6575 27 P 0 ;1
L 3.9075 3.7075 3.9075 3.7075 27 P 0 ;1
L 3.9075 3.7575 3.9075 3.7575 27 P 0 ;1
L 3.9075 3.8075 3.9075 3.8075 27 P 0 ;1
L 3.9075 3.8575 3.9075 3.8575 27 P 0 ;1
L 3.9075 3.9075 3.9075 3.9075 27 P 0 ;1
L 3.9075 3.9575 3.9075 3.9575 27 P 0 ;1
L 3.9075 4.0075 3.9075 4.0075 27 P 0 ;1
L 3.9075 4.0575 3.9075 4.0575 27 P 0 ;1
L 3.9075 4.1075 3.9075 4.1075 27 P 0 ;1
L 3.9075 4.1575 3.9075 4.1575 27 P 0 ;1
L 3.9075 4.2075 3.9075 4.2075 27 P 0 ;1
L 3.9075 4.2575 3.9075 4.2575 27 P 0 ;1
L 3.9075 4.3075 3.9075 4.3075 27 P 0 ;1
L 3.9575 0.1575 3.9575 0.1575 27 P 0 ;1
L 3.9575 0.2075 3.9575 0.2075 27 P 0 ;1
L 3.9575 0.2575 3.9575 0.2575 27 P 0 ;1
L 3.9575 0.3075 3.9575 0.3075 27 P 0 ;1
L 3.9575 0.3575 3.9575 0.3575 27 P 0 ;1
L 3.9575 0.4075 3.9575 0.4075 27 P 0 ;1
L 3.9575 0.4575 3.9575 0.4575 27 P 0 ;1
L 3.9575 0.5075 3.9575 0.5075 27 P 0 ;1
L 3.9575 0.5575 3.9575 0.5575 27 P 0 ;1
L 3.9575 0.6075 3.9575 0.6075 27 P 0 ;1
L 3.9575 0.6575 3.9575 0.6575 27 P 0 ;1
L 3.9575 0.7075 3.9575 0.7075 27 P 0 ;1
L 3.9575 0.7575 3.9575 0.7575 27 P 0 ;1
L 3.9575 0.8075 3.9575 0.8075 27 P 0 ;1
L 3.9575 0.8575 3.9575 0.8575 27 P 0 ;1
L 3.9575 0.9075 3.9575 0.9075 27 P 0 ;1
L 3.9575 0.9575 3.9575 0.9575 27 P 0 ;1
L 3.9575 1.0075 3.9575 1.0075 27 P 0 ;1
L 3.9575 1.0575 3.9575 1.0575 27 P 0 ;1
L 3.9575 1.1075 3.9575 1.1075 27 P 0 ;1
L 3.9575 1.1575 3.9575 1.1575 27 P 0 ;1
L 3.9575 1.2075 3.9575 1.2075 27 P 0 ;1
L 3.9575 1.2575 3.9575 1.2575 27 P 0 ;1
L 3.9575 1.3075 3.9575 1.3075 27 P 0 ;1
L 3.9575 1.3575 3.9575 1.3575 27 P 0 ;1
L 3.9575 1.4075 3.9575 1.4075 27 P 0 ;1
L 3.9575 1.4575 3.9575 1.4575 27 P 0 ;1
L 3.9575 1.5075 3.9575 1.5075 27 P 0 ;1
L 3.9575 1.5575 3.9575 1.5575 27 P 0 ;1
L 3.9575 1.6075 3.9575 1.6075 27 P 0 ;1
L 3.9575 1.6575 3.9575 1.6575 27 P 0 ;1
L 3.9575 1.7075 3.9575 1.7075 27 P 0 ;1
L 3.9575 1.7575 3.9575 1.7575 27 P 0 ;1
L 3.9575 1.8075 3.9575 1.8075 27 P 0 ;1
L 3.9575 1.8575 3.9575 1.8575 27 P 0 ;1
L 3.9575 1.9075 3.9575 1.9075 27 P 0 ;1
L 3.9575 1.9575 3.9575 1.9575 27 P 0 ;1
L 3.9575 2.0075 3.9575 2.0075 27 P 0 ;1
L 3.9575 2.0575 3.9575 2.0575 27 P 0 ;1
L 3.9575 2.1075 3.9575 2.1075 27 P 0 ;1
L 3.9575 2.1575 3.9575 2.1575 27 P 0 ;1
L 3.9575 2.2075 3.9575 2.2075 27 P 0 ;1
L 3.9575 2.2575 3.9575 2.2575 27 P 0 ;1
L 3.9575 2.3075 3.9575 2.3075 27 P 0 ;1
L 3.9575 2.3575 3.9575 2.3575 27 P 0 ;1
L 3.9575 2.4075 3.9575 2.4075 27 P 0 ;1
L 3.9575 2.4575 3.9575 2.4575 27 P 0 ;1
L 3.9575 2.5075 3.9575 2.5075 27 P 0 ;1
L 3.9575 2.7075 3.9575 2.7075 27 P 0 ;1
L 3.9575 2.7575 3.9575 2.7575 27 P 0 ;1
L 3.9575 2.8075 3.9575 2.8075 27 P 0 ;1
L 3.9575 2.8575 3.9575 2.8575 27 P 0 ;1
L 3.9575 2.9075 3.9575 2.9075 27 P 0 ;1
L 3.9575 2.9575 3.9575 2.9575 27 P 0 ;1
L 3.9575 3.0075 3.9575 3.0075 27 P 0 ;1
L 3.9575 3.0575 3.9575 3.0575 27 P 0 ;1
L 3.9575 3.1075 3.9575 3.1075 27 P 0 ;1
L 3.9575 3.1575 3.9575 3.1575 27 P 0 ;1
L 3.9575 3.2075 3.9575 3.2075 27 P 0 ;1
L 3.9575 3.2575 3.9575 3.2575 27 P 0 ;1
L 3.9575 3.3075 3.9575 3.3075 27 P 0 ;1
L 3.9575 3.3575 3.9575 3.3575 27 P 0 ;1
L 3.9575 3.4075 3.9575 3.4075 27 P 0 ;1
L 3.9575 3.4575 3.9575 3.4575 27 P 0 ;1
L 3.9575 3.5075 3.9575 3.5075 27 P 0 ;1
L 3.9575 3.5575 3.9575 3.5575 27 P 0 ;1
L 3.9575 3.6075 3.9575 3.6075 27 P 0 ;1
L 3.9575 3.6575 3.9575 3.6575 27 P 0 ;1
L 3.9575 3.7075 3.9575 3.7075 27 P 0 ;1
L 3.9575 3.7575 3.9575 3.7575 27 P 0 ;1
L 3.9575 3.8075 3.9575 3.8075 27 P 0 ;1
L 3.9575 3.8575 3.9575 3.8575 27 P 0 ;1
L 3.9575 3.9075 3.9575 3.9075 27 P 0 ;1
L 3.9575 3.9575 3.9575 3.9575 27 P 0 ;1
L 3.9575 4.0075 3.9575 4.0075 27 P 0 ;1
L 3.9575 4.0575 3.9575 4.0575 27 P 0 ;1
L 3.9575 4.1075 3.9575 4.1075 27 P 0 ;1
L 3.9575 4.1575 3.9575 4.1575 27 P 0 ;1
L 3.9575 4.2075 3.9575 4.2075 27 P 0 ;1
L 3.9575 4.2575 3.9575 4.2575 27 P 0 ;1
L 4.0075 0.1575 4.0075 0.1575 27 P 0 ;1
L 4.0075 0.2075 4.0075 0.2075 27 P 0 ;1
L 4.0075 0.2575 4.0075 0.2575 27 P 0 ;1
L 4.0075 0.3075 4.0075 0.3075 27 P 0 ;1
L 4.0075 0.3575 4.0075 0.3575 27 P 0 ;1
L 4.0075 0.4075 4.0075 0.4075 27 P 0 ;1
L 4.0075 0.4575 4.0075 0.4575 27 P 0 ;1
L 4.0075 0.5075 4.0075 0.5075 27 P 0 ;1
L 4.0075 0.5575 4.0075 0.5575 27 P 0 ;1
L 4.0075 0.6075 4.0075 0.6075 27 P 0 ;1
L 4.0075 0.6575 4.0075 0.6575 27 P 0 ;1
L 4.0075 0.7075 4.0075 0.7075 27 P 0 ;1
L 4.0075 0.7575 4.0075 0.7575 27 P 0 ;1
L 4.0075 0.8075 4.0075 0.8075 27 P 0 ;1
L 4.0075 0.8575 4.0075 0.8575 27 P 0 ;1
L 4.0075 0.9075 4.0075 0.9075 27 P 0 ;1
L 4.0075 0.9575 4.0075 0.9575 27 P 0 ;1
L 4.0075 1.0075 4.0075 1.0075 27 P 0 ;1
L 4.0075 1.0575 4.0075 1.0575 27 P 0 ;1
L 4.0075 1.1075 4.0075 1.1075 27 P 0 ;1
L 4.0075 1.1575 4.0075 1.1575 27 P 0 ;1
L 4.0075 1.2075 4.0075 1.2075 27 P 0 ;1
L 4.0075 1.2575 4.0075 1.2575 27 P 0 ;1
L 4.0075 1.3075 4.0075 1.3075 27 P 0 ;1
L 4.0075 1.3575 4.0075 1.3575 27 P 0 ;1
L 4.0075 1.4075 4.0075 1.4075 27 P 0 ;1
L 4.0075 1.4575 4.0075 1.4575 27 P 0 ;1
L 4.0075 1.5075 4.0075 1.5075 27 P 0 ;1
L 4.0075 1.5575 4.0075 1.5575 27 P 0 ;1
L 4.0075 1.6075 4.0075 1.6075 27 P 0 ;1
L 4.0075 1.6575 4.0075 1.6575 27 P 0 ;1
L 4.0075 1.7075 4.0075 1.7075 27 P 0 ;1
L 4.0075 1.7575 4.0075 1.7575 27 P 0 ;1
L 4.0075 1.8075 4.0075 1.8075 27 P 0 ;1
L 4.0075 1.8575 4.0075 1.8575 27 P 0 ;1
L 4.0075 1.9075 4.0075 1.9075 27 P 0 ;1
L 4.0075 1.9575 4.0075 1.9575 27 P 0 ;1
L 4.0075 2.0075 4.0075 2.0075 27 P 0 ;1
L 4.0075 2.0575 4.0075 2.0575 27 P 0 ;1
L 4.0075 2.1075 4.0075 2.1075 27 P 0 ;1
L 4.0075 2.1575 4.0075 2.1575 27 P 0 ;1
L 4.0075 2.2075 4.0075 2.2075 27 P 0 ;1
L 4.0075 2.2575 4.0075 2.2575 27 P 0 ;1
L 4.0075 2.3075 4.0075 2.3075 27 P 0 ;1
L 4.0075 2.3575 4.0075 2.3575 27 P 0 ;1
L 4.0075 2.4075 4.0075 2.4075 27 P 0 ;1
L 4.0075 2.4575 4.0075 2.4575 27 P 0 ;1
L 4.0075 2.7075 4.0075 2.7075 27 P 0 ;1
L 4.0075 2.7575 4.0075 2.7575 27 P 0 ;1
L 4.0075 2.8075 4.0075 2.8075 27 P 0 ;1
L 4.0075 2.8575 4.0075 2.8575 27 P 0 ;1
L 4.0075 2.9075 4.0075 2.9075 27 P 0 ;1
L 4.0075 2.9575 4.0075 2.9575 27 P 0 ;1
L 4.0075 3.0075 4.0075 3.0075 27 P 0 ;1
L 4.0075 3.0575 4.0075 3.0575 27 P 0 ;1
L 4.0075 3.1075 4.0075 3.1075 27 P 0 ;1
L 4.0075 3.1575 4.0075 3.1575 27 P 0 ;1
L 4.0075 3.2075 4.0075 3.2075 27 P 0 ;1
L 4.0075 3.2575 4.0075 3.2575 27 P 0 ;1
L 4.0075 3.3075 4.0075 3.3075 27 P 0 ;1
L 4.0075 3.3575 4.0075 3.3575 27 P 0 ;1
L 4.0075 3.4075 4.0075 3.4075 27 P 0 ;1
L 4.0075 3.4575 4.0075 3.4575 27 P 0 ;1
L 4.0075 3.5075 4.0075 3.5075 27 P 0 ;1
L 4.0075 3.5575 4.0075 3.5575 27 P 0 ;1
L 4.0075 3.6075 4.0075 3.6075 27 P 0 ;1
L 4.0075 3.6575 4.0075 3.6575 27 P 0 ;1
L 4.0075 3.7075 4.0075 3.7075 27 P 0 ;1
L 4.0075 3.7575 4.0075 3.7575 27 P 0 ;1
L 4.0075 3.8075 4.0075 3.8075 27 P 0 ;1
L 4.0075 3.8575 4.0075 3.8575 27 P 0 ;1
L 4.0075 3.9075 4.0075 3.9075 27 P 0 ;1
L 4.0075 4.1075 4.0075 4.1075 27 P 0 ;1
L 4.0075 4.1575 4.0075 4.1575 27 P 0 ;1
L 4.0075 4.2075 4.0075 4.2075 27 P 0 ;1
L 4.0075 4.2575 4.0075 4.2575 27 P 0 ;1
L 4.0575 0.1575 4.0575 0.1575 27 P 0 ;1
L 4.0575 0.2075 4.0575 0.2075 27 P 0 ;1
L 4.0575 0.2575 4.0575 0.2575 27 P 0 ;1
L 4.0575 0.3075 4.0575 0.3075 27 P 0 ;1
L 4.0575 0.3575 4.0575 0.3575 27 P 0 ;1
L 4.0575 0.4075 4.0575 0.4075 27 P 0 ;1
L 4.0575 0.4575 4.0575 0.4575 27 P 0 ;1
L 4.0575 0.5075 4.0575 0.5075 27 P 0 ;1
L 4.0575 0.5575 4.0575 0.5575 27 P 0 ;1
L 4.0575 0.6075 4.0575 0.6075 27 P 0 ;1
L 4.0575 0.6575 4.0575 0.6575 27 P 0 ;1
L 4.0575 0.7075 4.0575 0.7075 27 P 0 ;1
L 4.0575 0.7575 4.0575 0.7575 27 P 0 ;1
L 4.0575 0.8075 4.0575 0.8075 27 P 0 ;1
L 4.0575 0.8575 4.0575 0.8575 27 P 0 ;1
L 4.0575 0.9075 4.0575 0.9075 27 P 0 ;1
L 4.0575 0.9575 4.0575 0.9575 27 P 0 ;1
L 4.0575 1.0075 4.0575 1.0075 27 P 0 ;1
L 4.0575 1.0575 4.0575 1.0575 27 P 0 ;1
L 4.0575 1.1075 4.0575 1.1075 27 P 0 ;1
L 4.0575 1.1575 4.0575 1.1575 27 P 0 ;1
L 4.0575 1.2075 4.0575 1.2075 27 P 0 ;1
L 4.0575 1.2575 4.0575 1.2575 27 P 0 ;1
L 4.0575 1.3075 4.0575 1.3075 27 P 0 ;1
L 4.0575 1.3575 4.0575 1.3575 27 P 0 ;1
L 4.0575 1.4075 4.0575 1.4075 27 P 0 ;1
L 4.0575 1.4575 4.0575 1.4575 27 P 0 ;1
L 4.0575 1.5075 4.0575 1.5075 27 P 0 ;1
L 4.0575 1.5575 4.0575 1.5575 27 P 0 ;1
L 4.0575 1.6075 4.0575 1.6075 27 P 0 ;1
L 4.0575 1.6575 4.0575 1.6575 27 P 0 ;1
L 4.0575 1.7075 4.0575 1.7075 27 P 0 ;1
L 4.0575 1.7575 4.0575 1.7575 27 P 0 ;1
L 4.0575 1.8075 4.0575 1.8075 27 P 0 ;1
L 4.0575 1.8575 4.0575 1.8575 27 P 0 ;1
L 4.0575 1.9075 4.0575 1.9075 27 P 0 ;1
L 4.0575 1.9575 4.0575 1.9575 27 P 0 ;1
L 4.0575 2.0075 4.0575 2.0075 27 P 0 ;1
L 4.0575 2.0575 4.0575 2.0575 27 P 0 ;1
L 4.0575 2.1075 4.0575 2.1075 27 P 0 ;1
L 4.0575 2.1575 4.0575 2.1575 27 P 0 ;1
L 4.0575 2.2075 4.0575 2.2075 27 P 0 ;1
L 4.0575 2.2575 4.0575 2.2575 27 P 0 ;1
L 4.0575 2.3075 4.0575 2.3075 27 P 0 ;1
L 4.0575 2.3575 4.0575 2.3575 27 P 0 ;1
L 4.0575 2.4075 4.0575 2.4075 27 P 0 ;1
L 4.0575 2.4575 4.0575 2.4575 27 P 0 ;1
L 4.0575 2.8075 4.0575 2.8075 27 P 0 ;1
L 4.0575 2.8575 4.0575 2.8575 27 P 0 ;1
L 4.0575 2.9075 4.0575 2.9075 27 P 0 ;1
L 4.0575 2.9575 4.0575 2.9575 27 P 0 ;1
L 4.0575 3.0075 4.0575 3.0075 27 P 0 ;1
L 4.0575 3.0575 4.0575 3.0575 27 P 0 ;1
L 4.0575 3.1075 4.0575 3.1075 27 P 0 ;1
L 4.0575 3.1575 4.0575 3.1575 27 P 0 ;1
L 4.0575 3.2075 4.0575 3.2075 27 P 0 ;1
L 4.0575 3.2575 4.0575 3.2575 27 P 0 ;1
L 4.0575 3.3075 4.0575 3.3075 27 P 0 ;1
L 4.0575 3.3575 4.0575 3.3575 27 P 0 ;1
L 4.0575 3.4075 4.0575 3.4075 27 P 0 ;1
L 4.0575 3.4575 4.0575 3.4575 27 P 0 ;1
L 4.0575 3.5075 4.0575 3.5075 27 P 0 ;1
L 4.0575 3.5575 4.0575 3.5575 27 P 0 ;1
L 4.0575 3.6075 4.0575 3.6075 27 P 0 ;1
L 4.0575 3.6575 4.0575 3.6575 27 P 0 ;1
L 4.0575 3.7075 4.0575 3.7075 27 P 0 ;1
L 4.0575 3.7575 4.0575 3.7575 27 P 0 ;1
L 4.0575 3.8075 4.0575 3.8075 27 P 0 ;1
L 4.0575 3.8575 4.0575 3.8575 27 P 0 ;1
L 4.0575 3.9075 4.0575 3.9075 27 P 0 ;1
L 4.0575 4.1575 4.0575 4.1575 27 P 0 ;1
L 4.0575 4.2075 4.0575 4.2075 27 P 0 ;1
L 4.0575 4.2575 4.0575 4.2575 27 P 0 ;1
L 4.1075 0.1575 4.1075 0.1575 27 P 0 ;1
L 4.1075 0.2075 4.1075 0.2075 27 P 0 ;1
L 4.1075 0.2575 4.1075 0.2575 27 P 0 ;1
L 4.1075 0.3075 4.1075 0.3075 27 P 0 ;1
L 4.1075 0.3575 4.1075 0.3575 27 P 0 ;1
L 4.1075 0.4075 4.1075 0.4075 27 P 0 ;1
L 4.1075 0.4575 4.1075 0.4575 27 P 0 ;1
L 4.1075 0.5075 4.1075 0.5075 27 P 0 ;1
L 4.1075 0.5575 4.1075 0.5575 27 P 0 ;1
L 4.1075 0.6075 4.1075 0.6075 27 P 0 ;1
L 4.1075 0.6575 4.1075 0.6575 27 P 0 ;1
L 4.1075 0.7075 4.1075 0.7075 27 P 0 ;1
L 4.1075 0.7575 4.1075 0.7575 27 P 0 ;1
L 4.1075 0.8075 4.1075 0.8075 27 P 0 ;1
L 4.1075 0.8575 4.1075 0.8575 27 P 0 ;1
L 4.1075 0.9075 4.1075 0.9075 27 P 0 ;1
L 4.1075 0.9575 4.1075 0.9575 27 P 0 ;1
L 4.1075 1.0075 4.1075 1.0075 27 P 0 ;1
L 4.1075 1.0575 4.1075 1.0575 27 P 0 ;1
L 4.1075 1.1075 4.1075 1.1075 27 P 0 ;1
L 4.1075 1.1575 4.1075 1.1575 27 P 0 ;1
L 4.1075 1.2075 4.1075 1.2075 27 P 0 ;1
L 4.1075 1.2575 4.1075 1.2575 27 P 0 ;1
L 4.1075 1.3075 4.1075 1.3075 27 P 0 ;1
L 4.1075 1.3575 4.1075 1.3575 27 P 0 ;1
L 4.1075 1.4075 4.1075 1.4075 27 P 0 ;1
L 4.1075 1.4575 4.1075 1.4575 27 P 0 ;1
L 4.1075 1.5075 4.1075 1.5075 27 P 0 ;1
L 4.1075 1.5575 4.1075 1.5575 27 P 0 ;1
L 4.1075 1.6075 4.1075 1.6075 27 P 0 ;1
L 4.1075 1.6575 4.1075 1.6575 27 P 0 ;1
L 4.1075 1.7075 4.1075 1.7075 27 P 0 ;1
L 4.1075 1.7575 4.1075 1.7575 27 P 0 ;1
L 4.1075 1.8075 4.1075 1.8075 27 P 0 ;1
L 4.1075 1.8575 4.1075 1.8575 27 P 0 ;1
L 4.1075 1.9075 4.1075 1.9075 27 P 0 ;1
L 4.1075 1.9575 4.1075 1.9575 27 P 0 ;1
L 4.1075 2.0075 4.1075 2.0075 27 P 0 ;1
L 4.1075 3.7575 4.1075 3.7575 27 P 0 ;1
L 4.1075 3.8075 4.1075 3.8075 27 P 0 ;1
L 4.1075 3.8575 4.1075 3.8575 27 P 0 ;1
L 4.1075 3.9075 4.1075 3.9075 27 P 0 ;1
L 4.1075 4.1575 4.1075 4.1575 27 P 0 ;1
L 4.1075 4.2075 4.1075 4.2075 27 P 0 ;1
L 4.1075 4.2575 4.1075 4.2575 27 P 0 ;1
L 4.1075 4.3075 4.1075 4.3075 27 P 0 ;1
L 4.1575 0.1575 4.1575 0.1575 27 P 0 ;1
L 4.1575 0.2075 4.1575 0.2075 27 P 0 ;1
L 4.1575 0.2575 4.1575 0.2575 27 P 0 ;1
L 4.1575 0.3075 4.1575 0.3075 27 P 0 ;1
L 4.1575 0.3575 4.1575 0.3575 27 P 0 ;1
L 4.1575 0.4075 4.1575 0.4075 27 P 0 ;1
L 4.1575 0.4575 4.1575 0.4575 27 P 0 ;1
L 4.1575 0.5075 4.1575 0.5075 27 P 0 ;1
L 4.1575 0.5575 4.1575 0.5575 27 P 0 ;1
L 4.1575 0.6075 4.1575 0.6075 27 P 0 ;1
L 4.1575 0.6575 4.1575 0.6575 27 P 0 ;1
L 4.1575 0.7075 4.1575 0.7075 27 P 0 ;1
L 4.1575 0.7575 4.1575 0.7575 27 P 0 ;1
L 4.1575 0.8075 4.1575 0.8075 27 P 0 ;1
L 4.1575 0.8575 4.1575 0.8575 27 P 0 ;1
L 4.1575 0.9075 4.1575 0.9075 27 P 0 ;1
L 4.1575 0.9575 4.1575 0.9575 27 P 0 ;1
L 4.1575 1.0075 4.1575 1.0075 27 P 0 ;1
L 4.1575 1.0575 4.1575 1.0575 27 P 0 ;1
L 4.1575 1.1075 4.1575 1.1075 27 P 0 ;1
L 4.1575 1.1575 4.1575 1.1575 27 P 0 ;1
L 4.1575 1.2075 4.1575 1.2075 27 P 0 ;1
L 4.1575 1.2575 4.1575 1.2575 27 P 0 ;1
L 4.1575 1.3075 4.1575 1.3075 27 P 0 ;1
L 4.1575 1.3575 4.1575 1.3575 27 P 0 ;1
L 4.1575 1.4075 4.1575 1.4075 27 P 0 ;1
L 4.1575 1.4575 4.1575 1.4575 27 P 0 ;1
L 4.1575 1.5075 4.1575 1.5075 27 P 0 ;1
L 4.1575 1.5575 4.1575 1.5575 27 P 0 ;1
L 4.1575 1.6075 4.1575 1.6075 27 P 0 ;1
L 4.1575 1.6575 4.1575 1.6575 27 P 0 ;1
L 4.1575 1.7075 4.1575 1.7075 27 P 0 ;1
L 4.1575 1.7575 4.1575 1.7575 27 P 0 ;1
L 4.1575 1.8075 4.1575 1.8075 27 P 0 ;1
L 4.1575 1.8575 4.1575 1.8575 27 P 0 ;1
L 4.1575 1.9075 4.1575 1.9075 27 P 0 ;1
L 4.1575 1.9575 4.1575 1.9575 27 P 0 ;1
L 4.1575 3.7575 4.1575 3.7575 27 P 0 ;1
L 4.1575 3.8075 4.1575 3.8075 27 P 0 ;1
L 4.1575 3.8575 4.1575 3.8575 27 P 0 ;1
L 4.1575 3.9075 4.1575 3.9075 27 P 0 ;1
L 4.1575 3.9575 4.1575 3.9575 27 P 0 ;1
L 4.1575 4.1075 4.1575 4.1075 27 P 0 ;1
L 4.1575 4.1575 4.1575 4.1575 27 P 0 ;1
L 4.1575 4.2075 4.1575 4.2075 27 P 0 ;1
L 4.1575 4.2575 4.1575 4.2575 27 P 0 ;1
L 4.1575 4.3075 4.1575 4.3075 27 P 0 ;1
L 4.1575 4.3575 4.1575 4.3575 27 P 0 ;1
L 4.1575 5.8075 4.1575 5.8075 27 P 0 ;1
L 4.2075 0.1575 4.2075 0.1575 27 P 0 ;1
L 4.2075 0.2075 4.2075 0.2075 27 P 0 ;1
L 4.2075 0.2575 4.2075 0.2575 27 P 0 ;1
L 4.2075 0.3075 4.2075 0.3075 27 P 0 ;1
L 4.2075 0.3575 4.2075 0.3575 27 P 0 ;1
L 4.2075 0.4075 4.2075 0.4075 27 P 0 ;1
L 4.2075 0.4575 4.2075 0.4575 27 P 0 ;1
L 4.2075 0.5075 4.2075 0.5075 27 P 0 ;1
L 4.2075 0.5575 4.2075 0.5575 27 P 0 ;1
L 4.2075 0.6075 4.2075 0.6075 27 P 0 ;1
L 4.2075 0.6575 4.2075 0.6575 27 P 0 ;1
L 4.2075 0.7075 4.2075 0.7075 27 P 0 ;1
L 4.2075 0.7575 4.2075 0.7575 27 P 0 ;1
L 4.2075 0.8075 4.2075 0.8075 27 P 0 ;1
L 4.2075 0.8575 4.2075 0.8575 27 P 0 ;1
L 4.2075 0.9075 4.2075 0.9075 27 P 0 ;1
L 4.2075 0.9575 4.2075 0.9575 27 P 0 ;1
L 4.2075 1.0075 4.2075 1.0075 27 P 0 ;1
L 4.2075 1.0575 4.2075 1.0575 27 P 0 ;1
L 4.2075 1.1075 4.2075 1.1075 27 P 0 ;1
L 4.2075 1.1575 4.2075 1.1575 27 P 0 ;1
L 4.2075 1.2075 4.2075 1.2075 27 P 0 ;1
L 4.2075 1.2575 4.2075 1.2575 27 P 0 ;1
L 4.2075 1.3075 4.2075 1.3075 27 P 0 ;1
L 4.2075 1.3575 4.2075 1.3575 27 P 0 ;1
L 4.2075 1.4075 4.2075 1.4075 27 P 0 ;1
L 4.2075 1.4575 4.2075 1.4575 27 P 0 ;1
L 4.2075 1.5075 4.2075 1.5075 27 P 0 ;1
L 4.2075 1.5575 4.2075 1.5575 27 P 0 ;1
L 4.2075 1.6075 4.2075 1.6075 27 P 0 ;1
L 4.2075 1.6575 4.2075 1.6575 27 P 0 ;1
L 4.2075 1.7075 4.2075 1.7075 27 P 0 ;1
L 4.2075 1.7575 4.2075 1.7575 27 P 0 ;1
L 4.2075 1.8075 4.2075 1.8075 27 P 0 ;1
L 4.2075 1.8575 4.2075 1.8575 27 P 0 ;1
L 4.2075 1.9075 4.2075 1.9075 27 P 0 ;1
L 4.2075 1.9575 4.2075 1.9575 27 P 0 ;1
L 4.2075 3.7575 4.2075 3.7575 27 P 0 ;1
L 4.2075 3.8075 4.2075 3.8075 27 P 0 ;1
L 4.2575 0.1575 4.2575 0.1575 27 P 0 ;1
L 4.2575 0.2075 4.2575 0.2075 27 P 0 ;1
L 4.2575 0.2575 4.2575 0.2575 27 P 0 ;1
L 4.2575 0.3075 4.2575 0.3075 27 P 0 ;1
L 4.2575 0.3575 4.2575 0.3575 27 P 0 ;1
L 4.2575 0.4075 4.2575 0.4075 27 P 0 ;1
L 4.2575 0.4575 4.2575 0.4575 27 P 0 ;1
L 4.2575 0.5075 4.2575 0.5075 27 P 0 ;1
L 4.2575 0.5575 4.2575 0.5575 27 P 0 ;1
L 4.2575 0.6075 4.2575 0.6075 27 P 0 ;1
L 4.2575 0.6575 4.2575 0.6575 27 P 0 ;1
L 4.2575 0.7075 4.2575 0.7075 27 P 0 ;1
L 4.2575 0.7575 4.2575 0.7575 27 P 0 ;1
L 4.2575 0.8075 4.2575 0.8075 27 P 0 ;1
L 4.2575 0.8575 4.2575 0.8575 27 P 0 ;1
L 4.2575 0.9075 4.2575 0.9075 27 P 0 ;1
L 4.2575 0.9575 4.2575 0.9575 27 P 0 ;1
L 4.2575 1.0075 4.2575 1.0075 27 P 0 ;1
L 4.2575 1.0575 4.2575 1.0575 27 P 0 ;1
L 4.2575 1.1075 4.2575 1.1075 27 P 0 ;1
L 4.2575 1.1575 4.2575 1.1575 27 P 0 ;1
L 4.2575 1.2075 4.2575 1.2075 27 P 0 ;1
L 4.2575 1.2575 4.2575 1.2575 27 P 0 ;1
L 4.2575 1.3075 4.2575 1.3075 27 P 0 ;1
L 4.2575 1.3575 4.2575 1.3575 27 P 0 ;1
L 4.2575 1.4075 4.2575 1.4075 27 P 0 ;1
L 4.2575 1.4575 4.2575 1.4575 27 P 0 ;1
L 4.2575 1.5075 4.2575 1.5075 27 P 0 ;1
L 4.2575 1.5575 4.2575 1.5575 27 P 0 ;1
L 4.2575 1.6075 4.2575 1.6075 27 P 0 ;1
L 4.2575 1.6575 4.2575 1.6575 27 P 0 ;1
L 4.2575 1.7075 4.2575 1.7075 27 P 0 ;1
L 4.2575 1.7575 4.2575 1.7575 27 P 0 ;1
L 4.2575 1.8075 4.2575 1.8075 27 P 0 ;1
L 4.2575 1.8575 4.2575 1.8575 27 P 0 ;1
L 4.2575 1.9075 4.2575 1.9075 27 P 0 ;1
L 4.2575 1.9575 4.2575 1.9575 27 P 0 ;1
L 4.2575 3.7575 4.2575 3.7575 27 P 0 ;1
L 4.3075 0.1575 4.3075 0.1575 27 P 0 ;1
L 4.3075 0.2075 4.3075 0.2075 27 P 0 ;1
L 4.3075 0.2575 4.3075 0.2575 27 P 0 ;1
L 4.3075 0.3075 4.3075 0.3075 27 P 0 ;1
L 4.3075 0.3575 4.3075 0.3575 27 P 0 ;1
L 4.3075 0.4075 4.3075 0.4075 27 P 0 ;1
L 4.3075 0.4575 4.3075 0.4575 27 P 0 ;1
L 4.3075 0.5075 4.3075 0.5075 27 P 0 ;1
L 4.3075 0.5575 4.3075 0.5575 27 P 0 ;1
L 4.3075 0.6075 4.3075 0.6075 27 P 0 ;1
L 4.3075 0.6575 4.3075 0.6575 27 P 0 ;1
L 4.3075 0.7075 4.3075 0.7075 27 P 0 ;1
L 4.3075 0.7575 4.3075 0.7575 27 P 0 ;1
L 4.3075 0.8075 4.3075 0.8075 27 P 0 ;1
L 4.3075 0.8575 4.3075 0.8575 27 P 0 ;1
L 4.3075 0.9075 4.3075 0.9075 27 P 0 ;1
L 4.3075 0.9575 4.3075 0.9575 27 P 0 ;1
L 4.3075 1.0075 4.3075 1.0075 27 P 0 ;1
L 4.3075 1.0575 4.3075 1.0575 27 P 0 ;1
L 4.3075 1.1075 4.3075 1.1075 27 P 0 ;1
L 4.3075 1.1575 4.3075 1.1575 27 P 0 ;1
L 4.3075 1.2075 4.3075 1.2075 27 P 0 ;1
L 4.3075 1.2575 4.3075 1.2575 27 P 0 ;1
L 4.3075 1.3075 4.3075 1.3075 27 P 0 ;1
L 4.3075 1.3575 4.3075 1.3575 27 P 0 ;1
L 4.3075 1.4075 4.3075 1.4075 27 P 0 ;1
L 4.3075 1.4575 4.3075 1.4575 27 P 0 ;1
L 4.3075 1.5075 4.3075 1.5075 27 P 0 ;1
L 4.3075 1.5575 4.3075 1.5575 27 P 0 ;1
L 4.3075 1.6075 4.3075 1.6075 27 P 0 ;1
L 4.3075 1.6575 4.3075 1.6575 27 P 0 ;1
L 4.3075 1.7075 4.3075 1.7075 27 P 0 ;1
L 4.3075 1.7575 4.3075 1.7575 27 P 0 ;1
L 4.3075 1.8075 4.3075 1.8075 27 P 0 ;1
L 4.3075 1.8575 4.3075 1.8575 27 P 0 ;1
L 4.3075 1.9075 4.3075 1.9075 27 P 0 ;1
L 4.3075 1.9575 4.3075 1.9575 27 P 0 ;1
L 4.3075 5.2575 4.3075 5.2575 27 P 0 ;1
L 4.3075 5.3075 4.3075 5.3075 27 P 0 ;1
L 4.3075 5.3575 4.3075 5.3575 27 P 0 ;1
L 4.3575 0.1575 4.3575 0.1575 27 P 0 ;1
L 4.3575 0.2075 4.3575 0.2075 27 P 0 ;1
L 4.3575 0.2575 4.3575 0.2575 27 P 0 ;1
L 4.3575 0.3075 4.3575 0.3075 27 P 0 ;1
L 4.3575 0.3575 4.3575 0.3575 27 P 0 ;1
L 4.3575 0.4075 4.3575 0.4075 27 P 0 ;1
L 4.3575 0.4575 4.3575 0.4575 27 P 0 ;1
L 4.3575 0.5075 4.3575 0.5075 27 P 0 ;1
L 4.3575 0.5575 4.3575 0.5575 27 P 0 ;1
L 4.3575 0.6075 4.3575 0.6075 27 P 0 ;1
L 4.3575 0.6575 4.3575 0.6575 27 P 0 ;1
L 4.3575 0.7075 4.3575 0.7075 27 P 0 ;1
L 4.3575 0.7575 4.3575 0.7575 27 P 0 ;1
L 4.3575 0.8075 4.3575 0.8075 27 P 0 ;1
L 4.3575 0.8575 4.3575 0.8575 27 P 0 ;1
L 4.3575 0.9075 4.3575 0.9075 27 P 0 ;1
L 4.3575 0.9575 4.3575 0.9575 27 P 0 ;1
L 4.3575 1.0075 4.3575 1.0075 27 P 0 ;1
L 4.3575 1.0575 4.3575 1.0575 27 P 0 ;1
L 4.3575 1.1075 4.3575 1.1075 27 P 0 ;1
L 4.3575 1.1575 4.3575 1.1575 27 P 0 ;1
L 4.3575 1.2075 4.3575 1.2075 27 P 0 ;1
L 4.3575 1.2575 4.3575 1.2575 27 P 0 ;1
L 4.3575 1.3075 4.3575 1.3075 27 P 0 ;1
L 4.3575 1.3575 4.3575 1.3575 27 P 0 ;1
L 4.3575 1.4075 4.3575 1.4075 27 P 0 ;1
L 4.3575 1.4575 4.3575 1.4575 27 P 0 ;1
L 4.3575 1.5075 4.3575 1.5075 27 P 0 ;1
L 4.3575 1.5575 4.3575 1.5575 27 P 0 ;1
L 4.3575 1.6075 4.3575 1.6075 27 P 0 ;1
L 4.3575 1.6575 4.3575 1.6575 27 P 0 ;1
L 4.3575 1.7075 4.3575 1.7075 27 P 0 ;1
L 4.3575 1.7575 4.3575 1.7575 27 P 0 ;1
L 4.3575 1.8075 4.3575 1.8075 27 P 0 ;1
L 4.3575 1.8575 4.3575 1.8575 27 P 0 ;1
L 4.3575 1.9075 4.3575 1.9075 27 P 0 ;1
L 4.3575 1.9575 4.3575 1.9575 27 P 0 ;1
L 4.3575 5.2575 4.3575 5.2575 27 P 0 ;1
L 4.3575 5.3075 4.3575 5.3075 27 P 0 ;1
L 4.3575 5.3575 4.3575 5.3575 27 P 0 ;1
L 4.4075 0.1575 4.4075 0.1575 27 P 0 ;1
L 4.4075 0.2075 4.4075 0.2075 27 P 0 ;1
L 4.4075 0.2575 4.4075 0.2575 27 P 0 ;1
L 4.4075 0.3075 4.4075 0.3075 27 P 0 ;1
L 4.4075 0.3575 4.4075 0.3575 27 P 0 ;1
L 4.4075 0.4075 4.4075 0.4075 27 P 0 ;1
L 4.4075 0.4575 4.4075 0.4575 27 P 0 ;1
L 4.4075 0.5075 4.4075 0.5075 27 P 0 ;1
L 4.4075 0.5575 4.4075 0.5575 27 P 0 ;1
L 4.4075 0.6075 4.4075 0.6075 27 P 0 ;1
L 4.4075 0.6575 4.4075 0.6575 27 P 0 ;1
L 4.4075 0.7075 4.4075 0.7075 27 P 0 ;1
L 4.4075 0.7575 4.4075 0.7575 27 P 0 ;1
L 4.4075 0.8075 4.4075 0.8075 27 P 0 ;1
L 4.4075 0.8575 4.4075 0.8575 27 P 0 ;1
L 4.4075 0.9075 4.4075 0.9075 27 P 0 ;1
L 4.4075 0.9575 4.4075 0.9575 27 P 0 ;1
L 4.4075 1.0075 4.4075 1.0075 27 P 0 ;1
L 4.4075 1.0575 4.4075 1.0575 27 P 0 ;1
L 4.4075 1.1075 4.4075 1.1075 27 P 0 ;1
L 4.4075 1.1575 4.4075 1.1575 27 P 0 ;1
L 4.4075 1.2075 4.4075 1.2075 27 P 0 ;1
L 4.4075 1.2575 4.4075 1.2575 27 P 0 ;1
L 4.4075 1.3075 4.4075 1.3075 27 P 0 ;1
L 4.4075 1.3575 4.4075 1.3575 27 P 0 ;1
L 4.4075 1.4075 4.4075 1.4075 27 P 0 ;1
L 4.4075 1.4575 4.4075 1.4575 27 P 0 ;1
L 4.4075 1.5075 4.4075 1.5075 27 P 0 ;1
L 4.4075 1.5575 4.4075 1.5575 27 P 0 ;1
L 4.4075 1.6075 4.4075 1.6075 27 P 0 ;1
L 4.4075 1.6575 4.4075 1.6575 27 P 0 ;1
L 4.4075 1.7075 4.4075 1.7075 27 P 0 ;1
L 4.4075 1.7575 4.4075 1.7575 27 P 0 ;1
L 4.4075 1.8075 4.4075 1.8075 27 P 0 ;1
L 4.4075 1.8575 4.4075 1.8575 27 P 0 ;1
L 4.4075 1.9075 4.4075 1.9075 27 P 0 ;1
L 4.4075 1.9575 4.4075 1.9575 27 P 0 ;1
L 4.4075 5.2575 4.4075 5.2575 27 P 0 ;1
L 4.4075 5.3075 4.4075 5.3075 27 P 0 ;1
L 4.4075 5.3575 4.4075 5.3575 27 P 0 ;1
L 4.4575 0.1575 4.4575 0.1575 27 P 0 ;1
L 4.4575 0.2075 4.4575 0.2075 27 P 0 ;1
L 4.4575 0.2575 4.4575 0.2575 27 P 0 ;1
L 4.4575 0.3075 4.4575 0.3075 27 P 0 ;1
L 4.4575 0.3575 4.4575 0.3575 27 P 0 ;1
L 4.4575 0.4075 4.4575 0.4075 27 P 0 ;1
L 4.4575 0.4575 4.4575 0.4575 27 P 0 ;1
L 4.4575 0.5075 4.4575 0.5075 27 P 0 ;1
L 4.4575 0.5575 4.4575 0.5575 27 P 0 ;1
L 4.4575 0.6075 4.4575 0.6075 27 P 0 ;1
L 4.4575 0.6575 4.4575 0.6575 27 P 0 ;1
L 4.4575 0.7075 4.4575 0.7075 27 P 0 ;1
L 4.4575 0.7575 4.4575 0.7575 27 P 0 ;1
L 4.4575 0.8075 4.4575 0.8075 27 P 0 ;1
L 4.4575 0.8575 4.4575 0.8575 27 P 0 ;1
L 4.4575 0.9075 4.4575 0.9075 27 P 0 ;1
L 4.4575 0.9575 4.4575 0.9575 27 P 0 ;1
L 4.4575 1.0075 4.4575 1.0075 27 P 0 ;1
L 4.4575 1.0575 4.4575 1.0575 27 P 0 ;1
L 4.4575 1.1075 4.4575 1.1075 27 P 0 ;1
L 4.4575 1.1575 4.4575 1.1575 27 P 0 ;1
L 4.4575 1.2075 4.4575 1.2075 27 P 0 ;1
L 4.4575 1.2575 4.4575 1.2575 27 P 0 ;1
L 4.4575 1.3075 4.4575 1.3075 27 P 0 ;1
L 4.4575 1.3575 4.4575 1.3575 27 P 0 ;1
L 4.4575 1.4075 4.4575 1.4075 27 P 0 ;1
L 4.4575 1.4575 4.4575 1.4575 27 P 0 ;1
L 4.4575 1.5075 4.4575 1.5075 27 P 0 ;1
L 4.4575 1.5575 4.4575 1.5575 27 P 0 ;1
L 4.4575 1.6075 4.4575 1.6075 27 P 0 ;1
L 4.4575 1.6575 4.4575 1.6575 27 P 0 ;1
L 4.4575 1.7075 4.4575 1.7075 27 P 0 ;1
L 4.4575 1.7575 4.4575 1.7575 27 P 0 ;1
L 4.4575 1.8075 4.4575 1.8075 27 P 0 ;1
L 4.4575 1.8575 4.4575 1.8575 27 P 0 ;1
L 4.4575 1.9075 4.4575 1.9075 27 P 0 ;1
L 4.4575 1.9575 4.4575 1.9575 27 P 0 ;1
L 4.4575 5.2575 4.4575 5.2575 27 P 0 ;1
L 4.4575 5.3075 4.4575 5.3075 27 P 0 ;1
L 4.5075 0.1575 4.5075 0.1575 27 P 0 ;1
L 4.5075 0.2075 4.5075 0.2075 27 P 0 ;1
L 4.5075 0.2575 4.5075 0.2575 27 P 0 ;1
L 4.5075 0.3075 4.5075 0.3075 27 P 0 ;1
L 4.5075 0.3575 4.5075 0.3575 27 P 0 ;1
L 4.5075 0.4075 4.5075 0.4075 27 P 0 ;1
L 4.5075 0.4575 4.5075 0.4575 27 P 0 ;1
L 4.5075 0.5075 4.5075 0.5075 27 P 0 ;1
L 4.5075 0.5575 4.5075 0.5575 27 P 0 ;1
L 4.5075 0.6075 4.5075 0.6075 27 P 0 ;1
L 4.5075 0.6575 4.5075 0.6575 27 P 0 ;1
L 4.5075 0.7075 4.5075 0.7075 27 P 0 ;1
L 4.5075 0.7575 4.5075 0.7575 27 P 0 ;1
L 4.5075 0.8075 4.5075 0.8075 27 P 0 ;1
L 4.5075 0.8575 4.5075 0.8575 27 P 0 ;1
L 4.5075 0.9075 4.5075 0.9075 27 P 0 ;1
L 4.5075 0.9575 4.5075 0.9575 27 P 0 ;1
L 4.5075 1.0075 4.5075 1.0075 27 P 0 ;1
L 4.5075 1.0575 4.5075 1.0575 27 P 0 ;1
L 4.5075 1.1075 4.5075 1.1075 27 P 0 ;1
L 4.5075 1.1575 4.5075 1.1575 27 P 0 ;1
L 4.5075 1.2075 4.5075 1.2075 27 P 0 ;1
L 4.5075 1.2575 4.5075 1.2575 27 P 0 ;1
L 4.5075 1.3075 4.5075 1.3075 27 P 0 ;1
L 4.5075 1.3575 4.5075 1.3575 27 P 0 ;1
L 4.5075 1.4075 4.5075 1.4075 27 P 0 ;1
L 4.5075 1.4575 4.5075 1.4575 27 P 0 ;1
L 4.5075 1.5075 4.5075 1.5075 27 P 0 ;1
L 4.5075 1.5575 4.5075 1.5575 27 P 0 ;1
L 4.5075 1.6075 4.5075 1.6075 27 P 0 ;1
L 4.5075 1.6575 4.5075 1.6575 27 P 0 ;1
L 4.5075 1.7075 4.5075 1.7075 27 P 0 ;1
L 4.5075 1.7575 4.5075 1.7575 27 P 0 ;1
L 4.5075 5.2575 4.5075 5.2575 27 P 0 ;1
L 4.5575 0.1575 4.5575 0.1575 27 P 0 ;1
L 4.5575 0.2075 4.5575 0.2075 27 P 0 ;1
L 4.5575 0.2575 4.5575 0.2575 27 P 0 ;1
L 4.5575 0.3075 4.5575 0.3075 27 P 0 ;1
L 4.5575 0.3575 4.5575 0.3575 27 P 0 ;1
L 4.5575 0.4075 4.5575 0.4075 27 P 0 ;1
L 4.5575 0.4575 4.5575 0.4575 27 P 0 ;1
L 4.5575 0.5075 4.5575 0.5075 27 P 0 ;1
L 4.5575 0.5575 4.5575 0.5575 27 P 0 ;1
L 4.5575 0.6075 4.5575 0.6075 27 P 0 ;1
L 4.5575 0.6575 4.5575 0.6575 27 P 0 ;1
L 4.5575 0.7075 4.5575 0.7075 27 P 0 ;1
L 4.5575 0.7575 4.5575 0.7575 27 P 0 ;1
L 4.5575 0.8075 4.5575 0.8075 27 P 0 ;1
L 4.5575 0.8575 4.5575 0.8575 27 P 0 ;1
L 4.5575 0.9075 4.5575 0.9075 27 P 0 ;1
L 4.5575 0.9575 4.5575 0.9575 27 P 0 ;1
L 4.5575 1.0075 4.5575 1.0075 27 P 0 ;1
L 4.5575 1.0575 4.5575 1.0575 27 P 0 ;1
L 4.5575 1.1075 4.5575 1.1075 27 P 0 ;1
L 4.5575 1.1575 4.5575 1.1575 27 P 0 ;1
L 4.5575 1.2075 4.5575 1.2075 27 P 0 ;1
L 4.5575 1.2575 4.5575 1.2575 27 P 0 ;1
L 4.5575 1.3075 4.5575 1.3075 27 P 0 ;1
L 4.5575 1.3575 4.5575 1.3575 27 P 0 ;1
L 4.5575 1.4075 4.5575 1.4075 27 P 0 ;1
L 4.5575 1.4575 4.5575 1.4575 27 P 0 ;1
L 4.5575 1.5075 4.5575 1.5075 27 P 0 ;1
L 4.5575 1.5575 4.5575 1.5575 27 P 0 ;1
L 4.5575 1.6075 4.5575 1.6075 27 P 0 ;1
L 4.5575 1.6575 4.5575 1.6575 27 P 0 ;1
L 4.5575 1.7075 4.5575 1.7075 27 P 0 ;1
L 4.5575 1.7575 4.5575 1.7575 27 P 0 ;1
L 4.6075 0.1575 4.6075 0.1575 27 P 0 ;1
L 4.6075 0.2075 4.6075 0.2075 27 P 0 ;1
L 4.6075 0.2575 4.6075 0.2575 27 P 0 ;1
L 4.6075 0.3075 4.6075 0.3075 27 P 0 ;1
L 4.6075 0.3575 4.6075 0.3575 27 P 0 ;1
L 4.6075 0.4075 4.6075 0.4075 27 P 0 ;1
L 4.6075 0.4575 4.6075 0.4575 27 P 0 ;1
L 4.6075 0.5075 4.6075 0.5075 27 P 0 ;1
L 4.6075 0.5575 4.6075 0.5575 27 P 0 ;1
L 4.6075 0.6075 4.6075 0.6075 27 P 0 ;1
L 4.6075 0.6575 4.6075 0.6575 27 P 0 ;1
L 4.6075 0.7075 4.6075 0.7075 27 P 0 ;1
L 4.6075 0.7575 4.6075 0.7575 27 P 0 ;1
L 4.6075 0.8075 4.6075 0.8075 27 P 0 ;1
L 4.6075 0.8575 4.6075 0.8575 27 P 0 ;1
L 4.6075 0.9075 4.6075 0.9075 27 P 0 ;1
L 4.6075 0.9575 4.6075 0.9575 27 P 0 ;1
L 4.6075 1.0075 4.6075 1.0075 27 P 0 ;1
L 4.6075 1.0575 4.6075 1.0575 27 P 0 ;1
L 4.6075 1.1075 4.6075 1.1075 27 P 0 ;1
L 4.6075 1.1575 4.6075 1.1575 27 P 0 ;1
L 4.6075 1.2075 4.6075 1.2075 27 P 0 ;1
L 4.6075 1.2575 4.6075 1.2575 27 P 0 ;1
L 4.6075 1.3075 4.6075 1.3075 27 P 0 ;1
L 4.6075 1.3575 4.6075 1.3575 27 P 0 ;1
L 4.6075 1.4075 4.6075 1.4075 27 P 0 ;1
L 4.6075 1.6075 4.6075 1.6075 27 P 0 ;1
L 4.6075 1.6575 4.6075 1.6575 27 P 0 ;1
L 4.6075 1.7075 4.6075 1.7075 27 P 0 ;1
L 4.6075 1.7575 4.6075 1.7575 27 P 0 ;1
L 4.6575 0.1575 4.6575 0.1575 27 P 0 ;1
L 4.6575 0.2075 4.6575 0.2075 27 P 0 ;1
L 4.6575 0.2575 4.6575 0.2575 27 P 0 ;1
L 4.6575 0.3075 4.6575 0.3075 27 P 0 ;1
L 4.6575 0.3575 4.6575 0.3575 27 P 0 ;1
L 4.6575 0.4075 4.6575 0.4075 27 P 0 ;1
L 4.6575 0.4575 4.6575 0.4575 27 P 0 ;1
L 4.6575 0.5075 4.6575 0.5075 27 P 0 ;1
L 4.6575 0.5575 4.6575 0.5575 27 P 0 ;1
L 4.6575 0.6075 4.6575 0.6075 27 P 0 ;1
L 4.6575 0.6575 4.6575 0.6575 27 P 0 ;1
L 4.6575 0.7075 4.6575 0.7075 27 P 0 ;1
L 4.6575 0.7575 4.6575 0.7575 27 P 0 ;1
L 4.6575 0.8075 4.6575 0.8075 27 P 0 ;1
L 4.6575 0.8575 4.6575 0.8575 27 P 0 ;1
L 4.6575 0.9075 4.6575 0.9075 27 P 0 ;1
L 4.6575 0.9575 4.6575 0.9575 27 P 0 ;1
L 4.6575 1.0075 4.6575 1.0075 27 P 0 ;1
L 4.6575 1.0575 4.6575 1.0575 27 P 0 ;1
L 4.6575 1.1075 4.6575 1.1075 27 P 0 ;1
L 4.6575 1.1575 4.6575 1.1575 27 P 0 ;1
L 4.6575 1.2075 4.6575 1.2075 27 P 0 ;1
L 4.6575 1.2575 4.6575 1.2575 27 P 0 ;1
L 4.6575 1.3075 4.6575 1.3075 27 P 0 ;1
L 4.6575 1.7075 4.6575 1.7075 27 P 0 ;1
L 4.6575 1.7575 4.6575 1.7575 27 P 0 ;1
L 4.7075 0.1575 4.7075 0.1575 27 P 0 ;1
L 4.7075 0.2075 4.7075 0.2075 27 P 0 ;1
L 4.7075 0.2575 4.7075 0.2575 27 P 0 ;1
L 4.7075 0.3075 4.7075 0.3075 27 P 0 ;1
L 4.7075 0.3575 4.7075 0.3575 27 P 0 ;1
L 4.7075 0.4075 4.7075 0.4075 27 P 0 ;1
L 4.7075 0.4575 4.7075 0.4575 27 P 0 ;1
L 4.7075 0.5075 4.7075 0.5075 27 P 0 ;1
L 4.7075 0.5575 4.7075 0.5575 27 P 0 ;1
L 4.7075 0.6075 4.7075 0.6075 27 P 0 ;1
L 4.7075 0.6575 4.7075 0.6575 27 P 0 ;1
L 4.7075 0.7075 4.7075 0.7075 27 P 0 ;1
L 4.7075 0.7575 4.7075 0.7575 27 P 0 ;1
L 4.7075 0.8075 4.7075 0.8075 27 P 0 ;1
L 4.7075 0.8575 4.7075 0.8575 27 P 0 ;1
L 4.7075 0.9075 4.7075 0.9075 27 P 0 ;1
L 4.7075 0.9575 4.7075 0.9575 27 P 0 ;1
L 4.7075 1.0075 4.7075 1.0075 27 P 0 ;1
L 4.7075 1.0575 4.7075 1.0575 27 P 0 ;1
L 4.7075 1.1075 4.7075 1.1075 27 P 0 ;1
L 4.7075 1.1575 4.7075 1.1575 27 P 0 ;1
L 4.7075 1.2075 4.7075 1.2075 27 P 0 ;1
L 4.7075 1.2575 4.7075 1.2575 27 P 0 ;1
L 4.7075 1.7575 4.7075 1.7575 27 P 0 ;1
L 4.7575 0.5075 4.7575 0.5075 27 P 0 ;1
L 4.7575 0.5575 4.7575 0.5575 27 P 0 ;1
L 4.7575 0.6075 4.7575 0.6075 27 P 0 ;1
L 4.7575 0.6575 4.7575 0.6575 27 P 0 ;1
L 4.7575 0.7075 4.7575 0.7075 27 P 0 ;1
L 4.7575 0.7575 4.7575 0.7575 27 P 0 ;1
L 4.7575 0.8075 4.7575 0.8075 27 P 0 ;1
L 4.7575 0.8575 4.7575 0.8575 27 P 0 ;1
L 4.7575 0.9075 4.7575 0.9075 27 P 0 ;1
L 4.7575 0.9575 4.7575 0.9575 27 P 0 ;1
L 4.7575 1.0075 4.7575 1.0075 27 P 0 ;1
L 4.7575 1.0575 4.7575 1.0575 27 P 0 ;1
L 4.7575 1.1075 4.7575 1.1075 27 P 0 ;1
L 4.7575 1.1575 4.7575 1.1575 27 P 0 ;1
L 4.7575 1.2075 4.7575 1.2075 27 P 0 ;1
L 4.7575 1.2575 4.7575 1.2575 27 P 0 ;1
L 4.7575 1.7575 4.7575 1.7575 27 P 0 ;1
L 4.8075 0.5575 4.8075 0.5575 27 P 0 ;1
L 4.8075 0.6075 4.8075 0.6075 27 P 0 ;1
L 4.8075 0.6575 4.8075 0.6575 27 P 0 ;1
L 4.8075 0.7075 4.8075 0.7075 27 P 0 ;1
L 4.8075 0.7575 4.8075 0.7575 27 P 0 ;1
L 4.8075 0.8075 4.8075 0.8075 27 P 0 ;1
L 4.8075 0.8575 4.8075 0.8575 27 P 0 ;1
L 4.8075 0.9075 4.8075 0.9075 27 P 0 ;1
L 4.8075 0.9575 4.8075 0.9575 27 P 0 ;1
L 4.8075 1.0075 4.8075 1.0075 27 P 0 ;1
L 4.8075 1.0575 4.8075 1.0575 27 P 0 ;1
L 4.8075 1.1075 4.8075 1.1075 27 P 0 ;1
L 4.8075 1.1575 4.8075 1.1575 27 P 0 ;1
L 4.8075 1.2075 4.8075 1.2075 27 P 0 ;1
L 4.8075 1.2575 4.8075 1.2575 27 P 0 ;1
L 4.8075 1.7575 4.8075 1.7575 27 P 0 ;1
L 4.8575 0.5575 4.8575 0.5575 27 P 0 ;1
L 4.8575 0.6075 4.8575 0.6075 27 P 0 ;1
L 4.8575 0.6575 4.8575 0.6575 27 P 0 ;1
L 4.8575 0.7075 4.8575 0.7075 27 P 0 ;1
L 4.8575 0.7575 4.8575 0.7575 27 P 0 ;1
L 4.8575 0.8075 4.8575 0.8075 27 P 0 ;1
L 4.8575 0.8575 4.8575 0.8575 27 P 0 ;1
L 4.8575 0.9075 4.8575 0.9075 27 P 0 ;1
L 4.8575 0.9575 4.8575 0.9575 27 P 0 ;1
L 4.8575 1.0075 4.8575 1.0075 27 P 0 ;1
L 4.8575 1.0575 4.8575 1.0575 27 P 0 ;1
L 4.8575 1.1075 4.8575 1.1075 27 P 0 ;1
L 4.8575 1.1575 4.8575 1.1575 27 P 0 ;1
L 4.8575 1.2075 4.8575 1.2075 27 P 0 ;1
L 4.8575 1.2575 4.8575 1.2575 27 P 0 ;1
L 4.8575 1.7575 4.8575 1.7575 27 P 0 ;1
L 4.9075 0.6075 4.9075 0.6075 27 P 0 ;1
L 4.9075 0.6575 4.9075 0.6575 27 P 0 ;1
L 4.9075 0.7075 4.9075 0.7075 27 P 0 ;1
L 4.9075 0.7575 4.9075 0.7575 27 P 0 ;1
L 4.9075 0.8075 4.9075 0.8075 27 P 0 ;1
L 4.9075 0.8575 4.9075 0.8575 27 P 0 ;1
L 4.9075 0.9075 4.9075 0.9075 27 P 0 ;1
L 4.9075 0.9575 4.9075 0.9575 27 P 0 ;1
L 4.9075 1.0075 4.9075 1.0075 27 P 0 ;1
L 4.9075 1.0575 4.9075 1.0575 27 P 0 ;1
L 4.9075 1.1075 4.9075 1.1075 27 P 0 ;1
L 4.9075 1.1575 4.9075 1.1575 27 P 0 ;1
L 4.9075 1.2075 4.9075 1.2075 27 P 0 ;1
L 4.9075 1.2575 4.9075 1.2575 27 P 0 ;1
L 4.9075 1.7575 4.9075 1.7575 27 P 0 ;1
L 4.9575 0.6075 4.9575 0.6075 27 P 0 ;1
L 4.9575 0.6575 4.9575 0.6575 27 P 0 ;1
L 4.9575 0.7075 4.9575 0.7075 27 P 0 ;1
L 4.9575 0.7575 4.9575 0.7575 27 P 0 ;1
L 4.9575 0.8075 4.9575 0.8075 27 P 0 ;1
L 4.9575 0.8575 4.9575 0.8575 27 P 0 ;1
L 4.9575 0.9075 4.9575 0.9075 27 P 0 ;1
L 4.9575 0.9575 4.9575 0.9575 27 P 0 ;1
L 4.9575 1.0075 4.9575 1.0075 27 P 0 ;1
L 4.9575 1.0575 4.9575 1.0575 27 P 0 ;1
L 4.9575 1.1075 4.9575 1.1075 27 P 0 ;1
L 4.9575 1.1575 4.9575 1.1575 27 P 0 ;1
L 4.9575 1.2075 4.9575 1.2075 27 P 0 ;1
L 4.9575 1.2575 4.9575 1.2575 27 P 0 ;1
L 4.9575 1.7575 4.9575 1.7575 27 P 0 ;1
L 5.0075 0.6075 5.0075 0.6075 27 P 0 ;1
L 5.0075 0.6575 5.0075 0.6575 27 P 0 ;1
L 5.0075 0.7075 5.0075 0.7075 27 P 0 ;1
L 5.0075 0.7575 5.0075 0.7575 27 P 0 ;1
L 5.0075 0.8075 5.0075 0.8075 27 P 0 ;1
L 5.0075 0.8575 5.0075 0.8575 27 P 0 ;1
L 5.0075 0.9075 5.0075 0.9075 27 P 0 ;1
L 5.0075 0.9575 5.0075 0.9575 27 P 0 ;1
L 5.0075 1.0075 5.0075 1.0075 27 P 0 ;1
L 5.0075 1.0575 5.0075 1.0575 27 P 0 ;1
L 5.0075 1.1075 5.0075 1.1075 27 P 0 ;1
L 5.0075 1.1575 5.0075 1.1575 27 P 0 ;1
L 5.0075 1.2075 5.0075 1.2075 27 P 0 ;1
L 5.0075 1.2575 5.0075 1.2575 27 P 0 ;1
L 5.0075 1.3075 5.0075 1.3075 27 P 0 ;1
L 5.0075 1.7075 5.0075 1.7075 27 P 0 ;1
L 5.0075 1.7575 5.0075 1.7575 27 P 0 ;1
L 5.0575 0.6075 5.0575 0.6075 27 P 0 ;1
L 5.0575 0.6575 5.0575 0.6575 27 P 0 ;1
L 5.0575 0.7075 5.0575 0.7075 27 P 0 ;1
L 5.0575 0.7575 5.0575 0.7575 27 P 0 ;1
L 5.0575 0.8075 5.0575 0.8075 27 P 0 ;1
L 5.0575 0.8575 5.0575 0.8575 27 P 0 ;1
L 5.0575 0.9075 5.0575 0.9075 27 P 0 ;1
L 5.0575 0.9575 5.0575 0.9575 27 P 0 ;1
L 5.0575 1.0075 5.0575 1.0075 27 P 0 ;1
L 5.0575 1.0575 5.0575 1.0575 27 P 0 ;1
L 5.0575 1.1075 5.0575 1.1075 27 P 0 ;1
L 5.0575 1.1575 5.0575 1.1575 27 P 0 ;1
L 5.0575 1.2075 5.0575 1.2075 27 P 0 ;1
L 5.0575 1.2575 5.0575 1.2575 27 P 0 ;1
L 5.0575 1.3075 5.0575 1.3075 27 P 0 ;1
L 5.0575 1.3575 5.0575 1.3575 27 P 0 ;1
L 5.0575 1.4075 5.0575 1.4075 27 P 0 ;1
L 5.0575 1.6075 5.0575 1.6075 27 P 0 ;1
L 5.0575 1.6575 5.0575 1.6575 27 P 0 ;1
L 5.0575 1.7075 5.0575 1.7075 27 P 0 ;1
L 5.0575 1.7575 5.0575 1.7575 27 P 0 ;1
L 5.1075 0.6075 5.1075 0.6075 27 P 0 ;1
L 5.1075 0.6575 5.1075 0.6575 27 P 0 ;1
L 5.1075 0.7075 5.1075 0.7075 27 P 0 ;1
L 5.1075 0.7575 5.1075 0.7575 27 P 0 ;1
L 5.1075 0.8075 5.1075 0.8075 27 P 0 ;1
L 5.1075 0.8575 5.1075 0.8575 27 P 0 ;1
L 5.1075 0.9075 5.1075 0.9075 27 P 0 ;1
L 5.1075 0.9575 5.1075 0.9575 27 P 0 ;1
L 5.1075 1.0075 5.1075 1.0075 27 P 0 ;1
L 5.1075 1.0575 5.1075 1.0575 27 P 0 ;1
L 5.1075 1.1075 5.1075 1.1075 27 P 0 ;1
L 5.1075 1.1575 5.1075 1.1575 27 P 0 ;1
L 5.1075 1.2075 5.1075 1.2075 27 P 0 ;1
L 5.1075 1.2575 5.1075 1.2575 27 P 0 ;1
L 5.1075 1.3075 5.1075 1.3075 27 P 0 ;1
L 5.1075 1.3575 5.1075 1.3575 27 P 0 ;1
L 5.1075 1.4075 5.1075 1.4075 27 P 0 ;1
L 5.1075 1.4575 5.1075 1.4575 27 P 0 ;1
L 5.1075 1.5075 5.1075 1.5075 27 P 0 ;1
L 5.1075 1.5575 5.1075 1.5575 27 P 0 ;1
L 5.1075 1.6075 5.1075 1.6075 27 P 0 ;1
L 5.1075 1.6575 5.1075 1.6575 27 P 0 ;1
L 5.1075 1.7075 5.1075 1.7075 27 P 0 ;1
L 5.1075 1.7575 5.1075 1.7575 27 P 0 ;1
L 5.1575 0.6075 5.1575 0.6075 27 P 0 ;1
L 5.1575 0.6575 5.1575 0.6575 27 P 0 ;1
L 5.1575 1.0075 5.1575 1.0075 27 P 0 ;1
L 5.1575 1.0575 5.1575 1.0575 27 P 0 ;1
L 5.1575 1.1075 5.1575 1.1075 27 P 0 ;1
L 5.1575 1.1575 5.1575 1.1575 27 P 0 ;1
L 5.1575 1.2075 5.1575 1.2075 27 P 0 ;1
L 5.1575 1.2575 5.1575 1.2575 27 P 0 ;1
L 5.1575 1.3075 5.1575 1.3075 27 P 0 ;1
L 5.1575 1.3575 5.1575 1.3575 27 P 0 ;1
L 5.1575 1.4075 5.1575 1.4075 27 P 0 ;1
L 5.1575 1.4575 5.1575 1.4575 27 P 0 ;1
L 5.1575 1.5075 5.1575 1.5075 27 P 0 ;1
L 5.1575 1.5575 5.1575 1.5575 27 P 0 ;1
L 5.1575 1.6075 5.1575 1.6075 27 P 0 ;1
L 5.1575 1.6575 5.1575 1.6575 27 P 0 ;1
L 5.1575 1.7075 5.1575 1.7075 27 P 0 ;1
L 5.1575 1.7575 5.1575 1.7575 27 P 0 ;1
L 5.2075 0.6075 5.2075 0.6075 27 P 0 ;1
L 5.2075 0.6575 5.2075 0.6575 27 P 0 ;1
L 5.2075 1.0075 5.2075 1.0075 27 P 0 ;1
L 5.2075 1.0575 5.2075 1.0575 27 P 0 ;1
L 5.2075 1.1075 5.2075 1.1075 27 P 0 ;1
L 5.2075 1.1575 5.2075 1.1575 27 P 0 ;1
L 5.2075 1.2075 5.2075 1.2075 27 P 0 ;1
L 5.2075 1.2575 5.2075 1.2575 27 P 0 ;1
L 5.2075 1.3075 5.2075 1.3075 27 P 0 ;1
L 5.2075 1.3575 5.2075 1.3575 27 P 0 ;1
L 5.2075 1.4075 5.2075 1.4075 27 P 0 ;1
L 5.2075 1.4575 5.2075 1.4575 27 P 0 ;1
L 5.2075 1.5075 5.2075 1.5075 27 P 0 ;1
L 5.2075 1.5575 5.2075 1.5575 27 P 0 ;1
L 5.2075 1.6075 5.2075 1.6075 27 P 0 ;1
L 5.2075 1.6575 5.2075 1.6575 27 P 0 ;1
L 5.2075 1.7075 5.2075 1.7075 27 P 0 ;1
L 5.2075 1.7575 5.2075 1.7575 27 P 0 ;1
L 5.2075 1.8075 5.2075 1.8075 27 P 0 ;1
L 5.2075 1.8575 5.2075 1.8575 27 P 0 ;1
L 5.2075 1.9075 5.2075 1.9075 27 P 0 ;1
L 5.2075 1.9575 5.2075 1.9575 27 P 0 ;1
L 5.2075 2.0075 5.2075 2.0075 27 P 0 ;1
L 5.2075 2.0575 5.2075 2.0575 27 P 0 ;1
L 5.2075 2.1075 5.2075 2.1075 27 P 0 ;1
L 5.2075 2.1575 5.2075 2.1575 27 P 0 ;1
L 5.2075 2.2075 5.2075 2.2075 27 P 0 ;1
L 5.2075 2.2575 5.2075 2.2575 27 P 0 ;1
L 5.2075 2.3075 5.2075 2.3075 27 P 0 ;1
L 5.2075 2.3575 5.2075 2.3575 27 P 0 ;1
L 5.2075 2.4075 5.2075 2.4075 27 P 0 ;1
L 5.2075 2.4575 5.2075 2.4575 27 P 0 ;1
L 5.2075 2.5075 5.2075 2.5075 27 P 0 ;1
L 5.2075 2.5575 5.2075 2.5575 27 P 0 ;1
L 5.2075 2.6075 5.2075 2.6075 27 P 0 ;1
L 5.2075 2.6575 5.2075 2.6575 27 P 0 ;1
L 5.2075 2.7075 5.2075 2.7075 27 P 0 ;1
L 5.2075 2.7575 5.2075 2.7575 27 P 0 ;1
L 5.2075 2.8075 5.2075 2.8075 27 P 0 ;1
L 5.2075 5.7575 5.2075 5.7575 27 P 0 ;1
L 5.2575 0.6075 5.2575 0.6075 27 P 0 ;1
L 5.2575 0.6575 5.2575 0.6575 27 P 0 ;1
L 5.2575 1.0075 5.2575 1.0075 27 P 0 ;1
L 5.2575 1.0575 5.2575 1.0575 27 P 0 ;1
L 5.2575 1.1075 5.2575 1.1075 27 P 0 ;1
L 5.2575 1.1575 5.2575 1.1575 27 P 0 ;1
L 5.2575 1.2075 5.2575 1.2075 27 P 0 ;1
L 5.2575 1.2575 5.2575 1.2575 27 P 0 ;1
L 5.2575 1.3075 5.2575 1.3075 27 P 0 ;1
L 5.2575 1.3575 5.2575 1.3575 27 P 0 ;1
L 5.2575 1.4075 5.2575 1.4075 27 P 0 ;1
L 5.2575 1.4575 5.2575 1.4575 27 P 0 ;1
L 5.2575 1.5075 5.2575 1.5075 27 P 0 ;1
L 5.2575 1.5575 5.2575 1.5575 27 P 0 ;1
L 5.2575 1.6075 5.2575 1.6075 27 P 0 ;1
L 5.2575 1.6575 5.2575 1.6575 27 P 0 ;1
L 5.2575 1.7075 5.2575 1.7075 27 P 0 ;1
L 5.2575 1.7575 5.2575 1.7575 27 P 0 ;1
L 5.2575 1.8075 5.2575 1.8075 27 P 0 ;1
L 5.2575 1.8575 5.2575 1.8575 27 P 0 ;1
L 5.2575 1.9075 5.2575 1.9075 27 P 0 ;1
L 5.2575 1.9575 5.2575 1.9575 27 P 0 ;1
L 5.2575 2.0075 5.2575 2.0075 27 P 0 ;1
L 5.2575 2.0575 5.2575 2.0575 27 P 0 ;1
L 5.2575 2.1075 5.2575 2.1075 27 P 0 ;1
L 5.2575 2.1575 5.2575 2.1575 27 P 0 ;1
L 5.2575 2.2075 5.2575 2.2075 27 P 0 ;1
L 5.2575 2.2575 5.2575 2.2575 27 P 0 ;1
L 5.2575 2.3075 5.2575 2.3075 27 P 0 ;1
L 5.2575 2.3575 5.2575 2.3575 27 P 0 ;1
L 5.2575 2.4075 5.2575 2.4075 27 P 0 ;1
L 5.2575 2.4575 5.2575 2.4575 27 P 0 ;1
L 5.2575 2.5075 5.2575 2.5075 27 P 0 ;1
L 5.2575 2.5575 5.2575 2.5575 27 P 0 ;1
L 5.2575 2.6075 5.2575 2.6075 27 P 0 ;1
L 5.2575 2.6575 5.2575 2.6575 27 P 0 ;1
L 5.2575 2.7075 5.2575 2.7075 27 P 0 ;1
L 5.2575 2.7575 5.2575 2.7575 27 P 0 ;1
L 5.2575 2.8075 5.2575 2.8075 27 P 0 ;1
L 5.2575 5.3075 5.2575 5.3075 27 P 0 ;1
L 5.2575 5.3575 5.2575 5.3575 27 P 0 ;1
L 5.2575 5.4075 5.2575 5.4075 27 P 0 ;1
L 5.2575 5.4575 5.2575 5.4575 27 P 0 ;1
L 5.2575 5.5075 5.2575 5.5075 27 P 0 ;1
L 5.2575 5.5575 5.2575 5.5575 27 P 0 ;1
L 5.2575 5.6075 5.2575 5.6075 27 P 0 ;1
L 5.2575 5.6575 5.2575 5.6575 27 P 0 ;1
L 5.2575 5.7075 5.2575 5.7075 27 P 0 ;1
L 5.2575 5.7575 5.2575 5.7575 27 P 0 ;1
L 5.3075 0.6075 5.3075 0.6075 27 P 0 ;1
L 5.3075 0.6575 5.3075 0.6575 27 P 0 ;1
L 5.3075 1.0075 5.3075 1.0075 27 P 0 ;1
L 5.3075 1.0575 5.3075 1.0575 27 P 0 ;1
L 5.3075 1.1075 5.3075 1.1075 27 P 0 ;1
L 5.3075 1.1575 5.3075 1.1575 27 P 0 ;1
L 5.3075 1.2075 5.3075 1.2075 27 P 0 ;1
L 5.3075 1.2575 5.3075 1.2575 27 P 0 ;1
L 5.3075 1.3075 5.3075 1.3075 27 P 0 ;1
L 5.3075 1.3575 5.3075 1.3575 27 P 0 ;1
L 5.3075 1.4075 5.3075 1.4075 27 P 0 ;1
L 5.3075 1.4575 5.3075 1.4575 27 P 0 ;1
L 5.3075 1.5075 5.3075 1.5075 27 P 0 ;1
L 5.3075 3.4075 5.3075 3.4075 27 P 0 ;1
L 5.3075 3.4575 5.3075 3.4575 27 P 0 ;1
L 5.3075 3.5075 5.3075 3.5075 27 P 0 ;1
L 5.3075 3.5575 5.3075 3.5575 27 P 0 ;1
L 5.3075 3.6075 5.3075 3.6075 27 P 0 ;1
L 5.3075 3.6575 5.3075 3.6575 27 P 0 ;1
L 5.3075 3.7075 5.3075 3.7075 27 P 0 ;1
L 5.3075 3.7575 5.3075 3.7575 27 P 0 ;1
L 5.3075 3.8075 5.3075 3.8075 27 P 0 ;1
L 5.3075 3.8575 5.3075 3.8575 27 P 0 ;1
L 5.3075 3.9075 5.3075 3.9075 27 P 0 ;1
L 5.3075 3.9575 5.3075 3.9575 27 P 0 ;1
L 5.3075 4.0075 5.3075 4.0075 27 P 0 ;1
L 5.3075 4.0575 5.3075 4.0575 27 P 0 ;1
L 5.3075 4.1075 5.3075 4.1075 27 P 0 ;1
L 5.3075 4.1575 5.3075 4.1575 27 P 0 ;1
L 5.3075 4.2075 5.3075 4.2075 27 P 0 ;1
L 5.3075 4.2575 5.3075 4.2575 27 P 0 ;1
L 5.3075 4.3075 5.3075 4.3075 27 P 0 ;1
L 5.3075 4.3575 5.3075 4.3575 27 P 0 ;1
L 5.3075 4.4075 5.3075 4.4075 27 P 0 ;1
L 5.3075 4.4575 5.3075 4.4575 27 P 0 ;1
L 5.3075 4.5075 5.3075 4.5075 27 P 0 ;1
L 5.3075 4.5575 5.3075 4.5575 27 P 0 ;1
L 5.3075 4.6075 5.3075 4.6075 27 P 0 ;1
L 5.3075 4.6575 5.3075 4.6575 27 P 0 ;1
L 5.3075 4.7075 5.3075 4.7075 27 P 0 ;1
L 5.3075 4.7575 5.3075 4.7575 27 P 0 ;1
L 5.3075 4.8075 5.3075 4.8075 27 P 0 ;1
L 5.3075 4.8575 5.3075 4.8575 27 P 0 ;1
L 5.3075 5.2575 5.3075 5.2575 27 P 0 ;1
L 5.3075 5.3075 5.3075 5.3075 27 P 0 ;1
L 5.3075 5.3575 5.3075 5.3575 27 P 0 ;1
L 5.3075 5.4075 5.3075 5.4075 27 P 0 ;1
L 5.3075 5.4575 5.3075 5.4575 27 P 0 ;1
L 5.3075 5.5075 5.3075 5.5075 27 P 0 ;1
L 5.3075 5.5575 5.3075 5.5575 27 P 0 ;1
L 5.3075 5.6075 5.3075 5.6075 27 P 0 ;1
L 5.3075 5.6575 5.3075 5.6575 27 P 0 ;1
L 5.3075 5.7075 5.3075 5.7075 27 P 0 ;1
L 5.3075 5.7575 5.3075 5.7575 27 P 0 ;1
L 5.3575 0.6075 5.3575 0.6075 27 P 0 ;1
L 5.3575 0.6575 5.3575 0.6575 27 P 0 ;1
L 5.3575 1.0075 5.3575 1.0075 27 P 0 ;1
L 5.3575 1.0575 5.3575 1.0575 27 P 0 ;1
L 5.3575 1.1075 5.3575 1.1075 27 P 0 ;1
L 5.3575 1.1575 5.3575 1.1575 27 P 0 ;1
L 5.3575 1.2075 5.3575 1.2075 27 P 0 ;1
L 5.3575 1.2575 5.3575 1.2575 27 P 0 ;1
L 5.3575 1.3075 5.3575 1.3075 27 P 0 ;1
L 5.3575 1.3575 5.3575 1.3575 27 P 0 ;1
L 5.3575 1.4075 5.3575 1.4075 27 P 0 ;1
L 5.3575 1.4575 5.3575 1.4575 27 P 0 ;1
L 5.3575 3.3575 5.3575 3.3575 27 P 0 ;1
L 5.3575 3.4075 5.3575 3.4075 27 P 0 ;1
L 5.3575 3.4575 5.3575 3.4575 27 P 0 ;1
L 5.3575 3.5075 5.3575 3.5075 27 P 0 ;1
L 5.3575 3.5575 5.3575 3.5575 27 P 0 ;1
L 5.3575 3.6075 5.3575 3.6075 27 P 0 ;1
L 5.3575 3.6575 5.3575 3.6575 27 P 0 ;1
L 5.3575 3.7075 5.3575 3.7075 27 P 0 ;1
L 5.3575 3.7575 5.3575 3.7575 27 P 0 ;1
L 5.3575 3.8075 5.3575 3.8075 27 P 0 ;1
L 5.3575 3.8575 5.3575 3.8575 27 P 0 ;1
L 5.3575 3.9075 5.3575 3.9075 27 P 0 ;1
L 5.3575 3.9575 5.3575 3.9575 27 P 0 ;1
L 5.3575 4.0075 5.3575 4.0075 27 P 0 ;1
L 5.3575 4.0575 5.3575 4.0575 27 P 0 ;1
L 5.3575 4.1075 5.3575 4.1075 27 P 0 ;1
L 5.3575 4.1575 5.3575 4.1575 27 P 0 ;1
L 5.3575 4.2075 5.3575 4.2075 27 P 0 ;1
L 5.3575 4.2575 5.3575 4.2575 27 P 0 ;1
L 5.3575 4.3075 5.3575 4.3075 27 P 0 ;1
L 5.3575 4.3575 5.3575 4.3575 27 P 0 ;1
L 5.3575 4.4075 5.3575 4.4075 27 P 0 ;1
L 5.3575 4.4575 5.3575 4.4575 27 P 0 ;1
L 5.3575 4.5075 5.3575 4.5075 27 P 0 ;1
L 5.3575 4.5575 5.3575 4.5575 27 P 0 ;1
L 5.3575 5.1575 5.3575 5.1575 27 P 0 ;1
L 5.3575 5.2075 5.3575 5.2075 27 P 0 ;1
L 5.3575 5.2575 5.3575 5.2575 27 P 0 ;1
L 5.3575 5.3075 5.3575 5.3075 27 P 0 ;1
L 5.3575 5.3575 5.3575 5.3575 27 P 0 ;1
L 5.3575 5.4075 5.3575 5.4075 27 P 0 ;1
L 5.3575 5.4575 5.3575 5.4575 27 P 0 ;1
L 5.3575 5.5075 5.3575 5.5075 27 P 0 ;1
L 5.3575 5.5575 5.3575 5.5575 27 P 0 ;1
L 5.3575 5.6075 5.3575 5.6075 27 P 0 ;1
L 5.3575 5.6575 5.3575 5.6575 27 P 0 ;1
L 5.3575 5.7075 5.3575 5.7075 27 P 0 ;1
L 5.3575 5.7575 5.3575 5.7575 27 P 0 ;1
L 5.4075 0.6075 5.4075 0.6075 27 P 0 ;1
L 5.4075 0.6575 5.4075 0.6575 27 P 0 ;1
L 5.4075 1.0075 5.4075 1.0075 27 P 0 ;1
L 5.4075 1.0575 5.4075 1.0575 27 P 0 ;1
L 5.4075 1.1075 5.4075 1.1075 27 P 0 ;1
L 5.4075 1.1575 5.4075 1.1575 27 P 0 ;1
L 5.4075 1.2075 5.4075 1.2075 27 P 0 ;1
L 5.4075 1.2575 5.4075 1.2575 27 P 0 ;1
L 5.4075 1.3075 5.4075 1.3075 27 P 0 ;1
L 5.4075 1.3575 5.4075 1.3575 27 P 0 ;1
L 5.4075 1.4075 5.4075 1.4075 27 P 0 ;1
L 5.4075 1.4575 5.4075 1.4575 27 P 0 ;1
L 5.4075 3.4075 5.4075 3.4075 27 P 0 ;1
L 5.4075 3.4575 5.4075 3.4575 27 P 0 ;1
L 5.4075 3.5075 5.4075 3.5075 27 P 0 ;1
L 5.4075 3.5575 5.4075 3.5575 27 P 0 ;1
L 5.4075 3.6075 5.4075 3.6075 27 P 0 ;1
L 5.4075 3.6575 5.4075 3.6575 27 P 0 ;1
L 5.4075 3.7075 5.4075 3.7075 27 P 0 ;1
L 5.4075 3.7575 5.4075 3.7575 27 P 0 ;1
L 5.4075 3.8075 5.4075 3.8075 27 P 0 ;1
L 5.4075 3.8575 5.4075 3.8575 27 P 0 ;1
L 5.4075 3.9075 5.4075 3.9075 27 P 0 ;1
L 5.4075 3.9575 5.4075 3.9575 27 P 0 ;1
L 5.4075 4.0075 5.4075 4.0075 27 P 0 ;1
L 5.4075 4.0575 5.4075 4.0575 27 P 0 ;1
L 5.4075 4.1075 5.4075 4.1075 27 P 0 ;1
L 5.4075 4.1575 5.4075 4.1575 27 P 0 ;1
L 5.4075 4.2075 5.4075 4.2075 27 P 0 ;1
L 5.4075 4.2575 5.4075 4.2575 27 P 0 ;1
L 5.4075 4.3075 5.4075 4.3075 27 P 0 ;1
L 5.4075 4.3575 5.4075 4.3575 27 P 0 ;1
L 5.4075 4.4075 5.4075 4.4075 27 P 0 ;1
L 5.4075 4.4575 5.4075 4.4575 27 P 0 ;1
L 5.4075 5.2075 5.4075 5.2075 27 P 0 ;1
L 5.4075 5.2575 5.4075 5.2575 27 P 0 ;1
L 5.4075 5.3075 5.4075 5.3075 27 P 0 ;1
L 5.4075 5.3575 5.4075 5.3575 27 P 0 ;1
L 5.4075 5.4075 5.4075 5.4075 27 P 0 ;1
L 5.4075 5.4575 5.4075 5.4575 27 P 0 ;1
L 5.4075 5.5075 5.4075 5.5075 27 P 0 ;1
L 5.4075 5.5575 5.4075 5.5575 27 P 0 ;1
L 5.4075 5.6075 5.4075 5.6075 27 P 0 ;1
L 5.4075 5.6575 5.4075 5.6575 27 P 0 ;1
L 5.4075 5.7075 5.4075 5.7075 27 P 0 ;1
L 5.4075 5.7575 5.4075 5.7575 27 P 0 ;1
L 5.4575 0.6075 5.4575 0.6075 27 P 0 ;1
L 5.4575 0.6575 5.4575 0.6575 27 P 0 ;1
L 5.4575 1.0075 5.4575 1.0075 27 P 0 ;1
L 5.4575 1.0575 5.4575 1.0575 27 P 0 ;1
L 5.4575 1.1075 5.4575 1.1075 27 P 0 ;1
L 5.4575 1.1575 5.4575 1.1575 27 P 0 ;1
L 5.4575 1.2075 5.4575 1.2075 27 P 0 ;1
L 5.4575 1.2575 5.4575 1.2575 27 P 0 ;1
L 5.4575 1.3075 5.4575 1.3075 27 P 0 ;1
L 5.4575 1.3575 5.4575 1.3575 27 P 0 ;1
L 5.4575 1.4075 5.4575 1.4075 27 P 0 ;1
L 5.4575 1.4575 5.4575 1.4575 27 P 0 ;1
L 5.4575 1.5075 5.4575 1.5075 27 P 0 ;1
L 5.4575 3.4075 5.4575 3.4075 27 P 0 ;1
L 5.4575 3.4575 5.4575 3.4575 27 P 0 ;1
L 5.4575 3.5075 5.4575 3.5075 27 P 0 ;1
L 5.4575 3.5575 5.4575 3.5575 27 P 0 ;1
L 5.4575 3.6075 5.4575 3.6075 27 P 0 ;1
L 5.4575 3.6575 5.4575 3.6575 27 P 0 ;1
L 5.4575 3.7075 5.4575 3.7075 27 P 0 ;1
L 5.4575 3.7575 5.4575 3.7575 27 P 0 ;1
L 5.4575 3.8075 5.4575 3.8075 27 P 0 ;1
L 5.4575 3.8575 5.4575 3.8575 27 P 0 ;1
L 5.4575 3.9075 5.4575 3.9075 27 P 0 ;1
L 5.4575 3.9575 5.4575 3.9575 27 P 0 ;1
L 5.4575 4.0075 5.4575 4.0075 27 P 0 ;1
L 5.4575 4.0575 5.4575 4.0575 27 P 0 ;1
L 5.4575 4.1075 5.4575 4.1075 27 P 0 ;1
L 5.4575 4.1575 5.4575 4.1575 27 P 0 ;1
L 5.4575 4.2075 5.4575 4.2075 27 P 0 ;1
L 5.4575 4.2575 5.4575 4.2575 27 P 0 ;1
L 5.4575 4.3075 5.4575 4.3075 27 P 0 ;1
L 5.4575 4.3575 5.4575 4.3575 27 P 0 ;1
L 5.4575 4.4075 5.4575 4.4075 27 P 0 ;1
L 5.4575 4.4575 5.4575 4.4575 27 P 0 ;1
L 5.4575 5.2575 5.4575 5.2575 27 P 0 ;1
L 5.4575 5.3075 5.4575 5.3075 27 P 0 ;1
L 5.4575 5.3575 5.4575 5.3575 27 P 0 ;1
L 5.4575 5.4075 5.4575 5.4075 27 P 0 ;1
L 5.4575 5.4575 5.4575 5.4575 27 P 0 ;1
L 5.4575 5.5075 5.4575 5.5075 27 P 0 ;1
L 5.4575 5.5575 5.4575 5.5575 27 P 0 ;1
L 5.4575 5.6075 5.4575 5.6075 27 P 0 ;1
L 5.4575 5.6575 5.4575 5.6575 27 P 0 ;1
L 5.4575 5.7075 5.4575 5.7075 27 P 0 ;1
L 5.4575 5.7575 5.4575 5.7575 27 P 0 ;1
L 5.5075 0.6075 5.5075 0.6075 27 P 0 ;1
L 5.5075 0.6575 5.5075 0.6575 27 P 0 ;1
L 5.5075 1.0075 5.5075 1.0075 27 P 0 ;1
L 5.5075 1.0575 5.5075 1.0575 27 P 0 ;1
L 5.5075 1.1075 5.5075 1.1075 27 P 0 ;1
L 5.5075 1.1575 5.5075 1.1575 27 P 0 ;1
L 5.5075 1.2075 5.5075 1.2075 27 P 0 ;1
L 5.5075 1.2575 5.5075 1.2575 27 P 0 ;1
L 5.5075 1.3075 5.5075 1.3075 27 P 0 ;1
L 5.5075 1.3575 5.5075 1.3575 27 P 0 ;1
L 5.5075 1.4075 5.5075 1.4075 27 P 0 ;1
L 5.5075 1.4575 5.5075 1.4575 27 P 0 ;1
L 5.5075 1.5075 5.5075 1.5075 27 P 0 ;1
L 5.5075 1.5575 5.5075 1.5575 27 P 0 ;1
L 5.5075 3.4075 5.5075 3.4075 27 P 0 ;1
L 5.5075 3.4575 5.5075 3.4575 27 P 0 ;1
L 5.5075 3.5075 5.5075 3.5075 27 P 0 ;1
L 5.5075 3.5575 5.5075 3.5575 27 P 0 ;1
L 5.5075 3.6075 5.5075 3.6075 27 P 0 ;1
L 5.5075 3.6575 5.5075 3.6575 27 P 0 ;1
L 5.5075 3.7075 5.5075 3.7075 27 P 0 ;1
L 5.5075 3.7575 5.5075 3.7575 27 P 0 ;1
L 5.5075 3.8075 5.5075 3.8075 27 P 0 ;1
L 5.5075 3.8575 5.5075 3.8575 27 P 0 ;1
L 5.5075 3.9075 5.5075 3.9075 27 P 0 ;1
L 5.5075 3.9575 5.5075 3.9575 27 P 0 ;1
L 5.5075 4.0075 5.5075 4.0075 27 P 0 ;1
L 5.5075 4.0575 5.5075 4.0575 27 P 0 ;1
L 5.5075 4.1075 5.5075 4.1075 27 P 0 ;1
L 5.5075 4.1575 5.5075 4.1575 27 P 0 ;1
L 5.5075 4.2075 5.5075 4.2075 27 P 0 ;1
L 5.5075 4.2575 5.5075 4.2575 27 P 0 ;1
L 5.5075 4.3075 5.5075 4.3075 27 P 0 ;1
L 5.5075 4.3575 5.5075 4.3575 27 P 0 ;1
L 5.5075 4.4075 5.5075 4.4075 27 P 0 ;1
L 5.5075 5.2575 5.5075 5.2575 27 P 0 ;1
L 5.5075 5.3075 5.5075 5.3075 27 P 0 ;1
L 5.5075 5.3575 5.5075 5.3575 27 P 0 ;1
L 5.5075 5.5075 5.5075 5.5075 27 P 0 ;1
L 5.5075 5.5575 5.5075 5.5575 27 P 0 ;1
L 5.5075 5.6075 5.5075 5.6075 27 P 0 ;1
L 5.5075 5.6575 5.5075 5.6575 27 P 0 ;1
L 5.5075 5.7075 5.5075 5.7075 27 P 0 ;1
L 5.5075 5.7575 5.5075 5.7575 27 P 0 ;1
L 5.5575 0.6075 5.5575 0.6075 27 P 0 ;1
L 5.5575 0.6575 5.5575 0.6575 27 P 0 ;1
L 5.5575 0.8075 5.5575 0.8075 27 P 0 ;1
L 5.5575 0.8575 5.5575 0.8575 27 P 0 ;1
L 5.5575 0.9075 5.5575 0.9075 27 P 0 ;1
L 5.5575 0.9575 5.5575 0.9575 27 P 0 ;1
L 5.5575 1.0075 5.5575 1.0075 27 P 0 ;1
L 5.5575 1.0575 5.5575 1.0575 27 P 0 ;1
L 5.5575 1.1075 5.5575 1.1075 27 P 0 ;1
L 5.5575 1.1575 5.5575 1.1575 27 P 0 ;1
L 5.5575 1.2075 5.5575 1.2075 27 P 0 ;1
L 5.5575 1.2575 5.5575 1.2575 27 P 0 ;1
L 5.5575 1.3075 5.5575 1.3075 27 P 0 ;1
L 5.5575 1.3575 5.5575 1.3575 27 P 0 ;1
L 5.5575 1.4075 5.5575 1.4075 27 P 0 ;1
L 5.5575 1.4575 5.5575 1.4575 27 P 0 ;1
L 5.5575 1.5075 5.5575 1.5075 27 P 0 ;1
L 5.5575 1.5575 5.5575 1.5575 27 P 0 ;1
L 5.5575 3.1075 5.5575 3.1075 27 P 0 ;1
L 5.5575 3.1575 5.5575 3.1575 27 P 0 ;1
L 5.5575 3.2075 5.5575 3.2075 27 P 0 ;1
L 5.5575 3.2575 5.5575 3.2575 27 P 0 ;1
L 5.5575 3.3075 5.5575 3.3075 27 P 0 ;1
L 5.5575 3.3575 5.5575 3.3575 27 P 0 ;1
L 5.5575 3.4075 5.5575 3.4075 27 P 0 ;1
L 5.5575 3.4575 5.5575 3.4575 27 P 0 ;1
L 5.5575 3.5075 5.5575 3.5075 27 P 0 ;1
L 5.5575 3.5575 5.5575 3.5575 27 P 0 ;1
L 5.5575 3.6075 5.5575 3.6075 27 P 0 ;1
L 5.5575 3.6575 5.5575 3.6575 27 P 0 ;1
L 5.5575 3.7075 5.5575 3.7075 27 P 0 ;1
L 5.5575 3.7575 5.5575 3.7575 27 P 0 ;1
L 5.5575 3.8075 5.5575 3.8075 27 P 0 ;1
L 5.5575 3.8575 5.5575 3.8575 27 P 0 ;1
L 5.5575 3.9075 5.5575 3.9075 27 P 0 ;1
L 5.5575 3.9575 5.5575 3.9575 27 P 0 ;1
L 5.5575 4.0075 5.5575 4.0075 27 P 0 ;1
L 5.5575 4.0575 5.5575 4.0575 27 P 0 ;1
L 5.5575 4.1075 5.5575 4.1075 27 P 0 ;1
L 5.5575 4.1575 5.5575 4.1575 27 P 0 ;1
L 5.5575 4.2075 5.5575 4.2075 27 P 0 ;1
L 5.5575 4.2575 5.5575 4.2575 27 P 0 ;1
L 5.5575 4.3075 5.5575 4.3075 27 P 0 ;1
L 5.5575 4.3575 5.5575 4.3575 27 P 0 ;1
L 5.5575 4.4075 5.5575 4.4075 27 P 0 ;1
L 5.5575 5.2575 5.5575 5.2575 27 P 0 ;1
L 5.5575 5.6575 5.5575 5.6575 27 P 0 ;1
L 5.5575 5.7075 5.5575 5.7075 27 P 0 ;1
L 5.5575 5.7575 5.5575 5.7575 27 P 0 ;1
L 5.6075 0.6075 5.6075 0.6075 27 P 0 ;1
L 5.6075 0.6575 5.6075 0.6575 27 P 0 ;1
L 5.6075 0.8075 5.6075 0.8075 27 P 0 ;1
L 5.6075 0.8575 5.6075 0.8575 27 P 0 ;1
L 5.6075 0.9075 5.6075 0.9075 27 P 0 ;1
L 5.6075 0.9575 5.6075 0.9575 27 P 0 ;1
L 5.6075 1.0075 5.6075 1.0075 27 P 0 ;1
L 5.6075 1.0575 5.6075 1.0575 27 P 0 ;1
L 5.6075 1.1075 5.6075 1.1075 27 P 0 ;1
L 5.6075 1.1575 5.6075 1.1575 27 P 0 ;1
L 5.6075 1.2075 5.6075 1.2075 27 P 0 ;1
L 5.6075 1.2575 5.6075 1.2575 27 P 0 ;1
L 5.6075 1.3075 5.6075 1.3075 27 P 0 ;1
L 5.6075 1.3575 5.6075 1.3575 27 P 0 ;1
L 5.6075 1.4075 5.6075 1.4075 27 P 0 ;1
L 5.6075 1.4575 5.6075 1.4575 27 P 0 ;1
L 5.6075 1.5075 5.6075 1.5075 27 P 0 ;1
L 5.6075 1.5575 5.6075 1.5575 27 P 0 ;1
L 5.6075 3.1075 5.6075 3.1075 27 P 0 ;1
L 5.6075 3.1575 5.6075 3.1575 27 P 0 ;1
L 5.6075 3.2075 5.6075 3.2075 27 P 0 ;1
L 5.6075 3.2575 5.6075 3.2575 27 P 0 ;1
L 5.6075 3.3075 5.6075 3.3075 27 P 0 ;1
L 5.6075 3.3575 5.6075 3.3575 27 P 0 ;1
L 5.6075 3.4075 5.6075 3.4075 27 P 0 ;1
L 5.6075 3.4575 5.6075 3.4575 27 P 0 ;1
L 5.6075 3.5075 5.6075 3.5075 27 P 0 ;1
L 5.6075 3.5575 5.6075 3.5575 27 P 0 ;1
L 5.6075 3.6075 5.6075 3.6075 27 P 0 ;1
L 5.6075 3.6575 5.6075 3.6575 27 P 0 ;1
L 5.6075 3.7075 5.6075 3.7075 27 P 0 ;1
L 5.6075 3.7575 5.6075 3.7575 27 P 0 ;1
L 5.6075 3.8075 5.6075 3.8075 27 P 0 ;1
L 5.6075 3.8575 5.6075 3.8575 27 P 0 ;1
L 5.6075 3.9075 5.6075 3.9075 27 P 0 ;1
L 5.6075 3.9575 5.6075 3.9575 27 P 0 ;1
L 5.6075 4.0075 5.6075 4.0075 27 P 0 ;1
L 5.6075 4.0575 5.6075 4.0575 27 P 0 ;1
L 5.6075 4.1075 5.6075 4.1075 27 P 0 ;1
L 5.6075 4.1575 5.6075 4.1575 27 P 0 ;1
L 5.6075 4.2075 5.6075 4.2075 27 P 0 ;1
L 5.6075 4.2575 5.6075 4.2575 27 P 0 ;1
L 5.6075 4.3075 5.6075 4.3075 27 P 0 ;1
L 5.6075 4.3575 5.6075 4.3575 27 P 0 ;1
L 5.6075 4.4075 5.6075 4.4075 27 P 0 ;1
L 5.6075 5.7075 5.6075 5.7075 27 P 0 ;1
L 5.6075 5.7575 5.6075 5.7575 27 P 0 ;1
L 5.6575 0.6075 5.6575 0.6075 27 P 0 ;1
L 5.6575 0.6575 5.6575 0.6575 27 P 0 ;1
L 5.6575 0.8075 5.6575 0.8075 27 P 0 ;1
L 5.6575 0.8575 5.6575 0.8575 27 P 0 ;1
L 5.6575 0.9075 5.6575 0.9075 27 P 0 ;1
L 5.6575 0.9575 5.6575 0.9575 27 P 0 ;1
L 5.6575 1.0075 5.6575 1.0075 27 P 0 ;1
L 5.6575 1.0575 5.6575 1.0575 27 P 0 ;1
L 5.6575 1.1075 5.6575 1.1075 27 P 0 ;1
L 5.6575 1.1575 5.6575 1.1575 27 P 0 ;1
L 5.6575 1.2075 5.6575 1.2075 27 P 0 ;1
L 5.6575 1.2575 5.6575 1.2575 27 P 0 ;1
L 5.6575 1.3075 5.6575 1.3075 27 P 0 ;1
L 5.6575 1.3575 5.6575 1.3575 27 P 0 ;1
L 5.6575 1.4075 5.6575 1.4075 27 P 0 ;1
L 5.6575 1.4575 5.6575 1.4575 27 P 0 ;1
L 5.6575 1.5075 5.6575 1.5075 27 P 0 ;1
L 5.6575 1.5575 5.6575 1.5575 27 P 0 ;1
L 5.6575 1.6075 5.6575 1.6075 27 P 0 ;1
L 5.6575 1.7575 5.6575 1.7575 27 P 0 ;1
L 5.6575 3.0575 5.6575 3.0575 27 P 0 ;1
L 5.6575 3.1075 5.6575 3.1075 27 P 0 ;1
L 5.6575 3.1575 5.6575 3.1575 27 P 0 ;1
L 5.6575 3.2075 5.6575 3.2075 27 P 0 ;1
L 5.6575 3.2575 5.6575 3.2575 27 P 0 ;1
L 5.6575 3.3075 5.6575 3.3075 27 P 0 ;1
L 5.6575 3.3575 5.6575 3.3575 27 P 0 ;1
L 5.6575 3.4075 5.6575 3.4075 27 P 0 ;1
L 5.6575 3.4575 5.6575 3.4575 27 P 0 ;1
L 5.6575 3.5075 5.6575 3.5075 27 P 0 ;1
L 5.6575 3.5575 5.6575 3.5575 27 P 0 ;1
L 5.6575 3.6075 5.6575 3.6075 27 P 0 ;1
L 5.6575 3.6575 5.6575 3.6575 27 P 0 ;1
L 5.6575 3.7075 5.6575 3.7075 27 P 0 ;1
L 5.6575 3.7575 5.6575 3.7575 27 P 0 ;1
L 5.6575 3.8075 5.6575 3.8075 27 P 0 ;1
L 5.6575 3.8575 5.6575 3.8575 27 P 0 ;1
L 5.6575 3.9075 5.6575 3.9075 27 P 0 ;1
L 5.6575 3.9575 5.6575 3.9575 27 P 0 ;1
L 5.6575 4.0075 5.6575 4.0075 27 P 0 ;1
L 5.6575 4.0575 5.6575 4.0575 27 P 0 ;1
L 5.6575 4.1075 5.6575 4.1075 27 P 0 ;1
L 5.6575 4.1575 5.6575 4.1575 27 P 0 ;1
L 5.6575 4.2075 5.6575 4.2075 27 P 0 ;1
L 5.6575 4.2575 5.6575 4.2575 27 P 0 ;1
L 5.6575 4.3075 5.6575 4.3075 27 P 0 ;1
L 5.6575 4.3575 5.6575 4.3575 27 P 0 ;1
L 5.6575 4.4075 5.6575 4.4075 27 P 0 ;1
L 5.6575 5.7075 5.6575 5.7075 27 P 0 ;1
L 5.6575 5.7575 5.6575 5.7575 27 P 0 ;1
L 5.7075 0.6075 5.7075 0.6075 27 P 0 ;1
L 5.7075 0.6575 5.7075 0.6575 27 P 0 ;1
L 5.7075 0.8075 5.7075 0.8075 27 P 0 ;1
L 5.7075 0.8575 5.7075 0.8575 27 P 0 ;1
L 5.7075 0.9075 5.7075 0.9075 27 P 0 ;1
L 5.7075 0.9575 5.7075 0.9575 27 P 0 ;1
L 5.7075 1.0075 5.7075 1.0075 27 P 0 ;1
L 5.7075 1.0575 5.7075 1.0575 27 P 0 ;1
L 5.7075 1.1075 5.7075 1.1075 27 P 0 ;1
L 5.7075 1.1575 5.7075 1.1575 27 P 0 ;1
L 5.7075 1.2075 5.7075 1.2075 27 P 0 ;1
L 5.7075 1.2575 5.7075 1.2575 27 P 0 ;1
L 5.7075 1.3075 5.7075 1.3075 27 P 0 ;1
L 5.7075 1.3575 5.7075 1.3575 27 P 0 ;1
L 5.7075 1.4075 5.7075 1.4075 27 P 0 ;1
L 5.7075 1.4575 5.7075 1.4575 27 P 0 ;1
L 5.7075 1.5075 5.7075 1.5075 27 P 0 ;1
L 5.7075 1.5575 5.7075 1.5575 27 P 0 ;1
L 5.7075 1.6075 5.7075 1.6075 27 P 0 ;1
L 5.7075 1.6575 5.7075 1.6575 27 P 0 ;1
L 5.7075 1.7075 5.7075 1.7075 27 P 0 ;1
L 5.7075 1.7575 5.7075 1.7575 27 P 0 ;1
L 5.7075 1.8075 5.7075 1.8075 27 P 0 ;1
L 5.7075 1.8575 5.7075 1.8575 27 P 0 ;1
L 5.7075 1.9075 5.7075 1.9075 27 P 0 ;1
L 5.7075 1.9575 5.7075 1.9575 27 P 0 ;1
L 5.7075 2.0075 5.7075 2.0075 27 P 0 ;1
L 5.7075 2.0575 5.7075 2.0575 27 P 0 ;1
L 5.7075 2.1075 5.7075 2.1075 27 P 0 ;1
L 5.7075 2.1575 5.7075 2.1575 27 P 0 ;1
L 5.7075 2.2075 5.7075 2.2075 27 P 0 ;1
L 5.7075 2.2575 5.7075 2.2575 27 P 0 ;1
L 5.7075 2.3075 5.7075 2.3075 27 P 0 ;1
L 5.7075 2.3575 5.7075 2.3575 27 P 0 ;1
L 5.7075 2.4075 5.7075 2.4075 27 P 0 ;1
L 5.7075 2.4575 5.7075 2.4575 27 P 0 ;1
L 5.7075 2.5075 5.7075 2.5075 27 P 0 ;1
L 5.7075 2.5575 5.7075 2.5575 27 P 0 ;1
L 5.7075 2.7575 5.7075 2.7575 27 P 0 ;1
L 5.7075 3.1075 5.7075 3.1075 27 P 0 ;1
L 5.7075 3.1575 5.7075 3.1575 27 P 0 ;1
L 5.7075 3.2075 5.7075 3.2075 27 P 0 ;1
L 5.7075 3.2575 5.7075 3.2575 27 P 0 ;1
L 5.7075 3.3075 5.7075 3.3075 27 P 0 ;1
L 5.7075 3.3575 5.7075 3.3575 27 P 0 ;1
L 5.7075 3.4075 5.7075 3.4075 27 P 0 ;1
L 5.7075 3.4575 5.7075 3.4575 27 P 0 ;1
L 5.7075 3.5075 5.7075 3.5075 27 P 0 ;1
L 5.7075 3.5575 5.7075 3.5575 27 P 0 ;1
L 5.7075 3.6075 5.7075 3.6075 27 P 0 ;1
L 5.7075 3.6575 5.7075 3.6575 27 P 0 ;1
L 5.7075 3.7075 5.7075 3.7075 27 P 0 ;1
L 5.7075 3.7575 5.7075 3.7575 27 P 0 ;1
L 5.7075 3.8075 5.7075 3.8075 27 P 0 ;1
L 5.7075 3.8575 5.7075 3.8575 27 P 0 ;1
L 5.7075 3.9075 5.7075 3.9075 27 P 0 ;1
L 5.7075 3.9575 5.7075 3.9575 27 P 0 ;1
L 5.7075 4.0075 5.7075 4.0075 27 P 0 ;1
L 5.7075 4.0575 5.7075 4.0575 27 P 0 ;1
L 5.7075 4.1075 5.7075 4.1075 27 P 0 ;1
L 5.7075 4.1575 5.7075 4.1575 27 P 0 ;1
L 5.7075 4.2075 5.7075 4.2075 27 P 0 ;1
L 5.7075 4.2575 5.7075 4.2575 27 P 0 ;1
L 5.7075 4.3075 5.7075 4.3075 27 P 0 ;1
L 5.7075 4.3575 5.7075 4.3575 27 P 0 ;1
L 5.7075 4.4075 5.7075 4.4075 27 P 0 ;1
L 5.7075 5.7575 5.7075 5.7575 27 P 0 ;1
L 5.7575 0.6075 5.7575 0.6075 27 P 0 ;1
L 5.7575 0.6575 5.7575 0.6575 27 P 0 ;1
L 5.7575 0.8075 5.7575 0.8075 27 P 0 ;1
L 5.7575 1.0075 5.7575 1.0075 27 P 0 ;1
L 5.7575 1.0575 5.7575 1.0575 27 P 0 ;1
L 5.7575 1.1075 5.7575 1.1075 27 P 0 ;1
L 5.7575 1.1575 5.7575 1.1575 27 P 0 ;1
L 5.7575 1.2075 5.7575 1.2075 27 P 0 ;1
L 5.7575 1.2575 5.7575 1.2575 27 P 0 ;1
L 5.7575 1.3075 5.7575 1.3075 27 P 0 ;1
L 5.7575 1.3575 5.7575 1.3575 27 P 0 ;1
L 5.7575 1.4075 5.7575 1.4075 27 P 0 ;1
L 5.7575 1.4575 5.7575 1.4575 27 P 0 ;1
L 5.7575 1.5075 5.7575 1.5075 27 P 0 ;1
L 5.7575 1.5575 5.7575 1.5575 27 P 0 ;1
L 5.7575 1.6075 5.7575 1.6075 27 P 0 ;1
L 5.7575 1.6575 5.7575 1.6575 27 P 0 ;1
L 5.7575 1.7075 5.7575 1.7075 27 P 0 ;1
L 5.7575 1.7575 5.7575 1.7575 27 P 0 ;1
L 5.7575 1.8075 5.7575 1.8075 27 P 0 ;1
L 5.7575 1.8575 5.7575 1.8575 27 P 0 ;1
L 5.7575 1.9075 5.7575 1.9075 27 P 0 ;1
L 5.7575 1.9575 5.7575 1.9575 27 P 0 ;1
L 5.7575 2.0075 5.7575 2.0075 27 P 0 ;1
L 5.7575 2.0575 5.7575 2.0575 27 P 0 ;1
L 5.7575 2.1075 5.7575 2.1075 27 P 0 ;1
L 5.7575 2.1575 5.7575 2.1575 27 P 0 ;1
L 5.7575 2.2075 5.7575 2.2075 27 P 0 ;1
L 5.7575 2.2575 5.7575 2.2575 27 P 0 ;1
L 5.7575 2.3075 5.7575 2.3075 27 P 0 ;1
L 5.7575 2.3575 5.7575 2.3575 27 P 0 ;1
L 5.7575 2.4075 5.7575 2.4075 27 P 0 ;1
L 5.7575 2.4575 5.7575 2.4575 27 P 0 ;1
L 5.7575 2.5075 5.7575 2.5075 27 P 0 ;1
L 5.7575 2.5575 5.7575 2.5575 27 P 0 ;1
L 5.7575 2.7575 5.7575 2.7575 27 P 0 ;1
L 5.7575 2.9075 5.7575 2.9075 27 P 0 ;1
L 5.7575 3.1575 5.7575 3.1575 27 P 0 ;1
L 5.7575 3.2075 5.7575 3.2075 27 P 0 ;1
L 5.7575 3.2575 5.7575 3.2575 27 P 0 ;1
L 5.7575 3.3075 5.7575 3.3075 27 P 0 ;1
L 5.7575 3.3575 5.7575 3.3575 27 P 0 ;1
L 5.7575 3.4075 5.7575 3.4075 27 P 0 ;1
L 5.7575 3.4575 5.7575 3.4575 27 P 0 ;1
L 5.7575 3.5075 5.7575 3.5075 27 P 0 ;1
L 5.7575 3.5575 5.7575 3.5575 27 P 0 ;1
L 5.7575 3.6075 5.7575 3.6075 27 P 0 ;1
L 5.7575 3.6575 5.7575 3.6575 27 P 0 ;1
L 5.7575 3.7075 5.7575 3.7075 27 P 0 ;1
L 5.7575 3.7575 5.7575 3.7575 27 P 0 ;1
L 5.7575 3.8075 5.7575 3.8075 27 P 0 ;1
L 5.7575 3.8575 5.7575 3.8575 27 P 0 ;1
L 5.7575 3.9075 5.7575 3.9075 27 P 0 ;1
L 5.7575 3.9575 5.7575 3.9575 27 P 0 ;1
L 5.7575 4.0075 5.7575 4.0075 27 P 0 ;1
L 5.7575 4.0575 5.7575 4.0575 27 P 0 ;1
L 5.7575 4.1075 5.7575 4.1075 27 P 0 ;1
L 5.7575 4.1575 5.7575 4.1575 27 P 0 ;1
L 5.7575 4.2075 5.7575 4.2075 27 P 0 ;1
L 5.7575 4.2575 5.7575 4.2575 27 P 0 ;1
L 5.7575 4.3075 5.7575 4.3075 27 P 0 ;1
L 5.7575 4.3575 5.7575 4.3575 27 P 0 ;1
L 5.7575 4.4075 5.7575 4.4075 27 P 0 ;1
L 5.7575 5.7575 5.7575 5.7575 27 P 0 ;1
L 5.8075 0.6075 5.8075 0.6075 27 P 0 ;1
L 5.8075 0.6575 5.8075 0.6575 27 P 0 ;1
L 5.8075 0.8075 5.8075 0.8075 27 P 0 ;1
L 5.8075 1.0575 5.8075 1.0575 27 P 0 ;1
L 5.8075 1.1075 5.8075 1.1075 27 P 0 ;1
L 5.8075 1.1575 5.8075 1.1575 27 P 0 ;1
L 5.8075 1.2075 5.8075 1.2075 27 P 0 ;1
L 5.8075 1.2575 5.8075 1.2575 27 P 0 ;1
L 5.8075 1.3075 5.8075 1.3075 27 P 0 ;1
L 5.8075 1.3575 5.8075 1.3575 27 P 0 ;1
L 5.8075 1.4075 5.8075 1.4075 27 P 0 ;1
L 5.8075 1.4575 5.8075 1.4575 27 P 0 ;1
L 5.8075 1.5075 5.8075 1.5075 27 P 0 ;1
L 5.8075 1.5575 5.8075 1.5575 27 P 0 ;1
L 5.8075 1.6075 5.8075 1.6075 27 P 0 ;1
L 5.8075 1.6575 5.8075 1.6575 27 P 0 ;1
L 5.8075 1.7075 5.8075 1.7075 27 P 0 ;1
L 5.8075 1.7575 5.8075 1.7575 27 P 0 ;1
L 5.8075 1.8075 5.8075 1.8075 27 P 0 ;1
L 5.8075 1.8575 5.8075 1.8575 27 P 0 ;1
L 5.8075 1.9075 5.8075 1.9075 27 P 0 ;1
L 5.8075 1.9575 5.8075 1.9575 27 P 0 ;1
L 5.8075 2.0075 5.8075 2.0075 27 P 0 ;1
L 5.8075 2.0575 5.8075 2.0575 27 P 0 ;1
L 5.8075 2.1075 5.8075 2.1075 27 P 0 ;1
L 5.8075 2.1575 5.8075 2.1575 27 P 0 ;1
L 5.8075 2.2075 5.8075 2.2075 27 P 0 ;1
L 5.8075 2.2575 5.8075 2.2575 27 P 0 ;1
L 5.8075 2.3075 5.8075 2.3075 27 P 0 ;1
L 5.8075 2.3575 5.8075 2.3575 27 P 0 ;1
L 5.8075 2.4075 5.8075 2.4075 27 P 0 ;1
L 5.8075 2.4575 5.8075 2.4575 27 P 0 ;1
L 5.8075 2.5075 5.8075 2.5075 27 P 0 ;1
L 5.8075 2.5575 5.8075 2.5575 27 P 0 ;1
L 5.8075 2.7575 5.8075 2.7575 27 P 0 ;1
L 5.8075 3.1575 5.8075 3.1575 27 P 0 ;1
L 5.8075 3.2075 5.8075 3.2075 27 P 0 ;1
L 5.8075 3.2575 5.8075 3.2575 27 P 0 ;1
L 5.8075 3.3075 5.8075 3.3075 27 P 0 ;1
L 5.8075 3.3575 5.8075 3.3575 27 P 0 ;1
L 5.8075 3.4075 5.8075 3.4075 27 P 0 ;1
L 5.8075 3.4575 5.8075 3.4575 27 P 0 ;1
L 5.8075 3.5075 5.8075 3.5075 27 P 0 ;1
L 5.8075 3.5575 5.8075 3.5575 27 P 0 ;1
L 5.8075 3.6075 5.8075 3.6075 27 P 0 ;1
L 5.8075 3.6575 5.8075 3.6575 27 P 0 ;1
L 5.8075 3.7075 5.8075 3.7075 27 P 0 ;1
L 5.8075 3.7575 5.8075 3.7575 27 P 0 ;1
L 5.8075 3.8075 5.8075 3.8075 27 P 0 ;1
L 5.8075 3.8575 5.8075 3.8575 27 P 0 ;1
L 5.8075 3.9075 5.8075 3.9075 27 P 0 ;1
L 5.8075 3.9575 5.8075 3.9575 27 P 0 ;1
L 5.8075 4.0075 5.8075 4.0075 27 P 0 ;1
L 5.8075 4.0575 5.8075 4.0575 27 P 0 ;1
L 5.8075 4.1075 5.8075 4.1075 27 P 0 ;1
L 5.8075 4.1575 5.8075 4.1575 27 P 0 ;1
L 5.8075 4.2075 5.8075 4.2075 27 P 0 ;1
L 5.8075 4.2575 5.8075 4.2575 27 P 0 ;1
L 5.8075 4.3075 5.8075 4.3075 27 P 0 ;1
L 5.8075 4.3575 5.8075 4.3575 27 P 0 ;1
L 5.8075 4.4075 5.8075 4.4075 27 P 0 ;1
L 5.8075 5.7575 5.8075 5.7575 27 P 0 ;1
L 5.8575 0.6075 5.8575 0.6075 27 P 0 ;1
L 5.8575 0.6575 5.8575 0.6575 27 P 0 ;1
L 5.8575 0.8075 5.8575 0.8075 27 P 0 ;1
L 5.8575 1.0575 5.8575 1.0575 27 P 0 ;1
L 5.8575 1.1075 5.8575 1.1075 27 P 0 ;1
L 5.8575 1.1575 5.8575 1.1575 27 P 0 ;1
L 5.8575 1.2075 5.8575 1.2075 27 P 0 ;1
L 5.8575 1.2575 5.8575 1.2575 27 P 0 ;1
L 5.8575 1.3075 5.8575 1.3075 27 P 0 ;1
L 5.8575 1.3575 5.8575 1.3575 27 P 0 ;1
L 5.8575 1.4075 5.8575 1.4075 27 P 0 ;1
L 5.8575 1.4575 5.8575 1.4575 27 P 0 ;1
L 5.8575 1.5075 5.8575 1.5075 27 P 0 ;1
L 5.8575 1.5575 5.8575 1.5575 27 P 0 ;1
L 5.8575 1.6075 5.8575 1.6075 27 P 0 ;1
L 5.8575 1.6575 5.8575 1.6575 27 P 0 ;1
L 5.8575 1.7075 5.8575 1.7075 27 P 0 ;1
L 5.8575 1.7575 5.8575 1.7575 27 P 0 ;1
L 5.8575 1.8075 5.8575 1.8075 27 P 0 ;1
L 5.8575 1.8575 5.8575 1.8575 27 P 0 ;1
L 5.8575 1.9075 5.8575 1.9075 27 P 0 ;1
L 5.8575 1.9575 5.8575 1.9575 27 P 0 ;1
L 5.8575 2.0075 5.8575 2.0075 27 P 0 ;1
L 5.8575 2.0575 5.8575 2.0575 27 P 0 ;1
L 5.8575 2.1075 5.8575 2.1075 27 P 0 ;1
L 5.8575 2.1575 5.8575 2.1575 27 P 0 ;1
L 5.8575 2.2075 5.8575 2.2075 27 P 0 ;1
L 5.8575 2.2575 5.8575 2.2575 27 P 0 ;1
L 5.8575 2.3075 5.8575 2.3075 27 P 0 ;1
L 5.8575 2.3575 5.8575 2.3575 27 P 0 ;1
L 5.8575 2.4075 5.8575 2.4075 27 P 0 ;1
L 5.8575 2.4575 5.8575 2.4575 27 P 0 ;1
L 5.8575 2.5075 5.8575 2.5075 27 P 0 ;1
L 5.8575 2.5575 5.8575 2.5575 27 P 0 ;1
L 5.8575 2.6075 5.8575 2.6075 27 P 0 ;1
L 5.8575 2.6575 5.8575 2.6575 27 P 0 ;1
L 5.8575 2.7075 5.8575 2.7075 27 P 0 ;1
L 5.8575 2.7575 5.8575 2.7575 27 P 0 ;1
L 5.8575 3.2075 5.8575 3.2075 27 P 0 ;1
L 5.8575 3.2575 5.8575 3.2575 27 P 0 ;1
L 5.8575 3.3075 5.8575 3.3075 27 P 0 ;1
L 5.8575 3.3575 5.8575 3.3575 27 P 0 ;1
L 5.8575 3.4075 5.8575 3.4075 27 P 0 ;1
L 5.8575 3.4575 5.8575 3.4575 27 P 0 ;1
L 5.8575 3.5075 5.8575 3.5075 27 P 0 ;1
L 5.8575 3.5575 5.8575 3.5575 27 P 0 ;1
L 5.8575 3.6075 5.8575 3.6075 27 P 0 ;1
L 5.8575 3.6575 5.8575 3.6575 27 P 0 ;1
L 5.8575 3.7075 5.8575 3.7075 27 P 0 ;1
L 5.8575 3.7575 5.8575 3.7575 27 P 0 ;1
L 5.8575 3.8075 5.8575 3.8075 27 P 0 ;1
L 5.8575 3.8575 5.8575 3.8575 27 P 0 ;1
L 5.8575 3.9075 5.8575 3.9075 27 P 0 ;1
L 5.8575 3.9575 5.8575 3.9575 27 P 0 ;1
L 5.8575 4.0075 5.8575 4.0075 27 P 0 ;1
L 5.8575 4.0575 5.8575 4.0575 27 P 0 ;1
L 5.8575 4.1075 5.8575 4.1075 27 P 0 ;1
L 5.8575 4.1575 5.8575 4.1575 27 P 0 ;1
L 5.8575 4.2075 5.8575 4.2075 27 P 0 ;1
L 5.8575 4.2575 5.8575 4.2575 27 P 0 ;1
L 5.8575 4.3075 5.8575 4.3075 27 P 0 ;1
L 5.8575 4.3575 5.8575 4.3575 27 P 0 ;1
L 5.8575 4.4075 5.8575 4.4075 27 P 0 ;1
L 5.8575 5.7575 5.8575 5.7575 27 P 0 ;1
L 5.9075 0.6075 5.9075 0.6075 27 P 0 ;1
L 5.9075 0.6575 5.9075 0.6575 27 P 0 ;1
L 5.9075 0.8075 5.9075 0.8075 27 P 0 ;1
L 5.9075 1.0075 5.9075 1.0075 27 P 0 ;1
L 5.9075 1.0575 5.9075 1.0575 27 P 0 ;1
L 5.9075 1.1075 5.9075 1.1075 27 P 0 ;1
L 5.9075 1.1575 5.9075 1.1575 27 P 0 ;1
L 5.9075 1.2075 5.9075 1.2075 27 P 0 ;1
L 5.9075 1.2575 5.9075 1.2575 27 P 0 ;1
L 5.9075 1.3075 5.9075 1.3075 27 P 0 ;1
L 5.9075 1.3575 5.9075 1.3575 27 P 0 ;1
L 5.9075 1.6575 5.9075 1.6575 27 P 0 ;1
L 5.9075 1.7075 5.9075 1.7075 27 P 0 ;1
L 5.9075 1.7575 5.9075 1.7575 27 P 0 ;1
L 5.9075 1.8075 5.9075 1.8075 27 P 0 ;1
L 5.9075 1.8575 5.9075 1.8575 27 P 0 ;1
L 5.9075 1.9075 5.9075 1.9075 27 P 0 ;1
L 5.9075 1.9575 5.9075 1.9575 27 P 0 ;1
L 5.9075 2.0075 5.9075 2.0075 27 P 0 ;1
L 5.9075 2.0575 5.9075 2.0575 27 P 0 ;1
L 5.9075 2.1075 5.9075 2.1075 27 P 0 ;1
L 5.9075 2.1575 5.9075 2.1575 27 P 0 ;1
L 5.9075 2.2075 5.9075 2.2075 27 P 0 ;1
L 5.9075 2.2575 5.9075 2.2575 27 P 0 ;1
L 5.9075 2.3075 5.9075 2.3075 27 P 0 ;1
L 5.9075 2.3575 5.9075 2.3575 27 P 0 ;1
L 5.9075 2.4075 5.9075 2.4075 27 P 0 ;1
L 5.9075 2.4575 5.9075 2.4575 27 P 0 ;1
L 5.9075 2.5075 5.9075 2.5075 27 P 0 ;1
L 5.9075 2.6575 5.9075 2.6575 27 P 0 ;1
L 5.9075 2.7075 5.9075 2.7075 27 P 0 ;1
L 5.9075 2.7575 5.9075 2.7575 27 P 0 ;1
L 5.9075 3.1575 5.9075 3.1575 27 P 0 ;1
L 5.9075 3.2075 5.9075 3.2075 27 P 0 ;1
L 5.9075 3.2575 5.9075 3.2575 27 P 0 ;1
L 5.9075 3.3075 5.9075 3.3075 27 P 0 ;1
L 5.9075 3.3575 5.9075 3.3575 27 P 0 ;1
L 5.9075 3.4075 5.9075 3.4075 27 P 0 ;1
L 5.9075 3.4575 5.9075 3.4575 27 P 0 ;1
L 5.9075 3.5075 5.9075 3.5075 27 P 0 ;1
L 5.9075 3.5575 5.9075 3.5575 27 P 0 ;1
L 5.9075 3.6075 5.9075 3.6075 27 P 0 ;1
L 5.9075 3.6575 5.9075 3.6575 27 P 0 ;1
L 5.9075 3.7075 5.9075 3.7075 27 P 0 ;1
L 5.9075 3.7575 5.9075 3.7575 27 P 0 ;1
L 5.9075 3.8075 5.9075 3.8075 27 P 0 ;1
L 5.9075 3.8575 5.9075 3.8575 27 P 0 ;1
L 5.9075 3.9075 5.9075 3.9075 27 P 0 ;1
L 5.9075 3.9575 5.9075 3.9575 27 P 0 ;1
L 5.9075 4.0075 5.9075 4.0075 27 P 0 ;1
L 5.9075 4.0575 5.9075 4.0575 27 P 0 ;1
L 5.9075 4.3575 5.9075 4.3575 27 P 0 ;1
L 5.9075 4.4075 5.9075 4.4075 27 P 0 ;1
L 5.9075 5.7075 5.9075 5.7075 27 P 0 ;1
L 5.9075 5.7575 5.9075 5.7575 27 P 0 ;1
L 5.9575 0.6075 5.9575 0.6075 27 P 0 ;1
L 5.9575 0.6575 5.9575 0.6575 27 P 0 ;1
L 5.9575 0.8075 5.9575 0.8075 27 P 0 ;1
L 5.9575 0.8575 5.9575 0.8575 27 P 0 ;1
L 5.9575 0.9075 5.9575 0.9075 27 P 0 ;1
L 5.9575 0.9575 5.9575 0.9575 27 P 0 ;1
L 5.9575 1.0075 5.9575 1.0075 27 P 0 ;1
L 5.9575 1.0575 5.9575 1.0575 27 P 0 ;1
L 5.9575 1.1075 5.9575 1.1075 27 P 0 ;1
L 5.9575 1.1575 5.9575 1.1575 27 P 0 ;1
L 5.9575 1.2075 5.9575 1.2075 27 P 0 ;1
L 5.9575 1.2575 5.9575 1.2575 27 P 0 ;1
L 5.9575 1.3075 5.9575 1.3075 27 P 0 ;1
L 5.9575 1.7575 5.9575 1.7575 27 P 0 ;1
L 5.9575 1.8075 5.9575 1.8075 27 P 0 ;1
L 5.9575 1.8575 5.9575 1.8575 27 P 0 ;1
L 5.9575 1.9075 5.9575 1.9075 27 P 0 ;1
L 5.9575 1.9575 5.9575 1.9575 27 P 0 ;1
L 5.9575 2.0075 5.9575 2.0075 27 P 0 ;1
L 5.9575 2.0575 5.9575 2.0575 27 P 0 ;1
L 5.9575 2.1075 5.9575 2.1075 27 P 0 ;1
L 5.9575 2.1575 5.9575 2.1575 27 P 0 ;1
L 5.9575 2.2075 5.9575 2.2075 27 P 0 ;1
L 5.9575 2.2575 5.9575 2.2575 27 P 0 ;1
L 5.9575 2.3075 5.9575 2.3075 27 P 0 ;1
L 5.9575 2.3575 5.9575 2.3575 27 P 0 ;1
L 5.9575 2.4075 5.9575 2.4075 27 P 0 ;1
L 5.9575 2.4575 5.9575 2.4575 27 P 0 ;1
L 5.9575 2.7075 5.9575 2.7075 27 P 0 ;1
L 5.9575 2.7575 5.9575 2.7575 27 P 0 ;1
L 5.9575 2.8075 5.9575 2.8075 27 P 0 ;1
L 5.9575 3.0575 5.9575 3.0575 27 P 0 ;1
L 5.9575 3.1075 5.9575 3.1075 27 P 0 ;1
L 5.9575 3.1575 5.9575 3.1575 27 P 0 ;1
L 5.9575 3.2075 5.9575 3.2075 27 P 0 ;1
L 5.9575 3.2575 5.9575 3.2575 27 P 0 ;1
L 5.9575 3.3075 5.9575 3.3075 27 P 0 ;1
L 5.9575 3.3575 5.9575 3.3575 27 P 0 ;1
L 5.9575 3.4075 5.9575 3.4075 27 P 0 ;1
L 5.9575 3.4575 5.9575 3.4575 27 P 0 ;1
L 5.9575 3.5075 5.9575 3.5075 27 P 0 ;1
L 5.9575 3.5575 5.9575 3.5575 27 P 0 ;1
L 5.9575 3.6075 5.9575 3.6075 27 P 0 ;1
L 5.9575 3.6575 5.9575 3.6575 27 P 0 ;1
L 5.9575 3.7075 5.9575 3.7075 27 P 0 ;1
L 5.9575 3.7575 5.9575 3.7575 27 P 0 ;1
L 5.9575 3.8075 5.9575 3.8075 27 P 0 ;1
L 5.9575 3.8575 5.9575 3.8575 27 P 0 ;1
L 5.9575 3.9075 5.9575 3.9075 27 P 0 ;1
L 5.9575 3.9575 5.9575 3.9575 27 P 0 ;1
L 5.9575 4.0075 5.9575 4.0075 27 P 0 ;1
L 5.9575 4.4075 5.9575 4.4075 27 P 0 ;1
L 5.9575 5.7075 5.9575 5.7075 27 P 0 ;1
L 5.9575 5.7575 5.9575 5.7575 27 P 0 ;1
L 6.0075 0.6075 6.0075 0.6075 27 P 0 ;1
L 6.0075 0.6575 6.0075 0.6575 27 P 0 ;1
L 6.0075 0.8075 6.0075 0.8075 27 P 0 ;1
L 6.0075 0.8575 6.0075 0.8575 27 P 0 ;1
L 6.0075 0.9075 6.0075 0.9075 27 P 0 ;1
L 6.0075 0.9575 6.0075 0.9575 27 P 0 ;1
L 6.0075 1.0075 6.0075 1.0075 27 P 0 ;1
L 6.0075 1.0575 6.0075 1.0575 27 P 0 ;1
L 6.0075 1.1075 6.0075 1.1075 27 P 0 ;1
L 6.0075 1.1575 6.0075 1.1575 27 P 0 ;1
L 6.0075 1.2075 6.0075 1.2075 27 P 0 ;1
L 6.0075 1.2575 6.0075 1.2575 27 P 0 ;1
L 6.0075 1.3075 6.0075 1.3075 27 P 0 ;1
L 6.0075 1.7575 6.0075 1.7575 27 P 0 ;1
L 6.0075 1.8075 6.0075 1.8075 27 P 0 ;1
L 6.0075 1.8575 6.0075 1.8575 27 P 0 ;1
L 6.0075 1.9075 6.0075 1.9075 27 P 0 ;1
L 6.0075 1.9575 6.0075 1.9575 27 P 0 ;1
L 6.0075 2.0075 6.0075 2.0075 27 P 0 ;1
L 6.0075 2.0575 6.0075 2.0575 27 P 0 ;1
L 6.0075 2.1075 6.0075 2.1075 27 P 0 ;1
L 6.0075 2.1575 6.0075 2.1575 27 P 0 ;1
L 6.0075 2.2075 6.0075 2.2075 27 P 0 ;1
L 6.0075 2.2575 6.0075 2.2575 27 P 0 ;1
L 6.0075 2.3075 6.0075 2.3075 27 P 0 ;1
L 6.0075 2.3575 6.0075 2.3575 27 P 0 ;1
L 6.0075 2.4075 6.0075 2.4075 27 P 0 ;1
L 6.0075 2.7575 6.0075 2.7575 27 P 0 ;1
L 6.0075 2.8075 6.0075 2.8075 27 P 0 ;1
L 6.0075 2.8575 6.0075 2.8575 27 P 0 ;1
L 6.0075 2.9075 6.0075 2.9075 27 P 0 ;1
L 6.0075 3.0075 6.0075 3.0075 27 P 0 ;1
L 6.0075 3.0575 6.0075 3.0575 27 P 0 ;1
L 6.0075 3.1075 6.0075 3.1075 27 P 0 ;1
L 6.0075 3.1575 6.0075 3.1575 27 P 0 ;1
L 6.0075 3.2075 6.0075 3.2075 27 P 0 ;1
L 6.0075 3.2575 6.0075 3.2575 27 P 0 ;1
L 6.0075 3.3075 6.0075 3.3075 27 P 0 ;1
L 6.0075 3.3575 6.0075 3.3575 27 P 0 ;1
L 6.0075 3.4075 6.0075 3.4075 27 P 0 ;1
L 6.0075 3.4575 6.0075 3.4575 27 P 0 ;1
L 6.0075 3.5075 6.0075 3.5075 27 P 0 ;1
L 6.0075 3.5575 6.0075 3.5575 27 P 0 ;1
L 6.0075 3.6075 6.0075 3.6075 27 P 0 ;1
L 6.0075 3.6575 6.0075 3.6575 27 P 0 ;1
L 6.0075 3.7075 6.0075 3.7075 27 P 0 ;1
L 6.0075 3.7575 6.0075 3.7575 27 P 0 ;1
L 6.0075 3.8075 6.0075 3.8075 27 P 0 ;1
L 6.0075 3.8575 6.0075 3.8575 27 P 0 ;1
L 6.0075 3.9075 6.0075 3.9075 27 P 0 ;1
L 6.0075 3.9575 6.0075 3.9575 27 P 0 ;1
L 6.0075 5.2575 6.0075 5.2575 27 P 0 ;1
L 6.0075 5.6575 6.0075 5.6575 27 P 0 ;1
L 6.0075 5.7075 6.0075 5.7075 27 P 0 ;1
L 6.0075 5.7575 6.0075 5.7575 27 P 0 ;1
L 6.0575 0.6075 6.0575 0.6075 27 P 0 ;1
L 6.0575 0.6575 6.0575 0.6575 27 P 0 ;1
L 6.0575 0.8075 6.0575 0.8075 27 P 0 ;1
L 6.0575 0.8575 6.0575 0.8575 27 P 0 ;1
L 6.0575 0.9075 6.0575 0.9075 27 P 0 ;1
L 6.0575 0.9575 6.0575 0.9575 27 P 0 ;1
L 6.0575 1.0075 6.0575 1.0075 27 P 0 ;1
L 6.0575 1.0575 6.0575 1.0575 27 P 0 ;1
L 6.0575 1.1075 6.0575 1.1075 27 P 0 ;1
L 6.0575 1.1575 6.0575 1.1575 27 P 0 ;1
L 6.0575 1.2075 6.0575 1.2075 27 P 0 ;1
L 6.0575 1.2575 6.0575 1.2575 27 P 0 ;1
L 6.0575 1.8075 6.0575 1.8075 27 P 0 ;1
L 6.0575 1.8575 6.0575 1.8575 27 P 0 ;1
L 6.0575 1.9075 6.0575 1.9075 27 P 0 ;1
L 6.0575 1.9575 6.0575 1.9575 27 P 0 ;1
L 6.0575 2.0075 6.0575 2.0075 27 P 0 ;1
L 6.0575 2.0575 6.0575 2.0575 27 P 0 ;1
L 6.0575 2.1075 6.0575 2.1075 27 P 0 ;1
L 6.0575 2.1575 6.0575 2.1575 27 P 0 ;1
L 6.0575 2.2075 6.0575 2.2075 27 P 0 ;1
L 6.0575 2.2575 6.0575 2.2575 27 P 0 ;1
L 6.0575 2.3075 6.0575 2.3075 27 P 0 ;1
L 6.0575 2.3575 6.0575 2.3575 27 P 0 ;1
L 6.0575 2.4075 6.0575 2.4075 27 P 0 ;1
L 6.0575 2.7575 6.0575 2.7575 27 P 0 ;1
L 6.0575 2.8075 6.0575 2.8075 27 P 0 ;1
L 6.0575 2.8575 6.0575 2.8575 27 P 0 ;1
L 6.0575 2.9075 6.0575 2.9075 27 P 0 ;1
L 6.0575 2.9575 6.0575 2.9575 27 P 0 ;1
L 6.0575 3.0075 6.0575 3.0075 27 P 0 ;1
L 6.0575 3.0575 6.0575 3.0575 27 P 0 ;1
L 6.0575 3.1075 6.0575 3.1075 27 P 0 ;1
L 6.0575 3.1575 6.0575 3.1575 27 P 0 ;1
L 6.0575 3.2075 6.0575 3.2075 27 P 0 ;1
L 6.0575 3.2575 6.0575 3.2575 27 P 0 ;1
L 6.0575 3.3075 6.0575 3.3075 27 P 0 ;1
L 6.0575 3.3575 6.0575 3.3575 27 P 0 ;1
L 6.0575 3.4075 6.0575 3.4075 27 P 0 ;1
L 6.0575 3.4575 6.0575 3.4575 27 P 0 ;1
L 6.0575 3.5075 6.0575 3.5075 27 P 0 ;1
L 6.0575 3.5575 6.0575 3.5575 27 P 0 ;1
L 6.0575 3.6075 6.0575 3.6075 27 P 0 ;1
L 6.0575 3.6575 6.0575 3.6575 27 P 0 ;1
L 6.0575 3.7075 6.0575 3.7075 27 P 0 ;1
L 6.0575 3.7575 6.0575 3.7575 27 P 0 ;1
L 6.0575 3.8075 6.0575 3.8075 27 P 0 ;1
L 6.0575 3.8575 6.0575 3.8575 27 P 0 ;1
L 6.0575 3.9075 6.0575 3.9075 27 P 0 ;1
L 6.0575 3.9575 6.0575 3.9575 27 P 0 ;1
L 6.0575 5.2575 6.0575 5.2575 27 P 0 ;1
L 6.0575 5.3075 6.0575 5.3075 27 P 0 ;1
L 6.0575 5.3575 6.0575 5.3575 27 P 0 ;1
L 6.0575 5.5075 6.0575 5.5075 27 P 0 ;1
L 6.0575 5.5575 6.0575 5.5575 27 P 0 ;1
L 6.0575 5.6075 6.0575 5.6075 27 P 0 ;1
L 6.0575 5.6575 6.0575 5.6575 27 P 0 ;1
L 6.0575 5.7075 6.0575 5.7075 27 P 0 ;1
L 6.0575 5.7575 6.0575 5.7575 27 P 0 ;1
L 6.1075 0.6075 6.1075 0.6075 27 P 0 ;1
L 6.1075 0.6575 6.1075 0.6575 27 P 0 ;1
L 6.1075 0.8075 6.1075 0.8075 27 P 0 ;1
L 6.1075 0.8575 6.1075 0.8575 27 P 0 ;1
L 6.1075 0.9075 6.1075 0.9075 27 P 0 ;1
L 6.1075 0.9575 6.1075 0.9575 27 P 0 ;1
L 6.1075 1.0075 6.1075 1.0075 27 P 0 ;1
L 6.1075 1.0575 6.1075 1.0575 27 P 0 ;1
L 6.1075 1.1075 6.1075 1.1075 27 P 0 ;1
L 6.1075 1.1575 6.1075 1.1575 27 P 0 ;1
L 6.1075 1.2075 6.1075 1.2075 27 P 0 ;1
L 6.1075 1.2575 6.1075 1.2575 27 P 0 ;1
L 6.1075 1.8075 6.1075 1.8075 27 P 0 ;1
L 6.1075 1.8575 6.1075 1.8575 27 P 0 ;1
L 6.1075 1.9075 6.1075 1.9075 27 P 0 ;1
L 6.1075 1.9575 6.1075 1.9575 27 P 0 ;1
L 6.1075 2.0075 6.1075 2.0075 27 P 0 ;1
L 6.1075 2.0575 6.1075 2.0575 27 P 0 ;1
L 6.1075 2.1075 6.1075 2.1075 27 P 0 ;1
L 6.1075 2.1575 6.1075 2.1575 27 P 0 ;1
L 6.1075 2.2075 6.1075 2.2075 27 P 0 ;1
L 6.1075 2.2575 6.1075 2.2575 27 P 0 ;1
L 6.1075 2.3075 6.1075 2.3075 27 P 0 ;1
L 6.1075 2.3575 6.1075 2.3575 27 P 0 ;1
L 6.1075 2.4075 6.1075 2.4075 27 P 0 ;1
L 6.1075 2.7575 6.1075 2.7575 27 P 0 ;1
L 6.1075 2.8075 6.1075 2.8075 27 P 0 ;1
L 6.1075 2.8575 6.1075 2.8575 27 P 0 ;1
L 6.1075 2.9075 6.1075 2.9075 27 P 0 ;1
L 6.1075 2.9575 6.1075 2.9575 27 P 0 ;1
L 6.1075 3.0075 6.1075 3.0075 27 P 0 ;1
L 6.1075 3.0575 6.1075 3.0575 27 P 0 ;1
L 6.1075 3.1075 6.1075 3.1075 27 P 0 ;1
L 6.1075 3.1575 6.1075 3.1575 27 P 0 ;1
L 6.1075 3.2075 6.1075 3.2075 27 P 0 ;1
L 6.1075 3.2575 6.1075 3.2575 27 P 0 ;1
L 6.1075 3.3075 6.1075 3.3075 27 P 0 ;1
L 6.1075 3.3575 6.1075 3.3575 27 P 0 ;1
L 6.1075 3.4075 6.1075 3.4075 27 P 0 ;1
L 6.1075 3.4575 6.1075 3.4575 27 P 0 ;1
L 6.1075 3.5075 6.1075 3.5075 27 P 0 ;1
L 6.1075 3.5575 6.1075 3.5575 27 P 0 ;1
L 6.1075 3.6075 6.1075 3.6075 27 P 0 ;1
L 6.1075 3.6575 6.1075 3.6575 27 P 0 ;1
L 6.1075 3.7075 6.1075 3.7075 27 P 0 ;1
L 6.1075 3.7575 6.1075 3.7575 27 P 0 ;1
L 6.1075 3.8075 6.1075 3.8075 27 P 0 ;1
L 6.1075 3.8575 6.1075 3.8575 27 P 0 ;1
L 6.1075 3.9075 6.1075 3.9075 27 P 0 ;1
L 6.1075 3.9575 6.1075 3.9575 27 P 0 ;1
L 6.1075 5.2575 6.1075 5.2575 27 P 0 ;1
L 6.1075 5.3075 6.1075 5.3075 27 P 0 ;1
L 6.1075 5.3575 6.1075 5.3575 27 P 0 ;1
L 6.1075 5.4075 6.1075 5.4075 27 P 0 ;1
L 6.1075 5.4575 6.1075 5.4575 27 P 0 ;1
L 6.1075 5.5075 6.1075 5.5075 27 P 0 ;1
L 6.1075 5.5575 6.1075 5.5575 27 P 0 ;1
L 6.1075 5.6075 6.1075 5.6075 27 P 0 ;1
L 6.1075 5.6575 6.1075 5.6575 27 P 0 ;1
L 6.1075 5.7075 6.1075 5.7075 27 P 0 ;1
L 6.1075 5.7575 6.1075 5.7575 27 P 0 ;1
L 6.1575 0.6075 6.1575 0.6075 27 P 0 ;1
L 6.1575 0.6575 6.1575 0.6575 27 P 0 ;1
L 6.1575 0.7075 6.1575 0.7075 27 P 0 ;1
L 6.1575 0.7575 6.1575 0.7575 27 P 0 ;1
L 6.1575 0.8075 6.1575 0.8075 27 P 0 ;1
L 6.1575 0.8575 6.1575 0.8575 27 P 0 ;1
L 6.1575 0.9075 6.1575 0.9075 27 P 0 ;1
L 6.1575 0.9575 6.1575 0.9575 27 P 0 ;1
L 6.1575 1.0075 6.1575 1.0075 27 P 0 ;1
L 6.1575 1.0575 6.1575 1.0575 27 P 0 ;1
L 6.1575 1.1075 6.1575 1.1075 27 P 0 ;1
L 6.1575 1.1575 6.1575 1.1575 27 P 0 ;1
L 6.1575 1.2075 6.1575 1.2075 27 P 0 ;1
L 6.1575 1.2575 6.1575 1.2575 27 P 0 ;1
L 6.1575 1.8075 6.1575 1.8075 27 P 0 ;1
L 6.1575 1.8575 6.1575 1.8575 27 P 0 ;1
L 6.1575 1.9075 6.1575 1.9075 27 P 0 ;1
L 6.1575 1.9575 6.1575 1.9575 27 P 0 ;1
L 6.1575 2.0075 6.1575 2.0075 27 P 0 ;1
L 6.1575 2.0575 6.1575 2.0575 27 P 0 ;1
L 6.1575 2.1075 6.1575 2.1075 27 P 0 ;1
L 6.1575 2.1575 6.1575 2.1575 27 P 0 ;1
L 6.1575 2.2075 6.1575 2.2075 27 P 0 ;1
L 6.1575 2.2575 6.1575 2.2575 27 P 0 ;1
L 6.1575 2.3075 6.1575 2.3075 27 P 0 ;1
L 6.1575 2.3575 6.1575 2.3575 27 P 0 ;1
L 6.1575 2.4075 6.1575 2.4075 27 P 0 ;1
L 6.1575 2.4575 6.1575 2.4575 27 P 0 ;1
L 6.1575 2.7075 6.1575 2.7075 27 P 0 ;1
L 6.1575 2.7575 6.1575 2.7575 27 P 0 ;1
L 6.1575 2.8075 6.1575 2.8075 27 P 0 ;1
L 6.1575 2.8575 6.1575 2.8575 27 P 0 ;1
L 6.1575 2.9075 6.1575 2.9075 27 P 0 ;1
L 6.1575 2.9575 6.1575 2.9575 27 P 0 ;1
L 6.1575 3.0075 6.1575 3.0075 27 P 0 ;1
L 6.1575 3.0575 6.1575 3.0575 27 P 0 ;1
L 6.1575 3.1075 6.1575 3.1075 27 P 0 ;1
L 6.1575 3.1575 6.1575 3.1575 27 P 0 ;1
L 6.1575 3.2075 6.1575 3.2075 27 P 0 ;1
L 6.1575 3.2575 6.1575 3.2575 27 P 0 ;1
L 6.1575 3.3075 6.1575 3.3075 27 P 0 ;1
L 6.1575 3.3575 6.1575 3.3575 27 P 0 ;1
L 6.1575 3.4075 6.1575 3.4075 27 P 0 ;1
L 6.1575 3.4575 6.1575 3.4575 27 P 0 ;1
L 6.1575 3.5075 6.1575 3.5075 27 P 0 ;1
L 6.1575 3.5575 6.1575 3.5575 27 P 0 ;1
L 6.1575 3.6075 6.1575 3.6075 27 P 0 ;1
L 6.1575 3.6575 6.1575 3.6575 27 P 0 ;1
L 6.1575 3.7075 6.1575 3.7075 27 P 0 ;1
L 6.1575 3.7575 6.1575 3.7575 27 P 0 ;1
L 6.1575 3.8075 6.1575 3.8075 27 P 0 ;1
L 6.1575 3.8575 6.1575 3.8575 27 P 0 ;1
L 6.1575 3.9075 6.1575 3.9075 27 P 0 ;1
L 6.1575 3.9575 6.1575 3.9575 27 P 0 ;1
L 6.1575 5.2575 6.1575 5.2575 27 P 0 ;1
L 6.1575 5.3075 6.1575 5.3075 27 P 0 ;1
L 6.1575 5.3575 6.1575 5.3575 27 P 0 ;1
L 6.1575 5.4075 6.1575 5.4075 27 P 0 ;1
L 6.1575 5.4575 6.1575 5.4575 27 P 0 ;1
L 6.1575 5.5075 6.1575 5.5075 27 P 0 ;1
L 6.1575 5.5575 6.1575 5.5575 27 P 0 ;1
L 6.1575 5.6075 6.1575 5.6075 27 P 0 ;1
L 6.1575 5.6575 6.1575 5.6575 27 P 0 ;1
L 6.1575 5.7075 6.1575 5.7075 27 P 0 ;1
L 6.1575 5.7575 6.1575 5.7575 27 P 0 ;1
L 6.2075 0.6075 6.2075 0.6075 27 P 0 ;1
L 6.2075 0.6575 6.2075 0.6575 27 P 0 ;1
L 6.2075 0.7075 6.2075 0.7075 27 P 0 ;1
L 6.2075 0.7575 6.2075 0.7575 27 P 0 ;1
L 6.2075 0.8075 6.2075 0.8075 27 P 0 ;1
L 6.2075 0.8575 6.2075 0.8575 27 P 0 ;1
L 6.2075 0.9075 6.2075 0.9075 27 P 0 ;1
L 6.2075 0.9575 6.2075 0.9575 27 P 0 ;1
L 6.2075 1.0075 6.2075 1.0075 27 P 0 ;1
L 6.2075 1.0575 6.2075 1.0575 27 P 0 ;1
L 6.2075 1.1075 6.2075 1.1075 27 P 0 ;1
L 6.2075 1.1575 6.2075 1.1575 27 P 0 ;1
L 6.2075 1.2075 6.2075 1.2075 27 P 0 ;1
L 6.2075 1.2575 6.2075 1.2575 27 P 0 ;1
L 6.2075 1.7575 6.2075 1.7575 27 P 0 ;1
L 6.2075 1.8075 6.2075 1.8075 27 P 0 ;1
L 6.2075 1.8575 6.2075 1.8575 27 P 0 ;1
L 6.2075 1.9075 6.2075 1.9075 27 P 0 ;1
L 6.2075 1.9575 6.2075 1.9575 27 P 0 ;1
L 6.2075 2.0075 6.2075 2.0075 27 P 0 ;1
L 6.2075 2.0575 6.2075 2.0575 27 P 0 ;1
L 6.2075 2.1075 6.2075 2.1075 27 P 0 ;1
L 6.2075 2.1575 6.2075 2.1575 27 P 0 ;1
L 6.2075 2.2075 6.2075 2.2075 27 P 0 ;1
L 6.2075 2.2575 6.2075 2.2575 27 P 0 ;1
L 6.2075 2.3075 6.2075 2.3075 27 P 0 ;1
L 6.2075 2.3575 6.2075 2.3575 27 P 0 ;1
L 6.2075 2.4075 6.2075 2.4075 27 P 0 ;1
L 6.2075 2.4575 6.2075 2.4575 27 P 0 ;1
L 6.2075 2.5075 6.2075 2.5075 27 P 0 ;1
L 6.2075 2.5575 6.2075 2.5575 27 P 0 ;1
L 6.2075 2.6075 6.2075 2.6075 27 P 0 ;1
L 6.2075 2.6575 6.2075 2.6575 27 P 0 ;1
L 6.2075 2.7075 6.2075 2.7075 27 P 0 ;1
L 6.2075 2.7575 6.2075 2.7575 27 P 0 ;1
L 6.2075 2.8075 6.2075 2.8075 27 P 0 ;1
L 6.2075 2.8575 6.2075 2.8575 27 P 0 ;1
L 6.2075 2.9075 6.2075 2.9075 27 P 0 ;1
L 6.2075 2.9575 6.2075 2.9575 27 P 0 ;1
L 6.2075 3.0075 6.2075 3.0075 27 P 0 ;1
L 6.2075 3.0575 6.2075 3.0575 27 P 0 ;1
L 6.2075 3.1075 6.2075 3.1075 27 P 0 ;1
L 6.2075 3.1575 6.2075 3.1575 27 P 0 ;1
L 6.2075 3.2075 6.2075 3.2075 27 P 0 ;1
L 6.2075 3.2575 6.2075 3.2575 27 P 0 ;1
L 6.2075 3.3075 6.2075 3.3075 27 P 0 ;1
L 6.2075 3.3575 6.2075 3.3575 27 P 0 ;1
L 6.2075 3.4075 6.2075 3.4075 27 P 0 ;1
L 6.2075 3.4575 6.2075 3.4575 27 P 0 ;1
L 6.2075 3.5075 6.2075 3.5075 27 P 0 ;1
L 6.2075 3.5575 6.2075 3.5575 27 P 0 ;1
L 6.2075 3.6075 6.2075 3.6075 27 P 0 ;1
L 6.2075 3.6575 6.2075 3.6575 27 P 0 ;1
L 6.2075 3.7075 6.2075 3.7075 27 P 0 ;1
L 6.2075 3.7575 6.2075 3.7575 27 P 0 ;1
L 6.2075 3.8075 6.2075 3.8075 27 P 0 ;1
L 6.2075 3.8575 6.2075 3.8575 27 P 0 ;1
L 6.2075 3.9075 6.2075 3.9075 27 P 0 ;1
L 6.2075 3.9575 6.2075 3.9575 27 P 0 ;1
L 6.2075 4.4575 6.2075 4.4575 27 P 0 ;1
L 6.2075 4.5075 6.2075 4.5075 27 P 0 ;1
L 6.2075 5.2575 6.2075 5.2575 27 P 0 ;1
L 6.2075 5.3075 6.2075 5.3075 27 P 0 ;1
L 6.2075 5.3575 6.2075 5.3575 27 P 0 ;1
L 6.2075 5.4075 6.2075 5.4075 27 P 0 ;1
L 6.2075 5.4575 6.2075 5.4575 27 P 0 ;1
L 6.2075 5.5075 6.2075 5.5075 27 P 0 ;1
L 6.2075 5.5575 6.2075 5.5575 27 P 0 ;1
L 6.2075 5.6075 6.2075 5.6075 27 P 0 ;1
L 6.2075 5.6575 6.2075 5.6575 27 P 0 ;1
L 6.2075 5.7075 6.2075 5.7075 27 P 0 ;1
L 6.2075 5.7575 6.2075 5.7575 27 P 0 ;1
L 6.2575 0.6075 6.2575 0.6075 27 P 0 ;1
L 6.2575 0.6575 6.2575 0.6575 27 P 0 ;1
L 6.2575 0.7075 6.2575 0.7075 27 P 0 ;1
L 6.2575 0.7575 6.2575 0.7575 27 P 0 ;1
L 6.2575 0.8075 6.2575 0.8075 27 P 0 ;1
L 6.2575 0.8575 6.2575 0.8575 27 P 0 ;1
L 6.2575 0.9075 6.2575 0.9075 27 P 0 ;1
L 6.2575 0.9575 6.2575 0.9575 27 P 0 ;1
L 6.2575 1.0075 6.2575 1.0075 27 P 0 ;1
L 6.2575 1.0575 6.2575 1.0575 27 P 0 ;1
L 6.2575 1.1075 6.2575 1.1075 27 P 0 ;1
L 6.2575 1.1575 6.2575 1.1575 27 P 0 ;1
L 6.2575 1.2075 6.2575 1.2075 27 P 0 ;1
L 6.2575 1.2575 6.2575 1.2575 27 P 0 ;1
L 6.2575 1.3075 6.2575 1.3075 27 P 0 ;1
L 6.2575 1.7575 6.2575 1.7575 27 P 0 ;1
L 6.2575 1.8075 6.2575 1.8075 27 P 0 ;1
L 6.2575 1.8575 6.2575 1.8575 27 P 0 ;1
L 6.2575 1.9075 6.2575 1.9075 27 P 0 ;1
L 6.2575 1.9575 6.2575 1.9575 27 P 0 ;1
L 6.2575 2.0075 6.2575 2.0075 27 P 0 ;1
L 6.2575 2.0575 6.2575 2.0575 27 P 0 ;1
L 6.2575 2.1075 6.2575 2.1075 27 P 0 ;1
L 6.2575 2.1575 6.2575 2.1575 27 P 0 ;1
L 6.2575 2.2075 6.2575 2.2075 27 P 0 ;1
L 6.2575 2.2575 6.2575 2.2575 27 P 0 ;1
L 6.2575 2.3075 6.2575 2.3075 27 P 0 ;1
L 6.2575 2.3575 6.2575 2.3575 27 P 0 ;1
L 6.2575 2.4075 6.2575 2.4075 27 P 0 ;1
L 6.2575 2.4575 6.2575 2.4575 27 P 0 ;1
L 6.2575 2.5075 6.2575 2.5075 27 P 0 ;1
L 6.2575 2.5575 6.2575 2.5575 27 P 0 ;1
L 6.2575 2.6075 6.2575 2.6075 27 P 0 ;1
L 6.2575 2.6575 6.2575 2.6575 27 P 0 ;1
L 6.2575 2.7075 6.2575 2.7075 27 P 0 ;1
L 6.2575 2.7575 6.2575 2.7575 27 P 0 ;1
L 6.2575 2.8075 6.2575 2.8075 27 P 0 ;1
L 6.2575 2.8575 6.2575 2.8575 27 P 0 ;1
L 6.2575 2.9075 6.2575 2.9075 27 P 0 ;1
L 6.2575 2.9575 6.2575 2.9575 27 P 0 ;1
L 6.2575 3.0075 6.2575 3.0075 27 P 0 ;1
L 6.2575 3.0575 6.2575 3.0575 27 P 0 ;1
L 6.2575 3.1075 6.2575 3.1075 27 P 0 ;1
L 6.2575 3.1575 6.2575 3.1575 27 P 0 ;1
L 6.2575 3.2075 6.2575 3.2075 27 P 0 ;1
L 6.2575 3.2575 6.2575 3.2575 27 P 0 ;1
L 6.2575 3.3075 6.2575 3.3075 27 P 0 ;1
L 6.2575 3.3575 6.2575 3.3575 27 P 0 ;1
L 6.2575 3.4075 6.2575 3.4075 27 P 0 ;1
L 6.2575 3.4575 6.2575 3.4575 27 P 0 ;1
L 6.2575 3.5075 6.2575 3.5075 27 P 0 ;1
L 6.2575 3.5575 6.2575 3.5575 27 P 0 ;1
L 6.2575 3.6075 6.2575 3.6075 27 P 0 ;1
L 6.2575 3.6575 6.2575 3.6575 27 P 0 ;1
L 6.2575 3.7075 6.2575 3.7075 27 P 0 ;1
L 6.2575 3.7575 6.2575 3.7575 27 P 0 ;1
L 6.2575 3.8075 6.2575 3.8075 27 P 0 ;1
L 6.2575 3.8575 6.2575 3.8575 27 P 0 ;1
L 6.2575 3.9075 6.2575 3.9075 27 P 0 ;1
L 6.2575 3.9575 6.2575 3.9575 27 P 0 ;1
L 6.2575 4.4075 6.2575 4.4075 27 P 0 ;1
L 6.2575 4.4575 6.2575 4.4575 27 P 0 ;1
L 6.2575 4.5075 6.2575 4.5075 27 P 0 ;1
L 6.2575 5.2575 6.2575 5.2575 27 P 0 ;1
L 6.2575 5.3075 6.2575 5.3075 27 P 0 ;1
L 6.2575 5.3575 6.2575 5.3575 27 P 0 ;1
L 6.2575 5.4075 6.2575 5.4075 27 P 0 ;1
L 6.2575 5.4575 6.2575 5.4575 27 P 0 ;1
L 6.2575 5.5075 6.2575 5.5075 27 P 0 ;1
L 6.2575 5.5575 6.2575 5.5575 27 P 0 ;1
L 6.2575 5.6075 6.2575 5.6075 27 P 0 ;1
L 6.2575 5.6575 6.2575 5.6575 27 P 0 ;1
L 6.2575 5.7075 6.2575 5.7075 27 P 0 ;1
L 6.2575 5.7575 6.2575 5.7575 27 P 0 ;1
L 6.3075 0.6075 6.3075 0.6075 27 P 0 ;1
L 6.3075 0.6575 6.3075 0.6575 27 P 0 ;1
L 6.3075 0.7075 6.3075 0.7075 27 P 0 ;1
L 6.3075 0.7575 6.3075 0.7575 27 P 0 ;1
L 6.3075 0.8075 6.3075 0.8075 27 P 0 ;1
L 6.3075 0.8575 6.3075 0.8575 27 P 0 ;1
L 6.3075 0.9075 6.3075 0.9075 27 P 0 ;1
L 6.3075 0.9575 6.3075 0.9575 27 P 0 ;1
L 6.3075 1.0075 6.3075 1.0075 27 P 0 ;1
L 6.3075 1.0575 6.3075 1.0575 27 P 0 ;1
L 6.3075 1.1075 6.3075 1.1075 27 P 0 ;1
L 6.3075 1.1575 6.3075 1.1575 27 P 0 ;1
L 6.3075 1.2075 6.3075 1.2075 27 P 0 ;1
L 6.3075 1.2575 6.3075 1.2575 27 P 0 ;1
L 6.3075 1.3075 6.3075 1.3075 27 P 0 ;1
L 6.3075 1.3575 6.3075 1.3575 27 P 0 ;1
L 6.3075 1.7075 6.3075 1.7075 27 P 0 ;1
L 6.3075 1.7575 6.3075 1.7575 27 P 0 ;1
L 6.3075 1.8075 6.3075 1.8075 27 P 0 ;1
L 6.3075 1.8575 6.3075 1.8575 27 P 0 ;1
L 6.3075 1.9075 6.3075 1.9075 27 P 0 ;1
L 6.3075 1.9575 6.3075 1.9575 27 P 0 ;1
L 6.3075 2.0075 6.3075 2.0075 27 P 0 ;1
L 6.3075 2.0575 6.3075 2.0575 27 P 0 ;1
L 6.3075 2.1075 6.3075 2.1075 27 P 0 ;1
L 6.3075 2.1575 6.3075 2.1575 27 P 0 ;1
L 6.3075 2.2075 6.3075 2.2075 27 P 0 ;1
L 6.3075 2.2575 6.3075 2.2575 27 P 0 ;1
L 6.3075 2.3075 6.3075 2.3075 27 P 0 ;1
L 6.3075 2.3575 6.3075 2.3575 27 P 0 ;1
L 6.3075 2.4075 6.3075 2.4075 27 P 0 ;1
L 6.3075 2.4575 6.3075 2.4575 27 P 0 ;1
L 6.3075 2.5075 6.3075 2.5075 27 P 0 ;1
L 6.3075 2.5575 6.3075 2.5575 27 P 0 ;1
L 6.3075 2.6075 6.3075 2.6075 27 P 0 ;1
L 6.3075 2.6575 6.3075 2.6575 27 P 0 ;1
L 6.3075 2.7075 6.3075 2.7075 27 P 0 ;1
L 6.3075 2.7575 6.3075 2.7575 27 P 0 ;1
L 6.3075 2.8075 6.3075 2.8075 27 P 0 ;1
L 6.3075 2.8575 6.3075 2.8575 27 P 0 ;1
L 6.3075 2.9075 6.3075 2.9075 27 P 0 ;1
L 6.3075 2.9575 6.3075 2.9575 27 P 0 ;1
L 6.3075 3.0075 6.3075 3.0075 27 P 0 ;1
L 6.3075 3.0575 6.3075 3.0575 27 P 0 ;1
L 6.3075 3.1075 6.3075 3.1075 27 P 0 ;1
L 6.3075 3.1575 6.3075 3.1575 27 P 0 ;1
L 6.3075 3.2075 6.3075 3.2075 27 P 0 ;1
L 6.3075 3.2575 6.3075 3.2575 27 P 0 ;1
L 6.3075 3.3075 6.3075 3.3075 27 P 0 ;1
L 6.3075 3.3575 6.3075 3.3575 27 P 0 ;1
L 6.3075 3.4075 6.3075 3.4075 27 P 0 ;1
L 6.3075 3.4575 6.3075 3.4575 27 P 0 ;1
L 6.3075 3.5075 6.3075 3.5075 27 P 0 ;1
L 6.3075 3.5575 6.3075 3.5575 27 P 0 ;1
L 6.3075 3.6075 6.3075 3.6075 27 P 0 ;1
L 6.3075 3.6575 6.3075 3.6575 27 P 0 ;1
L 6.3075 3.7075 6.3075 3.7075 27 P 0 ;1
L 6.3075 3.7575 6.3075 3.7575 27 P 0 ;1
L 6.3075 3.8075 6.3075 3.8075 27 P 0 ;1
L 6.3075 3.8575 6.3075 3.8575 27 P 0 ;1
L 6.3075 3.9075 6.3075 3.9075 27 P 0 ;1
L 6.3075 3.9575 6.3075 3.9575 27 P 0 ;1
L 6.3075 4.0075 6.3075 4.0075 27 P 0 ;1
L 6.3075 4.3575 6.3075 4.3575 27 P 0 ;1
L 6.3075 4.4075 6.3075 4.4075 27 P 0 ;1
L 6.3075 4.4575 6.3075 4.4575 27 P 0 ;1
L 6.3075 4.5075 6.3075 4.5075 27 P 0 ;1
L 6.3075 5.2575 6.3075 5.2575 27 P 0 ;1
L 6.3075 5.3075 6.3075 5.3075 27 P 0 ;1
L 6.3075 5.3575 6.3075 5.3575 27 P 0 ;1
L 6.3075 5.4075 6.3075 5.4075 27 P 0 ;1
L 6.3075 5.4575 6.3075 5.4575 27 P 0 ;1
L 6.3075 5.5075 6.3075 5.5075 27 P 0 ;1
L 6.3075 5.5575 6.3075 5.5575 27 P 0 ;1
L 6.3075 5.6075 6.3075 5.6075 27 P 0 ;1
L 6.3075 5.6575 6.3075 5.6575 27 P 0 ;1
L 6.3075 5.7075 6.3075 5.7075 27 P 0 ;1
L 6.3075 5.7575 6.3075 5.7575 27 P 0 ;1
L 6.3575 0.6075 6.3575 0.6075 27 P 0 ;1
L 6.3575 0.6575 6.3575 0.6575 27 P 0 ;1
L 6.3575 0.7075 6.3575 0.7075 27 P 0 ;1
L 6.3575 0.7575 6.3575 0.7575 27 P 0 ;1
L 6.3575 0.8075 6.3575 0.8075 27 P 0 ;1
L 6.3575 0.8575 6.3575 0.8575 27 P 0 ;1
L 6.3575 0.9075 6.3575 0.9075 27 P 0 ;1
L 6.3575 0.9575 6.3575 0.9575 27 P 0 ;1
L 6.3575 1.0075 6.3575 1.0075 27 P 0 ;1
L 6.3575 1.0575 6.3575 1.0575 27 P 0 ;1
L 6.3575 1.1075 6.3575 1.1075 27 P 0 ;1
L 6.3575 1.1575 6.3575 1.1575 27 P 0 ;1
L 6.3575 1.2075 6.3575 1.2075 27 P 0 ;1
L 6.3575 1.2575 6.3575 1.2575 27 P 0 ;1
L 6.3575 1.3075 6.3575 1.3075 27 P 0 ;1
L 6.3575 1.3575 6.3575 1.3575 27 P 0 ;1
L 6.3575 1.4075 6.3575 1.4075 27 P 0 ;1
L 6.3575 1.4575 6.3575 1.4575 27 P 0 ;1
L 6.3575 1.5575 6.3575 1.5575 27 P 0 ;1
L 6.3575 1.6075 6.3575 1.6075 27 P 0 ;1
L 6.3575 1.6575 6.3575 1.6575 27 P 0 ;1
L 6.3575 1.7075 6.3575 1.7075 27 P 0 ;1
L 6.3575 1.7575 6.3575 1.7575 27 P 0 ;1
L 6.3575 1.8075 6.3575 1.8075 27 P 0 ;1
L 6.3575 1.8575 6.3575 1.8575 27 P 0 ;1
L 6.3575 1.9075 6.3575 1.9075 27 P 0 ;1
L 6.3575 1.9575 6.3575 1.9575 27 P 0 ;1
L 6.3575 2.0075 6.3575 2.0075 27 P 0 ;1
L 6.3575 2.0575 6.3575 2.0575 27 P 0 ;1
L 6.3575 2.1075 6.3575 2.1075 27 P 0 ;1
L 6.3575 2.1575 6.3575 2.1575 27 P 0 ;1
L 6.3575 2.2075 6.3575 2.2075 27 P 0 ;1
L 6.3575 2.2575 6.3575 2.2575 27 P 0 ;1
L 6.3575 2.3075 6.3575 2.3075 27 P 0 ;1
L 6.3575 2.3575 6.3575 2.3575 27 P 0 ;1
L 6.3575 2.4075 6.3575 2.4075 27 P 0 ;1
L 6.3575 2.4575 6.3575 2.4575 27 P 0 ;1
L 6.3575 2.5075 6.3575 2.5075 27 P 0 ;1
L 6.3575 2.5575 6.3575 2.5575 27 P 0 ;1
L 6.3575 2.6075 6.3575 2.6075 27 P 0 ;1
L 6.3575 2.6575 6.3575 2.6575 27 P 0 ;1
L 6.3575 2.7075 6.3575 2.7075 27 P 0 ;1
L 6.3575 2.7575 6.3575 2.7575 27 P 0 ;1
L 6.3575 2.8075 6.3575 2.8075 27 P 0 ;1
L 6.3575 2.8575 6.3575 2.8575 27 P 0 ;1
L 6.3575 2.9075 6.3575 2.9075 27 P 0 ;1
L 6.3575 2.9575 6.3575 2.9575 27 P 0 ;1
L 6.3575 3.0075 6.3575 3.0075 27 P 0 ;1
L 6.3575 3.0575 6.3575 3.0575 27 P 0 ;1
L 6.3575 3.1075 6.3575 3.1075 27 P 0 ;1
L 6.3575 3.1575 6.3575 3.1575 27 P 0 ;1
L 6.3575 3.2075 6.3575 3.2075 27 P 0 ;1
L 6.3575 3.2575 6.3575 3.2575 27 P 0 ;1
L 6.3575 3.3075 6.3575 3.3075 27 P 0 ;1
L 6.3575 3.3575 6.3575 3.3575 27 P 0 ;1
L 6.3575 3.4075 6.3575 3.4075 27 P 0 ;1
L 6.3575 3.4575 6.3575 3.4575 27 P 0 ;1
L 6.3575 3.5075 6.3575 3.5075 27 P 0 ;1
L 6.3575 3.5575 6.3575 3.5575 27 P 0 ;1
L 6.3575 3.6075 6.3575 3.6075 27 P 0 ;1
L 6.3575 3.6575 6.3575 3.6575 27 P 0 ;1
L 6.3575 3.7075 6.3575 3.7075 27 P 0 ;1
L 6.3575 3.7575 6.3575 3.7575 27 P 0 ;1
L 6.3575 3.8075 6.3575 3.8075 27 P 0 ;1
L 6.3575 3.8575 6.3575 3.8575 27 P 0 ;1
L 6.3575 3.9075 6.3575 3.9075 27 P 0 ;1
L 6.3575 3.9575 6.3575 3.9575 27 P 0 ;1
L 6.3575 4.0075 6.3575 4.0075 27 P 0 ;1
L 6.3575 4.0575 6.3575 4.0575 27 P 0 ;1
L 6.3575 4.1075 6.3575 4.1075 27 P 0 ;1
L 6.3575 4.1575 6.3575 4.1575 27 P 0 ;1
L 6.3575 4.2575 6.3575 4.2575 27 P 0 ;1
L 6.3575 4.3075 6.3575 4.3075 27 P 0 ;1
L 6.3575 4.3575 6.3575 4.3575 27 P 0 ;1
L 6.3575 4.4075 6.3575 4.4075 27 P 0 ;1
L 6.3575 4.4575 6.3575 4.4575 27 P 0 ;1
L 6.3575 4.5075 6.3575 4.5075 27 P 0 ;1
L 6.3575 5.2575 6.3575 5.2575 27 P 0 ;1
L 6.3575 5.3075 6.3575 5.3075 27 P 0 ;1
L 6.3575 5.3575 6.3575 5.3575 27 P 0 ;1
L 6.3575 5.4075 6.3575 5.4075 27 P 0 ;1
L 6.3575 5.4575 6.3575 5.4575 27 P 0 ;1
L 6.3575 5.5075 6.3575 5.5075 27 P 0 ;1
L 6.3575 5.5575 6.3575 5.5575 27 P 0 ;1
L 6.3575 5.6075 6.3575 5.6075 27 P 0 ;1
L 6.3575 5.6575 6.3575 5.6575 27 P 0 ;1
L 6.3575 5.7075 6.3575 5.7075 27 P 0 ;1
L 6.3575 5.7575 6.3575 5.7575 27 P 0 ;1
L 6.4075 0.6075 6.4075 0.6075 27 P 0 ;1
L 6.4075 0.6575 6.4075 0.6575 27 P 0 ;1
L 6.4075 0.7075 6.4075 0.7075 27 P 0 ;1
L 6.4075 0.7575 6.4075 0.7575 27 P 0 ;1
L 6.4075 0.8075 6.4075 0.8075 27 P 0 ;1
L 6.4075 0.8575 6.4075 0.8575 27 P 0 ;1
L 6.4075 0.9075 6.4075 0.9075 27 P 0 ;1
L 6.4075 0.9575 6.4075 0.9575 27 P 0 ;1
L 6.4075 1.0075 6.4075 1.0075 27 P 0 ;1
L 6.4075 1.0575 6.4075 1.0575 27 P 0 ;1
L 6.4075 1.1075 6.4075 1.1075 27 P 0 ;1
L 6.4075 1.1575 6.4075 1.1575 27 P 0 ;1
L 6.4075 1.2075 6.4075 1.2075 27 P 0 ;1
L 6.4075 1.2575 6.4075 1.2575 27 P 0 ;1
L 6.4075 1.3075 6.4075 1.3075 27 P 0 ;1
L 6.4075 1.3575 6.4075 1.3575 27 P 0 ;1
L 6.4075 1.4075 6.4075 1.4075 27 P 0 ;1
L 6.4075 1.4575 6.4075 1.4575 27 P 0 ;1
L 6.4075 1.5075 6.4075 1.5075 27 P 0 ;1
L 6.4075 1.5575 6.4075 1.5575 27 P 0 ;1
L 6.4075 1.6075 6.4075 1.6075 27 P 0 ;1
L 6.4075 1.6575 6.4075 1.6575 27 P 0 ;1
L 6.4075 1.7075 6.4075 1.7075 27 P 0 ;1
L 6.4075 1.7575 6.4075 1.7575 27 P 0 ;1
L 6.4075 1.8075 6.4075 1.8075 27 P 0 ;1
L 6.4075 1.8575 6.4075 1.8575 27 P 0 ;1
L 6.4075 1.9075 6.4075 1.9075 27 P 0 ;1
L 6.4075 1.9575 6.4075 1.9575 27 P 0 ;1
L 6.4075 2.0075 6.4075 2.0075 27 P 0 ;1
L 6.4075 2.0575 6.4075 2.0575 27 P 0 ;1
L 6.4075 2.1075 6.4075 2.1075 27 P 0 ;1
L 6.4075 2.1575 6.4075 2.1575 27 P 0 ;1
L 6.4075 2.2075 6.4075 2.2075 27 P 0 ;1
L 6.4075 2.2575 6.4075 2.2575 27 P 0 ;1
L 6.4075 2.3075 6.4075 2.3075 27 P 0 ;1
L 6.4075 2.3575 6.4075 2.3575 27 P 0 ;1
L 6.4075 2.4075 6.4075 2.4075 27 P 0 ;1
L 6.4075 2.4575 6.4075 2.4575 27 P 0 ;1
L 6.4075 2.5075 6.4075 2.5075 27 P 0 ;1
L 6.4075 2.5575 6.4075 2.5575 27 P 0 ;1
L 6.4075 2.6075 6.4075 2.6075 27 P 0 ;1
L 6.4075 2.6575 6.4075 2.6575 27 P 0 ;1
L 6.4075 2.7075 6.4075 2.7075 27 P 0 ;1
L 6.4075 2.7575 6.4075 2.7575 27 P 0 ;1
L 6.4075 2.8075 6.4075 2.8075 27 P 0 ;1
L 6.4075 2.8575 6.4075 2.8575 27 P 0 ;1
L 6.4075 2.9075 6.4075 2.9075 27 P 0 ;1
L 6.4075 2.9575 6.4075 2.9575 27 P 0 ;1
L 6.4075 3.0075 6.4075 3.0075 27 P 0 ;1
L 6.4075 3.0575 6.4075 3.0575 27 P 0 ;1
L 6.4075 3.1075 6.4075 3.1075 27 P 0 ;1
L 6.4075 3.1575 6.4075 3.1575 27 P 0 ;1
L 6.4075 3.2075 6.4075 3.2075 27 P 0 ;1
L 6.4075 3.2575 6.4075 3.2575 27 P 0 ;1
L 6.4075 3.3075 6.4075 3.3075 27 P 0 ;1
L 6.4075 3.3575 6.4075 3.3575 27 P 0 ;1
L 6.4075 3.4075 6.4075 3.4075 27 P 0 ;1
L 6.4075 3.4575 6.4075 3.4575 27 P 0 ;1
L 6.4075 3.5075 6.4075 3.5075 27 P 0 ;1
L 6.4075 3.5575 6.4075 3.5575 27 P 0 ;1
L 6.4075 3.6075 6.4075 3.6075 27 P 0 ;1
L 6.4075 3.6575 6.4075 3.6575 27 P 0 ;1
L 6.4075 3.7075 6.4075 3.7075 27 P 0 ;1
L 6.4075 3.7575 6.4075 3.7575 27 P 0 ;1
L 6.4075 3.8075 6.4075 3.8075 27 P 0 ;1
L 6.4075 3.8575 6.4075 3.8575 27 P 0 ;1
L 6.4075 3.9075 6.4075 3.9075 27 P 0 ;1
L 6.4075 3.9575 6.4075 3.9575 27 P 0 ;1
L 6.4075 4.0075 6.4075 4.0075 27 P 0 ;1
L 6.4075 4.0575 6.4075 4.0575 27 P 0 ;1
L 6.4075 4.1075 6.4075 4.1075 27 P 0 ;1
L 6.4075 4.1575 6.4075 4.1575 27 P 0 ;1
L 6.4075 4.2075 6.4075 4.2075 27 P 0 ;1
L 6.4075 4.2575 6.4075 4.2575 27 P 0 ;1
L 6.4075 4.3075 6.4075 4.3075 27 P 0 ;1
L 6.4075 4.3575 6.4075 4.3575 27 P 0 ;1
L 6.4075 4.4075 6.4075 4.4075 27 P 0 ;1
L 6.4075 4.4575 6.4075 4.4575 27 P 0 ;1
L 6.4075 4.5075 6.4075 4.5075 27 P 0 ;1
L 6.4075 4.5575 6.4075 4.5575 27 P 0 ;1
L 6.4075 4.6075 6.4075 4.6075 27 P 0 ;1
L 6.4075 5.2575 6.4075 5.2575 27 P 0 ;1
L 6.4075 5.3075 6.4075 5.3075 27 P 0 ;1
L 6.4075 5.3575 6.4075 5.3575 27 P 0 ;1
L 6.4075 5.4075 6.4075 5.4075 27 P 0 ;1
L 6.4075 5.4575 6.4075 5.4575 27 P 0 ;1
L 6.4075 5.5075 6.4075 5.5075 27 P 0 ;1
L 6.4075 5.5575 6.4075 5.5575 27 P 0 ;1
L 6.4075 5.6075 6.4075 5.6075 27 P 0 ;1
L 6.4075 5.6575 6.4075 5.6575 27 P 0 ;1
L 6.4075 5.7075 6.4075 5.7075 27 P 0 ;1
L 6.4075 5.7575 6.4075 5.7575 27 P 0 ;1
L 6.4575 0.6075 6.4575 0.6075 27 P 0 ;1
L 6.4575 0.6575 6.4575 0.6575 27 P 0 ;1
L 6.4575 0.7075 6.4575 0.7075 27 P 0 ;1
L 6.4575 0.7575 6.4575 0.7575 27 P 0 ;1
L 6.4575 0.8075 6.4575 0.8075 27 P 0 ;1
L 6.4575 0.8575 6.4575 0.8575 27 P 0 ;1
L 6.4575 0.9075 6.4575 0.9075 27 P 0 ;1
L 6.4575 0.9575 6.4575 0.9575 27 P 0 ;1
L 6.4575 1.0075 6.4575 1.0075 27 P 0 ;1
L 6.4575 1.0575 6.4575 1.0575 27 P 0 ;1
L 6.4575 1.1075 6.4575 1.1075 27 P 0 ;1
L 6.4575 1.1575 6.4575 1.1575 27 P 0 ;1
L 6.4575 1.2075 6.4575 1.2075 27 P 0 ;1
L 6.4575 1.2575 6.4575 1.2575 27 P 0 ;1
L 6.4575 1.3075 6.4575 1.3075 27 P 0 ;1
L 6.4575 1.3575 6.4575 1.3575 27 P 0 ;1
L 6.4575 1.4075 6.4575 1.4075 27 P 0 ;1
L 6.4575 1.4575 6.4575 1.4575 27 P 0 ;1
L 6.4575 1.5075 6.4575 1.5075 27 P 0 ;1
L 6.4575 1.5575 6.4575 1.5575 27 P 0 ;1
L 6.4575 1.6075 6.4575 1.6075 27 P 0 ;1
L 6.4575 1.6575 6.4575 1.6575 27 P 0 ;1
L 6.4575 1.7075 6.4575 1.7075 27 P 0 ;1
L 6.4575 1.7575 6.4575 1.7575 27 P 0 ;1
L 6.4575 1.8075 6.4575 1.8075 27 P 0 ;1
L 6.4575 1.8575 6.4575 1.8575 27 P 0 ;1
L 6.4575 1.9075 6.4575 1.9075 27 P 0 ;1
L 6.4575 1.9575 6.4575 1.9575 27 P 0 ;1
L 6.4575 2.0075 6.4575 2.0075 27 P 0 ;1
L 6.4575 2.0575 6.4575 2.0575 27 P 0 ;1
L 6.4575 2.1075 6.4575 2.1075 27 P 0 ;1
L 6.4575 2.1575 6.4575 2.1575 27 P 0 ;1
L 6.4575 2.2075 6.4575 2.2075 27 P 0 ;1
L 6.4575 2.2575 6.4575 2.2575 27 P 0 ;1
L 6.4575 2.3075 6.4575 2.3075 27 P 0 ;1
L 6.4575 2.3575 6.4575 2.3575 27 P 0 ;1
L 6.4575 2.4075 6.4575 2.4075 27 P 0 ;1
L 6.4575 2.4575 6.4575 2.4575 27 P 0 ;1
L 6.4575 2.5075 6.4575 2.5075 27 P 0 ;1
L 6.4575 2.5575 6.4575 2.5575 27 P 0 ;1
L 6.4575 2.6075 6.4575 2.6075 27 P 0 ;1
L 6.4575 2.6575 6.4575 2.6575 27 P 0 ;1
L 6.4575 2.7075 6.4575 2.7075 27 P 0 ;1
L 6.4575 2.7575 6.4575 2.7575 27 P 0 ;1
L 6.4575 2.8075 6.4575 2.8075 27 P 0 ;1
L 6.4575 2.8575 6.4575 2.8575 27 P 0 ;1
L 6.4575 2.9075 6.4575 2.9075 27 P 0 ;1
L 6.4575 2.9575 6.4575 2.9575 27 P 0 ;1
L 6.4575 3.0075 6.4575 3.0075 27 P 0 ;1
L 6.4575 3.0575 6.4575 3.0575 27 P 0 ;1
L 6.4575 3.1075 6.4575 3.1075 27 P 0 ;1
L 6.4575 3.1575 6.4575 3.1575 27 P 0 ;1
L 6.4575 3.2075 6.4575 3.2075 27 P 0 ;1
L 6.4575 3.2575 6.4575 3.2575 27 P 0 ;1
L 6.4575 3.3075 6.4575 3.3075 27 P 0 ;1
L 6.4575 3.3575 6.4575 3.3575 27 P 0 ;1
L 6.4575 3.4075 6.4575 3.4075 27 P 0 ;1
L 6.4575 3.4575 6.4575 3.4575 27 P 0 ;1
L 6.4575 3.5075 6.4575 3.5075 27 P 0 ;1
L 6.4575 3.5575 6.4575 3.5575 27 P 0 ;1
L 6.4575 3.6075 6.4575 3.6075 27 P 0 ;1
L 6.4575 3.6575 6.4575 3.6575 27 P 0 ;1
L 6.4575 3.7075 6.4575 3.7075 27 P 0 ;1
L 6.4575 3.7575 6.4575 3.7575 27 P 0 ;1
L 6.4575 3.8075 6.4575 3.8075 27 P 0 ;1
L 6.4575 3.8575 6.4575 3.8575 27 P 0 ;1
L 6.4575 3.9075 6.4575 3.9075 27 P 0 ;1
L 6.4575 3.9575 6.4575 3.9575 27 P 0 ;1
L 6.4575 4.0075 6.4575 4.0075 27 P 0 ;1
L 6.4575 4.0575 6.4575 4.0575 27 P 0 ;1
L 6.4575 4.1075 6.4575 4.1075 27 P 0 ;1
L 6.4575 4.1575 6.4575 4.1575 27 P 0 ;1
L 6.4575 4.2075 6.4575 4.2075 27 P 0 ;1
L 6.4575 4.2575 6.4575 4.2575 27 P 0 ;1
L 6.4575 4.3075 6.4575 4.3075 27 P 0 ;1
L 6.4575 4.3575 6.4575 4.3575 27 P 0 ;1
L 6.4575 4.4075 6.4575 4.4075 27 P 0 ;1
L 6.4575 4.4575 6.4575 4.4575 27 P 0 ;1
L 6.4575 4.5075 6.4575 4.5075 27 P 0 ;1
L 6.4575 5.2575 6.4575 5.2575 27 P 0 ;1
L 6.4575 5.3075 6.4575 5.3075 27 P 0 ;1
L 6.4575 5.3575 6.4575 5.3575 27 P 0 ;1
L 6.4575 5.4075 6.4575 5.4075 27 P 0 ;1
L 6.4575 5.4575 6.4575 5.4575 27 P 0 ;1
L 6.4575 5.5075 6.4575 5.5075 27 P 0 ;1
L 6.4575 5.5575 6.4575 5.5575 27 P 0 ;1
L 6.4575 5.6075 6.4575 5.6075 27 P 0 ;1
L 6.4575 5.6575 6.4575 5.6575 27 P 0 ;1
L 6.4575 5.7075 6.4575 5.7075 27 P 0 ;1
L 6.4575 5.7575 6.4575 5.7575 27 P 0 ;1
L 6.5075 0.6075 6.5075 0.6075 27 P 0 ;1
L 6.5075 0.6575 6.5075 0.6575 27 P 0 ;1
L 6.5075 0.7075 6.5075 0.7075 27 P 0 ;1
L 6.5075 0.7575 6.5075 0.7575 27 P 0 ;1
L 6.5075 0.8075 6.5075 0.8075 27 P 0 ;1
L 6.5075 0.8575 6.5075 0.8575 27 P 0 ;1
L 6.5075 0.9075 6.5075 0.9075 27 P 0 ;1
L 6.5075 0.9575 6.5075 0.9575 27 P 0 ;1
L 6.5075 1.0075 6.5075 1.0075 27 P 0 ;1
L 6.5075 1.0575 6.5075 1.0575 27 P 0 ;1
L 6.5075 1.1075 6.5075 1.1075 27 P 0 ;1
L 6.5075 1.1575 6.5075 1.1575 27 P 0 ;1
L 6.5075 1.2075 6.5075 1.2075 27 P 0 ;1
L 6.5075 1.2575 6.5075 1.2575 27 P 0 ;1
L 6.5075 1.3075 6.5075 1.3075 27 P 0 ;1
L 6.5075 1.3575 6.5075 1.3575 27 P 0 ;1
L 6.5075 1.4075 6.5075 1.4075 27 P 0 ;1
L 6.5075 1.4575 6.5075 1.4575 27 P 0 ;1
L 6.5075 1.5075 6.5075 1.5075 27 P 0 ;1
L 6.5075 1.5575 6.5075 1.5575 27 P 0 ;1
L 6.5075 1.6075 6.5075 1.6075 27 P 0 ;1
L 6.5075 1.6575 6.5075 1.6575 27 P 0 ;1
L 6.5075 1.7075 6.5075 1.7075 27 P 0 ;1
L 6.5075 1.7575 6.5075 1.7575 27 P 0 ;1
L 6.5075 1.8075 6.5075 1.8075 27 P 0 ;1
L 6.5075 1.8575 6.5075 1.8575 27 P 0 ;1
L 6.5075 1.9075 6.5075 1.9075 27 P 0 ;1
L 6.5075 1.9575 6.5075 1.9575 27 P 0 ;1
L 6.5075 2.0075 6.5075 2.0075 27 P 0 ;1
L 6.5075 2.0575 6.5075 2.0575 27 P 0 ;1
L 6.5075 2.1075 6.5075 2.1075 27 P 0 ;1
L 6.5075 2.1575 6.5075 2.1575 27 P 0 ;1
L 6.5075 2.2075 6.5075 2.2075 27 P 0 ;1
L 6.5075 2.2575 6.5075 2.2575 27 P 0 ;1
L 6.5075 2.3075 6.5075 2.3075 27 P 0 ;1
L 6.5075 2.3575 6.5075 2.3575 27 P 0 ;1
L 6.5075 2.4075 6.5075 2.4075 27 P 0 ;1
L 6.5075 2.4575 6.5075 2.4575 27 P 0 ;1
L 6.5075 2.5075 6.5075 2.5075 27 P 0 ;1
L 6.5075 2.5575 6.5075 2.5575 27 P 0 ;1
L 6.5075 2.6075 6.5075 2.6075 27 P 0 ;1
L 6.5075 2.6575 6.5075 2.6575 27 P 0 ;1
L 6.5075 2.7075 6.5075 2.7075 27 P 0 ;1
L 6.5075 2.7575 6.5075 2.7575 27 P 0 ;1
L 6.5075 2.8075 6.5075 2.8075 27 P 0 ;1
L 6.5075 2.8575 6.5075 2.8575 27 P 0 ;1
L 6.5075 2.9075 6.5075 2.9075 27 P 0 ;1
L 6.5075 2.9575 6.5075 2.9575 27 P 0 ;1
L 6.5075 3.0075 6.5075 3.0075 27 P 0 ;1
L 6.5075 3.0575 6.5075 3.0575 27 P 0 ;1
L 6.5075 3.1075 6.5075 3.1075 27 P 0 ;1
L 6.5075 3.1575 6.5075 3.1575 27 P 0 ;1
L 6.5075 3.2075 6.5075 3.2075 27 P 0 ;1
L 6.5075 3.2575 6.5075 3.2575 27 P 0 ;1
L 6.5075 3.3075 6.5075 3.3075 27 P 0 ;1
L 6.5075 3.3575 6.5075 3.3575 27 P 0 ;1
L 6.5075 3.4075 6.5075 3.4075 27 P 0 ;1
L 6.5075 3.4575 6.5075 3.4575 27 P 0 ;1
L 6.5075 3.5075 6.5075 3.5075 27 P 0 ;1
L 6.5075 3.5575 6.5075 3.5575 27 P 0 ;1
L 6.5075 3.6075 6.5075 3.6075 27 P 0 ;1
L 6.5075 3.6575 6.5075 3.6575 27 P 0 ;1
L 6.5075 3.7075 6.5075 3.7075 27 P 0 ;1
L 6.5075 3.7575 6.5075 3.7575 27 P 0 ;1
L 6.5075 3.8075 6.5075 3.8075 27 P 0 ;1
L 6.5075 3.8575 6.5075 3.8575 27 P 0 ;1
L 6.5075 3.9075 6.5075 3.9075 27 P 0 ;1
L 6.5075 3.9575 6.5075 3.9575 27 P 0 ;1
L 6.5075 4.0075 6.5075 4.0075 27 P 0 ;1
L 6.5075 4.0575 6.5075 4.0575 27 P 0 ;1
L 6.5075 4.1075 6.5075 4.1075 27 P 0 ;1
L 6.5075 4.1575 6.5075 4.1575 27 P 0 ;1
L 6.5075 4.2075 6.5075 4.2075 27 P 0 ;1
L 6.5075 4.2575 6.5075 4.2575 27 P 0 ;1
L 6.5075 4.3075 6.5075 4.3075 27 P 0 ;1
L 6.5075 4.3575 6.5075 4.3575 27 P 0 ;1
L 6.5075 4.4075 6.5075 4.4075 27 P 0 ;1
L 6.5075 4.4575 6.5075 4.4575 27 P 0 ;1
L 6.5075 4.5075 6.5075 4.5075 27 P 0 ;1
L 6.5075 5.2575 6.5075 5.2575 27 P 0 ;1
L 6.5075 5.3075 6.5075 5.3075 27 P 0 ;1
L 6.5075 5.3575 6.5075 5.3575 27 P 0 ;1
L 6.5075 5.4075 6.5075 5.4075 27 P 0 ;1
L 6.5075 5.4575 6.5075 5.4575 27 P 0 ;1
L 6.5075 5.5075 6.5075 5.5075 27 P 0 ;1
L 6.5075 5.5575 6.5075 5.5575 27 P 0 ;1
L 6.5075 5.6075 6.5075 5.6075 27 P 0 ;1
L 6.5075 5.6575 6.5075 5.6575 27 P 0 ;1
L 6.5075 5.7075 6.5075 5.7075 27 P 0 ;1
L 6.5075 5.7575 6.5075 5.7575 27 P 0 ;1
L 6.5575 0.6075 6.5575 0.6075 27 P 0 ;1
L 6.5575 0.6575 6.5575 0.6575 27 P 0 ;1
L 6.5575 0.7075 6.5575 0.7075 27 P 0 ;1
L 6.5575 0.7575 6.5575 0.7575 27 P 0 ;1
L 6.5575 0.8075 6.5575 0.8075 27 P 0 ;1
L 6.5575 0.8575 6.5575 0.8575 27 P 0 ;1
L 6.5575 0.9075 6.5575 0.9075 27 P 0 ;1
L 6.5575 0.9575 6.5575 0.9575 27 P 0 ;1
L 6.5575 1.0075 6.5575 1.0075 27 P 0 ;1
L 6.5575 1.0575 6.5575 1.0575 27 P 0 ;1
L 6.5575 1.1075 6.5575 1.1075 27 P 0 ;1
L 6.5575 1.1575 6.5575 1.1575 27 P 0 ;1
L 6.5575 1.2075 6.5575 1.2075 27 P 0 ;1
L 6.5575 1.2575 6.5575 1.2575 27 P 0 ;1
L 6.5575 1.3075 6.5575 1.3075 27 P 0 ;1
L 6.5575 1.3575 6.5575 1.3575 27 P 0 ;1
L 6.5575 1.4075 6.5575 1.4075 27 P 0 ;1
L 6.5575 1.4575 6.5575 1.4575 27 P 0 ;1
L 6.5575 1.5075 6.5575 1.5075 27 P 0 ;1
L 6.5575 1.5575 6.5575 1.5575 27 P 0 ;1
L 6.5575 1.6075 6.5575 1.6075 27 P 0 ;1
L 6.5575 1.6575 6.5575 1.6575 27 P 0 ;1
L 6.5575 1.7075 6.5575 1.7075 27 P 0 ;1
L 6.5575 1.7575 6.5575 1.7575 27 P 0 ;1
L 6.5575 1.8075 6.5575 1.8075 27 P 0 ;1
L 6.5575 1.8575 6.5575 1.8575 27 P 0 ;1
L 6.5575 1.9075 6.5575 1.9075 27 P 0 ;1
L 6.5575 1.9575 6.5575 1.9575 27 P 0 ;1
L 6.5575 2.0075 6.5575 2.0075 27 P 0 ;1
L 6.5575 2.0575 6.5575 2.0575 27 P 0 ;1
L 6.5575 2.1075 6.5575 2.1075 27 P 0 ;1
L 6.5575 2.1575 6.5575 2.1575 27 P 0 ;1
L 6.5575 2.2075 6.5575 2.2075 27 P 0 ;1
L 6.5575 2.2575 6.5575 2.2575 27 P 0 ;1
L 6.5575 2.3075 6.5575 2.3075 27 P 0 ;1
L 6.5575 2.3575 6.5575 2.3575 27 P 0 ;1
L 6.5575 2.4075 6.5575 2.4075 27 P 0 ;1
L 6.5575 2.4575 6.5575 2.4575 27 P 0 ;1
L 6.5575 2.5075 6.5575 2.5075 27 P 0 ;1
L 6.5575 2.5575 6.5575 2.5575 27 P 0 ;1
L 6.5575 2.6075 6.5575 2.6075 27 P 0 ;1
L 6.5575 2.6575 6.5575 2.6575 27 P 0 ;1
L 6.5575 2.7075 6.5575 2.7075 27 P 0 ;1
L 6.5575 2.7575 6.5575 2.7575 27 P 0 ;1
L 6.5575 2.8075 6.5575 2.8075 27 P 0 ;1
L 6.5575 2.8575 6.5575 2.8575 27 P 0 ;1
L 6.5575 2.9075 6.5575 2.9075 27 P 0 ;1
L 6.5575 2.9575 6.5575 2.9575 27 P 0 ;1
L 6.5575 3.0075 6.5575 3.0075 27 P 0 ;1
L 6.5575 3.0575 6.5575 3.0575 27 P 0 ;1
L 6.5575 3.1075 6.5575 3.1075 27 P 0 ;1
L 6.5575 3.1575 6.5575 3.1575 27 P 0 ;1
L 6.5575 3.2075 6.5575 3.2075 27 P 0 ;1
L 6.5575 3.2575 6.5575 3.2575 27 P 0 ;1
L 6.5575 3.3075 6.5575 3.3075 27 P 0 ;1
L 6.5575 3.3575 6.5575 3.3575 27 P 0 ;1
L 6.5575 3.4075 6.5575 3.4075 27 P 0 ;1
L 6.5575 3.4575 6.5575 3.4575 27 P 0 ;1
L 6.5575 3.5075 6.5575 3.5075 27 P 0 ;1
L 6.5575 3.5575 6.5575 3.5575 27 P 0 ;1
L 6.5575 3.6075 6.5575 3.6075 27 P 0 ;1
L 6.5575 3.6575 6.5575 3.6575 27 P 0 ;1
L 6.5575 3.7075 6.5575 3.7075 27 P 0 ;1
L 6.5575 3.7575 6.5575 3.7575 27 P 0 ;1
L 6.5575 3.8075 6.5575 3.8075 27 P 0 ;1
L 6.5575 3.8575 6.5575 3.8575 27 P 0 ;1
L 6.5575 3.9075 6.5575 3.9075 27 P 0 ;1
L 6.5575 3.9575 6.5575 3.9575 27 P 0 ;1
L 6.5575 4.0075 6.5575 4.0075 27 P 0 ;1
L 6.5575 4.0575 6.5575 4.0575 27 P 0 ;1
L 6.5575 4.1075 6.5575 4.1075 27 P 0 ;1
L 6.5575 4.1575 6.5575 4.1575 27 P 0 ;1
L 6.5575 4.2075 6.5575 4.2075 27 P 0 ;1
L 6.5575 4.2575 6.5575 4.2575 27 P 0 ;1
L 6.5575 4.3075 6.5575 4.3075 27 P 0 ;1
L 6.5575 4.3575 6.5575 4.3575 27 P 0 ;1
L 6.5575 4.4075 6.5575 4.4075 27 P 0 ;1
L 6.5575 4.4575 6.5575 4.4575 27 P 0 ;1
L 6.5575 4.5075 6.5575 4.5075 27 P 0 ;1
L 6.5575 5.2575 6.5575 5.2575 27 P 0 ;1
L 6.5575 5.3075 6.5575 5.3075 27 P 0 ;1
L 6.5575 5.3575 6.5575 5.3575 27 P 0 ;1
L 6.5575 5.4075 6.5575 5.4075 27 P 0 ;1
L 6.5575 5.4575 6.5575 5.4575 27 P 0 ;1
L 6.5575 5.5075 6.5575 5.5075 27 P 0 ;1
L 6.5575 5.5575 6.5575 5.5575 27 P 0 ;1
L 6.5575 5.6075 6.5575 5.6075 27 P 0 ;1
L 6.5575 5.6575 6.5575 5.6575 27 P 0 ;1
L 6.5575 5.7075 6.5575 5.7075 27 P 0 ;1
L 6.6075 0.5575 6.6075 0.5575 27 P 0 ;1
L 6.6075 0.6075 6.6075 0.6075 27 P 0 ;1
L 6.6075 0.6575 6.6075 0.6575 27 P 0 ;1
L 6.6075 0.7075 6.6075 0.7075 27 P 0 ;1
L 6.6075 0.7575 6.6075 0.7575 27 P 0 ;1
L 6.6075 0.8075 6.6075 0.8075 27 P 0 ;1
L 6.6075 0.8575 6.6075 0.8575 27 P 0 ;1
L 6.6075 0.9075 6.6075 0.9075 27 P 0 ;1
L 6.6075 0.9575 6.6075 0.9575 27 P 0 ;1
L 6.6075 1.0075 6.6075 1.0075 27 P 0 ;1
L 6.6075 1.0575 6.6075 1.0575 27 P 0 ;1
L 6.6075 1.1075 6.6075 1.1075 27 P 0 ;1
L 6.6075 1.1575 6.6075 1.1575 27 P 0 ;1
L 6.6075 1.2075 6.6075 1.2075 27 P 0 ;1
L 6.6075 1.2575 6.6075 1.2575 27 P 0 ;1
L 6.6075 1.3075 6.6075 1.3075 27 P 0 ;1
L 6.6075 1.3575 6.6075 1.3575 27 P 0 ;1
L 6.6075 1.4075 6.6075 1.4075 27 P 0 ;1
L 6.6075 1.4575 6.6075 1.4575 27 P 0 ;1
L 6.6075 1.5075 6.6075 1.5075 27 P 0 ;1
L 6.6075 1.5575 6.6075 1.5575 27 P 0 ;1
L 6.6075 1.6075 6.6075 1.6075 27 P 0 ;1
L 6.6075 1.6575 6.6075 1.6575 27 P 0 ;1
L 6.6075 1.7075 6.6075 1.7075 27 P 0 ;1
L 6.6075 1.7575 6.6075 1.7575 27 P 0 ;1
L 6.6075 1.8075 6.6075 1.8075 27 P 0 ;1
L 6.6075 1.8575 6.6075 1.8575 27 P 0 ;1
L 6.6075 1.9075 6.6075 1.9075 27 P 0 ;1
L 6.6075 1.9575 6.6075 1.9575 27 P 0 ;1
L 6.6075 2.0075 6.6075 2.0075 27 P 0 ;1
L 6.6075 2.0575 6.6075 2.0575 27 P 0 ;1
L 6.6075 2.1075 6.6075 2.1075 27 P 0 ;1
L 6.6075 2.1575 6.6075 2.1575 27 P 0 ;1
L 6.6075 2.2075 6.6075 2.2075 27 P 0 ;1
L 6.6075 2.2575 6.6075 2.2575 27 P 0 ;1
L 6.6075 2.3075 6.6075 2.3075 27 P 0 ;1
L 6.6075 2.3575 6.6075 2.3575 27 P 0 ;1
L 6.6075 2.4075 6.6075 2.4075 27 P 0 ;1
L 6.6075 2.4575 6.6075 2.4575 27 P 0 ;1
L 6.6075 2.5075 6.6075 2.5075 27 P 0 ;1
L 6.6075 2.5575 6.6075 2.5575 27 P 0 ;1
L 6.6075 2.6075 6.6075 2.6075 27 P 0 ;1
L 6.6075 2.6575 6.6075 2.6575 27 P 0 ;1
L 6.6075 2.7075 6.6075 2.7075 27 P 0 ;1
L 6.6075 2.7575 6.6075 2.7575 27 P 0 ;1
L 6.6075 2.8075 6.6075 2.8075 27 P 0 ;1
L 6.6075 2.8575 6.6075 2.8575 27 P 0 ;1
L 6.6075 2.9075 6.6075 2.9075 27 P 0 ;1
L 6.6075 2.9575 6.6075 2.9575 27 P 0 ;1
L 6.6075 3.0075 6.6075 3.0075 27 P 0 ;1
L 6.6075 3.0575 6.6075 3.0575 27 P 0 ;1
L 6.6075 3.1075 6.6075 3.1075 27 P 0 ;1
L 6.6075 3.1575 6.6075 3.1575 27 P 0 ;1
L 6.6075 3.2075 6.6075 3.2075 27 P 0 ;1
L 6.6075 3.2575 6.6075 3.2575 27 P 0 ;1
L 6.6075 3.3075 6.6075 3.3075 27 P 0 ;1
L 6.6075 3.3575 6.6075 3.3575 27 P 0 ;1
L 6.6075 3.4075 6.6075 3.4075 27 P 0 ;1
L 6.6075 3.4575 6.6075 3.4575 27 P 0 ;1
L 6.6075 3.5075 6.6075 3.5075 27 P 0 ;1
L 6.6075 3.5575 6.6075 3.5575 27 P 0 ;1
L 6.6075 3.6075 6.6075 3.6075 27 P 0 ;1
L 6.6075 3.6575 6.6075 3.6575 27 P 0 ;1
L 6.6075 3.7075 6.6075 3.7075 27 P 0 ;1
L 6.6075 3.7575 6.6075 3.7575 27 P 0 ;1
L 6.6075 3.8075 6.6075 3.8075 27 P 0 ;1
L 6.6075 3.8575 6.6075 3.8575 27 P 0 ;1
L 6.6075 3.9075 6.6075 3.9075 27 P 0 ;1
L 6.6075 3.9575 6.6075 3.9575 27 P 0 ;1
L 6.6075 4.0075 6.6075 4.0075 27 P 0 ;1
L 6.6075 4.0575 6.6075 4.0575 27 P 0 ;1
L 6.6075 4.1075 6.6075 4.1075 27 P 0 ;1
L 6.6075 4.1575 6.6075 4.1575 27 P 0 ;1
L 6.6075 4.2075 6.6075 4.2075 27 P 0 ;1
L 6.6075 4.2575 6.6075 4.2575 27 P 0 ;1
L 6.6075 4.3075 6.6075 4.3075 27 P 0 ;1
L 6.6075 4.3575 6.6075 4.3575 27 P 0 ;1
L 6.6075 4.4075 6.6075 4.4075 27 P 0 ;1
L 6.6075 4.4575 6.6075 4.4575 27 P 0 ;1
L 6.6075 4.5075 6.6075 4.5075 27 P 0 ;1
L 6.6075 5.2575 6.6075 5.2575 27 P 0 ;1
L 6.6075 5.3075 6.6075 5.3075 27 P 0 ;1
L 6.6075 5.3575 6.6075 5.3575 27 P 0 ;1
L 6.6075 5.4075 6.6075 5.4075 27 P 0 ;1
L 6.6075 5.4575 6.6075 5.4575 27 P 0 ;1
L 6.6075 5.5075 6.6075 5.5075 27 P 0 ;1
L 6.6075 5.5575 6.6075 5.5575 27 P 0 ;1
L 6.6075 5.6075 6.6075 5.6075 27 P 0 ;1
L 6.6075 5.6575 6.6075 5.6575 27 P 0 ;1
L 6.6575 0.5075 6.6575 0.5075 27 P 0 ;1
L 6.6575 0.5575 6.6575 0.5575 27 P 0 ;1
L 6.6575 0.6075 6.6575 0.6075 27 P 0 ;1
L 6.6575 0.6575 6.6575 0.6575 27 P 0 ;1
L 6.6575 0.7075 6.6575 0.7075 27 P 0 ;1
L 6.6575 0.7575 6.6575 0.7575 27 P 0 ;1
L 6.6575 0.8075 6.6575 0.8075 27 P 0 ;1
L 6.6575 0.8575 6.6575 0.8575 27 P 0 ;1
L 6.6575 0.9075 6.6575 0.9075 27 P 0 ;1
L 6.6575 0.9575 6.6575 0.9575 27 P 0 ;1
L 6.6575 1.0075 6.6575 1.0075 27 P 0 ;1
L 6.6575 1.0575 6.6575 1.0575 27 P 0 ;1
L 6.6575 1.1075 6.6575 1.1075 27 P 0 ;1
L 6.6575 1.1575 6.6575 1.1575 27 P 0 ;1
L 6.6575 1.2075 6.6575 1.2075 27 P 0 ;1
L 6.6575 1.2575 6.6575 1.2575 27 P 0 ;1
L 6.6575 1.3075 6.6575 1.3075 27 P 0 ;1
L 6.6575 1.3575 6.6575 1.3575 27 P 0 ;1
L 6.6575 1.4075 6.6575 1.4075 27 P 0 ;1
L 6.6575 1.4575 6.6575 1.4575 27 P 0 ;1
L 6.6575 1.5075 6.6575 1.5075 27 P 0 ;1
L 6.6575 1.5575 6.6575 1.5575 27 P 0 ;1
L 6.6575 1.6075 6.6575 1.6075 27 P 0 ;1
L 6.6575 1.6575 6.6575 1.6575 27 P 0 ;1
L 6.6575 1.7075 6.6575 1.7075 27 P 0 ;1
L 6.6575 1.7575 6.6575 1.7575 27 P 0 ;1
L 6.6575 1.8075 6.6575 1.8075 27 P 0 ;1
L 6.6575 1.8575 6.6575 1.8575 27 P 0 ;1
L 6.6575 1.9075 6.6575 1.9075 27 P 0 ;1
L 6.6575 1.9575 6.6575 1.9575 27 P 0 ;1
L 6.6575 2.0075 6.6575 2.0075 27 P 0 ;1
L 6.6575 2.0575 6.6575 2.0575 27 P 0 ;1
L 6.6575 2.1075 6.6575 2.1075 27 P 0 ;1
L 6.6575 2.1575 6.6575 2.1575 27 P 0 ;1
L 6.6575 2.2075 6.6575 2.2075 27 P 0 ;1
L 6.6575 2.2575 6.6575 2.2575 27 P 0 ;1
L 6.6575 2.3075 6.6575 2.3075 27 P 0 ;1
L 6.6575 2.3575 6.6575 2.3575 27 P 0 ;1
L 6.6575 2.4075 6.6575 2.4075 27 P 0 ;1
L 6.6575 2.4575 6.6575 2.4575 27 P 0 ;1
L 6.6575 2.5075 6.6575 2.5075 27 P 0 ;1
L 6.6575 2.5575 6.6575 2.5575 27 P 0 ;1
L 6.6575 2.6075 6.6575 2.6075 27 P 0 ;1
L 6.6575 2.6575 6.6575 2.6575 27 P 0 ;1
L 6.6575 2.7075 6.6575 2.7075 27 P 0 ;1
L 6.6575 2.7575 6.6575 2.7575 27 P 0 ;1
L 6.6575 2.8075 6.6575 2.8075 27 P 0 ;1
L 6.6575 2.8575 6.6575 2.8575 27 P 0 ;1
L 6.6575 2.9075 6.6575 2.9075 27 P 0 ;1
L 6.6575 2.9575 6.6575 2.9575 27 P 0 ;1
L 6.6575 3.0075 6.6575 3.0075 27 P 0 ;1
L 6.6575 3.0575 6.6575 3.0575 27 P 0 ;1
L 6.6575 3.1075 6.6575 3.1075 27 P 0 ;1
L 6.6575 3.1575 6.6575 3.1575 27 P 0 ;1
L 6.6575 3.2075 6.6575 3.2075 27 P 0 ;1
L 6.6575 3.2575 6.6575 3.2575 27 P 0 ;1
L 6.6575 3.3075 6.6575 3.3075 27 P 0 ;1
L 6.6575 3.3575 6.6575 3.3575 27 P 0 ;1
L 6.6575 3.4075 6.6575 3.4075 27 P 0 ;1
L 6.6575 3.4575 6.6575 3.4575 27 P 0 ;1
L 6.6575 3.5075 6.6575 3.5075 27 P 0 ;1
L 6.6575 3.5575 6.6575 3.5575 27 P 0 ;1
L 6.6575 3.6075 6.6575 3.6075 27 P 0 ;1
L 6.6575 3.6575 6.6575 3.6575 27 P 0 ;1
L 6.6575 3.7075 6.6575 3.7075 27 P 0 ;1
L 6.6575 3.7575 6.6575 3.7575 27 P 0 ;1
L 6.6575 3.8075 6.6575 3.8075 27 P 0 ;1
L 6.6575 3.8575 6.6575 3.8575 27 P 0 ;1
L 6.6575 3.9075 6.6575 3.9075 27 P 0 ;1
L 6.6575 3.9575 6.6575 3.9575 27 P 0 ;1
L 6.6575 4.0075 6.6575 4.0075 27 P 0 ;1
L 6.6575 4.0575 6.6575 4.0575 27 P 0 ;1
L 6.6575 4.1075 6.6575 4.1075 27 P 0 ;1
L 6.6575 4.1575 6.6575 4.1575 27 P 0 ;1
L 6.6575 4.2075 6.6575 4.2075 27 P 0 ;1
L 6.6575 4.2575 6.6575 4.2575 27 P 0 ;1
L 6.6575 4.3075 6.6575 4.3075 27 P 0 ;1
L 6.6575 4.3575 6.6575 4.3575 27 P 0 ;1
L 6.6575 4.4075 6.6575 4.4075 27 P 0 ;1
L 6.6575 5.2575 6.6575 5.2575 27 P 0 ;1
L 6.6575 5.3075 6.6575 5.3075 27 P 0 ;1
L 6.6575 5.3575 6.6575 5.3575 27 P 0 ;1
L 6.6575 5.4075 6.6575 5.4075 27 P 0 ;1
L 6.6575 5.4575 6.6575 5.4575 27 P 0 ;1
L 6.6575 5.5075 6.6575 5.5075 27 P 0 ;1
L 6.6575 5.5575 6.6575 5.5575 27 P 0 ;1
L 6.6575 5.6075 6.6575 5.6075 27 P 0 ;1
L 6.7075 0.4575 6.7075 0.4575 27 P 0 ;1
L 6.7075 0.5075 6.7075 0.5075 27 P 0 ;1
L 6.7075 0.5575 6.7075 0.5575 27 P 0 ;1
L 6.7075 0.6075 6.7075 0.6075 27 P 0 ;1
L 6.7075 0.6575 6.7075 0.6575 27 P 0 ;1
L 6.7075 0.7075 6.7075 0.7075 27 P 0 ;1
L 6.7075 0.7575 6.7075 0.7575 27 P 0 ;1
L 6.7075 0.8075 6.7075 0.8075 27 P 0 ;1
L 6.7075 0.8575 6.7075 0.8575 27 P 0 ;1
L 6.7075 0.9075 6.7075 0.9075 27 P 0 ;1
L 6.7075 0.9575 6.7075 0.9575 27 P 0 ;1
L 6.7075 1.0075 6.7075 1.0075 27 P 0 ;1
L 6.7075 1.0575 6.7075 1.0575 27 P 0 ;1
L 6.7075 1.1075 6.7075 1.1075 27 P 0 ;1
L 6.7075 1.1575 6.7075 1.1575 27 P 0 ;1
L 6.7075 1.2075 6.7075 1.2075 27 P 0 ;1
L 6.7075 1.2575 6.7075 1.2575 27 P 0 ;1
L 6.7075 1.3075 6.7075 1.3075 27 P 0 ;1
L 6.7075 1.3575 6.7075 1.3575 27 P 0 ;1
L 6.7075 1.4075 6.7075 1.4075 27 P 0 ;1
L 6.7075 1.4575 6.7075 1.4575 27 P 0 ;1
L 6.7075 1.5075 6.7075 1.5075 27 P 0 ;1
L 6.7075 1.5575 6.7075 1.5575 27 P 0 ;1
L 6.7075 1.6075 6.7075 1.6075 27 P 0 ;1
L 6.7075 1.6575 6.7075 1.6575 27 P 0 ;1
L 6.7075 1.7075 6.7075 1.7075 27 P 0 ;1
L 6.7075 1.7575 6.7075 1.7575 27 P 0 ;1
L 6.7075 1.8075 6.7075 1.8075 27 P 0 ;1
L 6.7075 1.8575 6.7075 1.8575 27 P 0 ;1
L 6.7075 1.9075 6.7075 1.9075 27 P 0 ;1
L 6.7075 1.9575 6.7075 1.9575 27 P 0 ;1
L 6.7075 2.0075 6.7075 2.0075 27 P 0 ;1
L 6.7075 2.0575 6.7075 2.0575 27 P 0 ;1
L 6.7075 2.1075 6.7075 2.1075 27 P 0 ;1
L 6.7075 2.1575 6.7075 2.1575 27 P 0 ;1
L 6.7075 2.2075 6.7075 2.2075 27 P 0 ;1
L 6.7075 2.2575 6.7075 2.2575 27 P 0 ;1
L 6.7075 2.3075 6.7075 2.3075 27 P 0 ;1
L 6.7075 2.3575 6.7075 2.3575 27 P 0 ;1
L 6.7075 2.4075 6.7075 2.4075 27 P 0 ;1
L 6.7075 2.4575 6.7075 2.4575 27 P 0 ;1
L 6.7075 2.5075 6.7075 2.5075 27 P 0 ;1
L 6.7075 2.5575 6.7075 2.5575 27 P 0 ;1
L 6.7075 2.6075 6.7075 2.6075 27 P 0 ;1
L 6.7075 2.6575 6.7075 2.6575 27 P 0 ;1
L 6.7075 2.7075 6.7075 2.7075 27 P 0 ;1
L 6.7075 2.7575 6.7075 2.7575 27 P 0 ;1
L 6.7075 2.8075 6.7075 2.8075 27 P 0 ;1
L 6.7075 2.8575 6.7075 2.8575 27 P 0 ;1
L 6.7075 2.9075 6.7075 2.9075 27 P 0 ;1
L 6.7075 2.9575 6.7075 2.9575 27 P 0 ;1
L 6.7075 3.0075 6.7075 3.0075 27 P 0 ;1
L 6.7075 3.0575 6.7075 3.0575 27 P 0 ;1
L 6.7075 3.1075 6.7075 3.1075 27 P 0 ;1
L 6.7075 3.1575 6.7075 3.1575 27 P 0 ;1
L 6.7075 3.2075 6.7075 3.2075 27 P 0 ;1
L 6.7075 3.2575 6.7075 3.2575 27 P 0 ;1
L 6.7075 3.3075 6.7075 3.3075 27 P 0 ;1
L 6.7075 3.3575 6.7075 3.3575 27 P 0 ;1
L 6.7075 3.4075 6.7075 3.4075 27 P 0 ;1
L 6.7075 3.4575 6.7075 3.4575 27 P 0 ;1
L 6.7075 3.5075 6.7075 3.5075 27 P 0 ;1
L 6.7075 3.5575 6.7075 3.5575 27 P 0 ;1
L 6.7075 3.6075 6.7075 3.6075 27 P 0 ;1
L 6.7075 3.6575 6.7075 3.6575 27 P 0 ;1
L 6.7075 3.7075 6.7075 3.7075 27 P 0 ;1
L 6.7075 3.7575 6.7075 3.7575 27 P 0 ;1
L 6.7075 3.8075 6.7075 3.8075 27 P 0 ;1
L 6.7075 3.8575 6.7075 3.8575 27 P 0 ;1
L 6.7075 3.9075 6.7075 3.9075 27 P 0 ;1
L 6.7075 3.9575 6.7075 3.9575 27 P 0 ;1
L 6.7075 4.0075 6.7075 4.0075 27 P 0 ;1
L 6.7075 4.0575 6.7075 4.0575 27 P 0 ;1
L 6.7075 4.1075 6.7075 4.1075 27 P 0 ;1
L 6.7075 4.1575 6.7075 4.1575 27 P 0 ;1
L 6.7075 4.2075 6.7075 4.2075 27 P 0 ;1
L 6.7075 4.2575 6.7075 4.2575 27 P 0 ;1
L 6.7075 4.3075 6.7075 4.3075 27 P 0 ;1
L 6.7075 4.3575 6.7075 4.3575 27 P 0 ;1
L 6.7075 4.4075 6.7075 4.4075 27 P 0 ;1
L 6.7075 5.2575 6.7075 5.2575 27 P 0 ;1
L 6.7075 5.3075 6.7075 5.3075 27 P 0 ;1
L 6.7075 5.3575 6.7075 5.3575 27 P 0 ;1
L 6.7075 5.4075 6.7075 5.4075 27 P 0 ;1
L 6.7075 5.4575 6.7075 5.4575 27 P 0 ;1
L 6.7075 5.5075 6.7075 5.5075 27 P 0 ;1
L 6.7075 5.5575 6.7075 5.5575 27 P 0 ;1
L 6.7575 0.1575 6.7575 0.1575 27 P 0 ;1
L 6.7575 0.2075 6.7575 0.2075 27 P 0 ;1
L 6.7575 0.2575 6.7575 0.2575 27 P 0 ;1
L 6.7575 0.3075 6.7575 0.3075 27 P 0 ;1
L 6.7575 0.3575 6.7575 0.3575 27 P 0 ;1
L 6.7575 0.4075 6.7575 0.4075 27 P 0 ;1
L 6.7575 0.4575 6.7575 0.4575 27 P 0 ;1
L 6.7575 0.5075 6.7575 0.5075 27 P 0 ;1
L 6.7575 0.5575 6.7575 0.5575 27 P 0 ;1
L 6.7575 0.6075 6.7575 0.6075 27 P 0 ;1
L 6.7575 0.6575 6.7575 0.6575 27 P 0 ;1
L 6.7575 0.7075 6.7575 0.7075 27 P 0 ;1
L 6.7575 0.7575 6.7575 0.7575 27 P 0 ;1
L 6.7575 0.8075 6.7575 0.8075 27 P 0 ;1
L 6.7575 0.8575 6.7575 0.8575 27 P 0 ;1
L 6.7575 0.9075 6.7575 0.9075 27 P 0 ;1
L 6.7575 0.9575 6.7575 0.9575 27 P 0 ;1
L 6.7575 1.0075 6.7575 1.0075 27 P 0 ;1
L 6.7575 1.0575 6.7575 1.0575 27 P 0 ;1
L 6.7575 1.1075 6.7575 1.1075 27 P 0 ;1
L 6.7575 1.1575 6.7575 1.1575 27 P 0 ;1
L 6.7575 1.2075 6.7575 1.2075 27 P 0 ;1
L 6.7575 1.2575 6.7575 1.2575 27 P 0 ;1
L 6.7575 1.3075 6.7575 1.3075 27 P 0 ;1
L 6.7575 1.3575 6.7575 1.3575 27 P 0 ;1
L 6.7575 1.6575 6.7575 1.6575 27 P 0 ;1
L 6.7575 1.7075 6.7575 1.7075 27 P 0 ;1
L 6.7575 1.7575 6.7575 1.7575 27 P 0 ;1
L 6.7575 1.8075 6.7575 1.8075 27 P 0 ;1
L 6.7575 1.8575 6.7575 1.8575 27 P 0 ;1
L 6.7575 1.9075 6.7575 1.9075 27 P 0 ;1
L 6.7575 1.9575 6.7575 1.9575 27 P 0 ;1
L 6.7575 2.0075 6.7575 2.0075 27 P 0 ;1
L 6.7575 2.0575 6.7575 2.0575 27 P 0 ;1
L 6.7575 2.1075 6.7575 2.1075 27 P 0 ;1
L 6.7575 2.1575 6.7575 2.1575 27 P 0 ;1
L 6.7575 2.2075 6.7575 2.2075 27 P 0 ;1
L 6.7575 2.2575 6.7575 2.2575 27 P 0 ;1
L 6.7575 2.3075 6.7575 2.3075 27 P 0 ;1
L 6.7575 2.3575 6.7575 2.3575 27 P 0 ;1
L 6.7575 2.4075 6.7575 2.4075 27 P 0 ;1
L 6.7575 2.4575 6.7575 2.4575 27 P 0 ;1
L 6.7575 2.5075 6.7575 2.5075 27 P 0 ;1
L 6.7575 2.5575 6.7575 2.5575 27 P 0 ;1
L 6.7575 2.6075 6.7575 2.6075 27 P 0 ;1
L 6.7575 2.6575 6.7575 2.6575 27 P 0 ;1
L 6.7575 2.7075 6.7575 2.7075 27 P 0 ;1
L 6.7575 2.7575 6.7575 2.7575 27 P 0 ;1
L 6.7575 2.8075 6.7575 2.8075 27 P 0 ;1
L 6.7575 2.8575 6.7575 2.8575 27 P 0 ;1
L 6.7575 2.9075 6.7575 2.9075 27 P 0 ;1
L 6.7575 2.9575 6.7575 2.9575 27 P 0 ;1
L 6.7575 3.0075 6.7575 3.0075 27 P 0 ;1
L 6.7575 3.0575 6.7575 3.0575 27 P 0 ;1
L 6.7575 3.1075 6.7575 3.1075 27 P 0 ;1
L 6.7575 3.1575 6.7575 3.1575 27 P 0 ;1
L 6.7575 3.2075 6.7575 3.2075 27 P 0 ;1
L 6.7575 3.2575 6.7575 3.2575 27 P 0 ;1
L 6.7575 3.3075 6.7575 3.3075 27 P 0 ;1
L 6.7575 3.3575 6.7575 3.3575 27 P 0 ;1
L 6.7575 3.4075 6.7575 3.4075 27 P 0 ;1
L 6.7575 3.4575 6.7575 3.4575 27 P 0 ;1
L 6.7575 3.5075 6.7575 3.5075 27 P 0 ;1
L 6.7575 3.5575 6.7575 3.5575 27 P 0 ;1
L 6.7575 3.6075 6.7575 3.6075 27 P 0 ;1
L 6.7575 3.6575 6.7575 3.6575 27 P 0 ;1
L 6.7575 3.7075 6.7575 3.7075 27 P 0 ;1
L 6.7575 3.7575 6.7575 3.7575 27 P 0 ;1
L 6.7575 3.8075 6.7575 3.8075 27 P 0 ;1
L 6.7575 3.8575 6.7575 3.8575 27 P 0 ;1
L 6.7575 3.9075 6.7575 3.9075 27 P 0 ;1
L 6.7575 3.9575 6.7575 3.9575 27 P 0 ;1
L 6.7575 4.0075 6.7575 4.0075 27 P 0 ;1
L 6.7575 4.0575 6.7575 4.0575 27 P 0 ;1
L 6.7575 4.3575 6.7575 4.3575 27 P 0 ;1
L 6.7575 4.4075 6.7575 4.4075 27 P 0 ;1
L 6.7575 5.2575 6.7575 5.2575 27 P 0 ;1
L 6.7575 5.3075 6.7575 5.3075 27 P 0 ;1
L 6.7575 5.3575 6.7575 5.3575 27 P 0 ;1
L 6.7575 5.4075 6.7575 5.4075 27 P 0 ;1
L 6.7575 5.4575 6.7575 5.4575 27 P 0 ;1
L 6.7575 5.5075 6.7575 5.5075 27 P 0 ;1
L 6.8075 0.1575 6.8075 0.1575 27 P 0 ;1
L 6.8075 0.2075 6.8075 0.2075 27 P 0 ;1
L 6.8075 0.2575 6.8075 0.2575 27 P 0 ;1
L 6.8075 0.3075 6.8075 0.3075 27 P 0 ;1
L 6.8075 0.3575 6.8075 0.3575 27 P 0 ;1
L 6.8075 0.4075 6.8075 0.4075 27 P 0 ;1
L 6.8075 0.4575 6.8075 0.4575 27 P 0 ;1
L 6.8075 0.5075 6.8075 0.5075 27 P 0 ;1
L 6.8075 0.5575 6.8075 0.5575 27 P 0 ;1
L 6.8075 0.6075 6.8075 0.6075 27 P 0 ;1
L 6.8075 0.6575 6.8075 0.6575 27 P 0 ;1
L 6.8075 0.7075 6.8075 0.7075 27 P 0 ;1
L 6.8075 0.7575 6.8075 0.7575 27 P 0 ;1
L 6.8075 0.8075 6.8075 0.8075 27 P 0 ;1
L 6.8075 0.8575 6.8075 0.8575 27 P 0 ;1
L 6.8075 0.9075 6.8075 0.9075 27 P 0 ;1
L 6.8075 0.9575 6.8075 0.9575 27 P 0 ;1
L 6.8075 1.0075 6.8075 1.0075 27 P 0 ;1
L 6.8075 1.0575 6.8075 1.0575 27 P 0 ;1
L 6.8075 1.1075 6.8075 1.1075 27 P 0 ;1
L 6.8075 1.1575 6.8075 1.1575 27 P 0 ;1
L 6.8075 1.2075 6.8075 1.2075 27 P 0 ;1
L 6.8075 1.2575 6.8075 1.2575 27 P 0 ;1
L 6.8075 1.3075 6.8075 1.3075 27 P 0 ;1
L 6.8075 1.7575 6.8075 1.7575 27 P 0 ;1
L 6.8075 1.8075 6.8075 1.8075 27 P 0 ;1
L 6.8075 1.8575 6.8075 1.8575 27 P 0 ;1
L 6.8075 1.9075 6.8075 1.9075 27 P 0 ;1
L 6.8075 1.9575 6.8075 1.9575 27 P 0 ;1
L 6.8075 2.0075 6.8075 2.0075 27 P 0 ;1
L 6.8075 2.0575 6.8075 2.0575 27 P 0 ;1
L 6.8075 2.1075 6.8075 2.1075 27 P 0 ;1
L 6.8075 2.1575 6.8075 2.1575 27 P 0 ;1
L 6.8075 2.2075 6.8075 2.2075 27 P 0 ;1
L 6.8075 2.2575 6.8075 2.2575 27 P 0 ;1
L 6.8075 2.3075 6.8075 2.3075 27 P 0 ;1
L 6.8075 2.3575 6.8075 2.3575 27 P 0 ;1
L 6.8075 2.4075 6.8075 2.4075 27 P 0 ;1
L 6.8075 2.4575 6.8075 2.4575 27 P 0 ;1
L 6.8075 2.5075 6.8075 2.5075 27 P 0 ;1
L 6.8075 2.5575 6.8075 2.5575 27 P 0 ;1
L 6.8075 2.6075 6.8075 2.6075 27 P 0 ;1
L 6.8075 2.6575 6.8075 2.6575 27 P 0 ;1
L 6.8075 2.7075 6.8075 2.7075 27 P 0 ;1
L 6.8075 2.7575 6.8075 2.7575 27 P 0 ;1
L 6.8075 2.8075 6.8075 2.8075 27 P 0 ;1
L 6.8075 2.8575 6.8075 2.8575 27 P 0 ;1
L 6.8075 2.9075 6.8075 2.9075 27 P 0 ;1
L 6.8075 2.9575 6.8075 2.9575 27 P 0 ;1
L 6.8075 3.0075 6.8075 3.0075 27 P 0 ;1
L 6.8075 3.0575 6.8075 3.0575 27 P 0 ;1
L 6.8075 3.1075 6.8075 3.1075 27 P 0 ;1
L 6.8075 3.1575 6.8075 3.1575 27 P 0 ;1
L 6.8075 3.2075 6.8075 3.2075 27 P 0 ;1
L 6.8075 3.2575 6.8075 3.2575 27 P 0 ;1
L 6.8075 3.3075 6.8075 3.3075 27 P 0 ;1
L 6.8075 3.3575 6.8075 3.3575 27 P 0 ;1
L 6.8075 3.4075 6.8075 3.4075 27 P 0 ;1
L 6.8075 3.4575 6.8075 3.4575 27 P 0 ;1
L 6.8075 3.5075 6.8075 3.5075 27 P 0 ;1
L 6.8075 3.5575 6.8075 3.5575 27 P 0 ;1
L 6.8075 3.6075 6.8075 3.6075 27 P 0 ;1
L 6.8075 3.6575 6.8075 3.6575 27 P 0 ;1
L 6.8075 3.7075 6.8075 3.7075 27 P 0 ;1
L 6.8075 3.7575 6.8075 3.7575 27 P 0 ;1
L 6.8075 3.8075 6.8075 3.8075 27 P 0 ;1
L 6.8075 3.8575 6.8075 3.8575 27 P 0 ;1
L 6.8075 3.9075 6.8075 3.9075 27 P 0 ;1
L 6.8075 3.9575 6.8075 3.9575 27 P 0 ;1
L 6.8075 4.0075 6.8075 4.0075 27 P 0 ;1
L 6.8075 4.4075 6.8075 4.4075 27 P 0 ;1
L 6.8075 5.2575 6.8075 5.2575 27 P 0 ;1
L 6.8075 5.3075 6.8075 5.3075 27 P 0 ;1
L 6.8075 5.3575 6.8075 5.3575 27 P 0 ;1
L 6.8075 5.4075 6.8075 5.4075 27 P 0 ;1
L 6.8075 5.4575 6.8075 5.4575 27 P 0 ;1
L 6.8575 0.1575 6.8575 0.1575 27 P 0 ;1
L 6.8575 0.2075 6.8575 0.2075 27 P 0 ;1
L 6.8575 0.2575 6.8575 0.2575 27 P 0 ;1
L 6.8575 0.3075 6.8575 0.3075 27 P 0 ;1
L 6.8575 0.3575 6.8575 0.3575 27 P 0 ;1
L 6.8575 0.4075 6.8575 0.4075 27 P 0 ;1
L 6.8575 0.4575 6.8575 0.4575 27 P 0 ;1
L 6.8575 0.5075 6.8575 0.5075 27 P 0 ;1
L 6.8575 0.5575 6.8575 0.5575 27 P 0 ;1
L 6.8575 0.6075 6.8575 0.6075 27 P 0 ;1
L 6.8575 0.6575 6.8575 0.6575 27 P 0 ;1
L 6.8575 0.7075 6.8575 0.7075 27 P 0 ;1
L 6.8575 0.7575 6.8575 0.7575 27 P 0 ;1
L 6.8575 0.8075 6.8575 0.8075 27 P 0 ;1
L 6.8575 0.8575 6.8575 0.8575 27 P 0 ;1
L 6.8575 0.9075 6.8575 0.9075 27 P 0 ;1
L 6.8575 0.9575 6.8575 0.9575 27 P 0 ;1
L 6.8575 1.0075 6.8575 1.0075 27 P 0 ;1
L 6.8575 1.0575 6.8575 1.0575 27 P 0 ;1
L 6.8575 1.1075 6.8575 1.1075 27 P 0 ;1
L 6.8575 1.1575 6.8575 1.1575 27 P 0 ;1
L 6.8575 1.2075 6.8575 1.2075 27 P 0 ;1
L 6.8575 1.2575 6.8575 1.2575 27 P 0 ;1
L 6.8575 1.3075 6.8575 1.3075 27 P 0 ;1
L 6.8575 1.7575 6.8575 1.7575 27 P 0 ;1
L 6.8575 1.8075 6.8575 1.8075 27 P 0 ;1
L 6.8575 1.8575 6.8575 1.8575 27 P 0 ;1
L 6.8575 1.9075 6.8575 1.9075 27 P 0 ;1
L 6.8575 1.9575 6.8575 1.9575 27 P 0 ;1
L 6.8575 2.0075 6.8575 2.0075 27 P 0 ;1
L 6.8575 2.0575 6.8575 2.0575 27 P 0 ;1
L 6.8575 2.1075 6.8575 2.1075 27 P 0 ;1
L 6.8575 2.1575 6.8575 2.1575 27 P 0 ;1
L 6.8575 2.2075 6.8575 2.2075 27 P 0 ;1
L 6.8575 2.2575 6.8575 2.2575 27 P 0 ;1
L 6.8575 2.3075 6.8575 2.3075 27 P 0 ;1
L 6.8575 2.3575 6.8575 2.3575 27 P 0 ;1
L 6.8575 2.4075 6.8575 2.4075 27 P 0 ;1
L 6.8575 2.4575 6.8575 2.4575 27 P 0 ;1
L 6.8575 2.5075 6.8575 2.5075 27 P 0 ;1
L 6.8575 2.5575 6.8575 2.5575 27 P 0 ;1
L 6.8575 2.6075 6.8575 2.6075 27 P 0 ;1
L 6.8575 2.6575 6.8575 2.6575 27 P 0 ;1
L 6.8575 2.7075 6.8575 2.7075 27 P 0 ;1
L 6.8575 2.7575 6.8575 2.7575 27 P 0 ;1
L 6.8575 2.8075 6.8575 2.8075 27 P 0 ;1
L 6.8575 2.8575 6.8575 2.8575 27 P 0 ;1
L 6.8575 2.9075 6.8575 2.9075 27 P 0 ;1
L 6.8575 2.9575 6.8575 2.9575 27 P 0 ;1
L 6.8575 3.0075 6.8575 3.0075 27 P 0 ;1
L 6.8575 3.0575 6.8575 3.0575 27 P 0 ;1
L 6.8575 3.1075 6.8575 3.1075 27 P 0 ;1
L 6.8575 3.1575 6.8575 3.1575 27 P 0 ;1
L 6.8575 3.2075 6.8575 3.2075 27 P 0 ;1
L 6.8575 3.2575 6.8575 3.2575 27 P 0 ;1
L 6.8575 3.3075 6.8575 3.3075 27 P 0 ;1
L 6.8575 3.3575 6.8575 3.3575 27 P 0 ;1
L 6.8575 3.4075 6.8575 3.4075 27 P 0 ;1
L 6.8575 3.4575 6.8575 3.4575 27 P 0 ;1
L 6.8575 3.5075 6.8575 3.5075 27 P 0 ;1
L 6.8575 3.5575 6.8575 3.5575 27 P 0 ;1
L 6.8575 3.6075 6.8575 3.6075 27 P 0 ;1
L 6.8575 3.6575 6.8575 3.6575 27 P 0 ;1
L 6.8575 3.7075 6.8575 3.7075 27 P 0 ;1
L 6.8575 3.7575 6.8575 3.7575 27 P 0 ;1
L 6.8575 3.8075 6.8575 3.8075 27 P 0 ;1
L 6.8575 3.8575 6.8575 3.8575 27 P 0 ;1
L 6.8575 3.9075 6.8575 3.9075 27 P 0 ;1
L 6.8575 3.9575 6.8575 3.9575 27 P 0 ;1
L 6.8575 5.1575 6.8575 5.1575 27 P 0 ;1
L 6.8575 5.2075 6.8575 5.2075 27 P 0 ;1
L 6.8575 5.2575 6.8575 5.2575 27 P 0 ;1
L 6.8575 5.3075 6.8575 5.3075 27 P 0 ;1
L 6.8575 5.3575 6.8575 5.3575 27 P 0 ;1
L 6.8575 5.4075 6.8575 5.4075 27 P 0 ;1
L 6.8575 5.8575 6.8575 5.8575 27 P 0 ;1
L 6.9075 0.1575 6.9075 0.1575 27 P 0 ;1
L 6.9075 0.2075 6.9075 0.2075 27 P 0 ;1
L 6.9075 0.2575 6.9075 0.2575 27 P 0 ;1
L 6.9075 0.3075 6.9075 0.3075 27 P 0 ;1
L 6.9075 0.3575 6.9075 0.3575 27 P 0 ;1
L 6.9075 0.4075 6.9075 0.4075 27 P 0 ;1
L 6.9075 0.4575 6.9075 0.4575 27 P 0 ;1
L 6.9075 0.5075 6.9075 0.5075 27 P 0 ;1
L 6.9075 0.5575 6.9075 0.5575 27 P 0 ;1
L 6.9075 0.6075 6.9075 0.6075 27 P 0 ;1
L 6.9075 0.6575 6.9075 0.6575 27 P 0 ;1
L 6.9075 0.7075 6.9075 0.7075 27 P 0 ;1
L 6.9075 0.7575 6.9075 0.7575 27 P 0 ;1
L 6.9075 0.8075 6.9075 0.8075 27 P 0 ;1
L 6.9075 0.8575 6.9075 0.8575 27 P 0 ;1
L 6.9075 0.9075 6.9075 0.9075 27 P 0 ;1
L 6.9075 0.9575 6.9075 0.9575 27 P 0 ;1
L 6.9075 1.0075 6.9075 1.0075 27 P 0 ;1
L 6.9075 1.0575 6.9075 1.0575 27 P 0 ;1
L 6.9075 1.1075 6.9075 1.1075 27 P 0 ;1
L 6.9075 1.1575 6.9075 1.1575 27 P 0 ;1
L 6.9075 1.2075 6.9075 1.2075 27 P 0 ;1
L 6.9075 1.2575 6.9075 1.2575 27 P 0 ;1
L 6.9075 1.8075 6.9075 1.8075 27 P 0 ;1
L 6.9075 1.8575 6.9075 1.8575 27 P 0 ;1
L 6.9075 1.9075 6.9075 1.9075 27 P 0 ;1
L 6.9075 1.9575 6.9075 1.9575 27 P 0 ;1
L 6.9075 2.0075 6.9075 2.0075 27 P 0 ;1
L 6.9075 2.0575 6.9075 2.0575 27 P 0 ;1
L 6.9075 2.1075 6.9075 2.1075 27 P 0 ;1
L 6.9075 2.1575 6.9075 2.1575 27 P 0 ;1
L 6.9075 2.2075 6.9075 2.2075 27 P 0 ;1
L 6.9075 2.2575 6.9075 2.2575 27 P 0 ;1
L 6.9075 2.3075 6.9075 2.3075 27 P 0 ;1
L 6.9075 2.3575 6.9075 2.3575 27 P 0 ;1
L 6.9075 2.4075 6.9075 2.4075 27 P 0 ;1
L 6.9075 2.4575 6.9075 2.4575 27 P 0 ;1
L 6.9075 2.7075 6.9075 2.7075 27 P 0 ;1
L 6.9075 2.7575 6.9075 2.7575 27 P 0 ;1
L 6.9075 2.8075 6.9075 2.8075 27 P 0 ;1
L 6.9075 2.8575 6.9075 2.8575 27 P 0 ;1
L 6.9075 2.9075 6.9075 2.9075 27 P 0 ;1
L 6.9075 2.9575 6.9075 2.9575 27 P 0 ;1
L 6.9075 3.0075 6.9075 3.0075 27 P 0 ;1
L 6.9075 3.0575 6.9075 3.0575 27 P 0 ;1
L 6.9075 3.1075 6.9075 3.1075 27 P 0 ;1
L 6.9075 3.1575 6.9075 3.1575 27 P 0 ;1
L 6.9075 3.2075 6.9075 3.2075 27 P 0 ;1
L 6.9075 3.2575 6.9075 3.2575 27 P 0 ;1
L 6.9075 3.3075 6.9075 3.3075 27 P 0 ;1
L 6.9075 3.3575 6.9075 3.3575 27 P 0 ;1
L 6.9075 3.4075 6.9075 3.4075 27 P 0 ;1
L 6.9075 3.4575 6.9075 3.4575 27 P 0 ;1
L 6.9075 3.5075 6.9075 3.5075 27 P 0 ;1
L 6.9075 3.5575 6.9075 3.5575 27 P 0 ;1
L 6.9075 3.6075 6.9075 3.6075 27 P 0 ;1
L 6.9075 3.6575 6.9075 3.6575 27 P 0 ;1
L 6.9075 3.7075 6.9075 3.7075 27 P 0 ;1
L 6.9075 3.7575 6.9075 3.7575 27 P 0 ;1
L 6.9075 3.8075 6.9075 3.8075 27 P 0 ;1
L 6.9075 3.8575 6.9075 3.8575 27 P 0 ;1
L 6.9075 3.9075 6.9075 3.9075 27 P 0 ;1
L 6.9075 3.9575 6.9075 3.9575 27 P 0 ;1
L 6.9075 5.1075 6.9075 5.1075 27 P 0 ;1
L 6.9075 5.1575 6.9075 5.1575 27 P 0 ;1
L 6.9075 5.2075 6.9075 5.2075 27 P 0 ;1
L 6.9075 5.2575 6.9075 5.2575 27 P 0 ;1
L 6.9075 5.3075 6.9075 5.3075 27 P 0 ;1
L 6.9075 5.3575 6.9075 5.3575 27 P 0 ;1
L 6.9075 5.8075 6.9075 5.8075 27 P 0 ;1
L 6.9075 5.8575 6.9075 5.8575 27 P 0 ;1
L 6.9575 0.4075 6.9575 0.4075 27 P 0 ;1
L 6.9575 0.4575 6.9575 0.4575 27 P 0 ;1
L 6.9575 0.5075 6.9575 0.5075 27 P 0 ;1
L 6.9575 0.5575 6.9575 0.5575 27 P 0 ;1
L 6.9575 0.6075 6.9575 0.6075 27 P 0 ;1
L 6.9575 0.6575 6.9575 0.6575 27 P 0 ;1
L 6.9575 0.7075 6.9575 0.7075 27 P 0 ;1
L 6.9575 0.7575 6.9575 0.7575 27 P 0 ;1
L 6.9575 0.8075 6.9575 0.8075 27 P 0 ;1
L 6.9575 0.8575 6.9575 0.8575 27 P 0 ;1
L 6.9575 0.9075 6.9575 0.9075 27 P 0 ;1
L 6.9575 0.9575 6.9575 0.9575 27 P 0 ;1
L 6.9575 1.0075 6.9575 1.0075 27 P 0 ;1
L 6.9575 1.0575 6.9575 1.0575 27 P 0 ;1
L 6.9575 1.1075 6.9575 1.1075 27 P 0 ;1
L 6.9575 1.1575 6.9575 1.1575 27 P 0 ;1
L 6.9575 1.2075 6.9575 1.2075 27 P 0 ;1
L 6.9575 1.2575 6.9575 1.2575 27 P 0 ;1
L 6.9575 1.8075 6.9575 1.8075 27 P 0 ;1
L 6.9575 1.8575 6.9575 1.8575 27 P 0 ;1
L 6.9575 1.9075 6.9575 1.9075 27 P 0 ;1
L 6.9575 1.9575 6.9575 1.9575 27 P 0 ;1
L 6.9575 2.0075 6.9575 2.0075 27 P 0 ;1
L 6.9575 2.0575 6.9575 2.0575 27 P 0 ;1
L 6.9575 2.1075 6.9575 2.1075 27 P 0 ;1
L 6.9575 2.1575 6.9575 2.1575 27 P 0 ;1
L 6.9575 2.2075 6.9575 2.2075 27 P 0 ;1
L 6.9575 2.2575 6.9575 2.2575 27 P 0 ;1
L 6.9575 2.3075 6.9575 2.3075 27 P 0 ;1
L 6.9575 2.3575 6.9575 2.3575 27 P 0 ;1
L 6.9575 2.4075 6.9575 2.4075 27 P 0 ;1
L 6.9575 2.7575 6.9575 2.7575 27 P 0 ;1
L 6.9575 2.8075 6.9575 2.8075 27 P 0 ;1
L 6.9575 2.8575 6.9575 2.8575 27 P 0 ;1
L 6.9575 2.9075 6.9575 2.9075 27 P 0 ;1
L 6.9575 2.9575 6.9575 2.9575 27 P 0 ;1
L 6.9575 3.0075 6.9575 3.0075 27 P 0 ;1
L 6.9575 3.0575 6.9575 3.0575 27 P 0 ;1
L 6.9575 3.1075 6.9575 3.1075 27 P 0 ;1
L 6.9575 3.1575 6.9575 3.1575 27 P 0 ;1
L 6.9575 3.2075 6.9575 3.2075 27 P 0 ;1
L 6.9575 3.2575 6.9575 3.2575 27 P 0 ;1
L 6.9575 3.3075 6.9575 3.3075 27 P 0 ;1
L 6.9575 3.3575 6.9575 3.3575 27 P 0 ;1
L 6.9575 3.4075 6.9575 3.4075 27 P 0 ;1
L 6.9575 3.4575 6.9575 3.4575 27 P 0 ;1
L 6.9575 3.5075 6.9575 3.5075 27 P 0 ;1
L 6.9575 3.5575 6.9575 3.5575 27 P 0 ;1
L 6.9575 3.6075 6.9575 3.6075 27 P 0 ;1
L 6.9575 3.6575 6.9575 3.6575 27 P 0 ;1
L 6.9575 3.7075 6.9575 3.7075 27 P 0 ;1
L 6.9575 3.7575 6.9575 3.7575 27 P 0 ;1
L 6.9575 3.8075 6.9575 3.8075 27 P 0 ;1
L 6.9575 3.8575 6.9575 3.8575 27 P 0 ;1
L 6.9575 3.9075 6.9575 3.9075 27 P 0 ;1
L 6.9575 3.9575 6.9575 3.9575 27 P 0 ;1
L 6.9575 5.0575 6.9575 5.0575 27 P 0 ;1
L 6.9575 5.1075 6.9575 5.1075 27 P 0 ;1
L 6.9575 5.1575 6.9575 5.1575 27 P 0 ;1
L 6.9575 5.2075 6.9575 5.2075 27 P 0 ;1
L 6.9575 5.2575 6.9575 5.2575 27 P 0 ;1
L 6.9575 5.3075 6.9575 5.3075 27 P 0 ;1
L 6.9575 5.3575 6.9575 5.3575 27 P 0 ;1
L 7.0075 0.4575 7.0075 0.4575 27 P 0 ;1
L 7.0075 0.5075 7.0075 0.5075 27 P 0 ;1
L 7.0075 0.5575 7.0075 0.5575 27 P 0 ;1
L 7.0075 0.6075 7.0075 0.6075 27 P 0 ;1
L 7.0075 0.6575 7.0075 0.6575 27 P 0 ;1
L 7.0075 0.7075 7.0075 0.7075 27 P 0 ;1
L 7.0075 0.7575 7.0075 0.7575 27 P 0 ;1
L 7.0075 0.8075 7.0075 0.8075 27 P 0 ;1
L 7.0075 0.8575 7.0075 0.8575 27 P 0 ;1
L 7.0075 0.9075 7.0075 0.9075 27 P 0 ;1
L 7.0075 0.9575 7.0075 0.9575 27 P 0 ;1
L 7.0075 1.0075 7.0075 1.0075 27 P 0 ;1
L 7.0075 1.0575 7.0075 1.0575 27 P 0 ;1
L 7.0075 1.1075 7.0075 1.1075 27 P 0 ;1
L 7.0075 1.1575 7.0075 1.1575 27 P 0 ;1
L 7.0075 1.2075 7.0075 1.2075 27 P 0 ;1
L 7.0075 1.2575 7.0075 1.2575 27 P 0 ;1
L 7.0075 1.8075 7.0075 1.8075 27 P 0 ;1
L 7.0075 1.8575 7.0075 1.8575 27 P 0 ;1
L 7.0075 1.9075 7.0075 1.9075 27 P 0 ;1
L 7.0075 1.9575 7.0075 1.9575 27 P 0 ;1
L 7.0075 2.0075 7.0075 2.0075 27 P 0 ;1
L 7.0075 2.0575 7.0075 2.0575 27 P 0 ;1
L 7.0075 2.1075 7.0075 2.1075 27 P 0 ;1
L 7.0075 2.1575 7.0075 2.1575 27 P 0 ;1
L 7.0075 2.2075 7.0075 2.2075 27 P 0 ;1
L 7.0075 2.2575 7.0075 2.2575 27 P 0 ;1
L 7.0075 2.3075 7.0075 2.3075 27 P 0 ;1
L 7.0075 2.3575 7.0075 2.3575 27 P 0 ;1
L 7.0075 2.4075 7.0075 2.4075 27 P 0 ;1
L 7.0075 2.7575 7.0075 2.7575 27 P 0 ;1
L 7.0075 2.8075 7.0075 2.8075 27 P 0 ;1
L 7.0075 2.8575 7.0075 2.8575 27 P 0 ;1
L 7.0075 2.9075 7.0075 2.9075 27 P 0 ;1
L 7.0075 2.9575 7.0075 2.9575 27 P 0 ;1
L 7.0075 3.0075 7.0075 3.0075 27 P 0 ;1
L 7.0075 3.0575 7.0075 3.0575 27 P 0 ;1
L 7.0075 3.1075 7.0075 3.1075 27 P 0 ;1
L 7.0075 3.1575 7.0075 3.1575 27 P 0 ;1
L 7.0075 3.2075 7.0075 3.2075 27 P 0 ;1
L 7.0075 3.2575 7.0075 3.2575 27 P 0 ;1
L 7.0075 3.3075 7.0075 3.3075 27 P 0 ;1
L 7.0075 3.3575 7.0075 3.3575 27 P 0 ;1
L 7.0075 3.4075 7.0075 3.4075 27 P 0 ;1
L 7.0075 3.4575 7.0075 3.4575 27 P 0 ;1
L 7.0075 3.5075 7.0075 3.5075 27 P 0 ;1
L 7.0075 3.5575 7.0075 3.5575 27 P 0 ;1
L 7.0075 3.6075 7.0075 3.6075 27 P 0 ;1
L 7.0075 3.6575 7.0075 3.6575 27 P 0 ;1
L 7.0075 3.7075 7.0075 3.7075 27 P 0 ;1
L 7.0075 3.7575 7.0075 3.7575 27 P 0 ;1
L 7.0075 3.8075 7.0075 3.8075 27 P 0 ;1
L 7.0075 3.8575 7.0075 3.8575 27 P 0 ;1
L 7.0075 3.9075 7.0075 3.9075 27 P 0 ;1
L 7.0075 3.9575 7.0075 3.9575 27 P 0 ;1
L 7.0075 4.4575 7.0075 4.4575 27 P 0 ;1
L 7.0075 4.5075 7.0075 4.5075 27 P 0 ;1
L 7.0075 4.5575 7.0075 4.5575 27 P 0 ;1
L 7.0075 4.6075 7.0075 4.6075 27 P 0 ;1
L 7.0075 4.9575 7.0075 4.9575 27 P 0 ;1
L 7.0075 5.0075 7.0075 5.0075 27 P 0 ;1
L 7.0075 5.0575 7.0075 5.0575 27 P 0 ;1
L 7.0075 5.1075 7.0075 5.1075 27 P 0 ;1
L 7.0075 5.1575 7.0075 5.1575 27 P 0 ;1
L 7.0075 5.2075 7.0075 5.2075 27 P 0 ;1
L 7.0075 5.2575 7.0075 5.2575 27 P 0 ;1
L 7.0075 5.3075 7.0075 5.3075 27 P 0 ;1
L 7.0075 5.3575 7.0075 5.3575 27 P 0 ;1
L 7.0575 0.5075 7.0575 0.5075 27 P 0 ;1
L 7.0575 0.5575 7.0575 0.5575 27 P 0 ;1
L 7.0575 0.6075 7.0575 0.6075 27 P 0 ;1
L 7.0575 0.6575 7.0575 0.6575 27 P 0 ;1
L 7.0575 0.7075 7.0575 0.7075 27 P 0 ;1
L 7.0575 0.7575 7.0575 0.7575 27 P 0 ;1
L 7.0575 0.8075 7.0575 0.8075 27 P 0 ;1
L 7.0575 0.8575 7.0575 0.8575 27 P 0 ;1
L 7.0575 0.9075 7.0575 0.9075 27 P 0 ;1
L 7.0575 0.9575 7.0575 0.9575 27 P 0 ;1
L 7.0575 1.0075 7.0575 1.0075 27 P 0 ;1
L 7.0575 1.0575 7.0575 1.0575 27 P 0 ;1
L 7.0575 1.1075 7.0575 1.1075 27 P 0 ;1
L 7.0575 1.1575 7.0575 1.1575 27 P 0 ;1
L 7.0575 1.2075 7.0575 1.2075 27 P 0 ;1
L 7.0575 1.2575 7.0575 1.2575 27 P 0 ;1
L 7.0575 1.7575 7.0575 1.7575 27 P 0 ;1
L 7.0575 1.8075 7.0575 1.8075 27 P 0 ;1
L 7.0575 1.8575 7.0575 1.8575 27 P 0 ;1
L 7.0575 1.9075 7.0575 1.9075 27 P 0 ;1
L 7.0575 1.9575 7.0575 1.9575 27 P 0 ;1
L 7.0575 2.0075 7.0575 2.0075 27 P 0 ;1
L 7.0575 2.0575 7.0575 2.0575 27 P 0 ;1
L 7.0575 2.1075 7.0575 2.1075 27 P 0 ;1
L 7.0575 2.1575 7.0575 2.1575 27 P 0 ;1
L 7.0575 2.2075 7.0575 2.2075 27 P 0 ;1
L 7.0575 2.2575 7.0575 2.2575 27 P 0 ;1
L 7.0575 2.3075 7.0575 2.3075 27 P 0 ;1
L 7.0575 2.3575 7.0575 2.3575 27 P 0 ;1
L 7.0575 2.4075 7.0575 2.4075 27 P 0 ;1
L 7.0575 2.7575 7.0575 2.7575 27 P 0 ;1
L 7.0575 2.8075 7.0575 2.8075 27 P 0 ;1
L 7.0575 2.8575 7.0575 2.8575 27 P 0 ;1
L 7.0575 2.9075 7.0575 2.9075 27 P 0 ;1
L 7.0575 2.9575 7.0575 2.9575 27 P 0 ;1
L 7.0575 3.0075 7.0575 3.0075 27 P 0 ;1
L 7.0575 3.0575 7.0575 3.0575 27 P 0 ;1
L 7.0575 3.1075 7.0575 3.1075 27 P 0 ;1
L 7.0575 3.1575 7.0575 3.1575 27 P 0 ;1
L 7.0575 3.2075 7.0575 3.2075 27 P 0 ;1
L 7.0575 3.2575 7.0575 3.2575 27 P 0 ;1
L 7.0575 3.3075 7.0575 3.3075 27 P 0 ;1
L 7.0575 3.3575 7.0575 3.3575 27 P 0 ;1
L 7.0575 3.4075 7.0575 3.4075 27 P 0 ;1
L 7.0575 3.4575 7.0575 3.4575 27 P 0 ;1
L 7.0575 3.5075 7.0575 3.5075 27 P 0 ;1
L 7.0575 3.5575 7.0575 3.5575 27 P 0 ;1
L 7.0575 3.6075 7.0575 3.6075 27 P 0 ;1
L 7.0575 3.6575 7.0575 3.6575 27 P 0 ;1
L 7.0575 3.7075 7.0575 3.7075 27 P 0 ;1
L 7.0575 3.7575 7.0575 3.7575 27 P 0 ;1
L 7.0575 3.8075 7.0575 3.8075 27 P 0 ;1
L 7.0575 3.8575 7.0575 3.8575 27 P 0 ;1
L 7.0575 3.9075 7.0575 3.9075 27 P 0 ;1
L 7.0575 3.9575 7.0575 3.9575 27 P 0 ;1
L 7.0575 4.4575 7.0575 4.4575 27 P 0 ;1
L 7.0575 4.5075 7.0575 4.5075 27 P 0 ;1
L 7.0575 4.5575 7.0575 4.5575 27 P 0 ;1
L 7.0575 4.6075 7.0575 4.6075 27 P 0 ;1
L 7.0575 4.6575 7.0575 4.6575 27 P 0 ;1
L 7.0575 4.7075 7.0575 4.7075 27 P 0 ;1
L 7.0575 4.7575 7.0575 4.7575 27 P 0 ;1
L 7.0575 4.8075 7.0575 4.8075 27 P 0 ;1
L 7.0575 4.8575 7.0575 4.8575 27 P 0 ;1
L 7.0575 4.9075 7.0575 4.9075 27 P 0 ;1
L 7.0575 4.9575 7.0575 4.9575 27 P 0 ;1
L 7.0575 5.0075 7.0575 5.0075 27 P 0 ;1
L 7.0575 5.0575 7.0575 5.0575 27 P 0 ;1
L 7.0575 5.1075 7.0575 5.1075 27 P 0 ;1
L 7.0575 5.1575 7.0575 5.1575 27 P 0 ;1
L 7.0575 5.2075 7.0575 5.2075 27 P 0 ;1
L 7.0575 5.2575 7.0575 5.2575 27 P 0 ;1
L 7.0575 5.3075 7.0575 5.3075 27 P 0 ;1
L 7.0575 5.3575 7.0575 5.3575 27 P 0 ;1
L 7.1075 0.5075 7.1075 0.5075 27 P 0 ;1
L 7.1075 0.5575 7.1075 0.5575 27 P 0 ;1
L 7.1075 0.6075 7.1075 0.6075 27 P 0 ;1
L 7.1075 0.6575 7.1075 0.6575 27 P 0 ;1
L 7.1075 0.7075 7.1075 0.7075 27 P 0 ;1
L 7.1075 0.7575 7.1075 0.7575 27 P 0 ;1
L 7.1075 0.8075 7.1075 0.8075 27 P 0 ;1
L 7.1075 0.8575 7.1075 0.8575 27 P 0 ;1
L 7.1075 0.9075 7.1075 0.9075 27 P 0 ;1
L 7.1075 0.9575 7.1075 0.9575 27 P 0 ;1
L 7.1075 1.0075 7.1075 1.0075 27 P 0 ;1
L 7.1075 1.0575 7.1075 1.0575 27 P 0 ;1
L 7.1075 1.1075 7.1075 1.1075 27 P 0 ;1
L 7.1075 1.1575 7.1075 1.1575 27 P 0 ;1
L 7.1075 1.2075 7.1075 1.2075 27 P 0 ;1
L 7.1075 1.2575 7.1075 1.2575 27 P 0 ;1
L 7.1075 1.3075 7.1075 1.3075 27 P 0 ;1
L 7.1075 1.7575 7.1075 1.7575 27 P 0 ;1
L 7.1075 1.8075 7.1075 1.8075 27 P 0 ;1
L 7.1075 1.8575 7.1075 1.8575 27 P 0 ;1
L 7.1075 1.9075 7.1075 1.9075 27 P 0 ;1
L 7.1075 1.9575 7.1075 1.9575 27 P 0 ;1
L 7.1075 2.0075 7.1075 2.0075 27 P 0 ;1
L 7.1075 2.0575 7.1075 2.0575 27 P 0 ;1
L 7.1075 2.1075 7.1075 2.1075 27 P 0 ;1
L 7.1075 2.1575 7.1075 2.1575 27 P 0 ;1
L 7.1075 2.2075 7.1075 2.2075 27 P 0 ;1
L 7.1075 2.2575 7.1075 2.2575 27 P 0 ;1
L 7.1075 2.3075 7.1075 2.3075 27 P 0 ;1
L 7.1075 2.3575 7.1075 2.3575 27 P 0 ;1
L 7.1075 2.4075 7.1075 2.4075 27 P 0 ;1
L 7.1075 2.7575 7.1075 2.7575 27 P 0 ;1
L 7.1075 2.8075 7.1075 2.8075 27 P 0 ;1
L 7.1075 2.8575 7.1075 2.8575 27 P 0 ;1
L 7.1075 2.9075 7.1075 2.9075 27 P 0 ;1
L 7.1075 2.9575 7.1075 2.9575 27 P 0 ;1
L 7.1075 3.0075 7.1075 3.0075 27 P 0 ;1
L 7.1075 3.0575 7.1075 3.0575 27 P 0 ;1
L 7.1075 3.1075 7.1075 3.1075 27 P 0 ;1
L 7.1075 3.1575 7.1075 3.1575 27 P 0 ;1
L 7.1075 3.2075 7.1075 3.2075 27 P 0 ;1
L 7.1075 3.2575 7.1075 3.2575 27 P 0 ;1
L 7.1075 3.3075 7.1075 3.3075 27 P 0 ;1
L 7.1075 3.3575 7.1075 3.3575 27 P 0 ;1
L 7.1075 3.4075 7.1075 3.4075 27 P 0 ;1
L 7.1075 3.4575 7.1075 3.4575 27 P 0 ;1
L 7.1075 3.5075 7.1075 3.5075 27 P 0 ;1
L 7.1075 3.5575 7.1075 3.5575 27 P 0 ;1
L 7.1075 3.6075 7.1075 3.6075 27 P 0 ;1
L 7.1075 3.6575 7.1075 3.6575 27 P 0 ;1
L 7.1075 3.7075 7.1075 3.7075 27 P 0 ;1
L 7.1075 3.7575 7.1075 3.7575 27 P 0 ;1
L 7.1075 3.8075 7.1075 3.8075 27 P 0 ;1
L 7.1075 3.8575 7.1075 3.8575 27 P 0 ;1
L 7.1075 3.9075 7.1075 3.9075 27 P 0 ;1
L 7.1075 3.9575 7.1075 3.9575 27 P 0 ;1
L 7.1075 4.0075 7.1075 4.0075 27 P 0 ;1
L 7.1075 4.4075 7.1075 4.4075 27 P 0 ;1
L 7.1075 4.4575 7.1075 4.4575 27 P 0 ;1
L 7.1075 4.5075 7.1075 4.5075 27 P 0 ;1
L 7.1075 4.5575 7.1075 4.5575 27 P 0 ;1
L 7.1075 4.6075 7.1075 4.6075 27 P 0 ;1
L 7.1075 4.6575 7.1075 4.6575 27 P 0 ;1
L 7.1075 4.7075 7.1075 4.7075 27 P 0 ;1
L 7.1075 4.7575 7.1075 4.7575 27 P 0 ;1
L 7.1075 4.8075 7.1075 4.8075 27 P 0 ;1
L 7.1075 4.8575 7.1075 4.8575 27 P 0 ;1
L 7.1075 4.9075 7.1075 4.9075 27 P 0 ;1
L 7.1075 5.2075 7.1075 5.2075 27 P 0 ;1
L 7.1075 5.2575 7.1075 5.2575 27 P 0 ;1
L 7.1075 5.3075 7.1075 5.3075 27 P 0 ;1
L 7.1075 5.3575 7.1075 5.3575 27 P 0 ;1
L 7.1575 0.5075 7.1575 0.5075 27 P 0 ;1
L 7.1575 0.5575 7.1575 0.5575 27 P 0 ;1
L 7.1575 0.6075 7.1575 0.6075 27 P 0 ;1
L 7.1575 0.6575 7.1575 0.6575 27 P 0 ;1
L 7.1575 0.7075 7.1575 0.7075 27 P 0 ;1
L 7.1575 0.7575 7.1575 0.7575 27 P 0 ;1
L 7.1575 0.8075 7.1575 0.8075 27 P 0 ;1
L 7.1575 0.8575 7.1575 0.8575 27 P 0 ;1
L 7.1575 0.9075 7.1575 0.9075 27 P 0 ;1
L 7.1575 0.9575 7.1575 0.9575 27 P 0 ;1
L 7.1575 1.0075 7.1575 1.0075 27 P 0 ;1
L 7.1575 1.0575 7.1575 1.0575 27 P 0 ;1
L 7.1575 1.1075 7.1575 1.1075 27 P 0 ;1
L 7.1575 1.1575 7.1575 1.1575 27 P 0 ;1
L 7.1575 1.2075 7.1575 1.2075 27 P 0 ;1
L 7.1575 1.2575 7.1575 1.2575 27 P 0 ;1
L 7.1575 1.3075 7.1575 1.3075 27 P 0 ;1
L 7.1575 1.3575 7.1575 1.3575 27 P 0 ;1
L 7.1575 1.7075 7.1575 1.7075 27 P 0 ;1
L 7.1575 1.7575 7.1575 1.7575 27 P 0 ;1
L 7.1575 1.8075 7.1575 1.8075 27 P 0 ;1
L 7.1575 1.8575 7.1575 1.8575 27 P 0 ;1
L 7.1575 1.9075 7.1575 1.9075 27 P 0 ;1
L 7.1575 1.9575 7.1575 1.9575 27 P 0 ;1
L 7.1575 2.0075 7.1575 2.0075 27 P 0 ;1
L 7.1575 2.0575 7.1575 2.0575 27 P 0 ;1
L 7.1575 2.1075 7.1575 2.1075 27 P 0 ;1
L 7.1575 2.1575 7.1575 2.1575 27 P 0 ;1
L 7.1575 2.2075 7.1575 2.2075 27 P 0 ;1
L 7.1575 2.2575 7.1575 2.2575 27 P 0 ;1
L 7.1575 2.3075 7.1575 2.3075 27 P 0 ;1
L 7.1575 2.3575 7.1575 2.3575 27 P 0 ;1
L 7.1575 2.4075 7.1575 2.4075 27 P 0 ;1
L 7.1575 2.7575 7.1575 2.7575 27 P 0 ;1
L 7.1575 2.8075 7.1575 2.8075 27 P 0 ;1
L 7.1575 2.8575 7.1575 2.8575 27 P 0 ;1
L 7.1575 2.9075 7.1575 2.9075 27 P 0 ;1
L 7.1575 2.9575 7.1575 2.9575 27 P 0 ;1
L 7.1575 3.0075 7.1575 3.0075 27 P 0 ;1
L 7.1575 3.0575 7.1575 3.0575 27 P 0 ;1
L 7.1575 3.1075 7.1575 3.1075 27 P 0 ;1
L 7.1575 3.1575 7.1575 3.1575 27 P 0 ;1
L 7.1575 3.2075 7.1575 3.2075 27 P 0 ;1
L 7.1575 3.2575 7.1575 3.2575 27 P 0 ;1
L 7.1575 3.3075 7.1575 3.3075 27 P 0 ;1
L 7.1575 3.3575 7.1575 3.3575 27 P 0 ;1
L 7.1575 3.4075 7.1575 3.4075 27 P 0 ;1
L 7.1575 3.4575 7.1575 3.4575 27 P 0 ;1
L 7.1575 3.5075 7.1575 3.5075 27 P 0 ;1
L 7.1575 3.5575 7.1575 3.5575 27 P 0 ;1
L 7.1575 3.6075 7.1575 3.6075 27 P 0 ;1
L 7.1575 3.6575 7.1575 3.6575 27 P 0 ;1
L 7.1575 3.7075 7.1575 3.7075 27 P 0 ;1
L 7.1575 3.7575 7.1575 3.7575 27 P 0 ;1
L 7.1575 3.8075 7.1575 3.8075 27 P 0 ;1
L 7.1575 3.8575 7.1575 3.8575 27 P 0 ;1
L 7.1575 3.9075 7.1575 3.9075 27 P 0 ;1
L 7.1575 3.9575 7.1575 3.9575 27 P 0 ;1
L 7.1575 4.0075 7.1575 4.0075 27 P 0 ;1
L 7.1575 4.3575 7.1575 4.3575 27 P 0 ;1
L 7.1575 4.4075 7.1575 4.4075 27 P 0 ;1
L 7.1575 4.4575 7.1575 4.4575 27 P 0 ;1
L 7.1575 4.5075 7.1575 4.5075 27 P 0 ;1
L 7.1575 4.5575 7.1575 4.5575 27 P 0 ;1
L 7.1575 4.8075 7.1575 4.8075 27 P 0 ;1
L 7.1575 4.8575 7.1575 4.8575 27 P 0 ;1
L 7.1575 5.2575 7.1575 5.2575 27 P 0 ;1
L 7.1575 5.3075 7.1575 5.3075 27 P 0 ;1
L 7.1575 5.3575 7.1575 5.3575 27 P 0 ;1
L 7.2075 0.5075 7.2075 0.5075 27 P 0 ;1
L 7.2075 0.5575 7.2075 0.5575 27 P 0 ;1
L 7.2075 0.6075 7.2075 0.6075 27 P 0 ;1
L 7.2075 0.6575 7.2075 0.6575 27 P 0 ;1
L 7.2075 0.7075 7.2075 0.7075 27 P 0 ;1
L 7.2075 0.7575 7.2075 0.7575 27 P 0 ;1
L 7.2075 0.8075 7.2075 0.8075 27 P 0 ;1
L 7.2075 0.8575 7.2075 0.8575 27 P 0 ;1
L 7.2075 0.9075 7.2075 0.9075 27 P 0 ;1
L 7.2075 0.9575 7.2075 0.9575 27 P 0 ;1
L 7.2075 1.0075 7.2075 1.0075 27 P 0 ;1
L 7.2075 1.0575 7.2075 1.0575 27 P 0 ;1
L 7.2075 1.1075 7.2075 1.1075 27 P 0 ;1
L 7.2075 1.1575 7.2075 1.1575 27 P 0 ;1
L 7.2075 1.2075 7.2075 1.2075 27 P 0 ;1
L 7.2075 1.2575 7.2075 1.2575 27 P 0 ;1
L 7.2075 1.3075 7.2075 1.3075 27 P 0 ;1
L 7.2075 1.3575 7.2075 1.3575 27 P 0 ;1
L 7.2075 1.4075 7.2075 1.4075 27 P 0 ;1
L 7.2075 1.4575 7.2075 1.4575 27 P 0 ;1
L 7.2075 1.5075 7.2075 1.5075 27 P 0 ;1
L 7.2075 1.5575 7.2075 1.5575 27 P 0 ;1
L 7.2075 1.6075 7.2075 1.6075 27 P 0 ;1
L 7.2075 1.6575 7.2075 1.6575 27 P 0 ;1
L 7.2075 1.7075 7.2075 1.7075 27 P 0 ;1
L 7.2075 1.7575 7.2075 1.7575 27 P 0 ;1
L 7.2075 1.8075 7.2075 1.8075 27 P 0 ;1
L 7.2075 1.8575 7.2075 1.8575 27 P 0 ;1
L 7.2075 1.9075 7.2075 1.9075 27 P 0 ;1
L 7.2075 1.9575 7.2075 1.9575 27 P 0 ;1
L 7.2075 2.0075 7.2075 2.0075 27 P 0 ;1
L 7.2075 2.0575 7.2075 2.0575 27 P 0 ;1
L 7.2075 2.1075 7.2075 2.1075 27 P 0 ;1
L 7.2075 2.1575 7.2075 2.1575 27 P 0 ;1
L 7.2075 2.2075 7.2075 2.2075 27 P 0 ;1
L 7.2075 2.2575 7.2075 2.2575 27 P 0 ;1
L 7.2075 2.3075 7.2075 2.3075 27 P 0 ;1
L 7.2075 2.3575 7.2075 2.3575 27 P 0 ;1
L 7.2075 2.4075 7.2075 2.4075 27 P 0 ;1
L 7.2075 2.4575 7.2075 2.4575 27 P 0 ;1
L 7.2075 2.7075 7.2075 2.7075 27 P 0 ;1
L 7.2075 2.7575 7.2075 2.7575 27 P 0 ;1
L 7.2075 2.8075 7.2075 2.8075 27 P 0 ;1
L 7.2075 2.8575 7.2075 2.8575 27 P 0 ;1
L 7.2075 2.9075 7.2075 2.9075 27 P 0 ;1
L 7.2075 2.9575 7.2075 2.9575 27 P 0 ;1
L 7.2075 3.0075 7.2075 3.0075 27 P 0 ;1
L 7.2075 3.0575 7.2075 3.0575 27 P 0 ;1
L 7.2075 3.1075 7.2075 3.1075 27 P 0 ;1
L 7.2075 3.1575 7.2075 3.1575 27 P 0 ;1
L 7.2075 3.2075 7.2075 3.2075 27 P 0 ;1
L 7.2075 3.2575 7.2075 3.2575 27 P 0 ;1
L 7.2075 3.3075 7.2075 3.3075 27 P 0 ;1
L 7.2075 3.3575 7.2075 3.3575 27 P 0 ;1
L 7.2075 3.4075 7.2075 3.4075 27 P 0 ;1
L 7.2075 3.4575 7.2075 3.4575 27 P 0 ;1
L 7.2075 3.5075 7.2075 3.5075 27 P 0 ;1
L 7.2075 3.5575 7.2075 3.5575 27 P 0 ;1
L 7.2075 3.6075 7.2075 3.6075 27 P 0 ;1
L 7.2075 3.6575 7.2075 3.6575 27 P 0 ;1
L 7.2075 3.7075 7.2075 3.7075 27 P 0 ;1
L 7.2075 3.7575 7.2075 3.7575 27 P 0 ;1
L 7.2075 3.8075 7.2075 3.8075 27 P 0 ;1
L 7.2075 3.8575 7.2075 3.8575 27 P 0 ;1
L 7.2075 3.9075 7.2075 3.9075 27 P 0 ;1
L 7.2075 3.9575 7.2075 3.9575 27 P 0 ;1
L 7.2075 4.0075 7.2075 4.0075 27 P 0 ;1
L 7.2075 4.0575 7.2075 4.0575 27 P 0 ;1
L 7.2075 4.1075 7.2075 4.1075 27 P 0 ;1
L 7.2075 4.1575 7.2075 4.1575 27 P 0 ;1
L 7.2075 4.2075 7.2075 4.2075 27 P 0 ;1
L 7.2075 4.2575 7.2075 4.2575 27 P 0 ;1
L 7.2075 4.3075 7.2075 4.3075 27 P 0 ;1
L 7.2075 4.3575 7.2075 4.3575 27 P 0 ;1
L 7.2075 4.4075 7.2075 4.4075 27 P 0 ;1
L 7.2075 4.4575 7.2075 4.4575 27 P 0 ;1
L 7.2075 4.5075 7.2075 4.5075 27 P 0 ;1
L 7.2075 5.2575 7.2075 5.2575 27 P 0 ;1
L 7.2075 5.3075 7.2075 5.3075 27 P 0 ;1
L 7.2075 5.3575 7.2075 5.3575 27 P 0 ;1
L 7.2575 0.5075 7.2575 0.5075 27 P 0 ;1
L 7.2575 0.5575 7.2575 0.5575 27 P 0 ;1
L 7.2575 0.6075 7.2575 0.6075 27 P 0 ;1
L 7.2575 0.6575 7.2575 0.6575 27 P 0 ;1
L 7.2575 0.7075 7.2575 0.7075 27 P 0 ;1
L 7.2575 0.7575 7.2575 0.7575 27 P 0 ;1
L 7.2575 0.8075 7.2575 0.8075 27 P 0 ;1
L 7.2575 0.8575 7.2575 0.8575 27 P 0 ;1
L 7.2575 0.9075 7.2575 0.9075 27 P 0 ;1
L 7.2575 0.9575 7.2575 0.9575 27 P 0 ;1
L 7.2575 1.0075 7.2575 1.0075 27 P 0 ;1
L 7.2575 1.0575 7.2575 1.0575 27 P 0 ;1
L 7.2575 1.1075 7.2575 1.1075 27 P 0 ;1
L 7.2575 1.1575 7.2575 1.1575 27 P 0 ;1
L 7.2575 1.2075 7.2575 1.2075 27 P 0 ;1
L 7.2575 1.2575 7.2575 1.2575 27 P 0 ;1
L 7.2575 1.3075 7.2575 1.3075 27 P 0 ;1
L 7.2575 1.3575 7.2575 1.3575 27 P 0 ;1
L 7.2575 1.4075 7.2575 1.4075 27 P 0 ;1
L 7.2575 1.4575 7.2575 1.4575 27 P 0 ;1
L 7.2575 1.5075 7.2575 1.5075 27 P 0 ;1
L 7.2575 1.5575 7.2575 1.5575 27 P 0 ;1
L 7.2575 1.6075 7.2575 1.6075 27 P 0 ;1
L 7.2575 1.6575 7.2575 1.6575 27 P 0 ;1
L 7.2575 1.7075 7.2575 1.7075 27 P 0 ;1
L 7.2575 1.7575 7.2575 1.7575 27 P 0 ;1
L 7.2575 1.8075 7.2575 1.8075 27 P 0 ;1
L 7.2575 1.8575 7.2575 1.8575 27 P 0 ;1
L 7.2575 1.9075 7.2575 1.9075 27 P 0 ;1
L 7.2575 1.9575 7.2575 1.9575 27 P 0 ;1
L 7.2575 2.0075 7.2575 2.0075 27 P 0 ;1
L 7.2575 2.0575 7.2575 2.0575 27 P 0 ;1
L 7.2575 2.1075 7.2575 2.1075 27 P 0 ;1
L 7.2575 2.1575 7.2575 2.1575 27 P 0 ;1
L 7.2575 2.2075 7.2575 2.2075 27 P 0 ;1
L 7.2575 2.2575 7.2575 2.2575 27 P 0 ;1
L 7.2575 2.3075 7.2575 2.3075 27 P 0 ;1
L 7.2575 2.3575 7.2575 2.3575 27 P 0 ;1
L 7.2575 2.4075 7.2575 2.4075 27 P 0 ;1
L 7.2575 2.4575 7.2575 2.4575 27 P 0 ;1
L 7.2575 2.5075 7.2575 2.5075 27 P 0 ;1
L 7.2575 2.5575 7.2575 2.5575 27 P 0 ;1
L 7.2575 2.6075 7.2575 2.6075 27 P 0 ;1
L 7.2575 2.6575 7.2575 2.6575 27 P 0 ;1
L 7.2575 2.7075 7.2575 2.7075 27 P 0 ;1
L 7.2575 2.7575 7.2575 2.7575 27 P 0 ;1
L 7.2575 2.8075 7.2575 2.8075 27 P 0 ;1
L 7.2575 2.8575 7.2575 2.8575 27 P 0 ;1
L 7.2575 2.9075 7.2575 2.9075 27 P 0 ;1
L 7.2575 2.9575 7.2575 2.9575 27 P 0 ;1
L 7.2575 3.0075 7.2575 3.0075 27 P 0 ;1
L 7.2575 3.0575 7.2575 3.0575 27 P 0 ;1
L 7.2575 3.1075 7.2575 3.1075 27 P 0 ;1
L 7.2575 3.1575 7.2575 3.1575 27 P 0 ;1
L 7.2575 3.2075 7.2575 3.2075 27 P 0 ;1
L 7.2575 3.2575 7.2575 3.2575 27 P 0 ;1
L 7.2575 3.3075 7.2575 3.3075 27 P 0 ;1
L 7.2575 3.3575 7.2575 3.3575 27 P 0 ;1
L 7.2575 3.4075 7.2575 3.4075 27 P 0 ;1
L 7.2575 3.4575 7.2575 3.4575 27 P 0 ;1
L 7.2575 3.5075 7.2575 3.5075 27 P 0 ;1
L 7.2575 3.5575 7.2575 3.5575 27 P 0 ;1
L 7.2575 3.6075 7.2575 3.6075 27 P 0 ;1
L 7.2575 3.6575 7.2575 3.6575 27 P 0 ;1
L 7.2575 3.7075 7.2575 3.7075 27 P 0 ;1
L 7.2575 3.7575 7.2575 3.7575 27 P 0 ;1
L 7.2575 3.8075 7.2575 3.8075 27 P 0 ;1
L 7.2575 3.8575 7.2575 3.8575 27 P 0 ;1
L 7.2575 3.9075 7.2575 3.9075 27 P 0 ;1
L 7.2575 3.9575 7.2575 3.9575 27 P 0 ;1
L 7.2575 4.0075 7.2575 4.0075 27 P 0 ;1
L 7.2575 4.0575 7.2575 4.0575 27 P 0 ;1
L 7.2575 4.1075 7.2575 4.1075 27 P 0 ;1
L 7.2575 4.1575 7.2575 4.1575 27 P 0 ;1
L 7.2575 4.2075 7.2575 4.2075 27 P 0 ;1
L 7.2575 4.2575 7.2575 4.2575 27 P 0 ;1
L 7.2575 4.3075 7.2575 4.3075 27 P 0 ;1
L 7.2575 4.3575 7.2575 4.3575 27 P 0 ;1
L 7.2575 4.4075 7.2575 4.4075 27 P 0 ;1
L 7.2575 4.4575 7.2575 4.4575 27 P 0 ;1
L 7.2575 4.5075 7.2575 4.5075 27 P 0 ;1
L 7.2575 5.2575 7.2575 5.2575 27 P 0 ;1
L 7.2575 5.3075 7.2575 5.3075 27 P 0 ;1
L 7.2575 5.3575 7.2575 5.3575 27 P 0 ;1
L 7.3075 0.5075 7.3075 0.5075 27 P 0 ;1
L 7.3075 0.5575 7.3075 0.5575 27 P 0 ;1
L 7.3075 0.6075 7.3075 0.6075 27 P 0 ;1
L 7.3075 0.6575 7.3075 0.6575 27 P 0 ;1
L 7.3075 0.7075 7.3075 0.7075 27 P 0 ;1
L 7.3075 0.7575 7.3075 0.7575 27 P 0 ;1
L 7.3075 0.8075 7.3075 0.8075 27 P 0 ;1
L 7.3075 0.8575 7.3075 0.8575 27 P 0 ;1
L 7.3075 0.9075 7.3075 0.9075 27 P 0 ;1
L 7.3075 0.9575 7.3075 0.9575 27 P 0 ;1
L 7.3075 1.0075 7.3075 1.0075 27 P 0 ;1
L 7.3075 1.0575 7.3075 1.0575 27 P 0 ;1
L 7.3075 1.1075 7.3075 1.1075 27 P 0 ;1
L 7.3075 1.1575 7.3075 1.1575 27 P 0 ;1
L 7.3075 1.2075 7.3075 1.2075 27 P 0 ;1
L 7.3075 1.2575 7.3075 1.2575 27 P 0 ;1
L 7.3075 1.3075 7.3075 1.3075 27 P 0 ;1
L 7.3075 1.3575 7.3075 1.3575 27 P 0 ;1
L 7.3075 1.4075 7.3075 1.4075 27 P 0 ;1
L 7.3075 1.4575 7.3075 1.4575 27 P 0 ;1
L 7.3075 1.5075 7.3075 1.5075 27 P 0 ;1
L 7.3075 1.5575 7.3075 1.5575 27 P 0 ;1
L 7.3075 1.6075 7.3075 1.6075 27 P 0 ;1
L 7.3075 1.6575 7.3075 1.6575 27 P 0 ;1
L 7.3075 1.7075 7.3075 1.7075 27 P 0 ;1
L 7.3075 1.7575 7.3075 1.7575 27 P 0 ;1
L 7.3075 1.8075 7.3075 1.8075 27 P 0 ;1
L 7.3075 1.8575 7.3075 1.8575 27 P 0 ;1
L 7.3075 1.9075 7.3075 1.9075 27 P 0 ;1
L 7.3075 1.9575 7.3075 1.9575 27 P 0 ;1
L 7.3075 2.0075 7.3075 2.0075 27 P 0 ;1
L 7.3075 2.0575 7.3075 2.0575 27 P 0 ;1
L 7.3075 2.1075 7.3075 2.1075 27 P 0 ;1
L 7.3075 2.1575 7.3075 2.1575 27 P 0 ;1
L 7.3075 2.2075 7.3075 2.2075 27 P 0 ;1
L 7.3075 2.2575 7.3075 2.2575 27 P 0 ;1
L 7.3075 2.3075 7.3075 2.3075 27 P 0 ;1
L 7.3075 2.3575 7.3075 2.3575 27 P 0 ;1
L 7.3075 2.4075 7.3075 2.4075 27 P 0 ;1
L 7.3075 2.4575 7.3075 2.4575 27 P 0 ;1
L 7.3075 2.5075 7.3075 2.5075 27 P 0 ;1
L 7.3075 2.5575 7.3075 2.5575 27 P 0 ;1
L 7.3075 2.6075 7.3075 2.6075 27 P 0 ;1
L 7.3075 2.6575 7.3075 2.6575 27 P 0 ;1
L 7.3075 2.7075 7.3075 2.7075 27 P 0 ;1
L 7.3075 2.7575 7.3075 2.7575 27 P 0 ;1
L 7.3075 2.8075 7.3075 2.8075 27 P 0 ;1
L 7.3075 2.8575 7.3075 2.8575 27 P 0 ;1
L 7.3075 2.9075 7.3075 2.9075 27 P 0 ;1
L 7.3075 2.9575 7.3075 2.9575 27 P 0 ;1
L 7.3075 3.0075 7.3075 3.0075 27 P 0 ;1
L 7.3075 3.0575 7.3075 3.0575 27 P 0 ;1
L 7.3075 3.1075 7.3075 3.1075 27 P 0 ;1
L 7.3075 3.1575 7.3075 3.1575 27 P 0 ;1
L 7.3075 3.2075 7.3075 3.2075 27 P 0 ;1
L 7.3075 3.2575 7.3075 3.2575 27 P 0 ;1
L 7.3075 3.3075 7.3075 3.3075 27 P 0 ;1
L 7.3075 3.3575 7.3075 3.3575 27 P 0 ;1
L 7.3075 3.4075 7.3075 3.4075 27 P 0 ;1
L 7.3075 3.4575 7.3075 3.4575 27 P 0 ;1
L 7.3075 3.5075 7.3075 3.5075 27 P 0 ;1
L 7.3075 3.5575 7.3075 3.5575 27 P 0 ;1
L 7.3075 3.6075 7.3075 3.6075 27 P 0 ;1
L 7.3075 3.6575 7.3075 3.6575 27 P 0 ;1
L 7.3075 3.7075 7.3075 3.7075 27 P 0 ;1
L 7.3075 3.7575 7.3075 3.7575 27 P 0 ;1
L 7.3075 3.8075 7.3075 3.8075 27 P 0 ;1
L 7.3075 3.8575 7.3075 3.8575 27 P 0 ;1
L 7.3075 3.9075 7.3075 3.9075 27 P 0 ;1
L 7.3075 3.9575 7.3075 3.9575 27 P 0 ;1
L 7.3075 4.0075 7.3075 4.0075 27 P 0 ;1
L 7.3075 4.0575 7.3075 4.0575 27 P 0 ;1
L 7.3075 4.1075 7.3075 4.1075 27 P 0 ;1
L 7.3075 4.1575 7.3075 4.1575 27 P 0 ;1
L 7.3075 4.2075 7.3075 4.2075 27 P 0 ;1
L 7.3075 4.2575 7.3075 4.2575 27 P 0 ;1
L 7.3075 4.3075 7.3075 4.3075 27 P 0 ;1
L 7.3075 4.3575 7.3075 4.3575 27 P 0 ;1
L 7.3075 4.4075 7.3075 4.4075 27 P 0 ;1
L 7.3075 4.4575 7.3075 4.4575 27 P 0 ;1
L 7.3075 4.5075 7.3075 4.5075 27 P 0 ;1
L 7.3075 5.2575 7.3075 5.2575 27 P 0 ;1
L 7.3075 5.3075 7.3075 5.3075 27 P 0 ;1
L 7.3075 5.3575 7.3075 5.3575 27 P 0 ;1
L 7.3575 0.4575 7.3575 0.4575 27 P 0 ;1
L 7.3575 0.5075 7.3575 0.5075 27 P 0 ;1
L 7.3575 0.5575 7.3575 0.5575 27 P 0 ;1
L 7.3575 0.6075 7.3575 0.6075 27 P 0 ;1
L 7.3575 0.6575 7.3575 0.6575 27 P 0 ;1
L 7.3575 0.7075 7.3575 0.7075 27 P 0 ;1
L 7.3575 0.7575 7.3575 0.7575 27 P 0 ;1
L 7.3575 0.8075 7.3575 0.8075 27 P 0 ;1
L 7.3575 0.8575 7.3575 0.8575 27 P 0 ;1
L 7.3575 0.9075 7.3575 0.9075 27 P 0 ;1
L 7.3575 0.9575 7.3575 0.9575 27 P 0 ;1
L 7.3575 1.0075 7.3575 1.0075 27 P 0 ;1
L 7.3575 1.0575 7.3575 1.0575 27 P 0 ;1
L 7.3575 1.1075 7.3575 1.1075 27 P 0 ;1
L 7.3575 1.1575 7.3575 1.1575 27 P 0 ;1
L 7.3575 1.2075 7.3575 1.2075 27 P 0 ;1
L 7.3575 1.2575 7.3575 1.2575 27 P 0 ;1
L 7.3575 1.3075 7.3575 1.3075 27 P 0 ;1
L 7.3575 1.3575 7.3575 1.3575 27 P 0 ;1
L 7.3575 1.4075 7.3575 1.4075 27 P 0 ;1
L 7.3575 1.4575 7.3575 1.4575 27 P 0 ;1
L 7.3575 1.5075 7.3575 1.5075 27 P 0 ;1
L 7.3575 1.5575 7.3575 1.5575 27 P 0 ;1
L 7.3575 1.6075 7.3575 1.6075 27 P 0 ;1
L 7.3575 1.6575 7.3575 1.6575 27 P 0 ;1
L 7.3575 1.7575 7.3575 1.7575 27 P 0 ;1
L 7.3575 1.8075 7.3575 1.8075 27 P 0 ;1
L 7.3575 1.8575 7.3575 1.8575 27 P 0 ;1
L 7.3575 1.9075 7.3575 1.9075 27 P 0 ;1
L 7.3575 1.9575 7.3575 1.9575 27 P 0 ;1
L 7.3575 2.0075 7.3575 2.0075 27 P 0 ;1
L 7.3575 2.0575 7.3575 2.0575 27 P 0 ;1
L 7.3575 2.1075 7.3575 2.1075 27 P 0 ;1
L 7.3575 2.1575 7.3575 2.1575 27 P 0 ;1
L 7.3575 2.2075 7.3575 2.2075 27 P 0 ;1
L 7.3575 2.2575 7.3575 2.2575 27 P 0 ;1
L 7.3575 2.3075 7.3575 2.3075 27 P 0 ;1
L 7.3575 2.3575 7.3575 2.3575 27 P 0 ;1
L 7.3575 2.4075 7.3575 2.4075 27 P 0 ;1
L 7.3575 2.4575 7.3575 2.4575 27 P 0 ;1
L 7.3575 2.5075 7.3575 2.5075 27 P 0 ;1
L 7.3575 2.5575 7.3575 2.5575 27 P 0 ;1
L 7.3575 2.6075 7.3575 2.6075 27 P 0 ;1
L 7.3575 2.6575 7.3575 2.6575 27 P 0 ;1
L 7.3575 2.7075 7.3575 2.7075 27 P 0 ;1
L 7.3575 2.7575 7.3575 2.7575 27 P 0 ;1
L 7.3575 2.8075 7.3575 2.8075 27 P 0 ;1
L 7.3575 2.8575 7.3575 2.8575 27 P 0 ;1
L 7.3575 2.9075 7.3575 2.9075 27 P 0 ;1
L 7.3575 2.9575 7.3575 2.9575 27 P 0 ;1
L 7.3575 3.0075 7.3575 3.0075 27 P 0 ;1
L 7.3575 3.0575 7.3575 3.0575 27 P 0 ;1
L 7.3575 3.1075 7.3575 3.1075 27 P 0 ;1
L 7.3575 3.1575 7.3575 3.1575 27 P 0 ;1
L 7.3575 3.2075 7.3575 3.2075 27 P 0 ;1
L 7.3575 3.2575 7.3575 3.2575 27 P 0 ;1
L 7.3575 3.3075 7.3575 3.3075 27 P 0 ;1
L 7.3575 3.3575 7.3575 3.3575 27 P 0 ;1
L 7.3575 3.5075 7.3575 3.5075 27 P 0 ;1
L 7.3575 3.5575 7.3575 3.5575 27 P 0 ;1
L 7.3575 3.6075 7.3575 3.6075 27 P 0 ;1
L 7.3575 3.6575 7.3575 3.6575 27 P 0 ;1
L 7.3575 3.7075 7.3575 3.7075 27 P 0 ;1
L 7.3575 3.7575 7.3575 3.7575 27 P 0 ;1
L 7.3575 3.8075 7.3575 3.8075 27 P 0 ;1
L 7.3575 3.8575 7.3575 3.8575 27 P 0 ;1
L 7.3575 3.9075 7.3575 3.9075 27 P 0 ;1
L 7.3575 3.9575 7.3575 3.9575 27 P 0 ;1
L 7.3575 4.0075 7.3575 4.0075 27 P 0 ;1
L 7.3575 4.0575 7.3575 4.0575 27 P 0 ;1
L 7.3575 4.1075 7.3575 4.1075 27 P 0 ;1
L 7.3575 4.1575 7.3575 4.1575 27 P 0 ;1
L 7.3575 4.2075 7.3575 4.2075 27 P 0 ;1
L 7.3575 4.2575 7.3575 4.2575 27 P 0 ;1
L 7.3575 4.3075 7.3575 4.3075 27 P 0 ;1
L 7.3575 4.3575 7.3575 4.3575 27 P 0 ;1
L 7.3575 4.4075 7.3575 4.4075 27 P 0 ;1
L 7.3575 4.4575 7.3575 4.4575 27 P 0 ;1
L 7.3575 4.5075 7.3575 4.5075 27 P 0 ;1
L 7.3575 5.2575 7.3575 5.2575 27 P 0 ;1
L 7.3575 5.3075 7.3575 5.3075 27 P 0 ;1
L 7.3575 5.3575 7.3575 5.3575 27 P 0 ;1
L 7.4075 0.4075 7.4075 0.4075 27 P 0 ;1
L 7.4075 0.4575 7.4075 0.4575 27 P 0 ;1
L 7.4075 0.5075 7.4075 0.5075 27 P 0 ;1
L 7.4075 0.5575 7.4075 0.5575 27 P 0 ;1
L 7.4075 0.6075 7.4075 0.6075 27 P 0 ;1
L 7.4075 0.6575 7.4075 0.6575 27 P 0 ;1
L 7.4075 0.7075 7.4075 0.7075 27 P 0 ;1
L 7.4075 0.7575 7.4075 0.7575 27 P 0 ;1
L 7.4075 0.8075 7.4075 0.8075 27 P 0 ;1
L 7.4075 0.8575 7.4075 0.8575 27 P 0 ;1
L 7.4075 0.9075 7.4075 0.9075 27 P 0 ;1
L 7.4075 0.9575 7.4075 0.9575 27 P 0 ;1
L 7.4075 1.0075 7.4075 1.0075 27 P 0 ;1
L 7.4075 1.0575 7.4075 1.0575 27 P 0 ;1
L 7.4075 1.1075 7.4075 1.1075 27 P 0 ;1
L 7.4075 1.1575 7.4075 1.1575 27 P 0 ;1
L 7.4075 1.2075 7.4075 1.2075 27 P 0 ;1
L 7.4075 1.2575 7.4075 1.2575 27 P 0 ;1
L 7.4075 1.3075 7.4075 1.3075 27 P 0 ;1
L 7.4075 1.3575 7.4075 1.3575 27 P 0 ;1
L 7.4075 1.4075 7.4075 1.4075 27 P 0 ;1
L 7.4075 1.4575 7.4075 1.4575 27 P 0 ;1
L 7.4075 1.5075 7.4075 1.5075 27 P 0 ;1
L 7.4075 1.5575 7.4075 1.5575 27 P 0 ;1
L 7.4075 1.6075 7.4075 1.6075 27 P 0 ;1
L 7.4075 1.8075 7.4075 1.8075 27 P 0 ;1
L 7.4075 1.8575 7.4075 1.8575 27 P 0 ;1
L 7.4075 1.9075 7.4075 1.9075 27 P 0 ;1
L 7.4075 1.9575 7.4075 1.9575 27 P 0 ;1
L 7.4075 2.0075 7.4075 2.0075 27 P 0 ;1
L 7.4075 2.0575 7.4075 2.0575 27 P 0 ;1
L 7.4075 2.1075 7.4075 2.1075 27 P 0 ;1
L 7.4075 2.1575 7.4075 2.1575 27 P 0 ;1
L 7.4075 2.2075 7.4075 2.2075 27 P 0 ;1
L 7.4075 2.2575 7.4075 2.2575 27 P 0 ;1
L 7.4075 2.3075 7.4075 2.3075 27 P 0 ;1
L 7.4075 2.3575 7.4075 2.3575 27 P 0 ;1
L 7.4075 2.4075 7.4075 2.4075 27 P 0 ;1
L 7.4075 2.4575 7.4075 2.4575 27 P 0 ;1
L 7.4075 2.5075 7.4075 2.5075 27 P 0 ;1
L 7.4075 2.5575 7.4075 2.5575 27 P 0 ;1
L 7.4075 2.6075 7.4075 2.6075 27 P 0 ;1
L 7.4075 2.6575 7.4075 2.6575 27 P 0 ;1
L 7.4075 2.7075 7.4075 2.7075 27 P 0 ;1
L 7.4075 2.7575 7.4075 2.7575 27 P 0 ;1
L 7.4075 2.8075 7.4075 2.8075 27 P 0 ;1
L 7.4075 2.8575 7.4075 2.8575 27 P 0 ;1
L 7.4075 2.9075 7.4075 2.9075 27 P 0 ;1
L 7.4075 2.9575 7.4075 2.9575 27 P 0 ;1
L 7.4075 3.0075 7.4075 3.0075 27 P 0 ;1
L 7.4075 3.0575 7.4075 3.0575 27 P 0 ;1
L 7.4075 3.1075 7.4075 3.1075 27 P 0 ;1
L 7.4075 3.1575 7.4075 3.1575 27 P 0 ;1
L 7.4075 3.2075 7.4075 3.2075 27 P 0 ;1
L 7.4075 3.2575 7.4075 3.2575 27 P 0 ;1
L 7.4075 3.3075 7.4075 3.3075 27 P 0 ;1
L 7.4075 3.5575 7.4075 3.5575 27 P 0 ;1
L 7.4075 3.6075 7.4075 3.6075 27 P 0 ;1
L 7.4075 3.6575 7.4075 3.6575 27 P 0 ;1
L 7.4075 3.7075 7.4075 3.7075 27 P 0 ;1
L 7.4075 3.7575 7.4075 3.7575 27 P 0 ;1
L 7.4075 3.8075 7.4075 3.8075 27 P 0 ;1
L 7.4075 3.8575 7.4075 3.8575 27 P 0 ;1
L 7.4075 3.9075 7.4075 3.9075 27 P 0 ;1
L 7.4075 3.9575 7.4075 3.9575 27 P 0 ;1
L 7.4075 4.0075 7.4075 4.0075 27 P 0 ;1
L 7.4075 4.0575 7.4075 4.0575 27 P 0 ;1
L 7.4075 4.1075 7.4075 4.1075 27 P 0 ;1
L 7.4075 4.1575 7.4075 4.1575 27 P 0 ;1
L 7.4075 4.2075 7.4075 4.2075 27 P 0 ;1
L 7.4075 4.2575 7.4075 4.2575 27 P 0 ;1
L 7.4075 4.3075 7.4075 4.3075 27 P 0 ;1
L 7.4075 4.3575 7.4075 4.3575 27 P 0 ;1
L 7.4075 4.4075 7.4075 4.4075 27 P 0 ;1
L 7.4075 4.4575 7.4075 4.4575 27 P 0 ;1
L 7.4075 4.5075 7.4075 4.5075 27 P 0 ;1
L 7.4075 5.2575 7.4075 5.2575 27 P 0 ;1
L 7.4075 5.3075 7.4075 5.3075 27 P 0 ;1
L 7.4075 5.3575 7.4075 5.3575 27 P 0 ;1
L 7.4075 5.6575 7.4075 5.6575 27 P 0 ;1
L 7.4575 0.1575 7.4575 0.1575 27 P 0 ;1
L 7.4575 0.2075 7.4575 0.2075 27 P 0 ;1
L 7.4575 0.2575 7.4575 0.2575 27 P 0 ;1
L 7.4575 0.3075 7.4575 0.3075 27 P 0 ;1
L 7.4575 0.3575 7.4575 0.3575 27 P 0 ;1
L 7.4575 0.4075 7.4575 0.4075 27 P 0 ;1
L 7.4575 0.4575 7.4575 0.4575 27 P 0 ;1
L 7.4575 0.5075 7.4575 0.5075 27 P 0 ;1
L 7.4575 0.5575 7.4575 0.5575 27 P 0 ;1
L 7.4575 0.6075 7.4575 0.6075 27 P 0 ;1
L 7.4575 0.6575 7.4575 0.6575 27 P 0 ;1
L 7.4575 0.7075 7.4575 0.7075 27 P 0 ;1
L 7.4575 0.7575 7.4575 0.7575 27 P 0 ;1
L 7.4575 0.8075 7.4575 0.8075 27 P 0 ;1
L 7.4575 0.8575 7.4575 0.8575 27 P 0 ;1
L 7.4575 0.9075 7.4575 0.9075 27 P 0 ;1
L 7.4575 0.9575 7.4575 0.9575 27 P 0 ;1
L 7.4575 1.0075 7.4575 1.0075 27 P 0 ;1
L 7.4575 1.0575 7.4575 1.0575 27 P 0 ;1
L 7.4575 1.1075 7.4575 1.1075 27 P 0 ;1
L 7.4575 1.1575 7.4575 1.1575 27 P 0 ;1
L 7.4575 1.2075 7.4575 1.2075 27 P 0 ;1
L 7.4575 1.2575 7.4575 1.2575 27 P 0 ;1
L 7.4575 1.3075 7.4575 1.3075 27 P 0 ;1
L 7.4575 1.3575 7.4575 1.3575 27 P 0 ;1
L 7.4575 1.4075 7.4575 1.4075 27 P 0 ;1
L 7.4575 1.4575 7.4575 1.4575 27 P 0 ;1
L 7.4575 1.5075 7.4575 1.5075 27 P 0 ;1
L 7.4575 1.5575 7.4575 1.5575 27 P 0 ;1
L 7.4575 1.6075 7.4575 1.6075 27 P 0 ;1
L 7.4575 1.8075 7.4575 1.8075 27 P 0 ;1
L 7.4575 1.8575 7.4575 1.8575 27 P 0 ;1
L 7.4575 1.9075 7.4575 1.9075 27 P 0 ;1
L 7.4575 1.9575 7.4575 1.9575 27 P 0 ;1
L 7.4575 2.0075 7.4575 2.0075 27 P 0 ;1
L 7.4575 2.0575 7.4575 2.0575 27 P 0 ;1
L 7.4575 2.1075 7.4575 2.1075 27 P 0 ;1
L 7.4575 2.1575 7.4575 2.1575 27 P 0 ;1
L 7.4575 2.2075 7.4575 2.2075 27 P 0 ;1
L 7.4575 2.2575 7.4575 2.2575 27 P 0 ;1
L 7.4575 2.3075 7.4575 2.3075 27 P 0 ;1
L 7.4575 2.3575 7.4575 2.3575 27 P 0 ;1
L 7.4575 2.4075 7.4575 2.4075 27 P 0 ;1
L 7.4575 2.4575 7.4575 2.4575 27 P 0 ;1
L 7.4575 2.5075 7.4575 2.5075 27 P 0 ;1
L 7.4575 2.5575 7.4575 2.5575 27 P 0 ;1
L 7.4575 2.6075 7.4575 2.6075 27 P 0 ;1
L 7.4575 2.6575 7.4575 2.6575 27 P 0 ;1
L 7.4575 2.7075 7.4575 2.7075 27 P 0 ;1
L 7.4575 2.7575 7.4575 2.7575 27 P 0 ;1
L 7.4575 2.8075 7.4575 2.8075 27 P 0 ;1
L 7.4575 2.8575 7.4575 2.8575 27 P 0 ;1
L 7.4575 2.9075 7.4575 2.9075 27 P 0 ;1
L 7.4575 2.9575 7.4575 2.9575 27 P 0 ;1
L 7.4575 3.0075 7.4575 3.0075 27 P 0 ;1
L 7.4575 3.0575 7.4575 3.0575 27 P 0 ;1
L 7.4575 3.1075 7.4575 3.1075 27 P 0 ;1
L 7.4575 3.1575 7.4575 3.1575 27 P 0 ;1
L 7.4575 3.2075 7.4575 3.2075 27 P 0 ;1
L 7.4575 3.2575 7.4575 3.2575 27 P 0 ;1
L 7.4575 3.3075 7.4575 3.3075 27 P 0 ;1
L 7.4575 3.5575 7.4575 3.5575 27 P 0 ;1
L 7.4575 3.6075 7.4575 3.6075 27 P 0 ;1
L 7.4575 3.6575 7.4575 3.6575 27 P 0 ;1
L 7.4575 3.7075 7.4575 3.7075 27 P 0 ;1
L 7.4575 3.7575 7.4575 3.7575 27 P 0 ;1
L 7.4575 3.8075 7.4575 3.8075 27 P 0 ;1
L 7.4575 3.8575 7.4575 3.8575 27 P 0 ;1
L 7.4575 3.9075 7.4575 3.9075 27 P 0 ;1
L 7.4575 3.9575 7.4575 3.9575 27 P 0 ;1
L 7.4575 4.0075 7.4575 4.0075 27 P 0 ;1
L 7.4575 4.0575 7.4575 4.0575 27 P 0 ;1
L 7.4575 4.1075 7.4575 4.1075 27 P 0 ;1
L 7.4575 4.1575 7.4575 4.1575 27 P 0 ;1
L 7.4575 4.2075 7.4575 4.2075 27 P 0 ;1
L 7.4575 4.2575 7.4575 4.2575 27 P 0 ;1
L 7.4575 4.3075 7.4575 4.3075 27 P 0 ;1
L 7.4575 4.3575 7.4575 4.3575 27 P 0 ;1
L 7.4575 4.4075 7.4575 4.4075 27 P 0 ;1
L 7.4575 4.4575 7.4575 4.4575 27 P 0 ;1
L 7.4575 4.5075 7.4575 4.5075 27 P 0 ;1
L 7.4575 4.5575 7.4575 4.5575 27 P 0 ;1
L 7.4575 4.6075 7.4575 4.6075 27 P 0 ;1
L 7.4575 4.6575 7.4575 4.6575 27 P 0 ;1
L 7.4575 5.2575 7.4575 5.2575 27 P 0 ;1
L 7.4575 5.3075 7.4575 5.3075 27 P 0 ;1
L 7.4575 5.3575 7.4575 5.3575 27 P 0 ;1
L 7.4575 5.6575 7.4575 5.6575 27 P 0 ;1
L 7.4575 5.7075 7.4575 5.7075 27 P 0 ;1
L 7.4575 5.7575 7.4575 5.7575 27 P 0 ;1
L 7.4575 5.8075 7.4575 5.8075 27 P 0 ;1
L 7.4575 5.8575 7.4575 5.8575 27 P 0 ;1
L 7.5075 0.1575 7.5075 0.1575 27 P 0 ;1
L 7.5075 0.2075 7.5075 0.2075 27 P 0 ;1
L 7.5075 0.2575 7.5075 0.2575 27 P 0 ;1
L 7.5075 0.3075 7.5075 0.3075 27 P 0 ;1
L 7.5075 0.3575 7.5075 0.3575 27 P 0 ;1
L 7.5075 0.4075 7.5075 0.4075 27 P 0 ;1
L 7.5075 0.4575 7.5075 0.4575 27 P 0 ;1
L 7.5075 0.5075 7.5075 0.5075 27 P 0 ;1
L 7.5075 0.5575 7.5075 0.5575 27 P 0 ;1
L 7.5075 0.6075 7.5075 0.6075 27 P 0 ;1
L 7.5075 0.6575 7.5075 0.6575 27 P 0 ;1
L 7.5075 0.7075 7.5075 0.7075 27 P 0 ;1
L 7.5075 0.7575 7.5075 0.7575 27 P 0 ;1
L 7.5075 0.8075 7.5075 0.8075 27 P 0 ;1
L 7.5075 0.8575 7.5075 0.8575 27 P 0 ;1
L 7.5075 0.9075 7.5075 0.9075 27 P 0 ;1
L 7.5075 0.9575 7.5075 0.9575 27 P 0 ;1
L 7.5075 1.0075 7.5075 1.0075 27 P 0 ;1
L 7.5075 1.0575 7.5075 1.0575 27 P 0 ;1
L 7.5075 1.1075 7.5075 1.1075 27 P 0 ;1
L 7.5075 1.1575 7.5075 1.1575 27 P 0 ;1
L 7.5075 1.2075 7.5075 1.2075 27 P 0 ;1
L 7.5075 1.2575 7.5075 1.2575 27 P 0 ;1
L 7.5075 1.3075 7.5075 1.3075 27 P 0 ;1
L 7.5075 1.3575 7.5075 1.3575 27 P 0 ;1
L 7.5075 1.4075 7.5075 1.4075 27 P 0 ;1
L 7.5075 1.4575 7.5075 1.4575 27 P 0 ;1
L 7.5075 1.5075 7.5075 1.5075 27 P 0 ;1
L 7.5075 1.5575 7.5075 1.5575 27 P 0 ;1
L 7.5075 1.6075 7.5075 1.6075 27 P 0 ;1
L 7.5075 1.8075 7.5075 1.8075 27 P 0 ;1
L 7.5075 1.8575 7.5075 1.8575 27 P 0 ;1
L 7.5075 1.9075 7.5075 1.9075 27 P 0 ;1
L 7.5075 1.9575 7.5075 1.9575 27 P 0 ;1
L 7.5075 2.0075 7.5075 2.0075 27 P 0 ;1
L 7.5075 2.0575 7.5075 2.0575 27 P 0 ;1
L 7.5075 2.1075 7.5075 2.1075 27 P 0 ;1
L 7.5075 2.1575 7.5075 2.1575 27 P 0 ;1
L 7.5075 2.2075 7.5075 2.2075 27 P 0 ;1
L 7.5075 2.2575 7.5075 2.2575 27 P 0 ;1
L 7.5075 2.3075 7.5075 2.3075 27 P 0 ;1
L 7.5075 2.3575 7.5075 2.3575 27 P 0 ;1
L 7.5075 2.4075 7.5075 2.4075 27 P 0 ;1
L 7.5075 2.4575 7.5075 2.4575 27 P 0 ;1
L 7.5075 2.5075 7.5075 2.5075 27 P 0 ;1
L 7.5075 2.5575 7.5075 2.5575 27 P 0 ;1
L 7.5075 2.6075 7.5075 2.6075 27 P 0 ;1
L 7.5075 2.6575 7.5075 2.6575 27 P 0 ;1
L 7.5075 2.7075 7.5075 2.7075 27 P 0 ;1
L 7.5075 2.7575 7.5075 2.7575 27 P 0 ;1
L 7.5075 2.8075 7.5075 2.8075 27 P 0 ;1
L 7.5075 2.8575 7.5075 2.8575 27 P 0 ;1
L 7.5075 2.9075 7.5075 2.9075 27 P 0 ;1
L 7.5075 2.9575 7.5075 2.9575 27 P 0 ;1
L 7.5075 3.0075 7.5075 3.0075 27 P 0 ;1
L 7.5075 3.0575 7.5075 3.0575 27 P 0 ;1
L 7.5075 3.1075 7.5075 3.1075 27 P 0 ;1
L 7.5075 3.1575 7.5075 3.1575 27 P 0 ;1
L 7.5075 3.2075 7.5075 3.2075 27 P 0 ;1
L 7.5075 3.2575 7.5075 3.2575 27 P 0 ;1
L 7.5075 3.3075 7.5075 3.3075 27 P 0 ;1
L 7.5075 3.3575 7.5075 3.3575 27 P 0 ;1
L 7.5075 3.5075 7.5075 3.5075 27 P 0 ;1
L 7.5075 3.5575 7.5075 3.5575 27 P 0 ;1
L 7.5075 3.6075 7.5075 3.6075 27 P 0 ;1
L 7.5075 3.6575 7.5075 3.6575 27 P 0 ;1
L 7.5075 3.7075 7.5075 3.7075 27 P 0 ;1
L 7.5075 3.7575 7.5075 3.7575 27 P 0 ;1
L 7.5075 3.8075 7.5075 3.8075 27 P 0 ;1
L 7.5075 3.8575 7.5075 3.8575 27 P 0 ;1
L 7.5075 3.9075 7.5075 3.9075 27 P 0 ;1
L 7.5075 3.9575 7.5075 3.9575 27 P 0 ;1
L 7.5075 4.0075 7.5075 4.0075 27 P 0 ;1
L 7.5075 4.0575 7.5075 4.0575 27 P 0 ;1
L 7.5075 4.1075 7.5075 4.1075 27 P 0 ;1
L 7.5075 4.1575 7.5075 4.1575 27 P 0 ;1
L 7.5075 4.2075 7.5075 4.2075 27 P 0 ;1
L 7.5075 4.2575 7.5075 4.2575 27 P 0 ;1
L 7.5075 4.3075 7.5075 4.3075 27 P 0 ;1
L 7.5075 4.3575 7.5075 4.3575 27 P 0 ;1
L 7.5075 4.4075 7.5075 4.4075 27 P 0 ;1
L 7.5075 4.4575 7.5075 4.4575 27 P 0 ;1
L 7.5075 4.5075 7.5075 4.5075 27 P 0 ;1
L 7.5075 4.5575 7.5075 4.5575 27 P 0 ;1
L 7.5075 5.2575 7.5075 5.2575 27 P 0 ;1
L 7.5075 5.3075 7.5075 5.3075 27 P 0 ;1
L 7.5075 5.3575 7.5075 5.3575 27 P 0 ;1
L 7.5075 5.6575 7.5075 5.6575 27 P 0 ;1
L 7.5075 5.7075 7.5075 5.7075 27 P 0 ;1
L 7.5075 5.7575 7.5075 5.7575 27 P 0 ;1
L 7.5075 5.8075 7.5075 5.8075 27 P 0 ;1
L 7.5075 5.8575 7.5075 5.8575 27 P 0 ;1
L 7.5575 0.1575 7.5575 0.1575 27 P 0 ;1
L 7.5575 0.2075 7.5575 0.2075 27 P 0 ;1
L 7.5575 0.2575 7.5575 0.2575 27 P 0 ;1
L 7.5575 0.3075 7.5575 0.3075 27 P 0 ;1
L 7.5575 0.3575 7.5575 0.3575 27 P 0 ;1
L 7.5575 0.4075 7.5575 0.4075 27 P 0 ;1
L 7.5575 0.4575 7.5575 0.4575 27 P 0 ;1
L 7.5575 0.5075 7.5575 0.5075 27 P 0 ;1
L 7.5575 0.5575 7.5575 0.5575 27 P 0 ;1
L 7.5575 0.6075 7.5575 0.6075 27 P 0 ;1
L 7.5575 0.6575 7.5575 0.6575 27 P 0 ;1
L 7.5575 0.7075 7.5575 0.7075 27 P 0 ;1
L 7.5575 0.7575 7.5575 0.7575 27 P 0 ;1
L 7.5575 0.8075 7.5575 0.8075 27 P 0 ;1
L 7.5575 0.8575 7.5575 0.8575 27 P 0 ;1
L 7.5575 0.9075 7.5575 0.9075 27 P 0 ;1
L 7.5575 0.9575 7.5575 0.9575 27 P 0 ;1
L 7.5575 1.0075 7.5575 1.0075 27 P 0 ;1
L 7.5575 1.0575 7.5575 1.0575 27 P 0 ;1
L 7.5575 1.1075 7.5575 1.1075 27 P 0 ;1
L 7.5575 1.1575 7.5575 1.1575 27 P 0 ;1
L 7.5575 1.2075 7.5575 1.2075 27 P 0 ;1
L 7.5575 1.2575 7.5575 1.2575 27 P 0 ;1
L 7.5575 1.3075 7.5575 1.3075 27 P 0 ;1
L 7.5575 1.3575 7.5575 1.3575 27 P 0 ;1
L 7.5575 1.4075 7.5575 1.4075 27 P 0 ;1
L 7.5575 1.4575 7.5575 1.4575 27 P 0 ;1
L 7.5575 1.5075 7.5575 1.5075 27 P 0 ;1
L 7.5575 1.5575 7.5575 1.5575 27 P 0 ;1
L 7.5575 1.6075 7.5575 1.6075 27 P 0 ;1
L 7.5575 1.6575 7.5575 1.6575 27 P 0 ;1
L 7.5575 1.7075 7.5575 1.7075 27 P 0 ;1
L 7.5575 1.7575 7.5575 1.7575 27 P 0 ;1
L 7.5575 1.8075 7.5575 1.8075 27 P 0 ;1
L 7.5575 1.8575 7.5575 1.8575 27 P 0 ;1
L 7.5575 1.9075 7.5575 1.9075 27 P 0 ;1
L 7.5575 1.9575 7.5575 1.9575 27 P 0 ;1
L 7.5575 2.0075 7.5575 2.0075 27 P 0 ;1
L 7.5575 2.0575 7.5575 2.0575 27 P 0 ;1
L 7.5575 2.1075 7.5575 2.1075 27 P 0 ;1
L 7.5575 2.1575 7.5575 2.1575 27 P 0 ;1
L 7.5575 2.2075 7.5575 2.2075 27 P 0 ;1
L 7.5575 2.2575 7.5575 2.2575 27 P 0 ;1
L 7.5575 2.3075 7.5575 2.3075 27 P 0 ;1
L 7.5575 2.3575 7.5575 2.3575 27 P 0 ;1
L 7.5575 2.4075 7.5575 2.4075 27 P 0 ;1
L 7.5575 2.4575 7.5575 2.4575 27 P 0 ;1
L 7.5575 2.5075 7.5575 2.5075 27 P 0 ;1
L 7.5575 2.5575 7.5575 2.5575 27 P 0 ;1
L 7.5575 2.6075 7.5575 2.6075 27 P 0 ;1
L 7.5575 2.6575 7.5575 2.6575 27 P 0 ;1
L 7.5575 2.7075 7.5575 2.7075 27 P 0 ;1
L 7.5575 2.7575 7.5575 2.7575 27 P 0 ;1
L 7.5575 2.8075 7.5575 2.8075 27 P 0 ;1
L 7.5575 2.8575 7.5575 2.8575 27 P 0 ;1
L 7.5575 2.9075 7.5575 2.9075 27 P 0 ;1
L 7.5575 2.9575 7.5575 2.9575 27 P 0 ;1
L 7.5575 3.0075 7.5575 3.0075 27 P 0 ;1
L 7.5575 3.0575 7.5575 3.0575 27 P 0 ;1
L 7.5575 3.1075 7.5575 3.1075 27 P 0 ;1
L 7.5575 3.1575 7.5575 3.1575 27 P 0 ;1
L 7.5575 3.2075 7.5575 3.2075 27 P 0 ;1
L 7.5575 3.2575 7.5575 3.2575 27 P 0 ;1
L 7.5575 3.3075 7.5575 3.3075 27 P 0 ;1
L 7.5575 3.3575 7.5575 3.3575 27 P 0 ;1
L 7.5575 3.4075 7.5575 3.4075 27 P 0 ;1
L 7.5575 3.4575 7.5575 3.4575 27 P 0 ;1
L 7.5575 3.5075 7.5575 3.5075 27 P 0 ;1
L 7.5575 3.5575 7.5575 3.5575 27 P 0 ;1
L 7.5575 3.6075 7.5575 3.6075 27 P 0 ;1
L 7.5575 3.6575 7.5575 3.6575 27 P 0 ;1
L 7.5575 3.7075 7.5575 3.7075 27 P 0 ;1
L 7.5575 3.7575 7.5575 3.7575 27 P 0 ;1
L 7.5575 3.8075 7.5575 3.8075 27 P 0 ;1
L 7.5575 3.8575 7.5575 3.8575 27 P 0 ;1
L 7.5575 3.9075 7.5575 3.9075 27 P 0 ;1
L 7.5575 3.9575 7.5575 3.9575 27 P 0 ;1
L 7.5575 4.0075 7.5575 4.0075 27 P 0 ;1
L 7.5575 4.0575 7.5575 4.0575 27 P 0 ;1
L 7.5575 4.1075 7.5575 4.1075 27 P 0 ;1
L 7.5575 4.1575 7.5575 4.1575 27 P 0 ;1
L 7.5575 4.2075 7.5575 4.2075 27 P 0 ;1
L 7.5575 4.2575 7.5575 4.2575 27 P 0 ;1
L 7.5575 4.3075 7.5575 4.3075 27 P 0 ;1
L 7.5575 4.3575 7.5575 4.3575 27 P 0 ;1
L 7.5575 4.4075 7.5575 4.4075 27 P 0 ;1
L 7.5575 4.4575 7.5575 4.4575 27 P 0 ;1
L 7.5575 4.5075 7.5575 4.5075 27 P 0 ;1
L 7.5575 4.5575 7.5575 4.5575 27 P 0 ;1
L 7.5575 5.3075 7.5575 5.3075 27 P 0 ;1
L 7.5575 5.3575 7.5575 5.3575 27 P 0 ;1
L 7.5575 5.6575 7.5575 5.6575 27 P 0 ;1
L 7.5575 5.7075 7.5575 5.7075 27 P 0 ;1
L 7.5575 5.7575 7.5575 5.7575 27 P 0 ;1
L 7.5575 5.8075 7.5575 5.8075 27 P 0 ;1
L 7.5575 5.8575 7.5575 5.8575 27 P 0 ;1
L 7.6075 0.1575 7.6075 0.1575 27 P 0 ;1
L 7.6075 0.2075 7.6075 0.2075 27 P 0 ;1
L 7.6075 0.2575 7.6075 0.2575 27 P 0 ;1
L 7.6075 0.3075 7.6075 0.3075 27 P 0 ;1
L 7.6075 0.3575 7.6075 0.3575 27 P 0 ;1
L 7.6075 0.4075 7.6075 0.4075 27 P 0 ;1
L 7.6075 0.4575 7.6075 0.4575 27 P 0 ;1
L 7.6075 0.5075 7.6075 0.5075 27 P 0 ;1
L 7.6075 0.5575 7.6075 0.5575 27 P 0 ;1
L 7.6075 0.6075 7.6075 0.6075 27 P 0 ;1
L 7.6075 0.6575 7.6075 0.6575 27 P 0 ;1
L 7.6075 0.7075 7.6075 0.7075 27 P 0 ;1
L 7.6075 0.7575 7.6075 0.7575 27 P 0 ;1
L 7.6075 0.8075 7.6075 0.8075 27 P 0 ;1
L 7.6075 0.8575 7.6075 0.8575 27 P 0 ;1
L 7.6075 0.9075 7.6075 0.9075 27 P 0 ;1
L 7.6075 0.9575 7.6075 0.9575 27 P 0 ;1
L 7.6075 1.0075 7.6075 1.0075 27 P 0 ;1
L 7.6075 1.0575 7.6075 1.0575 27 P 0 ;1
L 7.6075 1.1075 7.6075 1.1075 27 P 0 ;1
L 7.6075 1.1575 7.6075 1.1575 27 P 0 ;1
L 7.6075 1.2075 7.6075 1.2075 27 P 0 ;1
L 7.6075 1.2575 7.6075 1.2575 27 P 0 ;1
L 7.6075 1.3075 7.6075 1.3075 27 P 0 ;1
L 7.6075 1.3575 7.6075 1.3575 27 P 0 ;1
L 7.6075 1.4075 7.6075 1.4075 27 P 0 ;1
L 7.6075 1.4575 7.6075 1.4575 27 P 0 ;1
L 7.6075 1.5075 7.6075 1.5075 27 P 0 ;1
L 7.6075 1.5575 7.6075 1.5575 27 P 0 ;1
L 7.6075 1.6075 7.6075 1.6075 27 P 0 ;1
L 7.6075 1.6575 7.6075 1.6575 27 P 0 ;1
L 7.6075 1.7075 7.6075 1.7075 27 P 0 ;1
L 7.6075 1.7575 7.6075 1.7575 27 P 0 ;1
L 7.6075 1.8075 7.6075 1.8075 27 P 0 ;1
L 7.6075 1.8575 7.6075 1.8575 27 P 0 ;1
L 7.6075 1.9075 7.6075 1.9075 27 P 0 ;1
L 7.6075 1.9575 7.6075 1.9575 27 P 0 ;1
L 7.6075 2.0075 7.6075 2.0075 27 P 0 ;1
L 7.6075 2.0575 7.6075 2.0575 27 P 0 ;1
L 7.6075 2.1075 7.6075 2.1075 27 P 0 ;1
L 7.6075 2.1575 7.6075 2.1575 27 P 0 ;1
L 7.6075 2.2075 7.6075 2.2075 27 P 0 ;1
L 7.6075 2.2575 7.6075 2.2575 27 P 0 ;1
L 7.6075 2.3075 7.6075 2.3075 27 P 0 ;1
L 7.6075 2.3575 7.6075 2.3575 27 P 0 ;1
L 7.6075 2.4075 7.6075 2.4075 27 P 0 ;1
L 7.6075 2.4575 7.6075 2.4575 27 P 0 ;1
L 7.6075 2.5075 7.6075 2.5075 27 P 0 ;1
L 7.6075 2.5575 7.6075 2.5575 27 P 0 ;1
L 7.6075 2.6075 7.6075 2.6075 27 P 0 ;1
L 7.6075 2.6575 7.6075 2.6575 27 P 0 ;1
L 7.6075 2.7075 7.6075 2.7075 27 P 0 ;1
L 7.6075 2.7575 7.6075 2.7575 27 P 0 ;1
L 7.6075 2.8075 7.6075 2.8075 27 P 0 ;1
L 7.6075 2.8575 7.6075 2.8575 27 P 0 ;1
L 7.6075 2.9075 7.6075 2.9075 27 P 0 ;1
L 7.6075 2.9575 7.6075 2.9575 27 P 0 ;1
L 7.6075 3.0075 7.6075 3.0075 27 P 0 ;1
L 7.6075 3.0575 7.6075 3.0575 27 P 0 ;1
L 7.6075 3.1075 7.6075 3.1075 27 P 0 ;1
L 7.6075 3.1575 7.6075 3.1575 27 P 0 ;1
L 7.6075 3.2075 7.6075 3.2075 27 P 0 ;1
L 7.6075 3.2575 7.6075 3.2575 27 P 0 ;1
L 7.6075 3.3075 7.6075 3.3075 27 P 0 ;1
L 7.6075 3.3575 7.6075 3.3575 27 P 0 ;1
L 7.6075 3.4075 7.6075 3.4075 27 P 0 ;1
L 7.6075 3.4575 7.6075 3.4575 27 P 0 ;1
L 7.6075 3.5075 7.6075 3.5075 27 P 0 ;1
L 7.6075 3.5575 7.6075 3.5575 27 P 0 ;1
L 7.6075 3.6075 7.6075 3.6075 27 P 0 ;1
L 7.6075 3.6575 7.6075 3.6575 27 P 0 ;1
L 7.6075 3.7075 7.6075 3.7075 27 P 0 ;1
L 7.6075 3.7575 7.6075 3.7575 27 P 0 ;1
L 7.6075 3.8075 7.6075 3.8075 27 P 0 ;1
L 7.6075 3.8575 7.6075 3.8575 27 P 0 ;1
L 7.6075 3.9075 7.6075 3.9075 27 P 0 ;1
L 7.6075 3.9575 7.6075 3.9575 27 P 0 ;1
L 7.6075 4.0075 7.6075 4.0075 27 P 0 ;1
L 7.6075 4.0575 7.6075 4.0575 27 P 0 ;1
L 7.6075 4.1075 7.6075 4.1075 27 P 0 ;1
L 7.6075 4.1575 7.6075 4.1575 27 P 0 ;1
L 7.6075 4.2075 7.6075 4.2075 27 P 0 ;1
L 7.6075 4.2575 7.6075 4.2575 27 P 0 ;1
L 7.6075 4.3075 7.6075 4.3075 27 P 0 ;1
L 7.6075 4.3575 7.6075 4.3575 27 P 0 ;1
L 7.6075 4.4075 7.6075 4.4075 27 P 0 ;1
L 7.6075 4.4575 7.6075 4.4575 27 P 0 ;1
L 7.6075 4.5075 7.6075 4.5075 27 P 0 ;1
L 7.6075 4.5575 7.6075 4.5575 27 P 0 ;1
L 7.6075 5.3075 7.6075 5.3075 27 P 0 ;1
L 7.6075 5.3575 7.6075 5.3575 27 P 0 ;1
L 7.6075 5.6575 7.6075 5.6575 27 P 0 ;1
L 7.6075 5.7075 7.6075 5.7075 27 P 0 ;1
L 7.6075 5.7575 7.6075 5.7575 27 P 0 ;1
L 7.6075 5.8075 7.6075 5.8075 27 P 0 ;1
L 7.6075 5.8575 7.6075 5.8575 27 P 0 ;1
L 7.6575 0.1575 7.6575 0.1575 27 P 0 ;1
L 7.6575 0.2075 7.6575 0.2075 27 P 0 ;1
L 7.6575 0.2575 7.6575 0.2575 27 P 0 ;1
L 7.6575 0.3075 7.6575 0.3075 27 P 0 ;1
L 7.6575 0.3575 7.6575 0.3575 27 P 0 ;1
L 7.6575 0.4075 7.6575 0.4075 27 P 0 ;1
L 7.6575 0.4575 7.6575 0.4575 27 P 0 ;1
L 7.6575 0.5075 7.6575 0.5075 27 P 0 ;1
L 7.6575 0.5575 7.6575 0.5575 27 P 0 ;1
L 7.6575 0.6075 7.6575 0.6075 27 P 0 ;1
L 7.6575 0.6575 7.6575 0.6575 27 P 0 ;1
L 7.6575 0.7075 7.6575 0.7075 27 P 0 ;1
L 7.6575 0.7575 7.6575 0.7575 27 P 0 ;1
L 7.6575 0.8075 7.6575 0.8075 27 P 0 ;1
L 7.6575 0.8575 7.6575 0.8575 27 P 0 ;1
L 7.6575 0.9075 7.6575 0.9075 27 P 0 ;1
L 7.6575 0.9575 7.6575 0.9575 27 P 0 ;1
L 7.6575 1.0075 7.6575 1.0075 27 P 0 ;1
L 7.6575 1.0575 7.6575 1.0575 27 P 0 ;1
L 7.6575 1.1075 7.6575 1.1075 27 P 0 ;1
L 7.6575 1.1575 7.6575 1.1575 27 P 0 ;1
L 7.6575 1.2075 7.6575 1.2075 27 P 0 ;1
L 7.6575 1.2575 7.6575 1.2575 27 P 0 ;1
L 7.6575 1.3075 7.6575 1.3075 27 P 0 ;1
L 7.6575 1.3575 7.6575 1.3575 27 P 0 ;1
L 7.6575 1.4075 7.6575 1.4075 27 P 0 ;1
L 7.6575 1.4575 7.6575 1.4575 27 P 0 ;1
L 7.6575 1.5075 7.6575 1.5075 27 P 0 ;1
L 7.6575 1.5575 7.6575 1.5575 27 P 0 ;1
L 7.6575 1.6075 7.6575 1.6075 27 P 0 ;1
L 7.6575 1.6575 7.6575 1.6575 27 P 0 ;1
L 7.6575 1.7075 7.6575 1.7075 27 P 0 ;1
L 7.6575 1.7575 7.6575 1.7575 27 P 0 ;1
L 7.6575 1.8075 7.6575 1.8075 27 P 0 ;1
L 7.6575 1.8575 7.6575 1.8575 27 P 0 ;1
L 7.6575 1.9075 7.6575 1.9075 27 P 0 ;1
L 7.6575 1.9575 7.6575 1.9575 27 P 0 ;1
L 7.6575 2.0075 7.6575 2.0075 27 P 0 ;1
L 7.6575 2.0575 7.6575 2.0575 27 P 0 ;1
L 7.6575 2.1075 7.6575 2.1075 27 P 0 ;1
L 7.6575 2.1575 7.6575 2.1575 27 P 0 ;1
L 7.6575 2.2075 7.6575 2.2075 27 P 0 ;1
L 7.6575 2.2575 7.6575 2.2575 27 P 0 ;1
L 7.6575 2.3075 7.6575 2.3075 27 P 0 ;1
L 7.6575 2.3575 7.6575 2.3575 27 P 0 ;1
L 7.6575 2.4075 7.6575 2.4075 27 P 0 ;1
L 7.6575 2.4575 7.6575 2.4575 27 P 0 ;1
L 7.6575 2.5075 7.6575 2.5075 27 P 0 ;1
L 7.6575 2.5575 7.6575 2.5575 27 P 0 ;1
L 7.6575 2.6075 7.6575 2.6075 27 P 0 ;1
L 7.6575 2.6575 7.6575 2.6575 27 P 0 ;1
L 7.6575 2.7075 7.6575 2.7075 27 P 0 ;1
L 7.6575 2.7575 7.6575 2.7575 27 P 0 ;1
L 7.6575 2.8075 7.6575 2.8075 27 P 0 ;1
L 7.6575 2.8575 7.6575 2.8575 27 P 0 ;1
L 7.6575 2.9075 7.6575 2.9075 27 P 0 ;1
L 7.6575 2.9575 7.6575 2.9575 27 P 0 ;1
L 7.6575 3.0075 7.6575 3.0075 27 P 0 ;1
L 7.6575 3.0575 7.6575 3.0575 27 P 0 ;1
L 7.6575 3.1075 7.6575 3.1075 27 P 0 ;1
L 7.6575 3.1575 7.6575 3.1575 27 P 0 ;1
L 7.6575 3.2075 7.6575 3.2075 27 P 0 ;1
L 7.6575 3.2575 7.6575 3.2575 27 P 0 ;1
L 7.6575 3.3075 7.6575 3.3075 27 P 0 ;1
L 7.6575 3.3575 7.6575 3.3575 27 P 0 ;1
L 7.6575 3.4075 7.6575 3.4075 27 P 0 ;1
L 7.6575 3.4575 7.6575 3.4575 27 P 0 ;1
L 7.6575 3.5075 7.6575 3.5075 27 P 0 ;1
L 7.6575 3.5575 7.6575 3.5575 27 P 0 ;1
L 7.6575 3.6075 7.6575 3.6075 27 P 0 ;1
L 7.6575 3.6575 7.6575 3.6575 27 P 0 ;1
L 7.6575 3.7075 7.6575 3.7075 27 P 0 ;1
L 7.6575 3.7575 7.6575 3.7575 27 P 0 ;1
L 7.6575 3.8075 7.6575 3.8075 27 P 0 ;1
L 7.6575 3.8575 7.6575 3.8575 27 P 0 ;1
L 7.6575 3.9075 7.6575 3.9075 27 P 0 ;1
L 7.6575 3.9575 7.6575 3.9575 27 P 0 ;1
L 7.6575 4.0075 7.6575 4.0075 27 P 0 ;1
L 7.6575 4.0575 7.6575 4.0575 27 P 0 ;1
L 7.6575 4.1075 7.6575 4.1075 27 P 0 ;1
L 7.6575 4.1575 7.6575 4.1575 27 P 0 ;1
L 7.6575 4.2075 7.6575 4.2075 27 P 0 ;1
L 7.6575 4.2575 7.6575 4.2575 27 P 0 ;1
L 7.6575 4.3075 7.6575 4.3075 27 P 0 ;1
L 7.6575 4.3575 7.6575 4.3575 27 P 0 ;1
L 7.6575 4.4075 7.6575 4.4075 27 P 0 ;1
L 7.6575 4.4575 7.6575 4.4575 27 P 0 ;1
L 7.6575 4.5075 7.6575 4.5075 27 P 0 ;1
L 7.6575 4.5575 7.6575 4.5575 27 P 0 ;1
L 7.6575 5.2575 7.6575 5.2575 27 P 0 ;1
L 7.6575 5.3075 7.6575 5.3075 27 P 0 ;1
L 7.6575 5.3575 7.6575 5.3575 27 P 0 ;1
L 7.6575 5.6575 7.6575 5.6575 27 P 0 ;1
L 7.6575 5.7075 7.6575 5.7075 27 P 0 ;1
L 7.6575 5.7575 7.6575 5.7575 27 P 0 ;1
L 7.6575 5.8075 7.6575 5.8075 27 P 0 ;1
L 7.6575 5.8575 7.6575 5.8575 27 P 0 ;1
L 7.7075 0.1575 7.7075 0.1575 27 P 0 ;1
L 7.7075 0.2075 7.7075 0.2075 27 P 0 ;1
L 7.7075 0.2575 7.7075 0.2575 27 P 0 ;1
L 7.7075 0.3075 7.7075 0.3075 27 P 0 ;1
L 7.7075 0.3575 7.7075 0.3575 27 P 0 ;1
L 7.7075 0.4075 7.7075 0.4075 27 P 0 ;1
L 7.7075 0.4575 7.7075 0.4575 27 P 0 ;1
L 7.7075 0.5075 7.7075 0.5075 27 P 0 ;1
L 7.7075 0.5575 7.7075 0.5575 27 P 0 ;1
L 7.7075 0.6075 7.7075 0.6075 27 P 0 ;1
L 7.7075 0.6575 7.7075 0.6575 27 P 0 ;1
L 7.7075 0.7075 7.7075 0.7075 27 P 0 ;1
L 7.7075 0.7575 7.7075 0.7575 27 P 0 ;1
L 7.7075 0.8075 7.7075 0.8075 27 P 0 ;1
L 7.7075 0.8575 7.7075 0.8575 27 P 0 ;1
L 7.7075 0.9075 7.7075 0.9075 27 P 0 ;1
L 7.7075 0.9575 7.7075 0.9575 27 P 0 ;1
L 7.7075 1.0075 7.7075 1.0075 27 P 0 ;1
L 7.7075 1.0575 7.7075 1.0575 27 P 0 ;1
L 7.7075 1.1075 7.7075 1.1075 27 P 0 ;1
L 7.7075 1.1575 7.7075 1.1575 27 P 0 ;1
L 7.7075 1.2075 7.7075 1.2075 27 P 0 ;1
L 7.7075 1.2575 7.7075 1.2575 27 P 0 ;1
L 7.7075 1.3075 7.7075 1.3075 27 P 0 ;1
L 7.7075 1.3575 7.7075 1.3575 27 P 0 ;1
L 7.7075 1.4075 7.7075 1.4075 27 P 0 ;1
L 7.7075 1.4575 7.7075 1.4575 27 P 0 ;1
L 7.7075 1.5075 7.7075 1.5075 27 P 0 ;1
L 7.7075 1.5575 7.7075 1.5575 27 P 0 ;1
L 7.7075 1.6075 7.7075 1.6075 27 P 0 ;1
L 7.7075 1.6575 7.7075 1.6575 27 P 0 ;1
L 7.7075 1.7075 7.7075 1.7075 27 P 0 ;1
L 7.7075 1.7575 7.7075 1.7575 27 P 0 ;1
L 7.7075 1.8075 7.7075 1.8075 27 P 0 ;1
L 7.7075 1.8575 7.7075 1.8575 27 P 0 ;1
L 7.7075 1.9075 7.7075 1.9075 27 P 0 ;1
L 7.7075 1.9575 7.7075 1.9575 27 P 0 ;1
L 7.7075 2.0075 7.7075 2.0075 27 P 0 ;1
L 7.7075 2.0575 7.7075 2.0575 27 P 0 ;1
L 7.7075 2.1075 7.7075 2.1075 27 P 0 ;1
L 7.7075 2.1575 7.7075 2.1575 27 P 0 ;1
L 7.7075 2.2075 7.7075 2.2075 27 P 0 ;1
L 7.7075 2.2575 7.7075 2.2575 27 P 0 ;1
L 7.7075 2.3075 7.7075 2.3075 27 P 0 ;1
L 7.7075 2.3575 7.7075 2.3575 27 P 0 ;1
L 7.7075 2.4075 7.7075 2.4075 27 P 0 ;1
L 7.7075 2.5575 7.7075 2.5575 27 P 0 ;1
L 7.7075 2.6075 7.7075 2.6075 27 P 0 ;1
L 7.7075 2.6575 7.7075 2.6575 27 P 0 ;1
L 7.7075 2.7075 7.7075 2.7075 27 P 0 ;1
L 7.7075 2.7575 7.7075 2.7575 27 P 0 ;1
L 7.7075 2.8075 7.7075 2.8075 27 P 0 ;1
L 7.7075 2.8575 7.7075 2.8575 27 P 0 ;1
L 7.7075 2.9075 7.7075 2.9075 27 P 0 ;1
L 7.7075 2.9575 7.7075 2.9575 27 P 0 ;1
L 7.7075 3.0075 7.7075 3.0075 27 P 0 ;1
L 7.7075 3.0575 7.7075 3.0575 27 P 0 ;1
L 7.7075 3.1075 7.7075 3.1075 27 P 0 ;1
L 7.7075 3.1575 7.7075 3.1575 27 P 0 ;1
L 7.7075 3.2075 7.7075 3.2075 27 P 0 ;1
L 7.7075 3.2575 7.7075 3.2575 27 P 0 ;1
L 7.7075 3.3075 7.7075 3.3075 27 P 0 ;1
L 7.7075 3.3575 7.7075 3.3575 27 P 0 ;1
L 7.7075 3.4075 7.7075 3.4075 27 P 0 ;1
L 7.7075 3.4575 7.7075 3.4575 27 P 0 ;1
L 7.7075 3.5075 7.7075 3.5075 27 P 0 ;1
L 7.7075 3.5575 7.7075 3.5575 27 P 0 ;1
L 7.7075 3.6075 7.7075 3.6075 27 P 0 ;1
L 7.7075 3.6575 7.7075 3.6575 27 P 0 ;1
L 7.7075 3.7075 7.7075 3.7075 27 P 0 ;1
L 7.7075 3.7575 7.7075 3.7575 27 P 0 ;1
L 7.7075 3.8075 7.7075 3.8075 27 P 0 ;1
L 7.7075 3.8575 7.7075 3.8575 27 P 0 ;1
L 7.7075 3.9075 7.7075 3.9075 27 P 0 ;1
L 7.7075 3.9575 7.7075 3.9575 27 P 0 ;1
L 7.7075 4.0075 7.7075 4.0075 27 P 0 ;1
L 7.7075 4.0575 7.7075 4.0575 27 P 0 ;1
L 7.7075 4.1075 7.7075 4.1075 27 P 0 ;1
L 7.7075 4.1575 7.7075 4.1575 27 P 0 ;1
L 7.7075 4.2075 7.7075 4.2075 27 P 0 ;1
L 7.7075 4.2575 7.7075 4.2575 27 P 0 ;1
L 7.7075 4.3075 7.7075 4.3075 27 P 0 ;1
L 7.7075 4.3575 7.7075 4.3575 27 P 0 ;1
L 7.7075 4.5075 7.7075 4.5075 27 P 0 ;1
L 7.7075 4.5575 7.7075 4.5575 27 P 0 ;1
L 7.7075 4.6075 7.7075 4.6075 27 P 0 ;1
L 7.7075 5.2075 7.7075 5.2075 27 P 0 ;1
L 7.7075 5.2575 7.7075 5.2575 27 P 0 ;1
L 7.7075 5.3075 7.7075 5.3075 27 P 0 ;1
L 7.7075 5.3575 7.7075 5.3575 27 P 0 ;1
L 7.7075 5.6575 7.7075 5.6575 27 P 0 ;1
L 7.7075 5.7075 7.7075 5.7075 27 P 0 ;1
L 7.7075 5.7575 7.7075 5.7575 27 P 0 ;1
L 7.7075 5.8075 7.7075 5.8075 27 P 0 ;1
L 7.7075 5.8575 7.7075 5.8575 27 P 0 ;1
L 7.7575 0.1575 7.7575 0.1575 27 P 0 ;1
L 7.7575 0.2075 7.7575 0.2075 27 P 0 ;1
L 7.7575 0.2575 7.7575 0.2575 27 P 0 ;1
L 7.7575 0.3075 7.7575 0.3075 27 P 0 ;1
L 7.7575 0.3575 7.7575 0.3575 27 P 0 ;1
L 7.7575 0.4075 7.7575 0.4075 27 P 0 ;1
L 7.7575 0.4575 7.7575 0.4575 27 P 0 ;1
L 7.7575 0.5075 7.7575 0.5075 27 P 0 ;1
L 7.7575 0.5575 7.7575 0.5575 27 P 0 ;1
L 7.7575 0.6075 7.7575 0.6075 27 P 0 ;1
L 7.7575 0.6575 7.7575 0.6575 27 P 0 ;1
L 7.7575 0.7075 7.7575 0.7075 27 P 0 ;1
L 7.7575 0.7575 7.7575 0.7575 27 P 0 ;1
L 7.7575 0.8075 7.7575 0.8075 27 P 0 ;1
L 7.7575 0.8575 7.7575 0.8575 27 P 0 ;1
L 7.7575 0.9075 7.7575 0.9075 27 P 0 ;1
L 7.7575 0.9575 7.7575 0.9575 27 P 0 ;1
L 7.7575 1.0075 7.7575 1.0075 27 P 0 ;1
L 7.7575 1.0575 7.7575 1.0575 27 P 0 ;1
L 7.7575 1.1075 7.7575 1.1075 27 P 0 ;1
L 7.7575 1.1575 7.7575 1.1575 27 P 0 ;1
L 7.7575 1.2075 7.7575 1.2075 27 P 0 ;1
L 7.7575 1.2575 7.7575 1.2575 27 P 0 ;1
L 7.7575 1.3075 7.7575 1.3075 27 P 0 ;1
L 7.7575 1.3575 7.7575 1.3575 27 P 0 ;1
L 7.7575 1.4075 7.7575 1.4075 27 P 0 ;1
L 7.7575 1.4575 7.7575 1.4575 27 P 0 ;1
L 7.7575 1.5075 7.7575 1.5075 27 P 0 ;1
L 7.7575 1.5575 7.7575 1.5575 27 P 0 ;1
L 7.7575 1.6075 7.7575 1.6075 27 P 0 ;1
L 7.7575 1.6575 7.7575 1.6575 27 P 0 ;1
L 7.7575 1.7075 7.7575 1.7075 27 P 0 ;1
L 7.7575 1.7575 7.7575 1.7575 27 P 0 ;1
L 7.7575 1.8075 7.7575 1.8075 27 P 0 ;1
L 7.7575 1.8575 7.7575 1.8575 27 P 0 ;1
L 7.7575 1.9075 7.7575 1.9075 27 P 0 ;1
L 7.7575 1.9575 7.7575 1.9575 27 P 0 ;1
L 7.7575 2.0075 7.7575 2.0075 27 P 0 ;1
L 7.7575 2.0575 7.7575 2.0575 27 P 0 ;1
L 7.7575 2.1075 7.7575 2.1075 27 P 0 ;1
L 7.7575 2.1575 7.7575 2.1575 27 P 0 ;1
L 7.7575 2.2075 7.7575 2.2075 27 P 0 ;1
L 7.7575 2.2575 7.7575 2.2575 27 P 0 ;1
L 7.7575 2.3075 7.7575 2.3075 27 P 0 ;1
L 7.7575 2.3575 7.7575 2.3575 27 P 0 ;1
L 7.7575 2.6075 7.7575 2.6075 27 P 0 ;1
L 7.7575 2.6575 7.7575 2.6575 27 P 0 ;1
L 7.7575 2.7075 7.7575 2.7075 27 P 0 ;1
L 7.7575 2.7575 7.7575 2.7575 27 P 0 ;1
L 7.7575 2.8075 7.7575 2.8075 27 P 0 ;1
L 7.7575 2.8575 7.7575 2.8575 27 P 0 ;1
L 7.7575 2.9075 7.7575 2.9075 27 P 0 ;1
L 7.7575 2.9575 7.7575 2.9575 27 P 0 ;1
L 7.7575 3.0075 7.7575 3.0075 27 P 0 ;1
L 7.7575 3.0575 7.7575 3.0575 27 P 0 ;1
L 7.7575 3.1075 7.7575 3.1075 27 P 0 ;1
L 7.7575 3.1575 7.7575 3.1575 27 P 0 ;1
L 7.7575 3.2075 7.7575 3.2075 27 P 0 ;1
L 7.7575 3.2575 7.7575 3.2575 27 P 0 ;1
L 7.7575 3.3075 7.7575 3.3075 27 P 0 ;1
L 7.7575 3.3575 7.7575 3.3575 27 P 0 ;1
L 7.7575 3.4075 7.7575 3.4075 27 P 0 ;1
L 7.7575 3.4575 7.7575 3.4575 27 P 0 ;1
L 7.7575 3.5075 7.7575 3.5075 27 P 0 ;1
L 7.7575 3.5575 7.7575 3.5575 27 P 0 ;1
L 7.7575 3.6075 7.7575 3.6075 27 P 0 ;1
L 7.7575 3.6575 7.7575 3.6575 27 P 0 ;1
L 7.7575 3.7075 7.7575 3.7075 27 P 0 ;1
L 7.7575 3.7575 7.7575 3.7575 27 P 0 ;1
L 7.7575 3.8075 7.7575 3.8075 27 P 0 ;1
L 7.7575 3.8575 7.7575 3.8575 27 P 0 ;1
L 7.7575 3.9075 7.7575 3.9075 27 P 0 ;1
L 7.7575 3.9575 7.7575 3.9575 27 P 0 ;1
L 7.7575 4.0075 7.7575 4.0075 27 P 0 ;1
L 7.7575 4.0575 7.7575 4.0575 27 P 0 ;1
L 7.7575 4.1075 7.7575 4.1075 27 P 0 ;1
L 7.7575 4.1575 7.7575 4.1575 27 P 0 ;1
L 7.7575 4.2075 7.7575 4.2075 27 P 0 ;1
L 7.7575 4.2575 7.7575 4.2575 27 P 0 ;1
L 7.7575 4.3075 7.7575 4.3075 27 P 0 ;1
L 7.7575 4.5575 7.7575 4.5575 27 P 0 ;1
L 7.7575 4.6075 7.7575 4.6075 27 P 0 ;1
L 7.7575 5.2075 7.7575 5.2075 27 P 0 ;1
L 7.7575 5.2575 7.7575 5.2575 27 P 0 ;1
L 7.7575 5.3075 7.7575 5.3075 27 P 0 ;1
L 7.7575 5.3575 7.7575 5.3575 27 P 0 ;1
L 7.7575 5.6575 7.7575 5.6575 27 P 0 ;1
L 7.7575 5.7075 7.7575 5.7075 27 P 0 ;1
L 7.7575 5.7575 7.7575 5.7575 27 P 0 ;1
L 7.7575 5.8075 7.7575 5.8075 27 P 0 ;1
L 7.7575 5.8575 7.7575 5.8575 27 P 0 ;1
L 7.8075 0.1575 7.8075 0.1575 27 P 0 ;1
L 7.8075 0.2075 7.8075 0.2075 27 P 0 ;1
L 7.8075 0.2575 7.8075 0.2575 27 P 0 ;1
L 7.8075 0.3075 7.8075 0.3075 27 P 0 ;1
L 7.8075 0.3575 7.8075 0.3575 27 P 0 ;1
L 7.8075 0.4075 7.8075 0.4075 27 P 0 ;1
L 7.8075 0.4575 7.8075 0.4575 27 P 0 ;1
L 7.8075 0.5075 7.8075 0.5075 27 P 0 ;1
L 7.8075 0.5575 7.8075 0.5575 27 P 0 ;1
L 7.8075 0.6075 7.8075 0.6075 27 P 0 ;1
L 7.8075 0.6575 7.8075 0.6575 27 P 0 ;1
L 7.8075 0.7075 7.8075 0.7075 27 P 0 ;1
L 7.8075 0.7575 7.8075 0.7575 27 P 0 ;1
L 7.8075 0.8075 7.8075 0.8075 27 P 0 ;1
L 7.8075 0.8575 7.8075 0.8575 27 P 0 ;1
L 7.8075 0.9075 7.8075 0.9075 27 P 0 ;1
L 7.8075 0.9575 7.8075 0.9575 27 P 0 ;1
L 7.8075 1.0075 7.8075 1.0075 27 P 0 ;1
L 7.8075 1.0575 7.8075 1.0575 27 P 0 ;1
L 7.8075 1.1075 7.8075 1.1075 27 P 0 ;1
L 7.8075 1.1575 7.8075 1.1575 27 P 0 ;1
L 7.8075 1.2075 7.8075 1.2075 27 P 0 ;1
L 7.8075 1.2575 7.8075 1.2575 27 P 0 ;1
L 7.8075 1.3075 7.8075 1.3075 27 P 0 ;1
L 7.8075 1.3575 7.8075 1.3575 27 P 0 ;1
L 7.8075 1.4075 7.8075 1.4075 27 P 0 ;1
L 7.8075 1.4575 7.8075 1.4575 27 P 0 ;1
L 7.8075 1.5075 7.8075 1.5075 27 P 0 ;1
L 7.8075 1.5575 7.8075 1.5575 27 P 0 ;1
L 7.8075 1.6075 7.8075 1.6075 27 P 0 ;1
L 7.8075 1.6575 7.8075 1.6575 27 P 0 ;1
L 7.8075 1.7075 7.8075 1.7075 27 P 0 ;1
L 7.8075 1.7575 7.8075 1.7575 27 P 0 ;1
L 7.8075 1.8075 7.8075 1.8075 27 P 0 ;1
L 7.8075 1.8575 7.8075 1.8575 27 P 0 ;1
L 7.8075 1.9075 7.8075 1.9075 27 P 0 ;1
L 7.8075 1.9575 7.8075 1.9575 27 P 0 ;1
L 7.8075 2.0075 7.8075 2.0075 27 P 0 ;1
L 7.8075 2.0575 7.8075 2.0575 27 P 0 ;1
L 7.8075 2.1075 7.8075 2.1075 27 P 0 ;1
L 7.8075 2.1575 7.8075 2.1575 27 P 0 ;1
L 7.8075 2.2075 7.8075 2.2075 27 P 0 ;1
L 7.8075 2.2575 7.8075 2.2575 27 P 0 ;1
L 7.8075 2.3075 7.8075 2.3075 27 P 0 ;1
L 7.8075 2.3575 7.8075 2.3575 27 P 0 ;1
L 7.8075 2.6075 7.8075 2.6075 27 P 0 ;1
L 7.8075 2.6575 7.8075 2.6575 27 P 0 ;1
L 7.8075 2.7075 7.8075 2.7075 27 P 0 ;1
L 7.8075 2.7575 7.8075 2.7575 27 P 0 ;1
L 7.8075 2.8075 7.8075 2.8075 27 P 0 ;1
L 7.8075 2.8575 7.8075 2.8575 27 P 0 ;1
L 7.8075 2.9075 7.8075 2.9075 27 P 0 ;1
L 7.8075 2.9575 7.8075 2.9575 27 P 0 ;1
L 7.8075 3.0075 7.8075 3.0075 27 P 0 ;1
L 7.8075 3.0575 7.8075 3.0575 27 P 0 ;1
L 7.8075 3.1075 7.8075 3.1075 27 P 0 ;1
L 7.8075 3.1575 7.8075 3.1575 27 P 0 ;1
L 7.8075 3.2075 7.8075 3.2075 27 P 0 ;1
L 7.8075 3.2575 7.8075 3.2575 27 P 0 ;1
L 7.8075 3.3075 7.8075 3.3075 27 P 0 ;1
L 7.8075 3.3575 7.8075 3.3575 27 P 0 ;1
L 7.8075 3.4075 7.8075 3.4075 27 P 0 ;1
L 7.8075 3.4575 7.8075 3.4575 27 P 0 ;1
L 7.8075 3.5075 7.8075 3.5075 27 P 0 ;1
L 7.8075 3.5575 7.8075 3.5575 27 P 0 ;1
L 7.8075 3.6075 7.8075 3.6075 27 P 0 ;1
L 7.8075 3.6575 7.8075 3.6575 27 P 0 ;1
L 7.8075 3.7075 7.8075 3.7075 27 P 0 ;1
L 7.8075 3.7575 7.8075 3.7575 27 P 0 ;1
L 7.8075 3.8075 7.8075 3.8075 27 P 0 ;1
L 7.8075 3.8575 7.8075 3.8575 27 P 0 ;1
L 7.8075 3.9075 7.8075 3.9075 27 P 0 ;1
L 7.8075 3.9575 7.8075 3.9575 27 P 0 ;1
L 7.8075 4.0075 7.8075 4.0075 27 P 0 ;1
L 7.8075 4.0575 7.8075 4.0575 27 P 0 ;1
L 7.8075 4.1075 7.8075 4.1075 27 P 0 ;1
L 7.8075 4.1575 7.8075 4.1575 27 P 0 ;1
L 7.8075 4.2075 7.8075 4.2075 27 P 0 ;1
L 7.8075 4.2575 7.8075 4.2575 27 P 0 ;1
L 7.8075 4.3075 7.8075 4.3075 27 P 0 ;1
L 7.8075 5.2575 7.8075 5.2575 27 P 0 ;1
L 7.8075 5.3075 7.8075 5.3075 27 P 0 ;1
L 7.8075 5.3575 7.8075 5.3575 27 P 0 ;1
L 7.8075 5.6575 7.8075 5.6575 27 P 0 ;1
L 7.8075 5.7075 7.8075 5.7075 27 P 0 ;1
L 7.8075 5.7575 7.8075 5.7575 27 P 0 ;1
L 7.8075 5.8075 7.8075 5.8075 27 P 0 ;1
L 7.8075 5.8575 7.8075 5.8575 27 P 0 ;1
L 7.8575 0.1575 7.8575 0.1575 27 P 0 ;1
L 7.8575 0.2075 7.8575 0.2075 27 P 0 ;1
L 7.8575 0.2575 7.8575 0.2575 27 P 0 ;1
L 7.8575 0.3075 7.8575 0.3075 27 P 0 ;1
L 7.8575 0.3575 7.8575 0.3575 27 P 0 ;1
L 7.8575 0.4075 7.8575 0.4075 27 P 0 ;1
L 7.8575 0.4575 7.8575 0.4575 27 P 0 ;1
L 7.8575 0.5075 7.8575 0.5075 27 P 0 ;1
L 7.8575 0.5575 7.8575 0.5575 27 P 0 ;1
L 7.8575 0.6075 7.8575 0.6075 27 P 0 ;1
L 7.8575 0.6575 7.8575 0.6575 27 P 0 ;1
L 7.8575 0.7075 7.8575 0.7075 27 P 0 ;1
L 7.8575 0.7575 7.8575 0.7575 27 P 0 ;1
L 7.8575 0.8075 7.8575 0.8075 27 P 0 ;1
L 7.8575 0.8575 7.8575 0.8575 27 P 0 ;1
L 7.8575 0.9075 7.8575 0.9075 27 P 0 ;1
L 7.8575 0.9575 7.8575 0.9575 27 P 0 ;1
L 7.8575 1.0075 7.8575 1.0075 27 P 0 ;1
L 7.8575 1.0575 7.8575 1.0575 27 P 0 ;1
L 7.8575 1.1075 7.8575 1.1075 27 P 0 ;1
L 7.8575 1.1575 7.8575 1.1575 27 P 0 ;1
L 7.8575 1.2075 7.8575 1.2075 27 P 0 ;1
L 7.8575 1.2575 7.8575 1.2575 27 P 0 ;1
L 7.8575 1.3075 7.8575 1.3075 27 P 0 ;1
L 7.8575 1.3575 7.8575 1.3575 27 P 0 ;1
L 7.8575 1.4075 7.8575 1.4075 27 P 0 ;1
L 7.8575 1.4575 7.8575 1.4575 27 P 0 ;1
L 7.8575 1.5075 7.8575 1.5075 27 P 0 ;1
L 7.8575 1.5575 7.8575 1.5575 27 P 0 ;1
L 7.8575 1.6075 7.8575 1.6075 27 P 0 ;1
L 7.8575 1.6575 7.8575 1.6575 27 P 0 ;1
L 7.8575 1.7075 7.8575 1.7075 27 P 0 ;1
L 7.8575 1.7575 7.8575 1.7575 27 P 0 ;1
L 7.8575 1.8075 7.8575 1.8075 27 P 0 ;1
L 7.8575 1.8575 7.8575 1.8575 27 P 0 ;1
L 7.8575 1.9075 7.8575 1.9075 27 P 0 ;1
L 7.8575 1.9575 7.8575 1.9575 27 P 0 ;1
L 7.8575 2.0075 7.8575 2.0075 27 P 0 ;1
L 7.8575 2.0575 7.8575 2.0575 27 P 0 ;1
L 7.8575 2.1075 7.8575 2.1075 27 P 0 ;1
L 7.8575 2.1575 7.8575 2.1575 27 P 0 ;1
L 7.8575 2.2075 7.8575 2.2075 27 P 0 ;1
L 7.8575 2.2575 7.8575 2.2575 27 P 0 ;1
L 7.8575 2.3075 7.8575 2.3075 27 P 0 ;1
L 7.8575 2.3575 7.8575 2.3575 27 P 0 ;1
L 7.8575 2.4075 7.8575 2.4075 27 P 0 ;1
L 7.8575 2.5575 7.8575 2.5575 27 P 0 ;1
L 7.8575 2.6075 7.8575 2.6075 27 P 0 ;1
L 7.8575 2.6575 7.8575 2.6575 27 P 0 ;1
L 7.8575 2.7075 7.8575 2.7075 27 P 0 ;1
L 7.8575 2.7575 7.8575 2.7575 27 P 0 ;1
L 7.8575 2.8075 7.8575 2.8075 27 P 0 ;1
L 7.8575 2.8575 7.8575 2.8575 27 P 0 ;1
L 7.8575 2.9075 7.8575 2.9075 27 P 0 ;1
L 7.8575 2.9575 7.8575 2.9575 27 P 0 ;1
L 7.8575 3.0075 7.8575 3.0075 27 P 0 ;1
L 7.8575 3.0575 7.8575 3.0575 27 P 0 ;1
L 7.8575 3.1075 7.8575 3.1075 27 P 0 ;1
L 7.8575 3.1575 7.8575 3.1575 27 P 0 ;1
L 7.8575 3.2075 7.8575 3.2075 27 P 0 ;1
L 7.8575 3.2575 7.8575 3.2575 27 P 0 ;1
L 7.8575 3.3075 7.8575 3.3075 27 P 0 ;1
L 7.8575 3.3575 7.8575 3.3575 27 P 0 ;1
L 7.8575 3.4075 7.8575 3.4075 27 P 0 ;1
L 7.8575 3.4575 7.8575 3.4575 27 P 0 ;1
L 7.8575 3.5075 7.8575 3.5075 27 P 0 ;1
L 7.8575 3.5575 7.8575 3.5575 27 P 0 ;1
L 7.8575 3.6075 7.8575 3.6075 27 P 0 ;1
L 7.8575 3.6575 7.8575 3.6575 27 P 0 ;1
L 7.8575 3.7075 7.8575 3.7075 27 P 0 ;1
L 7.8575 3.7575 7.8575 3.7575 27 P 0 ;1
L 7.8575 3.8075 7.8575 3.8075 27 P 0 ;1
L 7.8575 3.8575 7.8575 3.8575 27 P 0 ;1
L 7.8575 3.9075 7.8575 3.9075 27 P 0 ;1
L 7.8575 3.9575 7.8575 3.9575 27 P 0 ;1
L 7.8575 4.0075 7.8575 4.0075 27 P 0 ;1
L 7.8575 4.0575 7.8575 4.0575 27 P 0 ;1
L 7.8575 4.1075 7.8575 4.1075 27 P 0 ;1
L 7.8575 4.1575 7.8575 4.1575 27 P 0 ;1
L 7.8575 4.2075 7.8575 4.2075 27 P 0 ;1
L 7.8575 4.2575 7.8575 4.2575 27 P 0 ;1
L 7.8575 4.3075 7.8575 4.3075 27 P 0 ;1
L 7.8575 5.3075 7.8575 5.3075 27 P 0 ;1
L 7.8575 5.6575 7.8575 5.6575 27 P 0 ;1
L 7.8575 5.7075 7.8575 5.7075 27 P 0 ;1
L 7.8575 5.7575 7.8575 5.7575 27 P 0 ;1
L 7.8575 5.8075 7.8575 5.8075 27 P 0 ;1
L 7.8575 5.8575 7.8575 5.8575 27 P 0 ;1
L 7.9075 0.1575 7.9075 0.1575 27 P 0 ;1
L 7.9075 0.2075 7.9075 0.2075 27 P 0 ;1
L 7.9075 0.2575 7.9075 0.2575 27 P 0 ;1
L 7.9075 0.3075 7.9075 0.3075 27 P 0 ;1
L 7.9075 0.3575 7.9075 0.3575 27 P 0 ;1
L 7.9075 0.4075 7.9075 0.4075 27 P 0 ;1
L 7.9075 0.4575 7.9075 0.4575 27 P 0 ;1
L 7.9075 0.5075 7.9075 0.5075 27 P 0 ;1
L 7.9075 0.5575 7.9075 0.5575 27 P 0 ;1
L 7.9075 0.6075 7.9075 0.6075 27 P 0 ;1
L 7.9075 0.6575 7.9075 0.6575 27 P 0 ;1
L 7.9075 0.7075 7.9075 0.7075 27 P 0 ;1
L 7.9075 0.7575 7.9075 0.7575 27 P 0 ;1
L 7.9075 0.8075 7.9075 0.8075 27 P 0 ;1
L 7.9075 0.8575 7.9075 0.8575 27 P 0 ;1
L 7.9075 0.9075 7.9075 0.9075 27 P 0 ;1
L 7.9075 0.9575 7.9075 0.9575 27 P 0 ;1
L 7.9075 1.0075 7.9075 1.0075 27 P 0 ;1
L 7.9075 1.0575 7.9075 1.0575 27 P 0 ;1
L 7.9075 1.1075 7.9075 1.1075 27 P 0 ;1
L 7.9075 1.1575 7.9075 1.1575 27 P 0 ;1
L 7.9075 1.2075 7.9075 1.2075 27 P 0 ;1
L 7.9075 1.2575 7.9075 1.2575 27 P 0 ;1
L 7.9075 1.3075 7.9075 1.3075 27 P 0 ;1
L 7.9075 1.3575 7.9075 1.3575 27 P 0 ;1
L 7.9075 1.4075 7.9075 1.4075 27 P 0 ;1
L 7.9075 1.4575 7.9075 1.4575 27 P 0 ;1
L 7.9075 1.5075 7.9075 1.5075 27 P 0 ;1
L 7.9075 1.5575 7.9075 1.5575 27 P 0 ;1
L 7.9075 1.6075 7.9075 1.6075 27 P 0 ;1
L 7.9075 1.6575 7.9075 1.6575 27 P 0 ;1
L 7.9075 1.7075 7.9075 1.7075 27 P 0 ;1
L 7.9075 1.7575 7.9075 1.7575 27 P 0 ;1
L 7.9075 1.8075 7.9075 1.8075 27 P 0 ;1
L 7.9075 1.8575 7.9075 1.8575 27 P 0 ;1
L 7.9075 1.9075 7.9075 1.9075 27 P 0 ;1
L 7.9075 1.9575 7.9075 1.9575 27 P 0 ;1
L 7.9075 2.0075 7.9075 2.0075 27 P 0 ;1
L 7.9075 2.0575 7.9075 2.0575 27 P 0 ;1
L 7.9075 2.1075 7.9075 2.1075 27 P 0 ;1
L 7.9075 2.1575 7.9075 2.1575 27 P 0 ;1
L 7.9075 2.2075 7.9075 2.2075 27 P 0 ;1
L 7.9075 2.2575 7.9075 2.2575 27 P 0 ;1
L 7.9075 2.3075 7.9075 2.3075 27 P 0 ;1
L 7.9075 2.3575 7.9075 2.3575 27 P 0 ;1
L 7.9075 2.4075 7.9075 2.4075 27 P 0 ;1
L 7.9075 2.4575 7.9075 2.4575 27 P 0 ;1
L 7.9075 2.5075 7.9075 2.5075 27 P 0 ;1
L 7.9075 2.5575 7.9075 2.5575 27 P 0 ;1
L 7.9075 2.6075 7.9075 2.6075 27 P 0 ;1
L 7.9075 2.6575 7.9075 2.6575 27 P 0 ;1
L 7.9075 2.7075 7.9075 2.7075 27 P 0 ;1
L 7.9075 2.7575 7.9075 2.7575 27 P 0 ;1
L 7.9075 2.8075 7.9075 2.8075 27 P 0 ;1
L 7.9075 2.8575 7.9075 2.8575 27 P 0 ;1
L 7.9075 2.9075 7.9075 2.9075 27 P 0 ;1
L 7.9075 2.9575 7.9075 2.9575 27 P 0 ;1
L 7.9075 3.0075 7.9075 3.0075 27 P 0 ;1
L 7.9075 3.0575 7.9075 3.0575 27 P 0 ;1
L 7.9075 3.1075 7.9075 3.1075 27 P 0 ;1
L 7.9075 3.1575 7.9075 3.1575 27 P 0 ;1
L 7.9075 3.2075 7.9075 3.2075 27 P 0 ;1
L 7.9075 3.2575 7.9075 3.2575 27 P 0 ;1
L 7.9075 3.3075 7.9075 3.3075 27 P 0 ;1
L 7.9075 3.3575 7.9075 3.3575 27 P 0 ;1
L 7.9075 3.4075 7.9075 3.4075 27 P 0 ;1
L 7.9075 3.4575 7.9075 3.4575 27 P 0 ;1
L 7.9075 3.5075 7.9075 3.5075 27 P 0 ;1
L 7.9075 3.5575 7.9075 3.5575 27 P 0 ;1
L 7.9075 3.6075 7.9075 3.6075 27 P 0 ;1
L 7.9075 3.6575 7.9075 3.6575 27 P 0 ;1
L 7.9075 3.7075 7.9075 3.7075 27 P 0 ;1
L 7.9075 3.7575 7.9075 3.7575 27 P 0 ;1
L 7.9075 3.8075 7.9075 3.8075 27 P 0 ;1
L 7.9075 3.8575 7.9075 3.8575 27 P 0 ;1
L 7.9075 3.9075 7.9075 3.9075 27 P 0 ;1
L 7.9075 3.9575 7.9075 3.9575 27 P 0 ;1
L 7.9075 4.0075 7.9075 4.0075 27 P 0 ;1
L 7.9075 4.0575 7.9075 4.0575 27 P 0 ;1
L 7.9075 4.1075 7.9075 4.1075 27 P 0 ;1
L 7.9075 4.1575 7.9075 4.1575 27 P 0 ;1
L 7.9075 4.2075 7.9075 4.2075 27 P 0 ;1
L 7.9075 4.2575 7.9075 4.2575 27 P 0 ;1
L 7.9075 4.3075 7.9075 4.3075 27 P 0 ;1
L 7.9075 5.6575 7.9075 5.6575 27 P 0 ;1
L 7.9075 5.7075 7.9075 5.7075 27 P 0 ;1
L 7.9075 5.7575 7.9075 5.7575 27 P 0 ;1
L 7.9075 5.8075 7.9075 5.8075 27 P 0 ;1
L 7.9075 5.8575 7.9075 5.8575 27 P 0 ;1
L 7.9575 0.1575 7.9575 0.1575 27 P 0 ;1
L 7.9575 0.2075 7.9575 0.2075 27 P 0 ;1
L 7.9575 0.2575 7.9575 0.2575 27 P 0 ;1
L 7.9575 0.3075 7.9575 0.3075 27 P 0 ;1
L 7.9575 0.3575 7.9575 0.3575 27 P 0 ;1
L 7.9575 0.4075 7.9575 0.4075 27 P 0 ;1
L 7.9575 0.4575 7.9575 0.4575 27 P 0 ;1
L 7.9575 0.5075 7.9575 0.5075 27 P 0 ;1
L 7.9575 0.5575 7.9575 0.5575 27 P 0 ;1
L 7.9575 0.6075 7.9575 0.6075 27 P 0 ;1
L 7.9575 0.6575 7.9575 0.6575 27 P 0 ;1
L 7.9575 0.7075 7.9575 0.7075 27 P 0 ;1
L 7.9575 0.7575 7.9575 0.7575 27 P 0 ;1
L 7.9575 0.8075 7.9575 0.8075 27 P 0 ;1
L 7.9575 0.8575 7.9575 0.8575 27 P 0 ;1
L 7.9575 0.9075 7.9575 0.9075 27 P 0 ;1
L 7.9575 0.9575 7.9575 0.9575 27 P 0 ;1
L 7.9575 1.0075 7.9575 1.0075 27 P 0 ;1
L 7.9575 1.0575 7.9575 1.0575 27 P 0 ;1
L 7.9575 1.1075 7.9575 1.1075 27 P 0 ;1
L 7.9575 1.1575 7.9575 1.1575 27 P 0 ;1
L 7.9575 1.2075 7.9575 1.2075 27 P 0 ;1
L 7.9575 1.2575 7.9575 1.2575 27 P 0 ;1
L 7.9575 1.3075 7.9575 1.3075 27 P 0 ;1
L 7.9575 1.3575 7.9575 1.3575 27 P 0 ;1
L 7.9575 1.4075 7.9575 1.4075 27 P 0 ;1
L 7.9575 1.4575 7.9575 1.4575 27 P 0 ;1
L 7.9575 1.5075 7.9575 1.5075 27 P 0 ;1
L 7.9575 1.5575 7.9575 1.5575 27 P 0 ;1
L 7.9575 1.6075 7.9575 1.6075 27 P 0 ;1
L 7.9575 1.6575 7.9575 1.6575 27 P 0 ;1
L 7.9575 1.7075 7.9575 1.7075 27 P 0 ;1
L 7.9575 1.7575 7.9575 1.7575 27 P 0 ;1
L 7.9575 1.8075 7.9575 1.8075 27 P 0 ;1
L 7.9575 3.9575 7.9575 3.9575 27 P 0 ;1
L 7.9575 4.0075 7.9575 4.0075 27 P 0 ;1
L 7.9575 4.0575 7.9575 4.0575 27 P 0 ;1
L 7.9575 4.1075 7.9575 4.1075 27 P 0 ;1
L 7.9575 4.1575 7.9575 4.1575 27 P 0 ;1
L 7.9575 4.2075 7.9575 4.2075 27 P 0 ;1
L 7.9575 4.2575 7.9575 4.2575 27 P 0 ;1
L 7.9575 4.3075 7.9575 4.3075 27 P 0 ;1
L 7.9575 5.6575 7.9575 5.6575 27 P 0 ;1
L 7.9575 5.7075 7.9575 5.7075 27 P 0 ;1
L 7.9575 5.7575 7.9575 5.7575 27 P 0 ;1
L 7.9575 5.8075 7.9575 5.8075 27 P 0 ;1
L 7.9575 5.8575 7.9575 5.8575 27 P 0 ;1
L 8.0075 0.1575 8.0075 0.1575 27 P 0 ;1
L 8.0075 0.2075 8.0075 0.2075 27 P 0 ;1
L 8.0075 0.2575 8.0075 0.2575 27 P 0 ;1
L 8.0075 0.3075 8.0075 0.3075 27 P 0 ;1
L 8.0075 0.3575 8.0075 0.3575 27 P 0 ;1
L 8.0075 0.4075 8.0075 0.4075 27 P 0 ;1
L 8.0075 0.4575 8.0075 0.4575 27 P 0 ;1
L 8.0075 0.5075 8.0075 0.5075 27 P 0 ;1
L 8.0075 0.5575 8.0075 0.5575 27 P 0 ;1
L 8.0075 0.6075 8.0075 0.6075 27 P 0 ;1
L 8.0075 0.6575 8.0075 0.6575 27 P 0 ;1
L 8.0075 0.7075 8.0075 0.7075 27 P 0 ;1
L 8.0075 0.7575 8.0075 0.7575 27 P 0 ;1
L 8.0075 0.8075 8.0075 0.8075 27 P 0 ;1
L 8.0075 0.8575 8.0075 0.8575 27 P 0 ;1
L 8.0075 0.9075 8.0075 0.9075 27 P 0 ;1
L 8.0075 0.9575 8.0075 0.9575 27 P 0 ;1
L 8.0075 1.0075 8.0075 1.0075 27 P 0 ;1
L 8.0075 1.0575 8.0075 1.0575 27 P 0 ;1
L 8.0075 1.1075 8.0075 1.1075 27 P 0 ;1
L 8.0075 1.1575 8.0075 1.1575 27 P 0 ;1
L 8.0075 1.2075 8.0075 1.2075 27 P 0 ;1
L 8.0075 1.2575 8.0075 1.2575 27 P 0 ;1
L 8.0075 1.3075 8.0075 1.3075 27 P 0 ;1
L 8.0075 1.3575 8.0075 1.3575 27 P 0 ;1
L 8.0075 1.4075 8.0075 1.4075 27 P 0 ;1
L 8.0075 1.4575 8.0075 1.4575 27 P 0 ;1
L 8.0075 1.5075 8.0075 1.5075 27 P 0 ;1
L 8.0075 1.5575 8.0075 1.5575 27 P 0 ;1
L 8.0075 1.6075 8.0075 1.6075 27 P 0 ;1
L 8.0075 1.6575 8.0075 1.6575 27 P 0 ;1
L 8.0075 1.7075 8.0075 1.7075 27 P 0 ;1
L 8.0075 1.7575 8.0075 1.7575 27 P 0 ;1
L 8.0075 3.9575 8.0075 3.9575 27 P 0 ;1
L 8.0075 4.0075 8.0075 4.0075 27 P 0 ;1
L 8.0075 4.0575 8.0075 4.0575 27 P 0 ;1
L 8.0075 4.1075 8.0075 4.1075 27 P 0 ;1
L 8.0075 4.1575 8.0075 4.1575 27 P 0 ;1
L 8.0075 4.2075 8.0075 4.2075 27 P 0 ;1
L 8.0075 4.2575 8.0075 4.2575 27 P 0 ;1
L 8.0075 4.3075 8.0075 4.3075 27 P 0 ;1
L 8.0075 4.3575 8.0075 4.3575 27 P 0 ;1
L 8.0075 5.6575 8.0075 5.6575 27 P 0 ;1
L 8.0075 5.7075 8.0075 5.7075 27 P 0 ;1
L 8.0075 5.7575 8.0075 5.7575 27 P 0 ;1
L 8.0075 5.8075 8.0075 5.8075 27 P 0 ;1
L 8.0075 5.8575 8.0075 5.8575 27 P 0 ;1
L 8.0575 0.1575 8.0575 0.1575 27 P 0 ;1
L 8.0575 0.2075 8.0575 0.2075 27 P 0 ;1
L 8.0575 0.2575 8.0575 0.2575 27 P 0 ;1
L 8.0575 0.3075 8.0575 0.3075 27 P 0 ;1
L 8.0575 0.3575 8.0575 0.3575 27 P 0 ;1
L 8.0575 0.4075 8.0575 0.4075 27 P 0 ;1
L 8.0575 0.4575 8.0575 0.4575 27 P 0 ;1
L 8.0575 0.5075 8.0575 0.5075 27 P 0 ;1
L 8.0575 0.5575 8.0575 0.5575 27 P 0 ;1
L 8.0575 0.6075 8.0575 0.6075 27 P 0 ;1
L 8.0575 0.6575 8.0575 0.6575 27 P 0 ;1
L 8.0575 0.7075 8.0575 0.7075 27 P 0 ;1
L 8.0575 0.7575 8.0575 0.7575 27 P 0 ;1
L 8.0575 0.8075 8.0575 0.8075 27 P 0 ;1
L 8.0575 0.8575 8.0575 0.8575 27 P 0 ;1
L 8.0575 0.9075 8.0575 0.9075 27 P 0 ;1
L 8.0575 0.9575 8.0575 0.9575 27 P 0 ;1
L 8.0575 1.0075 8.0575 1.0075 27 P 0 ;1
L 8.0575 1.0575 8.0575 1.0575 27 P 0 ;1
L 8.0575 1.1075 8.0575 1.1075 27 P 0 ;1
L 8.0575 1.1575 8.0575 1.1575 27 P 0 ;1
L 8.0575 1.2075 8.0575 1.2075 27 P 0 ;1
L 8.0575 1.2575 8.0575 1.2575 27 P 0 ;1
L 8.0575 1.3075 8.0575 1.3075 27 P 0 ;1
L 8.0575 1.3575 8.0575 1.3575 27 P 0 ;1
L 8.0575 1.6575 8.0575 1.6575 27 P 0 ;1
L 8.0575 1.7075 8.0575 1.7075 27 P 0 ;1
L 8.0575 1.7575 8.0575 1.7575 27 P 0 ;1
L 8.0575 4.0075 8.0575 4.0075 27 P 0 ;1
L 8.0575 4.0575 8.0575 4.0575 27 P 0 ;1
L 8.0575 4.4075 8.0575 4.4075 27 P 0 ;1
L 8.0575 4.4575 8.0575 4.4575 27 P 0 ;1
L 8.0575 5.6575 8.0575 5.6575 27 P 0 ;1
L 8.0575 5.7075 8.0575 5.7075 27 P 0 ;1
L 8.0575 5.7575 8.0575 5.7575 27 P 0 ;1
L 8.0575 5.8075 8.0575 5.8075 27 P 0 ;1
L 8.0575 5.8575 8.0575 5.8575 27 P 0 ;1
L 8.1075 0.1575 8.1075 0.1575 27 P 0 ;1
L 8.1075 0.2075 8.1075 0.2075 27 P 0 ;1
L 8.1075 0.2575 8.1075 0.2575 27 P 0 ;1
L 8.1075 0.3075 8.1075 0.3075 27 P 0 ;1
L 8.1075 0.3575 8.1075 0.3575 27 P 0 ;1
L 8.1075 0.4075 8.1075 0.4075 27 P 0 ;1
L 8.1075 0.4575 8.1075 0.4575 27 P 0 ;1
L 8.1075 0.5075 8.1075 0.5075 27 P 0 ;1
L 8.1075 0.5575 8.1075 0.5575 27 P 0 ;1
L 8.1075 0.6075 8.1075 0.6075 27 P 0 ;1
L 8.1075 0.6575 8.1075 0.6575 27 P 0 ;1
L 8.1075 0.7075 8.1075 0.7075 27 P 0 ;1
L 8.1075 0.7575 8.1075 0.7575 27 P 0 ;1
L 8.1075 0.8075 8.1075 0.8075 27 P 0 ;1
L 8.1075 0.8575 8.1075 0.8575 27 P 0 ;1
L 8.1075 0.9075 8.1075 0.9075 27 P 0 ;1
L 8.1075 0.9575 8.1075 0.9575 27 P 0 ;1
L 8.1075 1.0075 8.1075 1.0075 27 P 0 ;1
L 8.1075 1.0575 8.1075 1.0575 27 P 0 ;1
L 8.1075 1.1075 8.1075 1.1075 27 P 0 ;1
L 8.1075 1.1575 8.1075 1.1575 27 P 0 ;1
L 8.1075 1.2075 8.1075 1.2075 27 P 0 ;1
L 8.1075 1.2575 8.1075 1.2575 27 P 0 ;1
L 8.1075 1.3075 8.1075 1.3075 27 P 0 ;1
L 8.1075 1.7075 8.1075 1.7075 27 P 0 ;1
L 8.1075 1.7575 8.1075 1.7575 27 P 0 ;1
L 8.1075 3.9575 8.1075 3.9575 27 P 0 ;1
L 8.1075 4.0075 8.1075 4.0075 27 P 0 ;1
L 8.1075 4.4575 8.1075 4.4575 27 P 0 ;1
L 8.1075 4.5075 8.1075 4.5075 27 P 0 ;1
L 8.1075 5.6575 8.1075 5.6575 27 P 0 ;1
L 8.1075 5.7075 8.1075 5.7075 27 P 0 ;1
L 8.1075 5.7575 8.1075 5.7575 27 P 0 ;1
L 8.1075 5.8075 8.1075 5.8075 27 P 0 ;1
L 8.1075 5.8575 8.1075 5.8575 27 P 0 ;1
L 8.1575 0.1575 8.1575 0.1575 27 P 0 ;1
L 8.1575 0.2075 8.1575 0.2075 27 P 0 ;1
L 8.1575 0.2575 8.1575 0.2575 27 P 0 ;1
L 8.1575 0.3075 8.1575 0.3075 27 P 0 ;1
L 8.1575 0.3575 8.1575 0.3575 27 P 0 ;1
L 8.1575 0.4075 8.1575 0.4075 27 P 0 ;1
L 8.1575 0.4575 8.1575 0.4575 27 P 0 ;1
L 8.1575 0.5075 8.1575 0.5075 27 P 0 ;1
L 8.1575 0.5575 8.1575 0.5575 27 P 0 ;1
L 8.1575 0.6075 8.1575 0.6075 27 P 0 ;1
L 8.1575 0.6575 8.1575 0.6575 27 P 0 ;1
L 8.1575 0.7075 8.1575 0.7075 27 P 0 ;1
L 8.1575 0.7575 8.1575 0.7575 27 P 0 ;1
L 8.1575 0.8075 8.1575 0.8075 27 P 0 ;1
L 8.1575 0.8575 8.1575 0.8575 27 P 0 ;1
L 8.1575 0.9075 8.1575 0.9075 27 P 0 ;1
L 8.1575 0.9575 8.1575 0.9575 27 P 0 ;1
L 8.1575 1.0075 8.1575 1.0075 27 P 0 ;1
L 8.1575 1.0575 8.1575 1.0575 27 P 0 ;1
L 8.1575 1.1075 8.1575 1.1075 27 P 0 ;1
L 8.1575 1.1575 8.1575 1.1575 27 P 0 ;1
L 8.1575 1.2075 8.1575 1.2075 27 P 0 ;1
L 8.1575 1.2575 8.1575 1.2575 27 P 0 ;1
L 8.1575 1.7575 8.1575 1.7575 27 P 0 ;1
L 8.1575 4.4575 8.1575 4.4575 27 P 0 ;1
L 8.1575 4.5075 8.1575 4.5075 27 P 0 ;1
L 8.1575 5.6575 8.1575 5.6575 27 P 0 ;1
L 8.1575 5.7075 8.1575 5.7075 27 P 0 ;1
L 8.1575 5.7575 8.1575 5.7575 27 P 0 ;1
L 8.1575 5.8075 8.1575 5.8075 27 P 0 ;1
L 8.1575 5.8575 8.1575 5.8575 27 P 0 ;1
L 8.2075 0.1575 8.2075 0.1575 27 P 0 ;1
L 8.2075 0.2075 8.2075 0.2075 27 P 0 ;1
L 8.2075 0.2575 8.2075 0.2575 27 P 0 ;1
L 8.2075 0.3075 8.2075 0.3075 27 P 0 ;1
L 8.2075 0.3575 8.2075 0.3575 27 P 0 ;1
L 8.2075 0.4075 8.2075 0.4075 27 P 0 ;1
L 8.2075 0.4575 8.2075 0.4575 27 P 0 ;1
L 8.2075 0.5075 8.2075 0.5075 27 P 0 ;1
L 8.2075 0.5575 8.2075 0.5575 27 P 0 ;1
L 8.2075 0.6075 8.2075 0.6075 27 P 0 ;1
L 8.2075 0.6575 8.2075 0.6575 27 P 0 ;1
L 8.2075 0.7075 8.2075 0.7075 27 P 0 ;1
L 8.2075 0.7575 8.2075 0.7575 27 P 0 ;1
L 8.2075 0.8075 8.2075 0.8075 27 P 0 ;1
L 8.2075 0.8575 8.2075 0.8575 27 P 0 ;1
L 8.2075 0.9075 8.2075 0.9075 27 P 0 ;1
L 8.2075 0.9575 8.2075 0.9575 27 P 0 ;1
L 8.2075 1.0075 8.2075 1.0075 27 P 0 ;1
L 8.2075 1.0575 8.2075 1.0575 27 P 0 ;1
L 8.2075 1.1075 8.2075 1.1075 27 P 0 ;1
L 8.2075 1.1575 8.2075 1.1575 27 P 0 ;1
L 8.2075 1.2075 8.2075 1.2075 27 P 0 ;1
L 8.2075 1.2575 8.2075 1.2575 27 P 0 ;1
L 8.2075 1.7575 8.2075 1.7575 27 P 0 ;1
L 8.2075 3.9575 8.2075 3.9575 27 P 0 ;1
L 8.2075 4.5075 8.2075 4.5075 27 P 0 ;1
L 8.2075 5.2075 8.2075 5.2075 27 P 0 ;1
L 8.2075 5.2575 8.2075 5.2575 27 P 0 ;1
L 8.2075 5.6575 8.2075 5.6575 27 P 0 ;1
L 8.2075 5.7075 8.2075 5.7075 27 P 0 ;1
L 8.2075 5.7575 8.2075 5.7575 27 P 0 ;1
L 8.2075 5.8075 8.2075 5.8075 27 P 0 ;1
L 8.2075 5.8575 8.2075 5.8575 27 P 0 ;1
L 8.2575 0.1575 8.2575 0.1575 27 P 0 ;1
L 8.2575 0.2075 8.2575 0.2075 27 P 0 ;1
L 8.2575 0.2575 8.2575 0.2575 27 P 0 ;1
L 8.2575 0.3075 8.2575 0.3075 27 P 0 ;1
L 8.2575 0.3575 8.2575 0.3575 27 P 0 ;1
L 8.2575 0.4075 8.2575 0.4075 27 P 0 ;1
L 8.2575 0.4575 8.2575 0.4575 27 P 0 ;1
L 8.2575 0.5075 8.2575 0.5075 27 P 0 ;1
L 8.2575 0.5575 8.2575 0.5575 27 P 0 ;1
L 8.2575 0.6075 8.2575 0.6075 27 P 0 ;1
L 8.2575 0.6575 8.2575 0.6575 27 P 0 ;1
L 8.2575 0.7075 8.2575 0.7075 27 P 0 ;1
L 8.2575 0.7575 8.2575 0.7575 27 P 0 ;1
L 8.2575 0.8075 8.2575 0.8075 27 P 0 ;1
L 8.2575 0.8575 8.2575 0.8575 27 P 0 ;1
L 8.2575 0.9075 8.2575 0.9075 27 P 0 ;1
L 8.2575 0.9575 8.2575 0.9575 27 P 0 ;1
L 8.2575 1.0075 8.2575 1.0075 27 P 0 ;1
L 8.2575 1.0575 8.2575 1.0575 27 P 0 ;1
L 8.2575 1.1075 8.2575 1.1075 27 P 0 ;1
L 8.2575 1.1575 8.2575 1.1575 27 P 0 ;1
L 8.2575 1.2075 8.2575 1.2075 27 P 0 ;1
L 8.2575 1.2575 8.2575 1.2575 27 P 0 ;1
L 8.2575 1.7575 8.2575 1.7575 27 P 0 ;1
L 8.2575 4.5075 8.2575 4.5075 27 P 0 ;1
L 8.2575 5.2075 8.2575 5.2075 27 P 0 ;1
L 8.2575 5.2575 8.2575 5.2575 27 P 0 ;1
L 8.2575 5.3075 8.2575 5.3075 27 P 0 ;1
L 8.2575 5.3575 8.2575 5.3575 27 P 0 ;1
L 8.2575 5.6575 8.2575 5.6575 27 P 0 ;1
L 8.2575 5.7075 8.2575 5.7075 27 P 0 ;1
L 8.2575 5.7575 8.2575 5.7575 27 P 0 ;1
L 8.2575 5.8075 8.2575 5.8075 27 P 0 ;1
L 8.2575 5.8575 8.2575 5.8575 27 P 0 ;1
L 8.3075 0.1575 8.3075 0.1575 27 P 0 ;1
L 8.3075 0.2075 8.3075 0.2075 27 P 0 ;1
L 8.3075 0.2575 8.3075 0.2575 27 P 0 ;1
L 8.3075 0.3075 8.3075 0.3075 27 P 0 ;1
L 8.3075 0.3575 8.3075 0.3575 27 P 0 ;1
L 8.3075 0.4075 8.3075 0.4075 27 P 0 ;1
L 8.3075 0.4575 8.3075 0.4575 27 P 0 ;1
L 8.3075 0.5075 8.3075 0.5075 27 P 0 ;1
L 8.3075 0.5575 8.3075 0.5575 27 P 0 ;1
L 8.3075 0.6075 8.3075 0.6075 27 P 0 ;1
L 8.3075 0.6575 8.3075 0.6575 27 P 0 ;1
L 8.3075 0.7075 8.3075 0.7075 27 P 0 ;1
L 8.3075 0.7575 8.3075 0.7575 27 P 0 ;1
L 8.3075 0.8075 8.3075 0.8075 27 P 0 ;1
L 8.3075 0.8575 8.3075 0.8575 27 P 0 ;1
L 8.3075 0.9075 8.3075 0.9075 27 P 0 ;1
L 8.3075 0.9575 8.3075 0.9575 27 P 0 ;1
L 8.3075 1.0075 8.3075 1.0075 27 P 0 ;1
L 8.3075 1.0575 8.3075 1.0575 27 P 0 ;1
L 8.3075 1.1075 8.3075 1.1075 27 P 0 ;1
L 8.3075 1.1575 8.3075 1.1575 27 P 0 ;1
L 8.3075 1.2075 8.3075 1.2075 27 P 0 ;1
L 8.3075 1.2575 8.3075 1.2575 27 P 0 ;1
L 8.3075 1.7575 8.3075 1.7575 27 P 0 ;1
L 8.3075 4.5075 8.3075 4.5075 27 P 0 ;1
L 8.3075 5.2575 8.3075 5.2575 27 P 0 ;1
L 8.3075 5.3075 8.3075 5.3075 27 P 0 ;1
L 8.3075 5.3575 8.3075 5.3575 27 P 0 ;1
L 8.3075 5.6575 8.3075 5.6575 27 P 0 ;1
L 8.3075 5.7075 8.3075 5.7075 27 P 0 ;1
L 8.3075 5.7575 8.3075 5.7575 27 P 0 ;1
L 8.3075 5.8075 8.3075 5.8075 27 P 0 ;1
L 8.3075 5.8575 8.3075 5.8575 27 P 0 ;1
L 8.3575 0.1575 8.3575 0.1575 27 P 0 ;1
L 8.3575 0.2075 8.3575 0.2075 27 P 0 ;1
L 8.3575 0.2575 8.3575 0.2575 27 P 0 ;1
L 8.3575 0.3075 8.3575 0.3075 27 P 0 ;1
L 8.3575 0.3575 8.3575 0.3575 27 P 0 ;1
L 8.3575 0.4075 8.3575 0.4075 27 P 0 ;1
L 8.3575 0.4575 8.3575 0.4575 27 P 0 ;1
L 8.3575 0.5075 8.3575 0.5075 27 P 0 ;1
L 8.3575 0.5575 8.3575 0.5575 27 P 0 ;1
L 8.3575 0.6075 8.3575 0.6075 27 P 0 ;1
L 8.3575 0.6575 8.3575 0.6575 27 P 0 ;1
L 8.3575 0.7075 8.3575 0.7075 27 P 0 ;1
L 8.3575 0.7575 8.3575 0.7575 27 P 0 ;1
L 8.3575 0.8075 8.3575 0.8075 27 P 0 ;1
L 8.3575 0.8575 8.3575 0.8575 27 P 0 ;1
L 8.3575 0.9075 8.3575 0.9075 27 P 0 ;1
L 8.3575 0.9575 8.3575 0.9575 27 P 0 ;1
L 8.3575 1.0075 8.3575 1.0075 27 P 0 ;1
L 8.3575 1.0575 8.3575 1.0575 27 P 0 ;1
L 8.3575 1.1075 8.3575 1.1075 27 P 0 ;1
L 8.3575 1.1575 8.3575 1.1575 27 P 0 ;1
L 8.3575 1.2075 8.3575 1.2075 27 P 0 ;1
L 8.3575 1.2575 8.3575 1.2575 27 P 0 ;1
L 8.3575 1.7575 8.3575 1.7575 27 P 0 ;1
L 8.3575 3.9575 8.3575 3.9575 27 P 0 ;1
L 8.3575 4.4575 8.3575 4.4575 27 P 0 ;1
L 8.3575 4.5075 8.3575 4.5075 27 P 0 ;1
L 8.3575 4.5575 8.3575 4.5575 27 P 0 ;1
L 8.3575 5.2575 8.3575 5.2575 27 P 0 ;1
L 8.3575 5.3075 8.3575 5.3075 27 P 0 ;1
L 8.3575 5.3575 8.3575 5.3575 27 P 0 ;1
L 8.3575 5.6575 8.3575 5.6575 27 P 0 ;1
L 8.3575 5.7075 8.3575 5.7075 27 P 0 ;1
L 8.3575 5.7575 8.3575 5.7575 27 P 0 ;1
L 8.3575 5.8075 8.3575 5.8075 27 P 0 ;1
L 8.3575 5.8575 8.3575 5.8575 27 P 0 ;1
L 8.4075 0.1575 8.4075 0.1575 27 P 0 ;1
L 8.4075 0.2075 8.4075 0.2075 27 P 0 ;1
L 8.4075 0.2575 8.4075 0.2575 27 P 0 ;1
L 8.4075 0.3075 8.4075 0.3075 27 P 0 ;1
L 8.4075 0.3575 8.4075 0.3575 27 P 0 ;1
L 8.4075 0.4075 8.4075 0.4075 27 P 0 ;1
L 8.4075 0.4575 8.4075 0.4575 27 P 0 ;1
L 8.4075 0.5075 8.4075 0.5075 27 P 0 ;1
L 8.4075 0.5575 8.4075 0.5575 27 P 0 ;1
L 8.4075 0.6075 8.4075 0.6075 27 P 0 ;1
L 8.4075 0.6575 8.4075 0.6575 27 P 0 ;1
L 8.4075 0.7075 8.4075 0.7075 27 P 0 ;1
L 8.4075 0.7575 8.4075 0.7575 27 P 0 ;1
L 8.4075 0.8075 8.4075 0.8075 27 P 0 ;1
L 8.4075 0.8575 8.4075 0.8575 27 P 0 ;1
L 8.4075 0.9075 8.4075 0.9075 27 P 0 ;1
L 8.4075 0.9575 8.4075 0.9575 27 P 0 ;1
L 8.4075 1.0075 8.4075 1.0075 27 P 0 ;1
L 8.4075 1.0575 8.4075 1.0575 27 P 0 ;1
L 8.4075 1.1075 8.4075 1.1075 27 P 0 ;1
L 8.4075 1.1575 8.4075 1.1575 27 P 0 ;1
L 8.4075 1.2075 8.4075 1.2075 27 P 0 ;1
L 8.4075 1.2575 8.4075 1.2575 27 P 0 ;1
L 8.4075 1.3075 8.4075 1.3075 27 P 0 ;1
L 8.4075 1.7075 8.4075 1.7075 27 P 0 ;1
L 8.4075 1.7575 8.4075 1.7575 27 P 0 ;1
L 8.4075 4.0075 8.4075 4.0075 27 P 0 ;1
L 8.4075 4.4575 8.4075 4.4575 27 P 0 ;1
L 8.4075 4.5075 8.4075 4.5075 27 P 0 ;1
L 8.4075 4.5575 8.4075 4.5575 27 P 0 ;1
L 8.4075 4.6075 8.4075 4.6075 27 P 0 ;1
L 8.4075 5.2575 8.4075 5.2575 27 P 0 ;1
L 8.4075 5.3075 8.4075 5.3075 27 P 0 ;1
L 8.4075 5.3575 8.4075 5.3575 27 P 0 ;1
L 8.4075 5.6575 8.4075 5.6575 27 P 0 ;1
L 8.4075 5.7075 8.4075 5.7075 27 P 0 ;1
L 8.4075 5.7575 8.4075 5.7575 27 P 0 ;1
L 8.4075 5.8075 8.4075 5.8075 27 P 0 ;1
L 8.4075 5.8575 8.4075 5.8575 27 P 0 ;1
L 8.4575 0.1575 8.4575 0.1575 27 P 0 ;1
L 8.4575 0.2075 8.4575 0.2075 27 P 0 ;1
L 8.4575 0.2575 8.4575 0.2575 27 P 0 ;1
L 8.4575 0.3075 8.4575 0.3075 27 P 0 ;1
L 8.4575 0.3575 8.4575 0.3575 27 P 0 ;1
L 8.4575 0.4075 8.4575 0.4075 27 P 0 ;1
L 8.4575 0.4575 8.4575 0.4575 27 P 0 ;1
L 8.4575 0.5075 8.4575 0.5075 27 P 0 ;1
L 8.4575 0.5575 8.4575 0.5575 27 P 0 ;1
L 8.4575 0.6075 8.4575 0.6075 27 P 0 ;1
L 8.4575 0.6575 8.4575 0.6575 27 P 0 ;1
L 8.4575 0.7075 8.4575 0.7075 27 P 0 ;1
L 8.4575 0.7575 8.4575 0.7575 27 P 0 ;1
L 8.4575 0.8075 8.4575 0.8075 27 P 0 ;1
L 8.4575 0.8575 8.4575 0.8575 27 P 0 ;1
L 8.4575 0.9075 8.4575 0.9075 27 P 0 ;1
L 8.4575 0.9575 8.4575 0.9575 27 P 0 ;1
L 8.4575 1.0075 8.4575 1.0075 27 P 0 ;1
L 8.4575 1.0575 8.4575 1.0575 27 P 0 ;1
L 8.4575 1.1075 8.4575 1.1075 27 P 0 ;1
L 8.4575 1.1575 8.4575 1.1575 27 P 0 ;1
L 8.4575 1.2075 8.4575 1.2075 27 P 0 ;1
L 8.4575 1.2575 8.4575 1.2575 27 P 0 ;1
L 8.4575 1.3075 8.4575 1.3075 27 P 0 ;1
L 8.4575 1.3575 8.4575 1.3575 27 P 0 ;1
L 8.4575 1.6575 8.4575 1.6575 27 P 0 ;1
L 8.4575 1.7075 8.4575 1.7075 27 P 0 ;1
L 8.4575 1.7575 8.4575 1.7575 27 P 0 ;1
L 8.4575 3.9575 8.4575 3.9575 27 P 0 ;1
L 8.4575 4.0075 8.4575 4.0075 27 P 0 ;1
L 8.4575 4.0575 8.4575 4.0575 27 P 0 ;1
L 8.4575 4.3575 8.4575 4.3575 27 P 0 ;1
L 8.4575 4.4075 8.4575 4.4075 27 P 0 ;1
L 8.4575 4.4575 8.4575 4.4575 27 P 0 ;1
L 8.4575 4.5075 8.4575 4.5075 27 P 0 ;1
L 8.4575 4.5575 8.4575 4.5575 27 P 0 ;1
L 8.4575 4.6075 8.4575 4.6075 27 P 0 ;1
L 8.4575 5.2575 8.4575 5.2575 27 P 0 ;1
L 8.4575 5.3075 8.4575 5.3075 27 P 0 ;1
L 8.4575 5.3575 8.4575 5.3575 27 P 0 ;1
L 8.4575 5.6575 8.4575 5.6575 27 P 0 ;1
L 8.4575 5.7075 8.4575 5.7075 27 P 0 ;1
L 8.4575 5.7575 8.4575 5.7575 27 P 0 ;1
L 8.4575 5.8075 8.4575 5.8075 27 P 0 ;1
L 8.4575 5.8575 8.4575 5.8575 27 P 0 ;1
L 8.5075 0.1575 8.5075 0.1575 27 P 0 ;1
L 8.5075 0.2075 8.5075 0.2075 27 P 0 ;1
L 8.5075 0.2575 8.5075 0.2575 27 P 0 ;1
L 8.5075 0.3075 8.5075 0.3075 27 P 0 ;1
L 8.5075 0.3575 8.5075 0.3575 27 P 0 ;1
L 8.5075 0.4075 8.5075 0.4075 27 P 0 ;1
L 8.5075 0.4575 8.5075 0.4575 27 P 0 ;1
L 8.5075 0.5075 8.5075 0.5075 27 P 0 ;1
L 8.5075 0.5575 8.5075 0.5575 27 P 0 ;1
L 8.5075 0.6075 8.5075 0.6075 27 P 0 ;1
L 8.5075 0.6575 8.5075 0.6575 27 P 0 ;1
L 8.5075 0.7075 8.5075 0.7075 27 P 0 ;1
L 8.5075 0.7575 8.5075 0.7575 27 P 0 ;1
L 8.5075 0.8075 8.5075 0.8075 27 P 0 ;1
L 8.5075 0.8575 8.5075 0.8575 27 P 0 ;1
L 8.5075 0.9075 8.5075 0.9075 27 P 0 ;1
L 8.5075 0.9575 8.5075 0.9575 27 P 0 ;1
L 8.5075 1.0075 8.5075 1.0075 27 P 0 ;1
L 8.5075 1.0575 8.5075 1.0575 27 P 0 ;1
L 8.5075 1.1075 8.5075 1.1075 27 P 0 ;1
L 8.5075 1.1575 8.5075 1.1575 27 P 0 ;1
L 8.5075 1.2075 8.5075 1.2075 27 P 0 ;1
L 8.5075 1.2575 8.5075 1.2575 27 P 0 ;1
L 8.5075 1.3075 8.5075 1.3075 27 P 0 ;1
L 8.5075 1.3575 8.5075 1.3575 27 P 0 ;1
L 8.5075 1.4075 8.5075 1.4075 27 P 0 ;1
L 8.5075 1.4575 8.5075 1.4575 27 P 0 ;1
L 8.5075 1.5075 8.5075 1.5075 27 P 0 ;1
L 8.5075 1.5575 8.5075 1.5575 27 P 0 ;1
L 8.5075 1.6075 8.5075 1.6075 27 P 0 ;1
L 8.5075 1.6575 8.5075 1.6575 27 P 0 ;1
L 8.5075 1.7075 8.5075 1.7075 27 P 0 ;1
L 8.5075 1.7575 8.5075 1.7575 27 P 0 ;1
L 8.5075 4.0075 8.5075 4.0075 27 P 0 ;1
L 8.5075 4.0575 8.5075 4.0575 27 P 0 ;1
L 8.5075 4.1075 8.5075 4.1075 27 P 0 ;1
L 8.5075 4.1575 8.5075 4.1575 27 P 0 ;1
L 8.5075 4.2075 8.5075 4.2075 27 P 0 ;1
L 8.5075 4.2575 8.5075 4.2575 27 P 0 ;1
L 8.5075 4.3075 8.5075 4.3075 27 P 0 ;1
L 8.5075 4.3575 8.5075 4.3575 27 P 0 ;1
L 8.5075 4.4075 8.5075 4.4075 27 P 0 ;1
L 8.5075 4.4575 8.5075 4.4575 27 P 0 ;1
L 8.5075 4.5075 8.5075 4.5075 27 P 0 ;1
L 8.5075 4.5575 8.5075 4.5575 27 P 0 ;1
L 8.5075 4.6075 8.5075 4.6075 27 P 0 ;1
L 8.5075 4.6575 8.5075 4.6575 27 P 0 ;1
L 8.5075 5.1575 8.5075 5.1575 27 P 0 ;1
L 8.5075 5.2075 8.5075 5.2075 27 P 0 ;1
L 8.5075 5.2575 8.5075 5.2575 27 P 0 ;1
L 8.5075 5.3075 8.5075 5.3075 27 P 0 ;1
L 8.5075 5.3575 8.5075 5.3575 27 P 0 ;1
L 8.5075 5.6575 8.5075 5.6575 27 P 0 ;1
L 8.5075 5.7075 8.5075 5.7075 27 P 0 ;1
L 8.5075 5.7575 8.5075 5.7575 27 P 0 ;1
L 8.5075 5.8075 8.5075 5.8075 27 P 0 ;1
L 8.5075 5.8575 8.5075 5.8575 27 P 0 ;1
L 8.5575 0.1575 8.5575 0.1575 27 P 0 ;1
L 8.5575 0.2075 8.5575 0.2075 27 P 0 ;1
L 8.5575 0.2575 8.5575 0.2575 27 P 0 ;1
L 8.5575 0.3075 8.5575 0.3075 27 P 0 ;1
L 8.5575 0.3575 8.5575 0.3575 27 P 0 ;1
L 8.5575 0.4075 8.5575 0.4075 27 P 0 ;1
L 8.5575 0.4575 8.5575 0.4575 27 P 0 ;1
L 8.5575 0.5075 8.5575 0.5075 27 P 0 ;1
L 8.5575 0.5575 8.5575 0.5575 27 P 0 ;1
L 8.5575 0.6075 8.5575 0.6075 27 P 0 ;1
L 8.5575 0.6575 8.5575 0.6575 27 P 0 ;1
L 8.5575 0.7075 8.5575 0.7075 27 P 0 ;1
L 8.5575 0.7575 8.5575 0.7575 27 P 0 ;1
L 8.5575 0.8075 8.5575 0.8075 27 P 0 ;1
L 8.5575 0.8575 8.5575 0.8575 27 P 0 ;1
L 8.5575 0.9075 8.5575 0.9075 27 P 0 ;1
L 8.5575 0.9575 8.5575 0.9575 27 P 0 ;1
L 8.5575 1.0075 8.5575 1.0075 27 P 0 ;1
L 8.5575 1.0575 8.5575 1.0575 27 P 0 ;1
L 8.5575 1.1075 8.5575 1.1075 27 P 0 ;1
L 8.5575 1.1575 8.5575 1.1575 27 P 0 ;1
L 8.5575 1.2075 8.5575 1.2075 27 P 0 ;1
L 8.5575 1.2575 8.5575 1.2575 27 P 0 ;1
L 8.5575 1.3075 8.5575 1.3075 27 P 0 ;1
L 8.5575 1.3575 8.5575 1.3575 27 P 0 ;1
L 8.5575 1.4075 8.5575 1.4075 27 P 0 ;1
L 8.5575 1.4575 8.5575 1.4575 27 P 0 ;1
L 8.5575 1.5075 8.5575 1.5075 27 P 0 ;1
L 8.5575 1.5575 8.5575 1.5575 27 P 0 ;1
L 8.5575 1.6075 8.5575 1.6075 27 P 0 ;1
L 8.5575 1.6575 8.5575 1.6575 27 P 0 ;1
L 8.5575 1.7075 8.5575 1.7075 27 P 0 ;1
L 8.5575 1.7575 8.5575 1.7575 27 P 0 ;1
L 8.5575 3.9575 8.5575 3.9575 27 P 0 ;1
L 8.5575 4.0075 8.5575 4.0075 27 P 0 ;1
L 8.5575 4.0575 8.5575 4.0575 27 P 0 ;1
L 8.5575 4.1075 8.5575 4.1075 27 P 0 ;1
L 8.5575 4.1575 8.5575 4.1575 27 P 0 ;1
L 8.5575 4.2075 8.5575 4.2075 27 P 0 ;1
L 8.5575 4.2575 8.5575 4.2575 27 P 0 ;1
L 8.5575 4.3075 8.5575 4.3075 27 P 0 ;1
L 8.5575 4.3575 8.5575 4.3575 27 P 0 ;1
L 8.5575 4.4075 8.5575 4.4075 27 P 0 ;1
L 8.5575 4.4575 8.5575 4.4575 27 P 0 ;1
L 8.5575 4.5075 8.5575 4.5075 27 P 0 ;1
L 8.5575 4.5575 8.5575 4.5575 27 P 0 ;1
L 8.5575 4.6075 8.5575 4.6075 27 P 0 ;1
L 8.5575 4.6575 8.5575 4.6575 27 P 0 ;1
L 8.5575 4.7075 8.5575 4.7075 27 P 0 ;1
L 8.5575 4.8575 8.5575 4.8575 27 P 0 ;1
L 8.5575 4.9075 8.5575 4.9075 27 P 0 ;1
L 8.5575 4.9575 8.5575 4.9575 27 P 0 ;1
L 8.5575 5.0075 8.5575 5.0075 27 P 0 ;1
L 8.5575 5.0575 8.5575 5.0575 27 P 0 ;1
L 8.5575 5.1075 8.5575 5.1075 27 P 0 ;1
L 8.5575 5.1575 8.5575 5.1575 27 P 0 ;1
L 8.5575 5.2075 8.5575 5.2075 27 P 0 ;1
L 8.5575 5.2575 8.5575 5.2575 27 P 0 ;1
L 8.5575 5.3075 8.5575 5.3075 27 P 0 ;1
L 8.5575 5.3575 8.5575 5.3575 27 P 0 ;1
L 8.5575 5.6575 8.5575 5.6575 27 P 0 ;1
L 8.5575 5.7075 8.5575 5.7075 27 P 0 ;1
L 8.5575 5.7575 8.5575 5.7575 27 P 0 ;1
L 8.5575 5.8075 8.5575 5.8075 27 P 0 ;1
L 8.5575 5.8575 8.5575 5.8575 27 P 0 ;1
L 8.6075 0.1575 8.6075 0.1575 27 P 0 ;1
L 8.6075 0.2075 8.6075 0.2075 27 P 0 ;1
L 8.6075 0.2575 8.6075 0.2575 27 P 0 ;1
L 8.6075 0.3075 8.6075 0.3075 27 P 0 ;1
L 8.6075 0.3575 8.6075 0.3575 27 P 0 ;1
L 8.6075 0.4075 8.6075 0.4075 27 P 0 ;1
L 8.6075 0.4575 8.6075 0.4575 27 P 0 ;1
L 8.6075 0.5075 8.6075 0.5075 27 P 0 ;1
L 8.6075 0.5575 8.6075 0.5575 27 P 0 ;1
L 8.6075 0.6075 8.6075 0.6075 27 P 0 ;1
L 8.6075 0.6575 8.6075 0.6575 27 P 0 ;1
L 8.6075 0.7075 8.6075 0.7075 27 P 0 ;1
L 8.6075 0.7575 8.6075 0.7575 27 P 0 ;1
L 8.6075 0.8075 8.6075 0.8075 27 P 0 ;1
L 8.6075 0.8575 8.6075 0.8575 27 P 0 ;1
L 8.6075 0.9075 8.6075 0.9075 27 P 0 ;1
L 8.6075 0.9575 8.6075 0.9575 27 P 0 ;1
L 8.6075 1.0075 8.6075 1.0075 27 P 0 ;1
L 8.6075 1.0575 8.6075 1.0575 27 P 0 ;1
L 8.6075 1.1075 8.6075 1.1075 27 P 0 ;1
L 8.6075 1.1575 8.6075 1.1575 27 P 0 ;1
L 8.6075 1.2075 8.6075 1.2075 27 P 0 ;1
L 8.6075 1.2575 8.6075 1.2575 27 P 0 ;1
L 8.6075 1.3075 8.6075 1.3075 27 P 0 ;1
L 8.6075 1.3575 8.6075 1.3575 27 P 0 ;1
L 8.6075 1.4075 8.6075 1.4075 27 P 0 ;1
L 8.6075 1.4575 8.6075 1.4575 27 P 0 ;1
L 8.6075 1.5075 8.6075 1.5075 27 P 0 ;1
L 8.6075 1.5575 8.6075 1.5575 27 P 0 ;1
L 8.6075 1.6075 8.6075 1.6075 27 P 0 ;1
L 8.6075 1.6575 8.6075 1.6575 27 P 0 ;1
L 8.6075 1.7075 8.6075 1.7075 27 P 0 ;1
L 8.6075 1.7575 8.6075 1.7575 27 P 0 ;1
L 8.6075 1.8075 8.6075 1.8075 27 P 0 ;1
L 8.6075 1.8575 8.6075 1.8575 27 P 0 ;1
L 8.6075 1.9075 8.6075 1.9075 27 P 0 ;1
L 8.6075 1.9575 8.6075 1.9575 27 P 0 ;1
L 8.6075 3.7575 8.6075 3.7575 27 P 0 ;1
L 8.6075 3.8075 8.6075 3.8075 27 P 0 ;1
L 8.6075 3.8575 8.6075 3.8575 27 P 0 ;1
L 8.6075 3.9075 8.6075 3.9075 27 P 0 ;1
L 8.6075 3.9575 8.6075 3.9575 27 P 0 ;1
L 8.6075 4.0075 8.6075 4.0075 27 P 0 ;1
L 8.6075 4.0575 8.6075 4.0575 27 P 0 ;1
L 8.6075 4.1075 8.6075 4.1075 27 P 0 ;1
L 8.6075 4.1575 8.6075 4.1575 27 P 0 ;1
L 8.6075 4.2075 8.6075 4.2075 27 P 0 ;1
L 8.6075 4.2575 8.6075 4.2575 27 P 0 ;1
L 8.6075 4.3075 8.6075 4.3075 27 P 0 ;1
L 8.6075 4.3575 8.6075 4.3575 27 P 0 ;1
L 8.6075 4.4075 8.6075 4.4075 27 P 0 ;1
L 8.6075 4.4575 8.6075 4.4575 27 P 0 ;1
L 8.6075 4.5075 8.6075 4.5075 27 P 0 ;1
L 8.6075 4.5575 8.6075 4.5575 27 P 0 ;1
L 8.6075 4.6075 8.6075 4.6075 27 P 0 ;1
L 8.6075 4.6575 8.6075 4.6575 27 P 0 ;1
L 8.6075 4.8575 8.6075 4.8575 27 P 0 ;1
L 8.6075 4.9075 8.6075 4.9075 27 P 0 ;1
L 8.6075 4.9575 8.6075 4.9575 27 P 0 ;1
L 8.6075 5.1575 8.6075 5.1575 27 P 0 ;1
L 8.6075 5.2075 8.6075 5.2075 27 P 0 ;1
L 8.6075 5.2575 8.6075 5.2575 27 P 0 ;1
L 8.6075 5.3075 8.6075 5.3075 27 P 0 ;1
L 8.6075 5.3575 8.6075 5.3575 27 P 0 ;1
L 8.6075 5.6575 8.6075 5.6575 27 P 0 ;1
L 8.6075 5.7075 8.6075 5.7075 27 P 0 ;1
L 8.6075 5.7575 8.6075 5.7575 27 P 0 ;1
L 8.6075 5.8075 8.6075 5.8075 27 P 0 ;1
L 8.6075 5.8575 8.6075 5.8575 27 P 0 ;1
L 8.6575 0.1575 8.6575 0.1575 27 P 0 ;1
L 8.6575 0.2075 8.6575 0.2075 27 P 0 ;1
L 8.6575 0.2575 8.6575 0.2575 27 P 0 ;1
L 8.6575 0.3075 8.6575 0.3075 27 P 0 ;1
L 8.6575 0.3575 8.6575 0.3575 27 P 0 ;1
L 8.6575 0.4075 8.6575 0.4075 27 P 0 ;1
L 8.6575 0.4575 8.6575 0.4575 27 P 0 ;1
L 8.6575 0.5075 8.6575 0.5075 27 P 0 ;1
L 8.6575 0.5575 8.6575 0.5575 27 P 0 ;1
L 8.6575 0.6075 8.6575 0.6075 27 P 0 ;1
L 8.6575 0.6575 8.6575 0.6575 27 P 0 ;1
L 8.6575 0.7075 8.6575 0.7075 27 P 0 ;1
L 8.6575 0.7575 8.6575 0.7575 27 P 0 ;1
L 8.6575 0.8075 8.6575 0.8075 27 P 0 ;1
L 8.6575 0.8575 8.6575 0.8575 27 P 0 ;1
L 8.6575 0.9075 8.6575 0.9075 27 P 0 ;1
L 8.6575 0.9575 8.6575 0.9575 27 P 0 ;1
L 8.6575 1.0075 8.6575 1.0075 27 P 0 ;1
L 8.6575 1.0575 8.6575 1.0575 27 P 0 ;1
L 8.6575 1.1075 8.6575 1.1075 27 P 0 ;1
L 8.6575 1.1575 8.6575 1.1575 27 P 0 ;1
L 8.6575 1.2075 8.6575 1.2075 27 P 0 ;1
L 8.6575 1.2575 8.6575 1.2575 27 P 0 ;1
L 8.6575 1.3075 8.6575 1.3075 27 P 0 ;1
L 8.6575 1.3575 8.6575 1.3575 27 P 0 ;1
L 8.6575 1.4075 8.6575 1.4075 27 P 0 ;1
L 8.6575 1.4575 8.6575 1.4575 27 P 0 ;1
L 8.6575 1.5075 8.6575 1.5075 27 P 0 ;1
L 8.6575 1.5575 8.6575 1.5575 27 P 0 ;1
L 8.6575 1.6075 8.6575 1.6075 27 P 0 ;1
L 8.6575 1.6575 8.6575 1.6575 27 P 0 ;1
L 8.6575 1.7075 8.6575 1.7075 27 P 0 ;1
L 8.6575 1.7575 8.6575 1.7575 27 P 0 ;1
L 8.6575 1.8075 8.6575 1.8075 27 P 0 ;1
L 8.6575 1.8575 8.6575 1.8575 27 P 0 ;1
L 8.6575 1.9075 8.6575 1.9075 27 P 0 ;1
L 8.6575 1.9575 8.6575 1.9575 27 P 0 ;1
L 8.6575 3.7575 8.6575 3.7575 27 P 0 ;1
L 8.6575 3.8075 8.6575 3.8075 27 P 0 ;1
L 8.6575 3.8575 8.6575 3.8575 27 P 0 ;1
L 8.6575 3.9075 8.6575 3.9075 27 P 0 ;1
L 8.6575 3.9575 8.6575 3.9575 27 P 0 ;1
L 8.6575 4.0075 8.6575 4.0075 27 P 0 ;1
L 8.6575 4.0575 8.6575 4.0575 27 P 0 ;1
L 8.6575 4.1075 8.6575 4.1075 27 P 0 ;1
L 8.6575 4.1575 8.6575 4.1575 27 P 0 ;1
L 8.6575 4.2075 8.6575 4.2075 27 P 0 ;1
L 8.6575 4.2575 8.6575 4.2575 27 P 0 ;1
L 8.6575 4.3075 8.6575 4.3075 27 P 0 ;1
L 8.6575 4.3575 8.6575 4.3575 27 P 0 ;1
L 8.6575 4.4075 8.6575 4.4075 27 P 0 ;1
L 8.6575 4.4575 8.6575 4.4575 27 P 0 ;1
L 8.6575 4.5075 8.6575 4.5075 27 P 0 ;1
L 8.6575 4.5575 8.6575 4.5575 27 P 0 ;1
L 8.6575 4.6075 8.6575 4.6075 27 P 0 ;1
L 8.6575 5.2575 8.6575 5.2575 27 P 0 ;1
L 8.6575 5.3075 8.6575 5.3075 27 P 0 ;1
L 8.6575 5.3575 8.6575 5.3575 27 P 0 ;1
L 8.6575 5.6575 8.6575 5.6575 27 P 0 ;1
L 8.6575 5.7075 8.6575 5.7075 27 P 0 ;1
L 8.6575 5.7575 8.6575 5.7575 27 P 0 ;1
L 8.6575 5.8075 8.6575 5.8075 27 P 0 ;1
L 8.6575 5.8575 8.6575 5.8575 27 P 0 ;1
L 8.7075 0.1575 8.7075 0.1575 27 P 0 ;1
L 8.7075 0.2075 8.7075 0.2075 27 P 0 ;1
L 8.7075 0.2575 8.7075 0.2575 27 P 0 ;1
L 8.7075 0.3075 8.7075 0.3075 27 P 0 ;1
L 8.7075 0.3575 8.7075 0.3575 27 P 0 ;1
L 8.7075 0.4075 8.7075 0.4075 27 P 0 ;1
L 8.7075 0.4575 8.7075 0.4575 27 P 0 ;1
L 8.7075 0.5075 8.7075 0.5075 27 P 0 ;1
L 8.7075 0.5575 8.7075 0.5575 27 P 0 ;1
L 8.7075 0.6075 8.7075 0.6075 27 P 0 ;1
L 8.7075 0.6575 8.7075 0.6575 27 P 0 ;1
L 8.7075 0.7075 8.7075 0.7075 27 P 0 ;1
L 8.7075 0.7575 8.7075 0.7575 27 P 0 ;1
L 8.7075 0.8075 8.7075 0.8075 27 P 0 ;1
L 8.7075 0.8575 8.7075 0.8575 27 P 0 ;1
L 8.7075 0.9075 8.7075 0.9075 27 P 0 ;1
L 8.7075 0.9575 8.7075 0.9575 27 P 0 ;1
L 8.7075 1.0075 8.7075 1.0075 27 P 0 ;1
L 8.7075 1.0575 8.7075 1.0575 27 P 0 ;1
L 8.7075 1.1075 8.7075 1.1075 27 P 0 ;1
L 8.7075 1.1575 8.7075 1.1575 27 P 0 ;1
L 8.7075 1.2075 8.7075 1.2075 27 P 0 ;1
L 8.7075 1.2575 8.7075 1.2575 27 P 0 ;1
L 8.7075 1.3075 8.7075 1.3075 27 P 0 ;1
L 8.7075 1.3575 8.7075 1.3575 27 P 0 ;1
L 8.7075 1.4075 8.7075 1.4075 27 P 0 ;1
L 8.7075 1.4575 8.7075 1.4575 27 P 0 ;1
L 8.7075 1.5075 8.7075 1.5075 27 P 0 ;1
L 8.7075 1.5575 8.7075 1.5575 27 P 0 ;1
L 8.7075 1.6075 8.7075 1.6075 27 P 0 ;1
L 8.7075 1.6575 8.7075 1.6575 27 P 0 ;1
L 8.7075 1.7075 8.7075 1.7075 27 P 0 ;1
L 8.7075 1.7575 8.7075 1.7575 27 P 0 ;1
L 8.7075 1.8075 8.7075 1.8075 27 P 0 ;1
L 8.7075 1.8575 8.7075 1.8575 27 P 0 ;1
L 8.7075 1.9075 8.7075 1.9075 27 P 0 ;1
L 8.7075 1.9575 8.7075 1.9575 27 P 0 ;1
L 8.7075 3.7575 8.7075 3.7575 27 P 0 ;1
L 8.7075 3.8075 8.7075 3.8075 27 P 0 ;1
L 8.7075 3.8575 8.7075 3.8575 27 P 0 ;1
L 8.7075 3.9075 8.7075 3.9075 27 P 0 ;1
L 8.7075 3.9575 8.7075 3.9575 27 P 0 ;1
L 8.7075 4.0075 8.7075 4.0075 27 P 0 ;1
L 8.7075 4.0575 8.7075 4.0575 27 P 0 ;1
L 8.7075 4.1075 8.7075 4.1075 27 P 0 ;1
L 8.7075 4.1575 8.7075 4.1575 27 P 0 ;1
L 8.7075 4.2075 8.7075 4.2075 27 P 0 ;1
L 8.7075 4.2575 8.7075 4.2575 27 P 0 ;1
L 8.7075 4.3075 8.7075 4.3075 27 P 0 ;1
L 8.7075 4.3575 8.7075 4.3575 27 P 0 ;1
L 8.7075 4.4075 8.7075 4.4075 27 P 0 ;1
L 8.7075 4.4575 8.7075 4.4575 27 P 0 ;1
L 8.7075 4.5075 8.7075 4.5075 27 P 0 ;1
L 8.7075 4.5575 8.7075 4.5575 27 P 0 ;1
L 8.7075 5.3075 8.7075 5.3075 27 P 0 ;1
L 8.7075 5.3575 8.7075 5.3575 27 P 0 ;1
L 8.7075 5.6575 8.7075 5.6575 27 P 0 ;1
L 8.7075 5.7075 8.7075 5.7075 27 P 0 ;1
L 8.7075 5.7575 8.7075 5.7575 27 P 0 ;1
L 8.7075 5.8075 8.7075 5.8075 27 P 0 ;1
L 8.7075 5.8575 8.7075 5.8575 27 P 0 ;1
L 8.7575 0.1575 8.7575 0.1575 27 P 0 ;1
L 8.7575 0.2075 8.7575 0.2075 27 P 0 ;1
L 8.7575 0.2575 8.7575 0.2575 27 P 0 ;1
L 8.7575 0.3075 8.7575 0.3075 27 P 0 ;1
L 8.7575 0.3575 8.7575 0.3575 27 P 0 ;1
L 8.7575 0.4075 8.7575 0.4075 27 P 0 ;1
L 8.7575 0.4575 8.7575 0.4575 27 P 0 ;1
L 8.7575 0.5075 8.7575 0.5075 27 P 0 ;1
L 8.7575 0.5575 8.7575 0.5575 27 P 0 ;1
L 8.7575 0.6075 8.7575 0.6075 27 P 0 ;1
L 8.7575 0.6575 8.7575 0.6575 27 P 0 ;1
L 8.7575 0.7075 8.7575 0.7075 27 P 0 ;1
L 8.7575 0.7575 8.7575 0.7575 27 P 0 ;1
L 8.7575 0.8075 8.7575 0.8075 27 P 0 ;1
L 8.7575 0.8575 8.7575 0.8575 27 P 0 ;1
L 8.7575 0.9075 8.7575 0.9075 27 P 0 ;1
L 8.7575 0.9575 8.7575 0.9575 27 P 0 ;1
L 8.7575 1.0075 8.7575 1.0075 27 P 0 ;1
L 8.7575 1.0575 8.7575 1.0575 27 P 0 ;1
L 8.7575 1.1075 8.7575 1.1075 27 P 0 ;1
L 8.7575 1.1575 8.7575 1.1575 27 P 0 ;1
L 8.7575 1.2075 8.7575 1.2075 27 P 0 ;1
L 8.7575 1.2575 8.7575 1.2575 27 P 0 ;1
L 8.7575 1.3075 8.7575 1.3075 27 P 0 ;1
L 8.7575 1.3575 8.7575 1.3575 27 P 0 ;1
L 8.7575 1.4075 8.7575 1.4075 27 P 0 ;1
L 8.7575 1.4575 8.7575 1.4575 27 P 0 ;1
L 8.7575 1.5075 8.7575 1.5075 27 P 0 ;1
L 8.7575 1.5575 8.7575 1.5575 27 P 0 ;1
L 8.7575 1.6075 8.7575 1.6075 27 P 0 ;1
L 8.7575 1.6575 8.7575 1.6575 27 P 0 ;1
L 8.7575 1.7075 8.7575 1.7075 27 P 0 ;1
L 8.7575 1.7575 8.7575 1.7575 27 P 0 ;1
L 8.7575 1.8075 8.7575 1.8075 27 P 0 ;1
L 8.7575 1.8575 8.7575 1.8575 27 P 0 ;1
L 8.7575 1.9075 8.7575 1.9075 27 P 0 ;1
L 8.7575 1.9575 8.7575 1.9575 27 P 0 ;1
L 8.7575 3.7575 8.7575 3.7575 27 P 0 ;1
L 8.7575 3.8075 8.7575 3.8075 27 P 0 ;1
L 8.7575 3.8575 8.7575 3.8575 27 P 0 ;1
L 8.7575 3.9075 8.7575 3.9075 27 P 0 ;1
L 8.7575 3.9575 8.7575 3.9575 27 P 0 ;1
L 8.7575 4.0075 8.7575 4.0075 27 P 0 ;1
L 8.7575 4.0575 8.7575 4.0575 27 P 0 ;1
L 8.7575 4.1075 8.7575 4.1075 27 P 0 ;1
L 8.7575 4.1575 8.7575 4.1575 27 P 0 ;1
L 8.7575 4.2075 8.7575 4.2075 27 P 0 ;1
L 8.7575 4.2575 8.7575 4.2575 27 P 0 ;1
L 8.7575 4.3075 8.7575 4.3075 27 P 0 ;1
L 8.7575 4.3575 8.7575 4.3575 27 P 0 ;1
L 8.7575 4.4075 8.7575 4.4075 27 P 0 ;1
L 8.7575 4.4575 8.7575 4.4575 27 P 0 ;1
L 8.7575 4.5075 8.7575 4.5075 27 P 0 ;1
L 8.7575 4.5575 8.7575 4.5575 27 P 0 ;1
L 8.7575 5.3075 8.7575 5.3075 27 P 0 ;1
L 8.7575 5.3575 8.7575 5.3575 27 P 0 ;1
L 8.7575 5.6575 8.7575 5.6575 27 P 0 ;1
L 8.7575 5.7075 8.7575 5.7075 27 P 0 ;1
L 8.7575 5.7575 8.7575 5.7575 27 P 0 ;1
L 8.7575 5.8075 8.7575 5.8075 27 P 0 ;1
L 8.7575 5.8575 8.7575 5.8575 27 P 0 ;1
L 8.8075 0.1575 8.8075 0.1575 27 P 0 ;1
L 8.8075 0.2075 8.8075 0.2075 27 P 0 ;1
L 8.8075 0.2575 8.8075 0.2575 27 P 0 ;1
L 8.8075 0.3075 8.8075 0.3075 27 P 0 ;1
L 8.8075 0.3575 8.8075 0.3575 27 P 0 ;1
L 8.8075 0.4075 8.8075 0.4075 27 P 0 ;1
L 8.8075 0.4575 8.8075 0.4575 27 P 0 ;1
L 8.8075 0.5075 8.8075 0.5075 27 P 0 ;1
L 8.8075 0.5575 8.8075 0.5575 27 P 0 ;1
L 8.8075 0.6075 8.8075 0.6075 27 P 0 ;1
L 8.8075 0.6575 8.8075 0.6575 27 P 0 ;1
L 8.8075 0.7075 8.8075 0.7075 27 P 0 ;1
L 8.8075 0.7575 8.8075 0.7575 27 P 0 ;1
L 8.8075 0.8075 8.8075 0.8075 27 P 0 ;1
L 8.8075 0.8575 8.8075 0.8575 27 P 0 ;1
L 8.8075 0.9075 8.8075 0.9075 27 P 0 ;1
L 8.8075 0.9575 8.8075 0.9575 27 P 0 ;1
L 8.8075 1.0075 8.8075 1.0075 27 P 0 ;1
L 8.8075 1.0575 8.8075 1.0575 27 P 0 ;1
L 8.8075 1.1075 8.8075 1.1075 27 P 0 ;1
L 8.8075 1.1575 8.8075 1.1575 27 P 0 ;1
L 8.8075 1.2075 8.8075 1.2075 27 P 0 ;1
L 8.8075 1.2575 8.8075 1.2575 27 P 0 ;1
L 8.8075 1.3075 8.8075 1.3075 27 P 0 ;1
L 8.8075 1.3575 8.8075 1.3575 27 P 0 ;1
L 8.8075 1.4075 8.8075 1.4075 27 P 0 ;1
L 8.8075 1.4575 8.8075 1.4575 27 P 0 ;1
L 8.8075 1.5075 8.8075 1.5075 27 P 0 ;1
L 8.8075 1.5575 8.8075 1.5575 27 P 0 ;1
L 8.8075 1.6075 8.8075 1.6075 27 P 0 ;1
L 8.8075 1.6575 8.8075 1.6575 27 P 0 ;1
L 8.8075 1.7075 8.8075 1.7075 27 P 0 ;1
L 8.8075 1.7575 8.8075 1.7575 27 P 0 ;1
L 8.8075 1.8075 8.8075 1.8075 27 P 0 ;1
L 8.8075 1.8575 8.8075 1.8575 27 P 0 ;1
L 8.8075 1.9075 8.8075 1.9075 27 P 0 ;1
L 8.8075 1.9575 8.8075 1.9575 27 P 0 ;1
L 8.8075 3.7575 8.8075 3.7575 27 P 0 ;1
L 8.8075 3.8075 8.8075 3.8075 27 P 0 ;1
L 8.8075 3.8575 8.8075 3.8575 27 P 0 ;1
L 8.8075 3.9075 8.8075 3.9075 27 P 0 ;1
L 8.8075 3.9575 8.8075 3.9575 27 P 0 ;1
L 8.8075 4.0075 8.8075 4.0075 27 P 0 ;1
L 8.8075 4.0575 8.8075 4.0575 27 P 0 ;1
L 8.8075 4.1075 8.8075 4.1075 27 P 0 ;1
L 8.8075 4.1575 8.8075 4.1575 27 P 0 ;1
L 8.8075 4.2075 8.8075 4.2075 27 P 0 ;1
L 8.8075 4.2575 8.8075 4.2575 27 P 0 ;1
L 8.8075 4.3075 8.8075 4.3075 27 P 0 ;1
L 8.8075 4.3575 8.8075 4.3575 27 P 0 ;1
L 8.8075 4.4075 8.8075 4.4075 27 P 0 ;1
L 8.8075 4.4575 8.8075 4.4575 27 P 0 ;1
L 8.8075 4.5075 8.8075 4.5075 27 P 0 ;1
L 8.8075 4.5575 8.8075 4.5575 27 P 0 ;1
L 8.8075 5.3075 8.8075 5.3075 27 P 0 ;1
L 8.8075 5.3575 8.8075 5.3575 27 P 0 ;1
L 8.8075 5.6575 8.8075 5.6575 27 P 0 ;1
L 8.8075 5.7075 8.8075 5.7075 27 P 0 ;1
L 8.8075 5.7575 8.8075 5.7575 27 P 0 ;1
L 8.8075 5.8075 8.8075 5.8075 27 P 0 ;1
L 8.8075 5.8575 8.8075 5.8575 27 P 0 ;1
L 8.8575 0.1575 8.8575 0.1575 27 P 0 ;1
L 8.8575 0.2075 8.8575 0.2075 27 P 0 ;1
L 8.8575 0.2575 8.8575 0.2575 27 P 0 ;1
L 8.8575 0.3075 8.8575 0.3075 27 P 0 ;1
L 8.8575 0.3575 8.8575 0.3575 27 P 0 ;1
L 8.8575 0.4075 8.8575 0.4075 27 P 0 ;1
L 8.8575 0.4575 8.8575 0.4575 27 P 0 ;1
L 8.8575 0.5075 8.8575 0.5075 27 P 0 ;1
L 8.8575 0.5575 8.8575 0.5575 27 P 0 ;1
L 8.8575 0.6075 8.8575 0.6075 27 P 0 ;1
L 8.8575 0.6575 8.8575 0.6575 27 P 0 ;1
L 8.8575 0.7075 8.8575 0.7075 27 P 0 ;1
L 8.8575 0.7575 8.8575 0.7575 27 P 0 ;1
L 8.8575 0.8075 8.8575 0.8075 27 P 0 ;1
L 8.8575 0.8575 8.8575 0.8575 27 P 0 ;1
L 8.8575 0.9075 8.8575 0.9075 27 P 0 ;1
L 8.8575 0.9575 8.8575 0.9575 27 P 0 ;1
L 8.8575 1.0075 8.8575 1.0075 27 P 0 ;1
L 8.8575 1.0575 8.8575 1.0575 27 P 0 ;1
L 8.8575 1.1075 8.8575 1.1075 27 P 0 ;1
L 8.8575 1.1575 8.8575 1.1575 27 P 0 ;1
L 8.8575 1.2075 8.8575 1.2075 27 P 0 ;1
L 8.8575 1.2575 8.8575 1.2575 27 P 0 ;1
L 8.8575 1.3075 8.8575 1.3075 27 P 0 ;1
L 8.8575 1.3575 8.8575 1.3575 27 P 0 ;1
L 8.8575 1.4075 8.8575 1.4075 27 P 0 ;1
L 8.8575 1.4575 8.8575 1.4575 27 P 0 ;1
L 8.8575 1.5075 8.8575 1.5075 27 P 0 ;1
L 8.8575 1.5575 8.8575 1.5575 27 P 0 ;1
L 8.8575 1.6075 8.8575 1.6075 27 P 0 ;1
L 8.8575 1.6575 8.8575 1.6575 27 P 0 ;1
L 8.8575 1.7075 8.8575 1.7075 27 P 0 ;1
L 8.8575 1.7575 8.8575 1.7575 27 P 0 ;1
L 8.8575 1.8075 8.8575 1.8075 27 P 0 ;1
L 8.8575 1.8575 8.8575 1.8575 27 P 0 ;1
L 8.8575 1.9075 8.8575 1.9075 27 P 0 ;1
L 8.8575 1.9575 8.8575 1.9575 27 P 0 ;1
L 8.8575 3.7575 8.8575 3.7575 27 P 0 ;1
L 8.8575 3.8075 8.8575 3.8075 27 P 0 ;1
L 8.8575 3.8575 8.8575 3.8575 27 P 0 ;1
L 8.8575 3.9075 8.8575 3.9075 27 P 0 ;1
L 8.8575 3.9575 8.8575 3.9575 27 P 0 ;1
L 8.8575 4.0075 8.8575 4.0075 27 P 0 ;1
L 8.8575 4.0575 8.8575 4.0575 27 P 0 ;1
L 8.8575 4.1075 8.8575 4.1075 27 P 0 ;1
L 8.8575 4.1575 8.8575 4.1575 27 P 0 ;1
L 8.8575 4.2075 8.8575 4.2075 27 P 0 ;1
L 8.8575 4.2575 8.8575 4.2575 27 P 0 ;1
L 8.8575 4.3075 8.8575 4.3075 27 P 0 ;1
L 8.8575 4.3575 8.8575 4.3575 27 P 0 ;1
L 8.8575 4.4075 8.8575 4.4075 27 P 0 ;1
L 8.8575 4.4575 8.8575 4.4575 27 P 0 ;1
L 8.8575 4.5075 8.8575 4.5075 27 P 0 ;1
L 8.8575 4.5575 8.8575 4.5575 27 P 0 ;1
L 8.8575 5.3075 8.8575 5.3075 27 P 0 ;1
L 8.8575 5.3575 8.8575 5.3575 27 P 0 ;1
L 8.8575 5.6575 8.8575 5.6575 27 P 0 ;1
L 8.8575 5.7075 8.8575 5.7075 27 P 0 ;1
L 8.8575 5.7575 8.8575 5.7575 27 P 0 ;1
L 8.8575 5.8075 8.8575 5.8075 27 P 0 ;1
L 8.8575 5.8575 8.8575 5.8575 27 P 0 ;1
L 8.9075 0.1575 8.9075 0.1575 27 P 0 ;1
L 8.9075 0.2075 8.9075 0.2075 27 P 0 ;1
L 8.9075 0.2575 8.9075 0.2575 27 P 0 ;1
L 8.9075 0.3075 8.9075 0.3075 27 P 0 ;1
L 8.9075 0.3575 8.9075 0.3575 27 P 0 ;1
L 8.9075 0.4075 8.9075 0.4075 27 P 0 ;1
L 8.9075 0.4575 8.9075 0.4575 27 P 0 ;1
L 8.9075 0.5075 8.9075 0.5075 27 P 0 ;1
L 8.9075 0.5575 8.9075 0.5575 27 P 0 ;1
L 8.9075 0.6075 8.9075 0.6075 27 P 0 ;1
L 8.9075 0.6575 8.9075 0.6575 27 P 0 ;1
L 8.9075 0.7075 8.9075 0.7075 27 P 0 ;1
L 8.9075 0.7575 8.9075 0.7575 27 P 0 ;1
L 8.9075 0.8075 8.9075 0.8075 27 P 0 ;1
L 8.9075 0.8575 8.9075 0.8575 27 P 0 ;1
L 8.9075 0.9075 8.9075 0.9075 27 P 0 ;1
L 8.9075 0.9575 8.9075 0.9575 27 P 0 ;1
L 8.9075 1.0075 8.9075 1.0075 27 P 0 ;1
L 8.9075 1.0575 8.9075 1.0575 27 P 0 ;1
L 8.9075 1.1075 8.9075 1.1075 27 P 0 ;1
L 8.9075 1.1575 8.9075 1.1575 27 P 0 ;1
L 8.9075 1.2075 8.9075 1.2075 27 P 0 ;1
L 8.9075 1.2575 8.9075 1.2575 27 P 0 ;1
L 8.9075 1.3075 8.9075 1.3075 27 P 0 ;1
L 8.9075 1.3575 8.9075 1.3575 27 P 0 ;1
L 8.9075 1.4075 8.9075 1.4075 27 P 0 ;1
L 8.9075 1.4575 8.9075 1.4575 27 P 0 ;1
L 8.9075 1.5075 8.9075 1.5075 27 P 0 ;1
L 8.9075 1.5575 8.9075 1.5575 27 P 0 ;1
L 8.9075 1.6075 8.9075 1.6075 27 P 0 ;1
L 8.9075 1.6575 8.9075 1.6575 27 P 0 ;1
L 8.9075 1.7075 8.9075 1.7075 27 P 0 ;1
L 8.9075 1.7575 8.9075 1.7575 27 P 0 ;1
L 8.9075 1.8075 8.9075 1.8075 27 P 0 ;1
L 8.9075 1.8575 8.9075 1.8575 27 P 0 ;1
L 8.9075 1.9075 8.9075 1.9075 27 P 0 ;1
L 8.9075 1.9575 8.9075 1.9575 27 P 0 ;1
L 8.9075 3.7575 8.9075 3.7575 27 P 0 ;1
L 8.9075 3.8075 8.9075 3.8075 27 P 0 ;1
L 8.9075 3.8575 8.9075 3.8575 27 P 0 ;1
L 8.9075 3.9075 8.9075 3.9075 27 P 0 ;1
L 8.9075 3.9575 8.9075 3.9575 27 P 0 ;1
L 8.9075 4.0075 8.9075 4.0075 27 P 0 ;1
L 8.9075 4.0575 8.9075 4.0575 27 P 0 ;1
L 8.9075 4.1075 8.9075 4.1075 27 P 0 ;1
L 8.9075 4.1575 8.9075 4.1575 27 P 0 ;1
L 8.9075 4.2075 8.9075 4.2075 27 P 0 ;1
L 8.9075 4.2575 8.9075 4.2575 27 P 0 ;1
L 8.9075 4.3075 8.9075 4.3075 27 P 0 ;1
L 8.9075 4.3575 8.9075 4.3575 27 P 0 ;1
L 8.9075 4.4075 8.9075 4.4075 27 P 0 ;1
L 8.9075 4.4575 8.9075 4.4575 27 P 0 ;1
L 8.9075 4.5075 8.9075 4.5075 27 P 0 ;1
L 8.9075 4.5575 8.9075 4.5575 27 P 0 ;1
L 8.9075 5.3075 8.9075 5.3075 27 P 0 ;1
L 8.9075 5.3575 8.9075 5.3575 27 P 0 ;1
L 8.9075 5.6575 8.9075 5.6575 27 P 0 ;1
L 8.9075 5.7075 8.9075 5.7075 27 P 0 ;1
L 8.9075 5.7575 8.9075 5.7575 27 P 0 ;1
L 8.9075 5.8075 8.9075 5.8075 27 P 0 ;1
L 8.9075 5.8575 8.9075 5.8575 27 P 0 ;1
L 8.9575 0.1575 8.9575 0.1575 27 P 0 ;1
L 8.9575 0.2075 8.9575 0.2075 27 P 0 ;1
L 8.9575 0.2575 8.9575 0.2575 27 P 0 ;1
L 8.9575 0.3075 8.9575 0.3075 27 P 0 ;1
L 8.9575 0.3575 8.9575 0.3575 27 P 0 ;1
L 8.9575 0.4075 8.9575 0.4075 27 P 0 ;1
L 8.9575 0.4575 8.9575 0.4575 27 P 0 ;1
L 8.9575 0.5075 8.9575 0.5075 27 P 0 ;1
L 8.9575 0.5575 8.9575 0.5575 27 P 0 ;1
L 8.9575 0.6075 8.9575 0.6075 27 P 0 ;1
L 8.9575 0.6575 8.9575 0.6575 27 P 0 ;1
L 8.9575 0.7075 8.9575 0.7075 27 P 0 ;1
L 8.9575 0.7575 8.9575 0.7575 27 P 0 ;1
L 8.9575 0.8075 8.9575 0.8075 27 P 0 ;1
L 8.9575 0.8575 8.9575 0.8575 27 P 0 ;1
L 8.9575 0.9075 8.9575 0.9075 27 P 0 ;1
L 8.9575 0.9575 8.9575 0.9575 27 P 0 ;1
L 8.9575 1.0075 8.9575 1.0075 27 P 0 ;1
L 8.9575 1.0575 8.9575 1.0575 27 P 0 ;1
L 8.9575 1.1075 8.9575 1.1075 27 P 0 ;1
L 8.9575 1.1575 8.9575 1.1575 27 P 0 ;1
L 8.9575 1.2075 8.9575 1.2075 27 P 0 ;1
L 8.9575 1.2575 8.9575 1.2575 27 P 0 ;1
L 8.9575 1.3075 8.9575 1.3075 27 P 0 ;1
L 8.9575 1.3575 8.9575 1.3575 27 P 0 ;1
L 8.9575 1.4075 8.9575 1.4075 27 P 0 ;1
L 8.9575 1.4575 8.9575 1.4575 27 P 0 ;1
L 8.9575 1.5075 8.9575 1.5075 27 P 0 ;1
L 8.9575 1.5575 8.9575 1.5575 27 P 0 ;1
L 8.9575 1.6075 8.9575 1.6075 27 P 0 ;1
L 8.9575 1.6575 8.9575 1.6575 27 P 0 ;1
L 8.9575 1.7075 8.9575 1.7075 27 P 0 ;1
L 8.9575 1.7575 8.9575 1.7575 27 P 0 ;1
L 8.9575 1.8075 8.9575 1.8075 27 P 0 ;1
L 8.9575 1.8575 8.9575 1.8575 27 P 0 ;1
L 8.9575 1.9075 8.9575 1.9075 27 P 0 ;1
L 8.9575 1.9575 8.9575 1.9575 27 P 0 ;1
L 8.9575 3.7575 8.9575 3.7575 27 P 0 ;1
L 8.9575 3.8075 8.9575 3.8075 27 P 0 ;1
L 8.9575 3.8575 8.9575 3.8575 27 P 0 ;1
L 8.9575 3.9075 8.9575 3.9075 27 P 0 ;1
L 8.9575 3.9575 8.9575 3.9575 27 P 0 ;1
L 8.9575 4.0075 8.9575 4.0075 27 P 0 ;1
L 8.9575 4.0575 8.9575 4.0575 27 P 0 ;1
L 8.9575 4.1075 8.9575 4.1075 27 P 0 ;1
L 8.9575 4.1575 8.9575 4.1575 27 P 0 ;1
L 8.9575 4.2075 8.9575 4.2075 27 P 0 ;1
L 8.9575 4.2575 8.9575 4.2575 27 P 0 ;1
L 8.9575 4.3075 8.9575 4.3075 27 P 0 ;1
L 8.9575 4.3575 8.9575 4.3575 27 P 0 ;1
L 8.9575 4.4075 8.9575 4.4075 27 P 0 ;1
L 8.9575 4.4575 8.9575 4.4575 27 P 0 ;1
L 8.9575 4.5075 8.9575 4.5075 27 P 0 ;1
L 8.9575 4.5575 8.9575 4.5575 27 P 0 ;1
L 8.9575 5.3075 8.9575 5.3075 27 P 0 ;1
L 8.9575 5.3575 8.9575 5.3575 27 P 0 ;1
L 8.9575 5.6575 8.9575 5.6575 27 P 0 ;1
L 8.9575 5.7075 8.9575 5.7075 27 P 0 ;1
L 8.9575 5.7575 8.9575 5.7575 27 P 0 ;1
L 8.9575 5.8075 8.9575 5.8075 27 P 0 ;1
L 8.9575 5.8575 8.9575 5.8575 27 P 0 ;1
L 9.0075 0.1575 9.0075 0.1575 27 P 0 ;1
L 9.0075 0.2075 9.0075 0.2075 27 P 0 ;1
L 9.0075 0.2575 9.0075 0.2575 27 P 0 ;1
L 9.0075 0.3075 9.0075 0.3075 27 P 0 ;1
L 9.0075 0.3575 9.0075 0.3575 27 P 0 ;1
L 9.0075 0.4075 9.0075 0.4075 27 P 0 ;1
L 9.0075 0.4575 9.0075 0.4575 27 P 0 ;1
L 9.0075 0.5075 9.0075 0.5075 27 P 0 ;1
L 9.0075 0.5575 9.0075 0.5575 27 P 0 ;1
L 9.0075 0.6075 9.0075 0.6075 27 P 0 ;1
L 9.0075 0.6575 9.0075 0.6575 27 P 0 ;1
L 9.0075 0.7075 9.0075 0.7075 27 P 0 ;1
L 9.0075 0.7575 9.0075 0.7575 27 P 0 ;1
L 9.0075 0.8075 9.0075 0.8075 27 P 0 ;1
L 9.0075 0.8575 9.0075 0.8575 27 P 0 ;1
L 9.0075 0.9075 9.0075 0.9075 27 P 0 ;1
L 9.0075 0.9575 9.0075 0.9575 27 P 0 ;1
L 9.0075 1.0075 9.0075 1.0075 27 P 0 ;1
L 9.0075 1.0575 9.0075 1.0575 27 P 0 ;1
L 9.0075 1.1075 9.0075 1.1075 27 P 0 ;1
L 9.0075 1.1575 9.0075 1.1575 27 P 0 ;1
L 9.0075 1.2075 9.0075 1.2075 27 P 0 ;1
L 9.0075 1.2575 9.0075 1.2575 27 P 0 ;1
L 9.0075 1.3075 9.0075 1.3075 27 P 0 ;1
L 9.0075 1.3575 9.0075 1.3575 27 P 0 ;1
L 9.0075 1.4075 9.0075 1.4075 27 P 0 ;1
L 9.0075 1.4575 9.0075 1.4575 27 P 0 ;1
L 9.0075 1.5075 9.0075 1.5075 27 P 0 ;1
L 9.0075 1.5575 9.0075 1.5575 27 P 0 ;1
L 9.0075 1.6075 9.0075 1.6075 27 P 0 ;1
L 9.0075 1.6575 9.0075 1.6575 27 P 0 ;1
L 9.0075 1.7075 9.0075 1.7075 27 P 0 ;1
L 9.0075 1.7575 9.0075 1.7575 27 P 0 ;1
L 9.0075 1.8075 9.0075 1.8075 27 P 0 ;1
L 9.0075 1.8575 9.0075 1.8575 27 P 0 ;1
L 9.0075 1.9075 9.0075 1.9075 27 P 0 ;1
L 9.0075 1.9575 9.0075 1.9575 27 P 0 ;1
L 9.0075 2.0075 9.0075 2.0075 27 P 0 ;1
L 9.0075 2.0575 9.0075 2.0575 27 P 0 ;1
L 9.0075 2.1075 9.0075 2.1075 27 P 0 ;1
L 9.0075 2.1575 9.0075 2.1575 27 P 0 ;1
L 9.0075 2.2075 9.0075 2.2075 27 P 0 ;1
L 9.0075 2.2575 9.0075 2.2575 27 P 0 ;1
L 9.0075 2.3075 9.0075 2.3075 27 P 0 ;1
L 9.0075 2.3575 9.0075 2.3575 27 P 0 ;1
L 9.0075 2.4075 9.0075 2.4075 27 P 0 ;1
L 9.0075 2.4575 9.0075 2.4575 27 P 0 ;1
L 9.0075 2.5075 9.0075 2.5075 27 P 0 ;1
L 9.0075 2.5575 9.0075 2.5575 27 P 0 ;1
L 9.0075 2.6075 9.0075 2.6075 27 P 0 ;1
L 9.0075 2.6575 9.0075 2.6575 27 P 0 ;1
L 9.0075 3.0075 9.0075 3.0075 27 P 0 ;1
L 9.0075 3.0575 9.0075 3.0575 27 P 0 ;1
L 9.0075 3.1075 9.0075 3.1075 27 P 0 ;1
L 9.0075 3.1575 9.0075 3.1575 27 P 0 ;1
L 9.0075 3.2075 9.0075 3.2075 27 P 0 ;1
L 9.0075 3.2575 9.0075 3.2575 27 P 0 ;1
L 9.0075 3.3075 9.0075 3.3075 27 P 0 ;1
L 9.0075 3.3575 9.0075 3.3575 27 P 0 ;1
L 9.0075 3.4075 9.0075 3.4075 27 P 0 ;1
L 9.0075 3.4575 9.0075 3.4575 27 P 0 ;1
L 9.0075 3.5075 9.0075 3.5075 27 P 0 ;1
L 9.0075 3.5575 9.0075 3.5575 27 P 0 ;1
L 9.0075 3.6075 9.0075 3.6075 27 P 0 ;1
L 9.0075 3.6575 9.0075 3.6575 27 P 0 ;1
L 9.0075 3.7075 9.0075 3.7075 27 P 0 ;1
L 9.0075 3.7575 9.0075 3.7575 27 P 0 ;1
L 9.0075 3.8075 9.0075 3.8075 27 P 0 ;1
L 9.0075 3.8575 9.0075 3.8575 27 P 0 ;1
L 9.0075 3.9075 9.0075 3.9075 27 P 0 ;1
L 9.0075 3.9575 9.0075 3.9575 27 P 0 ;1
L 9.0075 4.0075 9.0075 4.0075 27 P 0 ;1
L 9.0075 4.0575 9.0075 4.0575 27 P 0 ;1
L 9.0075 4.1075 9.0075 4.1075 27 P 0 ;1
L 9.0075 4.1575 9.0075 4.1575 27 P 0 ;1
L 9.0075 4.2075 9.0075 4.2075 27 P 0 ;1
L 9.0075 4.2575 9.0075 4.2575 27 P 0 ;1
L 9.0075 4.3075 9.0075 4.3075 27 P 0 ;1
L 9.0075 5.6575 9.0075 5.6575 27 P 0 ;1
L 9.0075 5.7075 9.0075 5.7075 27 P 0 ;1
L 9.0075 5.7575 9.0075 5.7575 27 P 0 ;1
L 9.0075 5.8075 9.0075 5.8075 27 P 0 ;1
L 9.0075 5.8575 9.0075 5.8575 27 P 0 ;1
L 9.0575 0.1575 9.0575 0.1575 27 P 0 ;1
L 9.0575 0.2075 9.0575 0.2075 27 P 0 ;1
L 9.0575 0.2575 9.0575 0.2575 27 P 0 ;1
L 9.0575 0.3075 9.0575 0.3075 27 P 0 ;1
L 9.0575 0.3575 9.0575 0.3575 27 P 0 ;1
L 9.0575 0.4075 9.0575 0.4075 27 P 0 ;1
L 9.0575 0.4575 9.0575 0.4575 27 P 0 ;1
L 9.0575 0.5075 9.0575 0.5075 27 P 0 ;1
L 9.0575 0.5575 9.0575 0.5575 27 P 0 ;1
L 9.0575 0.6075 9.0575 0.6075 27 P 0 ;1
L 9.0575 0.6575 9.0575 0.6575 27 P 0 ;1
L 9.0575 0.7075 9.0575 0.7075 27 P 0 ;1
L 9.0575 0.7575 9.0575 0.7575 27 P 0 ;1
L 9.0575 0.8075 9.0575 0.8075 27 P 0 ;1
L 9.0575 0.8575 9.0575 0.8575 27 P 0 ;1
L 9.0575 0.9075 9.0575 0.9075 27 P 0 ;1
L 9.0575 0.9575 9.0575 0.9575 27 P 0 ;1
L 9.0575 1.0075 9.0575 1.0075 27 P 0 ;1
L 9.0575 1.0575 9.0575 1.0575 27 P 0 ;1
L 9.0575 1.1075 9.0575 1.1075 27 P 0 ;1
L 9.0575 1.1575 9.0575 1.1575 27 P 0 ;1
L 9.0575 1.2075 9.0575 1.2075 27 P 0 ;1
L 9.0575 1.2575 9.0575 1.2575 27 P 0 ;1
L 9.0575 1.3075 9.0575 1.3075 27 P 0 ;1
L 9.0575 1.3575 9.0575 1.3575 27 P 0 ;1
L 9.0575 1.4075 9.0575 1.4075 27 P 0 ;1
L 9.0575 1.4575 9.0575 1.4575 27 P 0 ;1
L 9.0575 1.5075 9.0575 1.5075 27 P 0 ;1
L 9.0575 1.5575 9.0575 1.5575 27 P 0 ;1
L 9.0575 1.6075 9.0575 1.6075 27 P 0 ;1
L 9.0575 1.6575 9.0575 1.6575 27 P 0 ;1
L 9.0575 1.7075 9.0575 1.7075 27 P 0 ;1
L 9.0575 1.7575 9.0575 1.7575 27 P 0 ;1
L 9.0575 1.8075 9.0575 1.8075 27 P 0 ;1
L 9.0575 1.8575 9.0575 1.8575 27 P 0 ;1
L 9.0575 1.9075 9.0575 1.9075 27 P 0 ;1
L 9.0575 1.9575 9.0575 1.9575 27 P 0 ;1
L 9.0575 2.0075 9.0575 2.0075 27 P 0 ;1
L 9.0575 2.0575 9.0575 2.0575 27 P 0 ;1
L 9.0575 2.1075 9.0575 2.1075 27 P 0 ;1
L 9.0575 2.1575 9.0575 2.1575 27 P 0 ;1
L 9.0575 2.2075 9.0575 2.2075 27 P 0 ;1
L 9.0575 2.2575 9.0575 2.2575 27 P 0 ;1
L 9.0575 2.3075 9.0575 2.3075 27 P 0 ;1
L 9.0575 2.3575 9.0575 2.3575 27 P 0 ;1
L 9.0575 2.4075 9.0575 2.4075 27 P 0 ;1
L 9.0575 2.4575 9.0575 2.4575 27 P 0 ;1
L 9.0575 2.5075 9.0575 2.5075 27 P 0 ;1
L 9.0575 2.5575 9.0575 2.5575 27 P 0 ;1
L 9.0575 2.6075 9.0575 2.6075 27 P 0 ;1
L 9.0575 2.6575 9.0575 2.6575 27 P 0 ;1
L 9.0575 2.7075 9.0575 2.7075 27 P 0 ;1
L 9.0575 2.9575 9.0575 2.9575 27 P 0 ;1
L 9.0575 3.0075 9.0575 3.0075 27 P 0 ;1
L 9.0575 3.0575 9.0575 3.0575 27 P 0 ;1
L 9.0575 3.1075 9.0575 3.1075 27 P 0 ;1
L 9.0575 3.1575 9.0575 3.1575 27 P 0 ;1
L 9.0575 3.2075 9.0575 3.2075 27 P 0 ;1
L 9.0575 3.2575 9.0575 3.2575 27 P 0 ;1
L 9.0575 3.3075 9.0575 3.3075 27 P 0 ;1
L 9.0575 3.3575 9.0575 3.3575 27 P 0 ;1
L 9.0575 3.4075 9.0575 3.4075 27 P 0 ;1
L 9.0575 3.4575 9.0575 3.4575 27 P 0 ;1
L 9.0575 3.5075 9.0575 3.5075 27 P 0 ;1
L 9.0575 3.5575 9.0575 3.5575 27 P 0 ;1
L 9.0575 3.6075 9.0575 3.6075 27 P 0 ;1
L 9.0575 3.6575 9.0575 3.6575 27 P 0 ;1
L 9.0575 3.7075 9.0575 3.7075 27 P 0 ;1
L 9.0575 3.7575 9.0575 3.7575 27 P 0 ;1
L 9.0575 3.8075 9.0575 3.8075 27 P 0 ;1
L 9.0575 3.8575 9.0575 3.8575 27 P 0 ;1
L 9.0575 3.9075 9.0575 3.9075 27 P 0 ;1
L 9.0575 3.9575 9.0575 3.9575 27 P 0 ;1
L 9.0575 4.0075 9.0575 4.0075 27 P 0 ;1
L 9.0575 4.0575 9.0575 4.0575 27 P 0 ;1
L 9.0575 4.1075 9.0575 4.1075 27 P 0 ;1
L 9.0575 4.1575 9.0575 4.1575 27 P 0 ;1
L 9.0575 4.2075 9.0575 4.2075 27 P 0 ;1
L 9.0575 4.2575 9.0575 4.2575 27 P 0 ;1
L 9.0575 4.3075 9.0575 4.3075 27 P 0 ;1
L 9.0575 5.6575 9.0575 5.6575 27 P 0 ;1
L 9.0575 5.7075 9.0575 5.7075 27 P 0 ;1
L 9.0575 5.7575 9.0575 5.7575 27 P 0 ;1
L 9.0575 5.8075 9.0575 5.8075 27 P 0 ;1
L 9.0575 5.8575 9.0575 5.8575 27 P 0 ;1
L 9.1075 0.1575 9.1075 0.1575 27 P 0 ;1
L 9.1075 0.2075 9.1075 0.2075 27 P 0 ;1
L 9.1075 0.2575 9.1075 0.2575 27 P 0 ;1
L 9.1075 0.3075 9.1075 0.3075 27 P 0 ;1
L 9.1075 0.3575 9.1075 0.3575 27 P 0 ;1
L 9.1075 0.4075 9.1075 0.4075 27 P 0 ;1
L 9.1075 0.4575 9.1075 0.4575 27 P 0 ;1
L 9.1075 0.5075 9.1075 0.5075 27 P 0 ;1
L 9.1075 0.5575 9.1075 0.5575 27 P 0 ;1
L 9.1075 0.6075 9.1075 0.6075 27 P 0 ;1
L 9.1075 0.6575 9.1075 0.6575 27 P 0 ;1
L 9.1075 0.7075 9.1075 0.7075 27 P 0 ;1
L 9.1075 0.7575 9.1075 0.7575 27 P 0 ;1
L 9.1075 0.8075 9.1075 0.8075 27 P 0 ;1
L 9.1075 0.8575 9.1075 0.8575 27 P 0 ;1
L 9.1075 0.9075 9.1075 0.9075 27 P 0 ;1
L 9.1075 0.9575 9.1075 0.9575 27 P 0 ;1
L 9.1075 1.0075 9.1075 1.0075 27 P 0 ;1
L 9.1075 1.0575 9.1075 1.0575 27 P 0 ;1
L 9.1075 1.1075 9.1075 1.1075 27 P 0 ;1
L 9.1075 1.1575 9.1075 1.1575 27 P 0 ;1
L 9.1075 1.2075 9.1075 1.2075 27 P 0 ;1
L 9.1075 1.2575 9.1075 1.2575 27 P 0 ;1
L 9.1075 1.3075 9.1075 1.3075 27 P 0 ;1
L 9.1075 1.3575 9.1075 1.3575 27 P 0 ;1
L 9.1075 1.4075 9.1075 1.4075 27 P 0 ;1
L 9.1075 1.4575 9.1075 1.4575 27 P 0 ;1
L 9.1075 1.5075 9.1075 1.5075 27 P 0 ;1
L 9.1075 1.5575 9.1075 1.5575 27 P 0 ;1
L 9.1075 1.6075 9.1075 1.6075 27 P 0 ;1
L 9.1075 1.6575 9.1075 1.6575 27 P 0 ;1
L 9.1075 1.7075 9.1075 1.7075 27 P 0 ;1
L 9.1075 1.7575 9.1075 1.7575 27 P 0 ;1
L 9.1075 1.8075 9.1075 1.8075 27 P 0 ;1
L 9.1075 1.8575 9.1075 1.8575 27 P 0 ;1
L 9.1075 1.9075 9.1075 1.9075 27 P 0 ;1
L 9.1075 1.9575 9.1075 1.9575 27 P 0 ;1
L 9.1075 2.0075 9.1075 2.0075 27 P 0 ;1
L 9.1075 2.0575 9.1075 2.0575 27 P 0 ;1
L 9.1075 2.1075 9.1075 2.1075 27 P 0 ;1
L 9.1075 2.1575 9.1075 2.1575 27 P 0 ;1
L 9.1075 2.2075 9.1075 2.2075 27 P 0 ;1
L 9.1075 2.2575 9.1075 2.2575 27 P 0 ;1
L 9.1075 2.3075 9.1075 2.3075 27 P 0 ;1
L 9.1075 2.3575 9.1075 2.3575 27 P 0 ;1
L 9.1075 2.4075 9.1075 2.4075 27 P 0 ;1
L 9.1075 2.4575 9.1075 2.4575 27 P 0 ;1
L 9.1075 2.5075 9.1075 2.5075 27 P 0 ;1
L 9.1075 2.5575 9.1075 2.5575 27 P 0 ;1
L 9.1075 2.6075 9.1075 2.6075 27 P 0 ;1
L 9.1075 2.6575 9.1075 2.6575 27 P 0 ;1
L 9.1075 2.7075 9.1075 2.7075 27 P 0 ;1
L 9.1075 2.7575 9.1075 2.7575 27 P 0 ;1
L 9.1075 2.8075 9.1075 2.8075 27 P 0 ;1
L 9.1075 2.8575 9.1075 2.8575 27 P 0 ;1
L 9.1075 2.9075 9.1075 2.9075 27 P 0 ;1
L 9.1075 2.9575 9.1075 2.9575 27 P 0 ;1
L 9.1075 3.0075 9.1075 3.0075 27 P 0 ;1
L 9.1075 3.0575 9.1075 3.0575 27 P 0 ;1
L 9.1075 3.1075 9.1075 3.1075 27 P 0 ;1
L 9.1075 3.1575 9.1075 3.1575 27 P 0 ;1
L 9.1075 3.2075 9.1075 3.2075 27 P 0 ;1
L 9.1075 3.2575 9.1075 3.2575 27 P 0 ;1
L 9.1075 3.3075 9.1075 3.3075 27 P 0 ;1
L 9.1075 3.3575 9.1075 3.3575 27 P 0 ;1
L 9.1075 3.4075 9.1075 3.4075 27 P 0 ;1
L 9.1075 3.4575 9.1075 3.4575 27 P 0 ;1
L 9.1075 3.5075 9.1075 3.5075 27 P 0 ;1
L 9.1075 3.5575 9.1075 3.5575 27 P 0 ;1
L 9.1075 3.6075 9.1075 3.6075 27 P 0 ;1
L 9.1075 3.6575 9.1075 3.6575 27 P 0 ;1
L 9.1075 3.7075 9.1075 3.7075 27 P 0 ;1
L 9.1075 3.7575 9.1075 3.7575 27 P 0 ;1
L 9.1075 3.8075 9.1075 3.8075 27 P 0 ;1
L 9.1075 3.8575 9.1075 3.8575 27 P 0 ;1
L 9.1075 3.9075 9.1075 3.9075 27 P 0 ;1
L 9.1075 3.9575 9.1075 3.9575 27 P 0 ;1
L 9.1075 4.0075 9.1075 4.0075 27 P 0 ;1
L 9.1075 4.0575 9.1075 4.0575 27 P 0 ;1
L 9.1075 4.1075 9.1075 4.1075 27 P 0 ;1
L 9.1075 4.1575 9.1075 4.1575 27 P 0 ;1
L 9.1075 4.2075 9.1075 4.2075 27 P 0 ;1
L 9.1075 4.2575 9.1075 4.2575 27 P 0 ;1
L 9.1075 4.3075 9.1075 4.3075 27 P 0 ;1
L 9.1075 5.6575 9.1075 5.6575 27 P 0 ;1
L 9.1075 5.7075 9.1075 5.7075 27 P 0 ;1
L 9.1075 5.7575 9.1075 5.7575 27 P 0 ;1
L 9.1075 5.8075 9.1075 5.8075 27 P 0 ;1
L 9.1075 5.8575 9.1075 5.8575 27 P 0 ;1
L 9.1575 0.1575 9.1575 0.1575 27 P 0 ;1
L 9.1575 0.2075 9.1575 0.2075 27 P 0 ;1
L 9.1575 0.2575 9.1575 0.2575 27 P 0 ;1
L 9.1575 0.3075 9.1575 0.3075 27 P 0 ;1
L 9.1575 0.3575 9.1575 0.3575 27 P 0 ;1
L 9.1575 0.4075 9.1575 0.4075 27 P 0 ;1
L 9.1575 0.4575 9.1575 0.4575 27 P 0 ;1
L 9.1575 0.5075 9.1575 0.5075 27 P 0 ;1
L 9.1575 0.5575 9.1575 0.5575 27 P 0 ;1
L 9.1575 0.6075 9.1575 0.6075 27 P 0 ;1
L 9.1575 0.6575 9.1575 0.6575 27 P 0 ;1
L 9.1575 0.7075 9.1575 0.7075 27 P 0 ;1
L 9.1575 0.7575 9.1575 0.7575 27 P 0 ;1
L 9.1575 0.8075 9.1575 0.8075 27 P 0 ;1
L 9.1575 0.8575 9.1575 0.8575 27 P 0 ;1
L 9.1575 0.9075 9.1575 0.9075 27 P 0 ;1
L 9.1575 0.9575 9.1575 0.9575 27 P 0 ;1
L 9.1575 1.0075 9.1575 1.0075 27 P 0 ;1
L 9.1575 1.0575 9.1575 1.0575 27 P 0 ;1
L 9.1575 1.1075 9.1575 1.1075 27 P 0 ;1
L 9.1575 1.1575 9.1575 1.1575 27 P 0 ;1
L 9.1575 1.2075 9.1575 1.2075 27 P 0 ;1
L 9.1575 1.2575 9.1575 1.2575 27 P 0 ;1
L 9.1575 1.3075 9.1575 1.3075 27 P 0 ;1
L 9.1575 1.3575 9.1575 1.3575 27 P 0 ;1
L 9.1575 1.4075 9.1575 1.4075 27 P 0 ;1
L 9.1575 1.4575 9.1575 1.4575 27 P 0 ;1
L 9.1575 1.5075 9.1575 1.5075 27 P 0 ;1
L 9.1575 1.5575 9.1575 1.5575 27 P 0 ;1
L 9.1575 1.6075 9.1575 1.6075 27 P 0 ;1
L 9.1575 1.6575 9.1575 1.6575 27 P 0 ;1
L 9.1575 1.7075 9.1575 1.7075 27 P 0 ;1
L 9.1575 1.7575 9.1575 1.7575 27 P 0 ;1
L 9.1575 1.8075 9.1575 1.8075 27 P 0 ;1
L 9.1575 1.8575 9.1575 1.8575 27 P 0 ;1
L 9.1575 1.9075 9.1575 1.9075 27 P 0 ;1
L 9.1575 1.9575 9.1575 1.9575 27 P 0 ;1
L 9.1575 2.0075 9.1575 2.0075 27 P 0 ;1
L 9.1575 2.0575 9.1575 2.0575 27 P 0 ;1
L 9.1575 2.1075 9.1575 2.1075 27 P 0 ;1
L 9.1575 2.1575 9.1575 2.1575 27 P 0 ;1
L 9.1575 2.2075 9.1575 2.2075 27 P 0 ;1
L 9.1575 2.2575 9.1575 2.2575 27 P 0 ;1
L 9.1575 2.3075 9.1575 2.3075 27 P 0 ;1
L 9.1575 2.3575 9.1575 2.3575 27 P 0 ;1
L 9.1575 2.4075 9.1575 2.4075 27 P 0 ;1
L 9.1575 2.4575 9.1575 2.4575 27 P 0 ;1
L 9.1575 2.5075 9.1575 2.5075 27 P 0 ;1
L 9.1575 2.5575 9.1575 2.5575 27 P 0 ;1
L 9.1575 2.6075 9.1575 2.6075 27 P 0 ;1
L 9.1575 2.6575 9.1575 2.6575 27 P 0 ;1
L 9.1575 2.7075 9.1575 2.7075 27 P 0 ;1
L 9.1575 2.7575 9.1575 2.7575 27 P 0 ;1
L 9.1575 2.8075 9.1575 2.8075 27 P 0 ;1
L 9.1575 2.8575 9.1575 2.8575 27 P 0 ;1
L 9.1575 2.9075 9.1575 2.9075 27 P 0 ;1
L 9.1575 2.9575 9.1575 2.9575 27 P 0 ;1
L 9.1575 3.0075 9.1575 3.0075 27 P 0 ;1
L 9.1575 3.0575 9.1575 3.0575 27 P 0 ;1
L 9.1575 3.1075 9.1575 3.1075 27 P 0 ;1
L 9.1575 3.1575 9.1575 3.1575 27 P 0 ;1
L 9.1575 3.2075 9.1575 3.2075 27 P 0 ;1
L 9.1575 3.2575 9.1575 3.2575 27 P 0 ;1
L 9.1575 3.3075 9.1575 3.3075 27 P 0 ;1
L 9.1575 3.3575 9.1575 3.3575 27 P 0 ;1
L 9.1575 3.4075 9.1575 3.4075 27 P 0 ;1
L 9.1575 3.4575 9.1575 3.4575 27 P 0 ;1
L 9.1575 3.5075 9.1575 3.5075 27 P 0 ;1
L 9.1575 3.5575 9.1575 3.5575 27 P 0 ;1
L 9.1575 3.6075 9.1575 3.6075 27 P 0 ;1
L 9.1575 3.6575 9.1575 3.6575 27 P 0 ;1
L 9.1575 3.7075 9.1575 3.7075 27 P 0 ;1
L 9.1575 3.7575 9.1575 3.7575 27 P 0 ;1
L 9.1575 3.8075 9.1575 3.8075 27 P 0 ;1
L 9.1575 3.8575 9.1575 3.8575 27 P 0 ;1
L 9.1575 3.9075 9.1575 3.9075 27 P 0 ;1
L 9.1575 3.9575 9.1575 3.9575 27 P 0 ;1
L 9.1575 4.0075 9.1575 4.0075 27 P 0 ;1
L 9.1575 4.0575 9.1575 4.0575 27 P 0 ;1
L 9.1575 4.1075 9.1575 4.1075 27 P 0 ;1
L 9.1575 4.1575 9.1575 4.1575 27 P 0 ;1
L 9.1575 4.2075 9.1575 4.2075 27 P 0 ;1
L 9.1575 4.2575 9.1575 4.2575 27 P 0 ;1
L 9.1575 4.3075 9.1575 4.3075 27 P 0 ;1
L 9.1575 4.3575 9.1575 4.3575 27 P 0 ;1
L 9.1575 5.6575 9.1575 5.6575 27 P 0 ;1
L 9.1575 5.7075 9.1575 5.7075 27 P 0 ;1
L 9.1575 5.7575 9.1575 5.7575 27 P 0 ;1
L 9.1575 5.8075 9.1575 5.8075 27 P 0 ;1
L 9.1575 5.8575 9.1575 5.8575 27 P 0 ;1
L 9.2075 0.1575 9.2075 0.1575 27 P 0 ;1
L 9.2075 0.2075 9.2075 0.2075 27 P 0 ;1
L 9.2075 0.2575 9.2075 0.2575 27 P 0 ;1
L 9.2075 0.3075 9.2075 0.3075 27 P 0 ;1
L 9.2075 0.3575 9.2075 0.3575 27 P 0 ;1
L 9.2075 0.4075 9.2075 0.4075 27 P 0 ;1
L 9.2075 0.4575 9.2075 0.4575 27 P 0 ;1
L 9.2075 0.5075 9.2075 0.5075 27 P 0 ;1
L 9.2075 0.5575 9.2075 0.5575 27 P 0 ;1
L 9.2075 0.6075 9.2075 0.6075 27 P 0 ;1
L 9.2075 0.6575 9.2075 0.6575 27 P 0 ;1
L 9.2075 0.7075 9.2075 0.7075 27 P 0 ;1
L 9.2075 0.7575 9.2075 0.7575 27 P 0 ;1
L 9.2075 0.8075 9.2075 0.8075 27 P 0 ;1
L 9.2075 0.8575 9.2075 0.8575 27 P 0 ;1
L 9.2075 0.9075 9.2075 0.9075 27 P 0 ;1
L 9.2075 0.9575 9.2075 0.9575 27 P 0 ;1
L 9.2075 1.0075 9.2075 1.0075 27 P 0 ;1
L 9.2075 1.0575 9.2075 1.0575 27 P 0 ;1
L 9.2075 1.1075 9.2075 1.1075 27 P 0 ;1
L 9.2075 1.1575 9.2075 1.1575 27 P 0 ;1
L 9.2075 1.2075 9.2075 1.2075 27 P 0 ;1
L 9.2075 1.2575 9.2075 1.2575 27 P 0 ;1
L 9.2075 1.3075 9.2075 1.3075 27 P 0 ;1
L 9.2075 1.3575 9.2075 1.3575 27 P 0 ;1
L 9.2075 1.4075 9.2075 1.4075 27 P 0 ;1
L 9.2075 1.4575 9.2075 1.4575 27 P 0 ;1
L 9.2075 1.5075 9.2075 1.5075 27 P 0 ;1
L 9.2075 1.5575 9.2075 1.5575 27 P 0 ;1
L 9.2075 1.6075 9.2075 1.6075 27 P 0 ;1
L 9.2075 1.6575 9.2075 1.6575 27 P 0 ;1
L 9.2075 1.7075 9.2075 1.7075 27 P 0 ;1
L 9.2075 1.7575 9.2075 1.7575 27 P 0 ;1
L 9.2075 1.8075 9.2075 1.8075 27 P 0 ;1
L 9.2075 1.8575 9.2075 1.8575 27 P 0 ;1
L 9.2075 1.9075 9.2075 1.9075 27 P 0 ;1
L 9.2075 1.9575 9.2075 1.9575 27 P 0 ;1
L 9.2075 2.0075 9.2075 2.0075 27 P 0 ;1
L 9.2075 2.0575 9.2075 2.0575 27 P 0 ;1
L 9.2075 2.1075 9.2075 2.1075 27 P 0 ;1
L 9.2075 2.1575 9.2075 2.1575 27 P 0 ;1
L 9.2075 2.2075 9.2075 2.2075 27 P 0 ;1
L 9.2075 2.2575 9.2075 2.2575 27 P 0 ;1
L 9.2075 2.3075 9.2075 2.3075 27 P 0 ;1
L 9.2075 2.3575 9.2075 2.3575 27 P 0 ;1
L 9.2075 2.4075 9.2075 2.4075 27 P 0 ;1
L 9.2075 2.4575 9.2075 2.4575 27 P 0 ;1
L 9.2075 2.5075 9.2075 2.5075 27 P 0 ;1
L 9.2075 2.5575 9.2075 2.5575 27 P 0 ;1
L 9.2075 2.6075 9.2075 2.6075 27 P 0 ;1
L 9.2075 2.6575 9.2075 2.6575 27 P 0 ;1
L 9.2075 2.7075 9.2075 2.7075 27 P 0 ;1
L 9.2075 2.7575 9.2075 2.7575 27 P 0 ;1
L 9.2075 2.8075 9.2075 2.8075 27 P 0 ;1
L 9.2075 2.8575 9.2075 2.8575 27 P 0 ;1
L 9.2075 2.9075 9.2075 2.9075 27 P 0 ;1
L 9.2075 2.9575 9.2075 2.9575 27 P 0 ;1
L 9.2075 3.0075 9.2075 3.0075 27 P 0 ;1
L 9.2075 3.0575 9.2075 3.0575 27 P 0 ;1
L 9.2075 3.1075 9.2075 3.1075 27 P 0 ;1
L 9.2075 3.1575 9.2075 3.1575 27 P 0 ;1
L 9.2075 3.2075 9.2075 3.2075 27 P 0 ;1
L 9.2075 3.2575 9.2075 3.2575 27 P 0 ;1
L 9.2075 3.3075 9.2075 3.3075 27 P 0 ;1
L 9.2075 3.3575 9.2075 3.3575 27 P 0 ;1
L 9.2075 3.4075 9.2075 3.4075 27 P 0 ;1
L 9.2075 3.4575 9.2075 3.4575 27 P 0 ;1
L 9.2075 3.5075 9.2075 3.5075 27 P 0 ;1
L 9.2075 3.5575 9.2075 3.5575 27 P 0 ;1
L 9.2075 3.6075 9.2075 3.6075 27 P 0 ;1
L 9.2075 3.6575 9.2075 3.6575 27 P 0 ;1
L 9.2075 3.7075 9.2075 3.7075 27 P 0 ;1
L 9.2075 3.7575 9.2075 3.7575 27 P 0 ;1
L 9.2075 3.8075 9.2075 3.8075 27 P 0 ;1
L 9.2075 3.8575 9.2075 3.8575 27 P 0 ;1
L 9.2075 3.9075 9.2075 3.9075 27 P 0 ;1
L 9.2075 3.9575 9.2075 3.9575 27 P 0 ;1
L 9.2075 4.0075 9.2075 4.0075 27 P 0 ;1
L 9.2075 4.0575 9.2075 4.0575 27 P 0 ;1
L 9.2075 4.1075 9.2075 4.1075 27 P 0 ;1
L 9.2075 4.1575 9.2075 4.1575 27 P 0 ;1
L 9.2075 4.2075 9.2075 4.2075 27 P 0 ;1
L 9.2075 4.2575 9.2075 4.2575 27 P 0 ;1
L 9.2075 4.3075 9.2075 4.3075 27 P 0 ;1
L 9.2075 4.3575 9.2075 4.3575 27 P 0 ;1
L 9.2075 4.4075 9.2075 4.4075 27 P 0 ;1
L 9.2075 4.4575 9.2075 4.4575 27 P 0 ;1
L 9.2075 5.6575 9.2075 5.6575 27 P 0 ;1
L 9.2075 5.7075 9.2075 5.7075 27 P 0 ;1
L 9.2075 5.7575 9.2075 5.7575 27 P 0 ;1
L 9.2075 5.8075 9.2075 5.8075 27 P 0 ;1
L 9.2075 5.8575 9.2075 5.8575 27 P 0 ;1
L 9.2575 0.1575 9.2575 0.1575 27 P 0 ;1
L 9.2575 0.2075 9.2575 0.2075 27 P 0 ;1
L 9.2575 0.2575 9.2575 0.2575 27 P 0 ;1
L 9.2575 0.3075 9.2575 0.3075 27 P 0 ;1
L 9.2575 0.3575 9.2575 0.3575 27 P 0 ;1
L 9.2575 0.4075 9.2575 0.4075 27 P 0 ;1
L 9.2575 0.4575 9.2575 0.4575 27 P 0 ;1
L 9.2575 0.5075 9.2575 0.5075 27 P 0 ;1
L 9.2575 0.5575 9.2575 0.5575 27 P 0 ;1
L 9.2575 0.6075 9.2575 0.6075 27 P 0 ;1
L 9.2575 0.6575 9.2575 0.6575 27 P 0 ;1
L 9.2575 0.7075 9.2575 0.7075 27 P 0 ;1
L 9.2575 0.7575 9.2575 0.7575 27 P 0 ;1
L 9.2575 0.8075 9.2575 0.8075 27 P 0 ;1
L 9.2575 0.8575 9.2575 0.8575 27 P 0 ;1
L 9.2575 0.9075 9.2575 0.9075 27 P 0 ;1
L 9.2575 0.9575 9.2575 0.9575 27 P 0 ;1
L 9.2575 1.0075 9.2575 1.0075 27 P 0 ;1
L 9.2575 1.0575 9.2575 1.0575 27 P 0 ;1
L 9.2575 1.1075 9.2575 1.1075 27 P 0 ;1
L 9.2575 1.1575 9.2575 1.1575 27 P 0 ;1
L 9.2575 1.2075 9.2575 1.2075 27 P 0 ;1
L 9.2575 1.2575 9.2575 1.2575 27 P 0 ;1
L 9.2575 1.3075 9.2575 1.3075 27 P 0 ;1
L 9.2575 1.3575 9.2575 1.3575 27 P 0 ;1
L 9.2575 1.4075 9.2575 1.4075 27 P 0 ;1
L 9.2575 1.4575 9.2575 1.4575 27 P 0 ;1
L 9.2575 1.5075 9.2575 1.5075 27 P 0 ;1
L 9.2575 1.5575 9.2575 1.5575 27 P 0 ;1
L 9.2575 1.6075 9.2575 1.6075 27 P 0 ;1
L 9.2575 1.6575 9.2575 1.6575 27 P 0 ;1
L 9.2575 1.7075 9.2575 1.7075 27 P 0 ;1
L 9.2575 1.7575 9.2575 1.7575 27 P 0 ;1
L 9.2575 1.8075 9.2575 1.8075 27 P 0 ;1
L 9.2575 1.8575 9.2575 1.8575 27 P 0 ;1
L 9.2575 1.9075 9.2575 1.9075 27 P 0 ;1
L 9.2575 1.9575 9.2575 1.9575 27 P 0 ;1
L 9.2575 2.0075 9.2575 2.0075 27 P 0 ;1
L 9.2575 2.0575 9.2575 2.0575 27 P 0 ;1
L 9.2575 2.1075 9.2575 2.1075 27 P 0 ;1
L 9.2575 2.1575 9.2575 2.1575 27 P 0 ;1
L 9.2575 2.2075 9.2575 2.2075 27 P 0 ;1
L 9.2575 2.2575 9.2575 2.2575 27 P 0 ;1
L 9.2575 2.3075 9.2575 2.3075 27 P 0 ;1
L 9.2575 2.3575 9.2575 2.3575 27 P 0 ;1
L 9.2575 2.4075 9.2575 2.4075 27 P 0 ;1
L 9.2575 2.4575 9.2575 2.4575 27 P 0 ;1
L 9.2575 2.5075 9.2575 2.5075 27 P 0 ;1
L 9.2575 2.5575 9.2575 2.5575 27 P 0 ;1
L 9.2575 2.6075 9.2575 2.6075 27 P 0 ;1
L 9.2575 2.6575 9.2575 2.6575 27 P 0 ;1
L 9.2575 2.7075 9.2575 2.7075 27 P 0 ;1
L 9.2575 2.7575 9.2575 2.7575 27 P 0 ;1
L 9.2575 2.8075 9.2575 2.8075 27 P 0 ;1
L 9.2575 2.8575 9.2575 2.8575 27 P 0 ;1
L 9.2575 2.9075 9.2575 2.9075 27 P 0 ;1
L 9.2575 2.9575 9.2575 2.9575 27 P 0 ;1
L 9.2575 3.0075 9.2575 3.0075 27 P 0 ;1
L 9.2575 3.0575 9.2575 3.0575 27 P 0 ;1
L 9.2575 3.1075 9.2575 3.1075 27 P 0 ;1
L 9.2575 3.1575 9.2575 3.1575 27 P 0 ;1
L 9.2575 3.2075 9.2575 3.2075 27 P 0 ;1
L 9.2575 3.2575 9.2575 3.2575 27 P 0 ;1
L 9.2575 3.3075 9.2575 3.3075 27 P 0 ;1
L 9.2575 3.3575 9.2575 3.3575 27 P 0 ;1
L 9.2575 3.4075 9.2575 3.4075 27 P 0 ;1
L 9.2575 3.4575 9.2575 3.4575 27 P 0 ;1
L 9.2575 3.5075 9.2575 3.5075 27 P 0 ;1
L 9.2575 3.5575 9.2575 3.5575 27 P 0 ;1
L 9.2575 3.6075 9.2575 3.6075 27 P 0 ;1
L 9.2575 3.6575 9.2575 3.6575 27 P 0 ;1
L 9.2575 3.7075 9.2575 3.7075 27 P 0 ;1
L 9.2575 3.7575 9.2575 3.7575 27 P 0 ;1
L 9.2575 3.8075 9.2575 3.8075 27 P 0 ;1
L 9.2575 3.8575 9.2575 3.8575 27 P 0 ;1
L 9.2575 3.9075 9.2575 3.9075 27 P 0 ;1
L 9.2575 3.9575 9.2575 3.9575 27 P 0 ;1
L 9.2575 4.0075 9.2575 4.0075 27 P 0 ;1
L 9.2575 4.0575 9.2575 4.0575 27 P 0 ;1
L 9.2575 4.1075 9.2575 4.1075 27 P 0 ;1
L 9.2575 4.1575 9.2575 4.1575 27 P 0 ;1
L 9.2575 4.2075 9.2575 4.2075 27 P 0 ;1
L 9.2575 4.2575 9.2575 4.2575 27 P 0 ;1
L 9.2575 4.3075 9.2575 4.3075 27 P 0 ;1
L 9.2575 4.3575 9.2575 4.3575 27 P 0 ;1
L 9.2575 4.4075 9.2575 4.4075 27 P 0 ;1
L 9.2575 4.4575 9.2575 4.4575 27 P 0 ;1
L 9.2575 4.5075 9.2575 4.5075 27 P 0 ;1
L 9.2575 5.6575 9.2575 5.6575 27 P 0 ;1
L 9.2575 5.7075 9.2575 5.7075 27 P 0 ;1
L 9.2575 5.7575 9.2575 5.7575 27 P 0 ;1
L 9.2575 5.8075 9.2575 5.8075 27 P 0 ;1
L 9.2575 5.8575 9.2575 5.8575 27 P 0 ;1
L 9.3075 0.1575 9.3075 0.1575 27 P 0 ;1
L 9.3075 0.2075 9.3075 0.2075 27 P 0 ;1
L 9.3075 0.2575 9.3075 0.2575 27 P 0 ;1
L 9.3075 0.3075 9.3075 0.3075 27 P 0 ;1
L 9.3075 0.3575 9.3075 0.3575 27 P 0 ;1
L 9.3075 0.4075 9.3075 0.4075 27 P 0 ;1
L 9.3075 0.6075 9.3075 0.6075 27 P 0 ;1
L 9.3075 0.6575 9.3075 0.6575 27 P 0 ;1
L 9.3075 0.7075 9.3075 0.7075 27 P 0 ;1
L 9.3075 0.7575 9.3075 0.7575 27 P 0 ;1
L 9.3075 0.8075 9.3075 0.8075 27 P 0 ;1
L 9.3075 0.8575 9.3075 0.8575 27 P 0 ;1
L 9.3075 0.9075 9.3075 0.9075 27 P 0 ;1
L 9.3075 0.9575 9.3075 0.9575 27 P 0 ;1
L 9.3075 1.0075 9.3075 1.0075 27 P 0 ;1
L 9.3075 1.0575 9.3075 1.0575 27 P 0 ;1
L 9.3075 1.1075 9.3075 1.1075 27 P 0 ;1
L 9.3075 1.1575 9.3075 1.1575 27 P 0 ;1
L 9.3075 1.2075 9.3075 1.2075 27 P 0 ;1
L 9.3075 1.2575 9.3075 1.2575 27 P 0 ;1
L 9.3075 1.3075 9.3075 1.3075 27 P 0 ;1
L 9.3075 1.3575 9.3075 1.3575 27 P 0 ;1
L 9.3075 1.4075 9.3075 1.4075 27 P 0 ;1
L 9.3075 1.4575 9.3075 1.4575 27 P 0 ;1
L 9.3075 1.5075 9.3075 1.5075 27 P 0 ;1
L 9.3075 1.5575 9.3075 1.5575 27 P 0 ;1
L 9.3075 1.6075 9.3075 1.6075 27 P 0 ;1
L 9.3075 1.6575 9.3075 1.6575 27 P 0 ;1
L 9.3075 1.7075 9.3075 1.7075 27 P 0 ;1
L 9.3075 1.7575 9.3075 1.7575 27 P 0 ;1
L 9.3075 1.8075 9.3075 1.8075 27 P 0 ;1
L 9.3075 1.8575 9.3075 1.8575 27 P 0 ;1
L 9.3075 1.9075 9.3075 1.9075 27 P 0 ;1
L 9.3075 1.9575 9.3075 1.9575 27 P 0 ;1
L 9.3075 2.0075 9.3075 2.0075 27 P 0 ;1
L 9.3075 2.0575 9.3075 2.0575 27 P 0 ;1
L 9.3075 2.1075 9.3075 2.1075 27 P 0 ;1
L 9.3075 2.1575 9.3075 2.1575 27 P 0 ;1
L 9.3075 2.2075 9.3075 2.2075 27 P 0 ;1
L 9.3075 2.2575 9.3075 2.2575 27 P 0 ;1
L 9.3075 2.3075 9.3075 2.3075 27 P 0 ;1
L 9.3075 2.3575 9.3075 2.3575 27 P 0 ;1
L 9.3075 2.4075 9.3075 2.4075 27 P 0 ;1
L 9.3075 2.4575 9.3075 2.4575 27 P 0 ;1
L 9.3075 2.5075 9.3075 2.5075 27 P 0 ;1
L 9.3075 2.5575 9.3075 2.5575 27 P 0 ;1
L 9.3075 2.6075 9.3075 2.6075 27 P 0 ;1
L 9.3075 2.6575 9.3075 2.6575 27 P 0 ;1
L 9.3075 2.7075 9.3075 2.7075 27 P 0 ;1
L 9.3075 2.7575 9.3075 2.7575 27 P 0 ;1
L 9.3075 2.8075 9.3075 2.8075 27 P 0 ;1
L 9.3075 2.8575 9.3075 2.8575 27 P 0 ;1
L 9.3075 2.9075 9.3075 2.9075 27 P 0 ;1
L 9.3075 2.9575 9.3075 2.9575 27 P 0 ;1
L 9.3075 3.0075 9.3075 3.0075 27 P 0 ;1
L 9.3075 3.0575 9.3075 3.0575 27 P 0 ;1
L 9.3075 3.1075 9.3075 3.1075 27 P 0 ;1
L 9.3075 3.1575 9.3075 3.1575 27 P 0 ;1
L 9.3075 3.2075 9.3075 3.2075 27 P 0 ;1
L 9.3075 3.2575 9.3075 3.2575 27 P 0 ;1
L 9.3075 3.3075 9.3075 3.3075 27 P 0 ;1
L 9.3075 3.3575 9.3075 3.3575 27 P 0 ;1
L 9.3075 3.4075 9.3075 3.4075 27 P 0 ;1
L 9.3075 3.4575 9.3075 3.4575 27 P 0 ;1
L 9.3075 3.5075 9.3075 3.5075 27 P 0 ;1
L 9.3075 3.5575 9.3075 3.5575 27 P 0 ;1
L 9.3075 3.6075 9.3075 3.6075 27 P 0 ;1
L 9.3075 3.6575 9.3075 3.6575 27 P 0 ;1
L 9.3075 3.7075 9.3075 3.7075 27 P 0 ;1
L 9.3075 3.7575 9.3075 3.7575 27 P 0 ;1
L 9.3075 3.8075 9.3075 3.8075 27 P 0 ;1
L 9.3075 3.8575 9.3075 3.8575 27 P 0 ;1
L 9.3075 3.9075 9.3075 3.9075 27 P 0 ;1
L 9.3075 3.9575 9.3075 3.9575 27 P 0 ;1
L 9.3075 4.0075 9.3075 4.0075 27 P 0 ;1
L 9.3075 4.0575 9.3075 4.0575 27 P 0 ;1
L 9.3075 4.1075 9.3075 4.1075 27 P 0 ;1
L 9.3075 4.1575 9.3075 4.1575 27 P 0 ;1
L 9.3075 4.2075 9.3075 4.2075 27 P 0 ;1
L 9.3075 4.2575 9.3075 4.2575 27 P 0 ;1
L 9.3075 4.3075 9.3075 4.3075 27 P 0 ;1
L 9.3075 4.3575 9.3075 4.3575 27 P 0 ;1
L 9.3075 4.4075 9.3075 4.4075 27 P 0 ;1
L 9.3075 4.4575 9.3075 4.4575 27 P 0 ;1
L 9.3075 4.5075 9.3075 4.5075 27 P 0 ;1
L 9.3075 5.6575 9.3075 5.6575 27 P 0 ;1
L 9.3075 5.7075 9.3075 5.7075 27 P 0 ;1
L 9.3075 5.7575 9.3075 5.7575 27 P 0 ;1
L 9.3075 5.8075 9.3075 5.8075 27 P 0 ;1
L 9.3075 5.8575 9.3075 5.8575 27 P 0 ;1
L 9.3575 0.1575 9.3575 0.1575 27 P 0 ;1
L 9.3575 0.9075 9.3575 0.9075 27 P 0 ;1
L 9.3575 0.9575 9.3575 0.9575 27 P 0 ;1
L 9.3575 1.0075 9.3575 1.0075 27 P 0 ;1
L 9.3575 1.0575 9.3575 1.0575 27 P 0 ;1
L 9.3575 1.1075 9.3575 1.1075 27 P 0 ;1
L 9.3575 1.1575 9.3575 1.1575 27 P 0 ;1
L 9.3575 1.2075 9.3575 1.2075 27 P 0 ;1
L 9.3575 1.2575 9.3575 1.2575 27 P 0 ;1
L 9.3575 1.3075 9.3575 1.3075 27 P 0 ;1
L 9.3575 1.3575 9.3575 1.3575 27 P 0 ;1
L 9.3575 1.4075 9.3575 1.4075 27 P 0 ;1
L 9.3575 1.4575 9.3575 1.4575 27 P 0 ;1
L 9.3575 1.5075 9.3575 1.5075 27 P 0 ;1
L 9.3575 1.5575 9.3575 1.5575 27 P 0 ;1
L 9.3575 1.6075 9.3575 1.6075 27 P 0 ;1
L 9.3575 1.6575 9.3575 1.6575 27 P 0 ;1
L 9.3575 1.7075 9.3575 1.7075 27 P 0 ;1
L 9.3575 1.7575 9.3575 1.7575 27 P 0 ;1
L 9.3575 1.8075 9.3575 1.8075 27 P 0 ;1
L 9.3575 1.8575 9.3575 1.8575 27 P 0 ;1
L 9.3575 1.9075 9.3575 1.9075 27 P 0 ;1
L 9.3575 1.9575 9.3575 1.9575 27 P 0 ;1
L 9.3575 2.0075 9.3575 2.0075 27 P 0 ;1
L 9.3575 2.0575 9.3575 2.0575 27 P 0 ;1
L 9.3575 2.1075 9.3575 2.1075 27 P 0 ;1
L 9.3575 2.1575 9.3575 2.1575 27 P 0 ;1
L 9.3575 2.2075 9.3575 2.2075 27 P 0 ;1
L 9.3575 2.2575 9.3575 2.2575 27 P 0 ;1
L 9.3575 2.3075 9.3575 2.3075 27 P 0 ;1
L 9.3575 2.3575 9.3575 2.3575 27 P 0 ;1
L 9.3575 2.4075 9.3575 2.4075 27 P 0 ;1
L 9.3575 2.4575 9.3575 2.4575 27 P 0 ;1
L 9.3575 2.5075 9.3575 2.5075 27 P 0 ;1
L 9.3575 2.5575 9.3575 2.5575 27 P 0 ;1
L 9.3575 2.6075 9.3575 2.6075 27 P 0 ;1
L 9.3575 2.6575 9.3575 2.6575 27 P 0 ;1
L 9.3575 2.7075 9.3575 2.7075 27 P 0 ;1
L 9.3575 2.7575 9.3575 2.7575 27 P 0 ;1
L 9.3575 2.8075 9.3575 2.8075 27 P 0 ;1
L 9.3575 2.8575 9.3575 2.8575 27 P 0 ;1
L 9.3575 2.9075 9.3575 2.9075 27 P 0 ;1
L 9.3575 2.9575 9.3575 2.9575 27 P 0 ;1
L 9.3575 3.0075 9.3575 3.0075 27 P 0 ;1
L 9.3575 3.0575 9.3575 3.0575 27 P 0 ;1
L 9.3575 3.1075 9.3575 3.1075 27 P 0 ;1
L 9.3575 3.1575 9.3575 3.1575 27 P 0 ;1
L 9.3575 3.2075 9.3575 3.2075 27 P 0 ;1
L 9.3575 3.2575 9.3575 3.2575 27 P 0 ;1
L 9.3575 3.3075 9.3575 3.3075 27 P 0 ;1
L 9.3575 3.3575 9.3575 3.3575 27 P 0 ;1
L 9.3575 3.4075 9.3575 3.4075 27 P 0 ;1
L 9.3575 3.4575 9.3575 3.4575 27 P 0 ;1
L 9.3575 3.5075 9.3575 3.5075 27 P 0 ;1
L 9.3575 3.5575 9.3575 3.5575 27 P 0 ;1
L 9.3575 3.6075 9.3575 3.6075 27 P 0 ;1
L 9.3575 3.6575 9.3575 3.6575 27 P 0 ;1
L 9.3575 3.7075 9.3575 3.7075 27 P 0 ;1
L 9.3575 3.7575 9.3575 3.7575 27 P 0 ;1
L 9.3575 3.8075 9.3575 3.8075 27 P 0 ;1
L 9.3575 3.8575 9.3575 3.8575 27 P 0 ;1
L 9.3575 3.9075 9.3575 3.9075 27 P 0 ;1
L 9.3575 3.9575 9.3575 3.9575 27 P 0 ;1
L 9.3575 4.0075 9.3575 4.0075 27 P 0 ;1
L 9.3575 4.0575 9.3575 4.0575 27 P 0 ;1
L 9.3575 4.1075 9.3575 4.1075 27 P 0 ;1
L 9.3575 4.1575 9.3575 4.1575 27 P 0 ;1
L 9.3575 4.2075 9.3575 4.2075 27 P 0 ;1
L 9.3575 4.2575 9.3575 4.2575 27 P 0 ;1
L 9.3575 4.3075 9.3575 4.3075 27 P 0 ;1
L 9.3575 4.3575 9.3575 4.3575 27 P 0 ;1
L 9.3575 4.4075 9.3575 4.4075 27 P 0 ;1
L 9.3575 4.4575 9.3575 4.4575 27 P 0 ;1
L 9.3575 4.5075 9.3575 4.5075 27 P 0 ;1
L 9.3575 4.5575 9.3575 4.5575 27 P 0 ;1
L 9.3575 5.6575 9.3575 5.6575 27 P 0 ;1
L 9.3575 5.7075 9.3575 5.7075 27 P 0 ;1
L 9.3575 5.7575 9.3575 5.7575 27 P 0 ;1
L 9.3575 5.8075 9.3575 5.8075 27 P 0 ;1
L 9.3575 5.8575 9.3575 5.8575 27 P 0 ;1
L 9.4075 0.1575 9.4075 0.1575 27 P 0 ;1
L 9.4075 0.9075 9.4075 0.9075 27 P 0 ;1
L 9.4075 0.9575 9.4075 0.9575 27 P 0 ;1
L 9.4075 1.0075 9.4075 1.0075 27 P 0 ;1
L 9.4075 1.0575 9.4075 1.0575 27 P 0 ;1
L 9.4075 1.1075 9.4075 1.1075 27 P 0 ;1
L 9.4075 1.1575 9.4075 1.1575 27 P 0 ;1
L 9.4075 1.2075 9.4075 1.2075 27 P 0 ;1
L 9.4075 1.2575 9.4075 1.2575 27 P 0 ;1
L 9.4075 1.3075 9.4075 1.3075 27 P 0 ;1
L 9.4075 1.3575 9.4075 1.3575 27 P 0 ;1
L 9.4075 1.4075 9.4075 1.4075 27 P 0 ;1
L 9.4075 1.4575 9.4075 1.4575 27 P 0 ;1
L 9.4075 1.5075 9.4075 1.5075 27 P 0 ;1
L 9.4075 1.5575 9.4075 1.5575 27 P 0 ;1
L 9.4075 1.6075 9.4075 1.6075 27 P 0 ;1
L 9.4075 1.6575 9.4075 1.6575 27 P 0 ;1
L 9.4075 1.7075 9.4075 1.7075 27 P 0 ;1
L 9.4075 1.7575 9.4075 1.7575 27 P 0 ;1
L 9.4075 1.8075 9.4075 1.8075 27 P 0 ;1
L 9.4075 1.8575 9.4075 1.8575 27 P 0 ;1
L 9.4075 1.9075 9.4075 1.9075 27 P 0 ;1
L 9.4075 1.9575 9.4075 1.9575 27 P 0 ;1
L 9.4075 2.0075 9.4075 2.0075 27 P 0 ;1
L 9.4075 2.0575 9.4075 2.0575 27 P 0 ;1
L 9.4075 2.1075 9.4075 2.1075 27 P 0 ;1
L 9.4075 2.1575 9.4075 2.1575 27 P 0 ;1
L 9.4075 2.2075 9.4075 2.2075 27 P 0 ;1
L 9.4075 2.2575 9.4075 2.2575 27 P 0 ;1
L 9.4075 2.3075 9.4075 2.3075 27 P 0 ;1
L 9.4075 2.3575 9.4075 2.3575 27 P 0 ;1
L 9.4075 2.4075 9.4075 2.4075 27 P 0 ;1
L 9.4075 2.4575 9.4075 2.4575 27 P 0 ;1
L 9.4075 2.5075 9.4075 2.5075 27 P 0 ;1
L 9.4075 2.5575 9.4075 2.5575 27 P 0 ;1
L 9.4075 2.6075 9.4075 2.6075 27 P 0 ;1
L 9.4075 2.6575 9.4075 2.6575 27 P 0 ;1
L 9.4075 2.7075 9.4075 2.7075 27 P 0 ;1
L 9.4075 2.7575 9.4075 2.7575 27 P 0 ;1
L 9.4075 2.8075 9.4075 2.8075 27 P 0 ;1
L 9.4075 2.8575 9.4075 2.8575 27 P 0 ;1
L 9.4075 2.9075 9.4075 2.9075 27 P 0 ;1
L 9.4075 2.9575 9.4075 2.9575 27 P 0 ;1
L 9.4075 3.0075 9.4075 3.0075 27 P 0 ;1
L 9.4075 3.0575 9.4075 3.0575 27 P 0 ;1
L 9.4075 3.1075 9.4075 3.1075 27 P 0 ;1
L 9.4075 3.1575 9.4075 3.1575 27 P 0 ;1
L 9.4075 3.2075 9.4075 3.2075 27 P 0 ;1
L 9.4075 3.2575 9.4075 3.2575 27 P 0 ;1
L 9.4075 3.3075 9.4075 3.3075 27 P 0 ;1
L 9.4075 3.3575 9.4075 3.3575 27 P 0 ;1
L 9.4075 3.4075 9.4075 3.4075 27 P 0 ;1
L 9.4075 3.4575 9.4075 3.4575 27 P 0 ;1
L 9.4075 3.5075 9.4075 3.5075 27 P 0 ;1
L 9.4075 3.5575 9.4075 3.5575 27 P 0 ;1
L 9.4075 3.6075 9.4075 3.6075 27 P 0 ;1
L 9.4075 3.6575 9.4075 3.6575 27 P 0 ;1
L 9.4075 3.7075 9.4075 3.7075 27 P 0 ;1
L 9.4075 3.7575 9.4075 3.7575 27 P 0 ;1
L 9.4075 3.8075 9.4075 3.8075 27 P 0 ;1
L 9.4075 3.8575 9.4075 3.8575 27 P 0 ;1
L 9.4075 3.9075 9.4075 3.9075 27 P 0 ;1
L 9.4075 3.9575 9.4075 3.9575 27 P 0 ;1
L 9.4075 4.0075 9.4075 4.0075 27 P 0 ;1
L 9.4075 4.0575 9.4075 4.0575 27 P 0 ;1
L 9.4075 4.1075 9.4075 4.1075 27 P 0 ;1
L 9.4075 4.1575 9.4075 4.1575 27 P 0 ;1
L 9.4075 4.2075 9.4075 4.2075 27 P 0 ;1
L 9.4075 4.2575 9.4075 4.2575 27 P 0 ;1
L 9.4075 4.3075 9.4075 4.3075 27 P 0 ;1
L 9.4075 4.3575 9.4075 4.3575 27 P 0 ;1
L 9.4075 4.4075 9.4075 4.4075 27 P 0 ;1
L 9.4075 4.4575 9.4075 4.4575 27 P 0 ;1
L 9.4075 5.6575 9.4075 5.6575 27 P 0 ;1
L 9.4075 5.7075 9.4075 5.7075 27 P 0 ;1
L 9.4075 5.7575 9.4075 5.7575 27 P 0 ;1
L 9.4075 5.8075 9.4075 5.8075 27 P 0 ;1
L 9.4075 5.8575 9.4075 5.8575 27 P 0 ;1
L 9.4575 0.1575 9.4575 0.1575 27 P 0 ;1
L 9.4575 0.9575 9.4575 0.9575 27 P 0 ;1
L 9.4575 1.0075 9.4575 1.0075 27 P 0 ;1
L 9.4575 1.0575 9.4575 1.0575 27 P 0 ;1
L 9.4575 1.1075 9.4575 1.1075 27 P 0 ;1
L 9.4575 1.1575 9.4575 1.1575 27 P 0 ;1
L 9.4575 1.2075 9.4575 1.2075 27 P 0 ;1
L 9.4575 1.2575 9.4575 1.2575 27 P 0 ;1
L 9.4575 1.3075 9.4575 1.3075 27 P 0 ;1
L 9.4575 1.3575 9.4575 1.3575 27 P 0 ;1
L 9.4575 1.4075 9.4575 1.4075 27 P 0 ;1
L 9.4575 1.4575 9.4575 1.4575 27 P 0 ;1
L 9.4575 1.5075 9.4575 1.5075 27 P 0 ;1
L 9.4575 1.5575 9.4575 1.5575 27 P 0 ;1
L 9.4575 1.6075 9.4575 1.6075 27 P 0 ;1
L 9.4575 1.6575 9.4575 1.6575 27 P 0 ;1
L 9.4575 1.7075 9.4575 1.7075 27 P 0 ;1
L 9.4575 1.7575 9.4575 1.7575 27 P 0 ;1
L 9.4575 1.8075 9.4575 1.8075 27 P 0 ;1
L 9.4575 1.8575 9.4575 1.8575 27 P 0 ;1
L 9.4575 1.9075 9.4575 1.9075 27 P 0 ;1
L 9.4575 1.9575 9.4575 1.9575 27 P 0 ;1
L 9.4575 2.0075 9.4575 2.0075 27 P 0 ;1
L 9.4575 2.0575 9.4575 2.0575 27 P 0 ;1
L 9.4575 2.1075 9.4575 2.1075 27 P 0 ;1
L 9.4575 2.1575 9.4575 2.1575 27 P 0 ;1
L 9.4575 2.2075 9.4575 2.2075 27 P 0 ;1
L 9.4575 2.2575 9.4575 2.2575 27 P 0 ;1
L 9.4575 2.3075 9.4575 2.3075 27 P 0 ;1
L 9.4575 2.3575 9.4575 2.3575 27 P 0 ;1
L 9.4575 2.4075 9.4575 2.4075 27 P 0 ;1
L 9.4575 2.4575 9.4575 2.4575 27 P 0 ;1
L 9.4575 2.5075 9.4575 2.5075 27 P 0 ;1
L 9.4575 2.5575 9.4575 2.5575 27 P 0 ;1
L 9.4575 2.6075 9.4575 2.6075 27 P 0 ;1
L 9.4575 2.6575 9.4575 2.6575 27 P 0 ;1
L 9.4575 2.7075 9.4575 2.7075 27 P 0 ;1
L 9.4575 2.7575 9.4575 2.7575 27 P 0 ;1
L 9.4575 2.8075 9.4575 2.8075 27 P 0 ;1
L 9.4575 2.8575 9.4575 2.8575 27 P 0 ;1
L 9.4575 2.9075 9.4575 2.9075 27 P 0 ;1
L 9.4575 2.9575 9.4575 2.9575 27 P 0 ;1
L 9.4575 3.0075 9.4575 3.0075 27 P 0 ;1
L 9.4575 3.0575 9.4575 3.0575 27 P 0 ;1
L 9.4575 3.1075 9.4575 3.1075 27 P 0 ;1
L 9.4575 3.1575 9.4575 3.1575 27 P 0 ;1
L 9.4575 3.2075 9.4575 3.2075 27 P 0 ;1
L 9.4575 3.2575 9.4575 3.2575 27 P 0 ;1
L 9.4575 3.3075 9.4575 3.3075 27 P 0 ;1
L 9.4575 3.3575 9.4575 3.3575 27 P 0 ;1
L 9.4575 3.4075 9.4575 3.4075 27 P 0 ;1
L 9.4575 3.4575 9.4575 3.4575 27 P 0 ;1
L 9.4575 3.5075 9.4575 3.5075 27 P 0 ;1
L 9.4575 3.5575 9.4575 3.5575 27 P 0 ;1
L 9.4575 3.6075 9.4575 3.6075 27 P 0 ;1
L 9.4575 3.6575 9.4575 3.6575 27 P 0 ;1
L 9.4575 3.7075 9.4575 3.7075 27 P 0 ;1
L 9.4575 3.7575 9.4575 3.7575 27 P 0 ;1
L 9.4575 3.8075 9.4575 3.8075 27 P 0 ;1
L 9.4575 3.8575 9.4575 3.8575 27 P 0 ;1
L 9.4575 3.9075 9.4575 3.9075 27 P 0 ;1
L 9.4575 3.9575 9.4575 3.9575 27 P 0 ;1
L 9.4575 4.0075 9.4575 4.0075 27 P 0 ;1
L 9.4575 4.0575 9.4575 4.0575 27 P 0 ;1
L 9.4575 4.1075 9.4575 4.1075 27 P 0 ;1
L 9.4575 4.1575 9.4575 4.1575 27 P 0 ;1
L 9.4575 4.2075 9.4575 4.2075 27 P 0 ;1
L 9.4575 4.2575 9.4575 4.2575 27 P 0 ;1
L 9.4575 4.3075 9.4575 4.3075 27 P 0 ;1
L 9.4575 4.3575 9.4575 4.3575 27 P 0 ;1
L 9.4575 4.4075 9.4575 4.4075 27 P 0 ;1
L 9.4575 4.4575 9.4575 4.4575 27 P 0 ;1
L 9.4575 5.6575 9.4575 5.6575 27 P 0 ;1
L 9.4575 5.7075 9.4575 5.7075 27 P 0 ;1
L 9.4575 5.7575 9.4575 5.7575 27 P 0 ;1
L 9.4575 5.8075 9.4575 5.8075 27 P 0 ;1
L 9.4575 5.8575 9.4575 5.8575 27 P 0 ;1
L 9.5075 0.1575 9.5075 0.1575 27 P 0 ;1
L 9.5075 0.9575 9.5075 0.9575 27 P 0 ;1
L 9.5075 1.0075 9.5075 1.0075 27 P 0 ;1
L 9.5075 1.0575 9.5075 1.0575 27 P 0 ;1
L 9.5075 1.1075 9.5075 1.1075 27 P 0 ;1
L 9.5075 1.1575 9.5075 1.1575 27 P 0 ;1
L 9.5075 1.2075 9.5075 1.2075 27 P 0 ;1
L 9.5075 1.2575 9.5075 1.2575 27 P 0 ;1
L 9.5075 1.3075 9.5075 1.3075 27 P 0 ;1
L 9.5075 1.3575 9.5075 1.3575 27 P 0 ;1
L 9.5075 1.4075 9.5075 1.4075 27 P 0 ;1
L 9.5075 1.4575 9.5075 1.4575 27 P 0 ;1
L 9.5075 1.5075 9.5075 1.5075 27 P 0 ;1
L 9.5075 1.5575 9.5075 1.5575 27 P 0 ;1
L 9.5075 1.6075 9.5075 1.6075 27 P 0 ;1
L 9.5075 1.6575 9.5075 1.6575 27 P 0 ;1
L 9.5075 1.7075 9.5075 1.7075 27 P 0 ;1
L 9.5075 1.7575 9.5075 1.7575 27 P 0 ;1
L 9.5075 1.8075 9.5075 1.8075 27 P 0 ;1
L 9.5075 1.8575 9.5075 1.8575 27 P 0 ;1
L 9.5075 1.9075 9.5075 1.9075 27 P 0 ;1
L 9.5075 1.9575 9.5075 1.9575 27 P 0 ;1
L 9.5075 2.0075 9.5075 2.0075 27 P 0 ;1
L 9.5075 2.0575 9.5075 2.0575 27 P 0 ;1
L 9.5075 2.1075 9.5075 2.1075 27 P 0 ;1
L 9.5075 2.1575 9.5075 2.1575 27 P 0 ;1
L 9.5075 2.2075 9.5075 2.2075 27 P 0 ;1
L 9.5075 2.2575 9.5075 2.2575 27 P 0 ;1
L 9.5075 2.3075 9.5075 2.3075 27 P 0 ;1
L 9.5075 2.3575 9.5075 2.3575 27 P 0 ;1
L 9.5075 2.4075 9.5075 2.4075 27 P 0 ;1
L 9.5075 2.4575 9.5075 2.4575 27 P 0 ;1
L 9.5075 2.5075 9.5075 2.5075 27 P 0 ;1
L 9.5075 2.5575 9.5075 2.5575 27 P 0 ;1
L 9.5075 2.6075 9.5075 2.6075 27 P 0 ;1
L 9.5075 2.6575 9.5075 2.6575 27 P 0 ;1
L 9.5075 2.7075 9.5075 2.7075 27 P 0 ;1
L 9.5075 2.7575 9.5075 2.7575 27 P 0 ;1
L 9.5075 2.8075 9.5075 2.8075 27 P 0 ;1
L 9.5075 2.8575 9.5075 2.8575 27 P 0 ;1
L 9.5075 2.9075 9.5075 2.9075 27 P 0 ;1
L 9.5075 2.9575 9.5075 2.9575 27 P 0 ;1
L 9.5075 3.0075 9.5075 3.0075 27 P 0 ;1
L 9.5075 3.0575 9.5075 3.0575 27 P 0 ;1
L 9.5075 3.1075 9.5075 3.1075 27 P 0 ;1
L 9.5075 3.1575 9.5075 3.1575 27 P 0 ;1
L 9.5075 3.2075 9.5075 3.2075 27 P 0 ;1
L 9.5075 3.2575 9.5075 3.2575 27 P 0 ;1
L 9.5075 3.3075 9.5075 3.3075 27 P 0 ;1
L 9.5075 3.3575 9.5075 3.3575 27 P 0 ;1
L 9.5075 3.4075 9.5075 3.4075 27 P 0 ;1
L 9.5075 3.4575 9.5075 3.4575 27 P 0 ;1
L 9.5075 3.5075 9.5075 3.5075 27 P 0 ;1
L 9.5075 3.5575 9.5075 3.5575 27 P 0 ;1
L 9.5075 3.6075 9.5075 3.6075 27 P 0 ;1
L 9.5075 3.6575 9.5075 3.6575 27 P 0 ;1
L 9.5075 3.7075 9.5075 3.7075 27 P 0 ;1
L 9.5075 3.7575 9.5075 3.7575 27 P 0 ;1
L 9.5075 3.8075 9.5075 3.8075 27 P 0 ;1
L 9.5075 3.8575 9.5075 3.8575 27 P 0 ;1
L 9.5075 3.9075 9.5075 3.9075 27 P 0 ;1
L 9.5075 3.9575 9.5075 3.9575 27 P 0 ;1
L 9.5075 4.0075 9.5075 4.0075 27 P 0 ;1
L 9.5075 4.0575 9.5075 4.0575 27 P 0 ;1
L 9.5075 4.1075 9.5075 4.1075 27 P 0 ;1
L 9.5075 4.1575 9.5075 4.1575 27 P 0 ;1
L 9.5075 4.2075 9.5075 4.2075 27 P 0 ;1
L 9.5075 4.2575 9.5075 4.2575 27 P 0 ;1
L 9.5075 4.3075 9.5075 4.3075 27 P 0 ;1
L 9.5075 4.3575 9.5075 4.3575 27 P 0 ;1
L 9.5075 4.4075 9.5075 4.4075 27 P 0 ;1
L 9.5075 4.4575 9.5075 4.4575 27 P 0 ;1
L 9.5075 5.6575 9.5075 5.6575 27 P 0 ;1
L 9.5075 5.7075 9.5075 5.7075 27 P 0 ;1
L 9.5075 5.7575 9.5075 5.7575 27 P 0 ;1
L 9.5075 5.8075 9.5075 5.8075 27 P 0 ;1
L 9.5075 5.8575 9.5075 5.8575 27 P 0 ;1
L 9.5575 0.1575 9.5575 0.1575 27 P 0 ;1
L 9.5575 0.9075 9.5575 0.9075 27 P 0 ;1
L 9.5575 0.9575 9.5575 0.9575 27 P 0 ;1
L 9.5575 1.0075 9.5575 1.0075 27 P 0 ;1
L 9.5575 1.0575 9.5575 1.0575 27 P 0 ;1
L 9.5575 1.1075 9.5575 1.1075 27 P 0 ;1
L 9.5575 1.1575 9.5575 1.1575 27 P 0 ;1
L 9.5575 1.2075 9.5575 1.2075 27 P 0 ;1
L 9.5575 1.2575 9.5575 1.2575 27 P 0 ;1
L 9.5575 1.3075 9.5575 1.3075 27 P 0 ;1
L 9.5575 1.3575 9.5575 1.3575 27 P 0 ;1
L 9.5575 1.4075 9.5575 1.4075 27 P 0 ;1
L 9.5575 1.4575 9.5575 1.4575 27 P 0 ;1
L 9.5575 1.5075 9.5575 1.5075 27 P 0 ;1
L 9.5575 1.5575 9.5575 1.5575 27 P 0 ;1
L 9.5575 1.6075 9.5575 1.6075 27 P 0 ;1
L 9.5575 1.6575 9.5575 1.6575 27 P 0 ;1
L 9.5575 1.7075 9.5575 1.7075 27 P 0 ;1
L 9.5575 1.7575 9.5575 1.7575 27 P 0 ;1
L 9.5575 1.8075 9.5575 1.8075 27 P 0 ;1
L 9.5575 1.8575 9.5575 1.8575 27 P 0 ;1
L 9.5575 1.9075 9.5575 1.9075 27 P 0 ;1
L 9.5575 1.9575 9.5575 1.9575 27 P 0 ;1
L 9.5575 2.0075 9.5575 2.0075 27 P 0 ;1
L 9.5575 2.0575 9.5575 2.0575 27 P 0 ;1
L 9.5575 2.1075 9.5575 2.1075 27 P 0 ;1
L 9.5575 2.1575 9.5575 2.1575 27 P 0 ;1
L 9.5575 2.2075 9.5575 2.2075 27 P 0 ;1
L 9.5575 2.2575 9.5575 2.2575 27 P 0 ;1
L 9.5575 2.3075 9.5575 2.3075 27 P 0 ;1
L 9.5575 2.3575 9.5575 2.3575 27 P 0 ;1
L 9.5575 2.4075 9.5575 2.4075 27 P 0 ;1
L 9.5575 2.4575 9.5575 2.4575 27 P 0 ;1
L 9.5575 2.5075 9.5575 2.5075 27 P 0 ;1
L 9.5575 2.5575 9.5575 2.5575 27 P 0 ;1
L 9.5575 2.6075 9.5575 2.6075 27 P 0 ;1
L 9.5575 2.6575 9.5575 2.6575 27 P 0 ;1
L 9.5575 2.7075 9.5575 2.7075 27 P 0 ;1
L 9.5575 2.7575 9.5575 2.7575 27 P 0 ;1
L 9.5575 2.8075 9.5575 2.8075 27 P 0 ;1
L 9.5575 2.8575 9.5575 2.8575 27 P 0 ;1
L 9.5575 2.9075 9.5575 2.9075 27 P 0 ;1
L 9.5575 2.9575 9.5575 2.9575 27 P 0 ;1
L 9.5575 3.0075 9.5575 3.0075 27 P 0 ;1
L 9.5575 3.0575 9.5575 3.0575 27 P 0 ;1
L 9.5575 3.1075 9.5575 3.1075 27 P 0 ;1
L 9.5575 3.1575 9.5575 3.1575 27 P 0 ;1
L 9.5575 3.2075 9.5575 3.2075 27 P 0 ;1
L 9.5575 3.2575 9.5575 3.2575 27 P 0 ;1
L 9.5575 3.3075 9.5575 3.3075 27 P 0 ;1
L 9.5575 3.3575 9.5575 3.3575 27 P 0 ;1
L 9.5575 3.4075 9.5575 3.4075 27 P 0 ;1
L 9.5575 3.4575 9.5575 3.4575 27 P 0 ;1
L 9.5575 3.5075 9.5575 3.5075 27 P 0 ;1
L 9.5575 3.5575 9.5575 3.5575 27 P 0 ;1
L 9.5575 3.6075 9.5575 3.6075 27 P 0 ;1
L 9.5575 3.6575 9.5575 3.6575 27 P 0 ;1
L 9.5575 3.7075 9.5575 3.7075 27 P 0 ;1
L 9.5575 3.7575 9.5575 3.7575 27 P 0 ;1
L 9.5575 3.8075 9.5575 3.8075 27 P 0 ;1
L 9.5575 3.8575 9.5575 3.8575 27 P 0 ;1
L 9.5575 3.9075 9.5575 3.9075 27 P 0 ;1
L 9.5575 3.9575 9.5575 3.9575 27 P 0 ;1
L 9.5575 4.0075 9.5575 4.0075 27 P 0 ;1
L 9.5575 4.0575 9.5575 4.0575 27 P 0 ;1
L 9.5575 4.1075 9.5575 4.1075 27 P 0 ;1
L 9.5575 4.1575 9.5575 4.1575 27 P 0 ;1
L 9.5575 4.2075 9.5575 4.2075 27 P 0 ;1
L 9.5575 4.2575 9.5575 4.2575 27 P 0 ;1
L 9.5575 4.3075 9.5575 4.3075 27 P 0 ;1
L 9.5575 4.3575 9.5575 4.3575 27 P 0 ;1
L 9.5575 4.4075 9.5575 4.4075 27 P 0 ;1
L 9.5575 4.4575 9.5575 4.4575 27 P 0 ;1
L 9.5575 4.5075 9.5575 4.5075 27 P 0 ;1
L 9.5575 5.3075 9.5575 5.3075 27 P 0 ;1
L 9.5575 5.3575 9.5575 5.3575 27 P 0 ;1
L 9.5575 5.6575 9.5575 5.6575 27 P 0 ;1
L 9.5575 5.7075 9.5575 5.7075 27 P 0 ;1
L 9.5575 5.7575 9.5575 5.7575 27 P 0 ;1
L 9.5575 5.8075 9.5575 5.8075 27 P 0 ;1
L 9.5575 5.8575 9.5575 5.8575 27 P 0 ;1
L 9.6075 0.1575 9.6075 0.1575 27 P 0 ;1
L 9.6075 0.9075 9.6075 0.9075 27 P 0 ;1
L 9.6075 0.9575 9.6075 0.9575 27 P 0 ;1
L 9.6075 1.0075 9.6075 1.0075 27 P 0 ;1
L 9.6075 1.0575 9.6075 1.0575 27 P 0 ;1
L 9.6075 1.1075 9.6075 1.1075 27 P 0 ;1
L 9.6075 1.1575 9.6075 1.1575 27 P 0 ;1
L 9.6075 1.2075 9.6075 1.2075 27 P 0 ;1
L 9.6075 1.2575 9.6075 1.2575 27 P 0 ;1
L 9.6075 1.3075 9.6075 1.3075 27 P 0 ;1
L 9.6075 1.3575 9.6075 1.3575 27 P 0 ;1
L 9.6075 1.4075 9.6075 1.4075 27 P 0 ;1
L 9.6075 1.4575 9.6075 1.4575 27 P 0 ;1
L 9.6075 1.5075 9.6075 1.5075 27 P 0 ;1
L 9.6075 1.5575 9.6075 1.5575 27 P 0 ;1
L 9.6075 1.6075 9.6075 1.6075 27 P 0 ;1
L 9.6075 1.6575 9.6075 1.6575 27 P 0 ;1
L 9.6075 1.7075 9.6075 1.7075 27 P 0 ;1
L 9.6075 1.7575 9.6075 1.7575 27 P 0 ;1
L 9.6075 1.8075 9.6075 1.8075 27 P 0 ;1
L 9.6075 1.8575 9.6075 1.8575 27 P 0 ;1
L 9.6075 1.9075 9.6075 1.9075 27 P 0 ;1
L 9.6075 1.9575 9.6075 1.9575 27 P 0 ;1
L 9.6075 2.0075 9.6075 2.0075 27 P 0 ;1
L 9.6075 2.0575 9.6075 2.0575 27 P 0 ;1
L 9.6075 2.1075 9.6075 2.1075 27 P 0 ;1
L 9.6075 2.1575 9.6075 2.1575 27 P 0 ;1
L 9.6075 2.2075 9.6075 2.2075 27 P 0 ;1
L 9.6075 2.2575 9.6075 2.2575 27 P 0 ;1
L 9.6075 2.3075 9.6075 2.3075 27 P 0 ;1
L 9.6075 2.3575 9.6075 2.3575 27 P 0 ;1
L 9.6075 2.4075 9.6075 2.4075 27 P 0 ;1
L 9.6075 2.4575 9.6075 2.4575 27 P 0 ;1
L 9.6075 2.5075 9.6075 2.5075 27 P 0 ;1
L 9.6075 2.5575 9.6075 2.5575 27 P 0 ;1
L 9.6075 2.6075 9.6075 2.6075 27 P 0 ;1
L 9.6075 2.6575 9.6075 2.6575 27 P 0 ;1
L 9.6075 2.7075 9.6075 2.7075 27 P 0 ;1
L 9.6075 2.7575 9.6075 2.7575 27 P 0 ;1
L 9.6075 2.8075 9.6075 2.8075 27 P 0 ;1
L 9.6075 2.8575 9.6075 2.8575 27 P 0 ;1
L 9.6075 2.9075 9.6075 2.9075 27 P 0 ;1
L 9.6075 2.9575 9.6075 2.9575 27 P 0 ;1
L 9.6075 3.0075 9.6075 3.0075 27 P 0 ;1
L 9.6075 3.0575 9.6075 3.0575 27 P 0 ;1
L 9.6075 3.1075 9.6075 3.1075 27 P 0 ;1
L 9.6075 3.1575 9.6075 3.1575 27 P 0 ;1
L 9.6075 3.2075 9.6075 3.2075 27 P 0 ;1
L 9.6075 3.2575 9.6075 3.2575 27 P 0 ;1
L 9.6075 3.3075 9.6075 3.3075 27 P 0 ;1
L 9.6075 3.3575 9.6075 3.3575 27 P 0 ;1
L 9.6075 3.4075 9.6075 3.4075 27 P 0 ;1
L 9.6075 3.4575 9.6075 3.4575 27 P 0 ;1
L 9.6075 3.5075 9.6075 3.5075 27 P 0 ;1
L 9.6075 3.5575 9.6075 3.5575 27 P 0 ;1
L 9.6075 3.6075 9.6075 3.6075 27 P 0 ;1
L 9.6075 3.6575 9.6075 3.6575 27 P 0 ;1
L 9.6075 3.7075 9.6075 3.7075 27 P 0 ;1
L 9.6075 3.7575 9.6075 3.7575 27 P 0 ;1
L 9.6075 3.8075 9.6075 3.8075 27 P 0 ;1
L 9.6075 3.8575 9.6075 3.8575 27 P 0 ;1
L 9.6075 3.9075 9.6075 3.9075 27 P 0 ;1
L 9.6075 3.9575 9.6075 3.9575 27 P 0 ;1
L 9.6075 4.0075 9.6075 4.0075 27 P 0 ;1
L 9.6075 4.0575 9.6075 4.0575 27 P 0 ;1
L 9.6075 4.1075 9.6075 4.1075 27 P 0 ;1
L 9.6075 4.1575 9.6075 4.1575 27 P 0 ;1
L 9.6075 4.2075 9.6075 4.2075 27 P 0 ;1
L 9.6075 4.2575 9.6075 4.2575 27 P 0 ;1
L 9.6075 4.3075 9.6075 4.3075 27 P 0 ;1
L 9.6075 4.3575 9.6075 4.3575 27 P 0 ;1
L 9.6075 4.4075 9.6075 4.4075 27 P 0 ;1
L 9.6075 4.4575 9.6075 4.4575 27 P 0 ;1
L 9.6075 4.5075 9.6075 4.5075 27 P 0 ;1
L 9.6075 4.5575 9.6075 4.5575 27 P 0 ;1
L 9.6075 5.3075 9.6075 5.3075 27 P 0 ;1
L 9.6075 5.3575 9.6075 5.3575 27 P 0 ;1
L 9.6075 5.6575 9.6075 5.6575 27 P 0 ;1
L 9.6075 5.7075 9.6075 5.7075 27 P 0 ;1
L 9.6075 5.7575 9.6075 5.7575 27 P 0 ;1
L 9.6075 5.8075 9.6075 5.8075 27 P 0 ;1
L 9.6075 5.8575 9.6075 5.8575 27 P 0 ;1
L 9.6575 0.1575 9.6575 0.1575 27 P 0 ;1
L 9.6575 0.2075 9.6575 0.2075 27 P 0 ;1
L 9.6575 0.2575 9.6575 0.2575 27 P 0 ;1
L 9.6575 0.3075 9.6575 0.3075 27 P 0 ;1
L 9.6575 0.9075 9.6575 0.9075 27 P 0 ;1
L 9.6575 0.9575 9.6575 0.9575 27 P 0 ;1
L 9.6575 1.0075 9.6575 1.0075 27 P 0 ;1
L 9.6575 1.0575 9.6575 1.0575 27 P 0 ;1
L 9.6575 1.1075 9.6575 1.1075 27 P 0 ;1
L 9.6575 1.1575 9.6575 1.1575 27 P 0 ;1
L 9.6575 1.2075 9.6575 1.2075 27 P 0 ;1
L 9.6575 1.2575 9.6575 1.2575 27 P 0 ;1
L 9.6575 1.3075 9.6575 1.3075 27 P 0 ;1
L 9.6575 1.3575 9.6575 1.3575 27 P 0 ;1
L 9.6575 1.4075 9.6575 1.4075 27 P 0 ;1
L 9.6575 1.4575 9.6575 1.4575 27 P 0 ;1
L 9.6575 1.5075 9.6575 1.5075 27 P 0 ;1
L 9.6575 1.5575 9.6575 1.5575 27 P 0 ;1
L 9.6575 1.6075 9.6575 1.6075 27 P 0 ;1
L 9.6575 1.6575 9.6575 1.6575 27 P 0 ;1
L 9.6575 1.7075 9.6575 1.7075 27 P 0 ;1
L 9.6575 1.7575 9.6575 1.7575 27 P 0 ;1
L 9.6575 1.8075 9.6575 1.8075 27 P 0 ;1
L 9.6575 1.8575 9.6575 1.8575 27 P 0 ;1
L 9.6575 1.9075 9.6575 1.9075 27 P 0 ;1
L 9.6575 1.9575 9.6575 1.9575 27 P 0 ;1
L 9.6575 2.0075 9.6575 2.0075 27 P 0 ;1
L 9.6575 2.0575 9.6575 2.0575 27 P 0 ;1
L 9.6575 2.1075 9.6575 2.1075 27 P 0 ;1
L 9.6575 2.1575 9.6575 2.1575 27 P 0 ;1
L 9.6575 2.2075 9.6575 2.2075 27 P 0 ;1
L 9.6575 2.2575 9.6575 2.2575 27 P 0 ;1
L 9.6575 2.3075 9.6575 2.3075 27 P 0 ;1
L 9.6575 2.3575 9.6575 2.3575 27 P 0 ;1
L 9.6575 2.4075 9.6575 2.4075 27 P 0 ;1
L 9.6575 2.4575 9.6575 2.4575 27 P 0 ;1
L 9.6575 2.5075 9.6575 2.5075 27 P 0 ;1
L 9.6575 2.5575 9.6575 2.5575 27 P 0 ;1
L 9.6575 2.6075 9.6575 2.6075 27 P 0 ;1
L 9.6575 2.6575 9.6575 2.6575 27 P 0 ;1
L 9.6575 2.7075 9.6575 2.7075 27 P 0 ;1
L 9.6575 2.7575 9.6575 2.7575 27 P 0 ;1
L 9.6575 2.8075 9.6575 2.8075 27 P 0 ;1
L 9.6575 2.8575 9.6575 2.8575 27 P 0 ;1
L 9.6575 2.9075 9.6575 2.9075 27 P 0 ;1
L 9.6575 2.9575 9.6575 2.9575 27 P 0 ;1
L 9.6575 3.0075 9.6575 3.0075 27 P 0 ;1
L 9.6575 3.0575 9.6575 3.0575 27 P 0 ;1
L 9.6575 3.1075 9.6575 3.1075 27 P 0 ;1
L 9.6575 3.1575 9.6575 3.1575 27 P 0 ;1
L 9.6575 3.2075 9.6575 3.2075 27 P 0 ;1
L 9.6575 3.2575 9.6575 3.2575 27 P 0 ;1
L 9.6575 3.3075 9.6575 3.3075 27 P 0 ;1
L 9.6575 3.3575 9.6575 3.3575 27 P 0 ;1
L 9.6575 3.4075 9.6575 3.4075 27 P 0 ;1
L 9.6575 3.4575 9.6575 3.4575 27 P 0 ;1
L 9.6575 3.5075 9.6575 3.5075 27 P 0 ;1
L 9.6575 3.5575 9.6575 3.5575 27 P 0 ;1
L 9.6575 3.6075 9.6575 3.6075 27 P 0 ;1
L 9.6575 3.6575 9.6575 3.6575 27 P 0 ;1
L 9.6575 3.7075 9.6575 3.7075 27 P 0 ;1
L 9.6575 3.7575 9.6575 3.7575 27 P 0 ;1
L 9.6575 3.8075 9.6575 3.8075 27 P 0 ;1
L 9.6575 3.8575 9.6575 3.8575 27 P 0 ;1
L 9.6575 3.9075 9.6575 3.9075 27 P 0 ;1
L 9.6575 3.9575 9.6575 3.9575 27 P 0 ;1
L 9.6575 4.0075 9.6575 4.0075 27 P 0 ;1
L 9.6575 4.0575 9.6575 4.0575 27 P 0 ;1
L 9.6575 4.1075 9.6575 4.1075 27 P 0 ;1
L 9.6575 4.1575 9.6575 4.1575 27 P 0 ;1
L 9.6575 4.2075 9.6575 4.2075 27 P 0 ;1
L 9.6575 4.2575 9.6575 4.2575 27 P 0 ;1
L 9.6575 4.3075 9.6575 4.3075 27 P 0 ;1
L 9.6575 4.3575 9.6575 4.3575 27 P 0 ;1
L 9.6575 4.4075 9.6575 4.4075 27 P 0 ;1
L 9.6575 4.4575 9.6575 4.4575 27 P 0 ;1
L 9.6575 4.5075 9.6575 4.5075 27 P 0 ;1
L 9.6575 4.5575 9.6575 4.5575 27 P 0 ;1
L 9.6575 4.6075 9.6575 4.6075 27 P 0 ;1
L 9.6575 5.2575 9.6575 5.2575 27 P 0 ;1
L 9.6575 5.3075 9.6575 5.3075 27 P 0 ;1
L 9.6575 5.6575 9.6575 5.6575 27 P 0 ;1
L 9.6575 5.7075 9.6575 5.7075 27 P 0 ;1
L 9.6575 5.7575 9.6575 5.7575 27 P 0 ;1
L 9.6575 5.8075 9.6575 5.8075 27 P 0 ;1
L 9.6575 5.8575 9.6575 5.8575 27 P 0 ;1
L 9.7075 0.1575 9.7075 0.1575 27 P 0 ;1
L 9.7075 0.2075 9.7075 0.2075 27 P 0 ;1
L 9.7075 0.2575 9.7075 0.2575 27 P 0 ;1
L 9.7075 0.3075 9.7075 0.3075 27 P 0 ;1
L 9.7075 0.3575 9.7075 0.3575 27 P 0 ;1
L 9.7075 0.4075 9.7075 0.4075 27 P 0 ;1
L 9.7075 0.4575 9.7075 0.4575 27 P 0 ;1
L 9.7075 0.5075 9.7075 0.5075 27 P 0 ;1
L 9.7075 0.5575 9.7075 0.5575 27 P 0 ;1
L 9.7075 0.6075 9.7075 0.6075 27 P 0 ;1
L 9.7075 0.9075 9.7075 0.9075 27 P 0 ;1
L 9.7075 0.9575 9.7075 0.9575 27 P 0 ;1
L 9.7075 1.0075 9.7075 1.0075 27 P 0 ;1
L 9.7075 1.0575 9.7075 1.0575 27 P 0 ;1
L 9.7075 1.1075 9.7075 1.1075 27 P 0 ;1
L 9.7075 1.1575 9.7075 1.1575 27 P 0 ;1
L 9.7075 1.2075 9.7075 1.2075 27 P 0 ;1
L 9.7075 1.2575 9.7075 1.2575 27 P 0 ;1
L 9.7075 1.3075 9.7075 1.3075 27 P 0 ;1
L 9.7075 1.3575 9.7075 1.3575 27 P 0 ;1
L 9.7075 1.4075 9.7075 1.4075 27 P 0 ;1
L 9.7075 1.4575 9.7075 1.4575 27 P 0 ;1
L 9.7075 1.5075 9.7075 1.5075 27 P 0 ;1
L 9.7075 1.5575 9.7075 1.5575 27 P 0 ;1
L 9.7075 1.6075 9.7075 1.6075 27 P 0 ;1
L 9.7075 1.6575 9.7075 1.6575 27 P 0 ;1
L 9.7075 1.7075 9.7075 1.7075 27 P 0 ;1
L 9.7075 1.7575 9.7075 1.7575 27 P 0 ;1
L 9.7075 1.8075 9.7075 1.8075 27 P 0 ;1
L 9.7075 1.8575 9.7075 1.8575 27 P 0 ;1
L 9.7075 1.9075 9.7075 1.9075 27 P 0 ;1
L 9.7075 1.9575 9.7075 1.9575 27 P 0 ;1
L 9.7075 2.0075 9.7075 2.0075 27 P 0 ;1
L 9.7075 2.0575 9.7075 2.0575 27 P 0 ;1
L 9.7075 2.1075 9.7075 2.1075 27 P 0 ;1
L 9.7075 2.1575 9.7075 2.1575 27 P 0 ;1
L 9.7075 2.2075 9.7075 2.2075 27 P 0 ;1
L 9.7075 2.2575 9.7075 2.2575 27 P 0 ;1
L 9.7075 2.3075 9.7075 2.3075 27 P 0 ;1
L 9.7075 2.3575 9.7075 2.3575 27 P 0 ;1
L 9.7075 2.4075 9.7075 2.4075 27 P 0 ;1
L 9.7075 2.4575 9.7075 2.4575 27 P 0 ;1
L 9.7075 2.5075 9.7075 2.5075 27 P 0 ;1
L 9.7075 2.5575 9.7075 2.5575 27 P 0 ;1
L 9.7075 2.6075 9.7075 2.6075 27 P 0 ;1
L 9.7075 2.6575 9.7075 2.6575 27 P 0 ;1
L 9.7075 2.7075 9.7075 2.7075 27 P 0 ;1
L 9.7075 2.7575 9.7075 2.7575 27 P 0 ;1
L 9.7075 2.8075 9.7075 2.8075 27 P 0 ;1
L 9.7075 2.8575 9.7075 2.8575 27 P 0 ;1
L 9.7075 2.9075 9.7075 2.9075 27 P 0 ;1
L 9.7075 2.9575 9.7075 2.9575 27 P 0 ;1
L 9.7075 3.0075 9.7075 3.0075 27 P 0 ;1
L 9.7075 3.0575 9.7075 3.0575 27 P 0 ;1
L 9.7075 3.1075 9.7075 3.1075 27 P 0 ;1
L 9.7075 3.1575 9.7075 3.1575 27 P 0 ;1
L 9.7075 3.2075 9.7075 3.2075 27 P 0 ;1
L 9.7075 3.2575 9.7075 3.2575 27 P 0 ;1
L 9.7075 3.3075 9.7075 3.3075 27 P 0 ;1
L 9.7075 3.3575 9.7075 3.3575 27 P 0 ;1
L 9.7075 3.4075 9.7075 3.4075 27 P 0 ;1
L 9.7075 3.4575 9.7075 3.4575 27 P 0 ;1
L 9.7075 3.5075 9.7075 3.5075 27 P 0 ;1
L 9.7075 3.5575 9.7075 3.5575 27 P 0 ;1
L 9.7075 3.6075 9.7075 3.6075 27 P 0 ;1
L 9.7075 3.6575 9.7075 3.6575 27 P 0 ;1
L 9.7075 3.7075 9.7075 3.7075 27 P 0 ;1
L 9.7075 3.7575 9.7075 3.7575 27 P 0 ;1
L 9.7075 3.8075 9.7075 3.8075 27 P 0 ;1
L 9.7075 3.8575 9.7075 3.8575 27 P 0 ;1
L 9.7075 3.9075 9.7075 3.9075 27 P 0 ;1
L 9.7075 3.9575 9.7075 3.9575 27 P 0 ;1
L 9.7075 4.0075 9.7075 4.0075 27 P 0 ;1
L 9.7075 4.0575 9.7075 4.0575 27 P 0 ;1
L 9.7075 4.1075 9.7075 4.1075 27 P 0 ;1
L 9.7075 4.1575 9.7075 4.1575 27 P 0 ;1
L 9.7075 4.2075 9.7075 4.2075 27 P 0 ;1
L 9.7075 4.2575 9.7075 4.2575 27 P 0 ;1
L 9.7075 4.3075 9.7075 4.3075 27 P 0 ;1
L 9.7075 4.3575 9.7075 4.3575 27 P 0 ;1
L 9.7075 4.4075 9.7075 4.4075 27 P 0 ;1
L 9.7075 4.4575 9.7075 4.4575 27 P 0 ;1
L 9.7075 4.5075 9.7075 4.5075 27 P 0 ;1
L 9.7075 4.5575 9.7075 4.5575 27 P 0 ;1
L 9.7075 4.6075 9.7075 4.6075 27 P 0 ;1
L 9.7075 4.6575 9.7075 4.6575 27 P 0 ;1
L 9.7075 4.7075 9.7075 4.7075 27 P 0 ;1
L 9.7075 4.8575 9.7075 4.8575 27 P 0 ;1
L 9.7075 4.9075 9.7075 4.9075 27 P 0 ;1
L 9.7075 4.9575 9.7075 4.9575 27 P 0 ;1
L 9.7075 5.0075 9.7075 5.0075 27 P 0 ;1
L 9.7075 5.1075 9.7075 5.1075 27 P 0 ;1
L 9.7075 5.1575 9.7075 5.1575 27 P 0 ;1
L 9.7075 5.2075 9.7075 5.2075 27 P 0 ;1
L 9.7075 5.2575 9.7075 5.2575 27 P 0 ;1
L 9.7075 5.6575 9.7075 5.6575 27 P 0 ;1
L 9.7075 5.7075 9.7075 5.7075 27 P 0 ;1
L 9.7075 5.7575 9.7075 5.7575 27 P 0 ;1
L 9.7075 5.8075 9.7075 5.8075 27 P 0 ;1
L 9.7075 5.8575 9.7075 5.8575 27 P 0 ;1
L 9.7575 0.1575 9.7575 0.1575 27 P 0 ;1
L 9.7575 0.2075 9.7575 0.2075 27 P 0 ;1
L 9.7575 0.2575 9.7575 0.2575 27 P 0 ;1
L 9.7575 0.3075 9.7575 0.3075 27 P 0 ;1
L 9.7575 0.3575 9.7575 0.3575 27 P 0 ;1
L 9.7575 0.4075 9.7575 0.4075 27 P 0 ;1
L 9.7575 0.4575 9.7575 0.4575 27 P 0 ;1
L 9.7575 0.5075 9.7575 0.5075 27 P 0 ;1
L 9.7575 0.5575 9.7575 0.5575 27 P 0 ;1
L 9.7575 0.6075 9.7575 0.6075 27 P 0 ;1
L 9.7575 0.6575 9.7575 0.6575 27 P 0 ;1
L 9.7575 0.7075 9.7575 0.7075 27 P 0 ;1
L 9.7575 0.7575 9.7575 0.7575 27 P 0 ;1
L 9.7575 0.8075 9.7575 0.8075 27 P 0 ;1
L 9.7575 0.8575 9.7575 0.8575 27 P 0 ;1
L 9.7575 0.9075 9.7575 0.9075 27 P 0 ;1
L 9.7575 0.9575 9.7575 0.9575 27 P 0 ;1
L 9.7575 1.0075 9.7575 1.0075 27 P 0 ;1
L 9.7575 1.0575 9.7575 1.0575 27 P 0 ;1
L 9.7575 1.1075 9.7575 1.1075 27 P 0 ;1
L 9.7575 1.1575 9.7575 1.1575 27 P 0 ;1
L 9.7575 1.2075 9.7575 1.2075 27 P 0 ;1
L 9.7575 1.2575 9.7575 1.2575 27 P 0 ;1
L 9.7575 1.3075 9.7575 1.3075 27 P 0 ;1
L 9.7575 1.3575 9.7575 1.3575 27 P 0 ;1
L 9.7575 1.4075 9.7575 1.4075 27 P 0 ;1
L 9.7575 1.4575 9.7575 1.4575 27 P 0 ;1
L 9.7575 1.5075 9.7575 1.5075 27 P 0 ;1
L 9.7575 1.5575 9.7575 1.5575 27 P 0 ;1
L 9.7575 1.6075 9.7575 1.6075 27 P 0 ;1
L 9.7575 1.6575 9.7575 1.6575 27 P 0 ;1
L 9.7575 1.7075 9.7575 1.7075 27 P 0 ;1
L 9.7575 1.7575 9.7575 1.7575 27 P 0 ;1
L 9.7575 1.8075 9.7575 1.8075 27 P 0 ;1
L 9.7575 1.8575 9.7575 1.8575 27 P 0 ;1
L 9.7575 1.9075 9.7575 1.9075 27 P 0 ;1
L 9.7575 1.9575 9.7575 1.9575 27 P 0 ;1
L 9.7575 2.0075 9.7575 2.0075 27 P 0 ;1
L 9.7575 2.0575 9.7575 2.0575 27 P 0 ;1
L 9.7575 2.1075 9.7575 2.1075 27 P 0 ;1
L 9.7575 2.1575 9.7575 2.1575 27 P 0 ;1
L 9.7575 2.2075 9.7575 2.2075 27 P 0 ;1
L 9.7575 2.2575 9.7575 2.2575 27 P 0 ;1
L 9.7575 2.3075 9.7575 2.3075 27 P 0 ;1
L 9.7575 2.3575 9.7575 2.3575 27 P 0 ;1
L 9.7575 2.4075 9.7575 2.4075 27 P 0 ;1
L 9.7575 2.4575 9.7575 2.4575 27 P 0 ;1
L 9.7575 2.5075 9.7575 2.5075 27 P 0 ;1
L 9.7575 2.5575 9.7575 2.5575 27 P 0 ;1
L 9.7575 2.6075 9.7575 2.6075 27 P 0 ;1
L 9.7575 2.6575 9.7575 2.6575 27 P 0 ;1
L 9.7575 2.7075 9.7575 2.7075 27 P 0 ;1
L 9.7575 2.7575 9.7575 2.7575 27 P 0 ;1
L 9.7575 2.8075 9.7575 2.8075 27 P 0 ;1
L 9.7575 2.8575 9.7575 2.8575 27 P 0 ;1
L 9.7575 2.9075 9.7575 2.9075 27 P 0 ;1
L 9.7575 2.9575 9.7575 2.9575 27 P 0 ;1
L 9.7575 3.0075 9.7575 3.0075 27 P 0 ;1
L 9.7575 3.0575 9.7575 3.0575 27 P 0 ;1
L 9.7575 3.1075 9.7575 3.1075 27 P 0 ;1
L 9.7575 3.1575 9.7575 3.1575 27 P 0 ;1
L 9.7575 3.2075 9.7575 3.2075 27 P 0 ;1
L 9.7575 3.2575 9.7575 3.2575 27 P 0 ;1
L 9.7575 3.3075 9.7575 3.3075 27 P 0 ;1
L 9.7575 3.3575 9.7575 3.3575 27 P 0 ;1
L 9.7575 3.4075 9.7575 3.4075 27 P 0 ;1
L 9.7575 3.4575 9.7575 3.4575 27 P 0 ;1
L 9.7575 3.5075 9.7575 3.5075 27 P 0 ;1
L 9.7575 3.5575 9.7575 3.5575 27 P 0 ;1
L 9.7575 3.6075 9.7575 3.6075 27 P 0 ;1
L 9.7575 3.6575 9.7575 3.6575 27 P 0 ;1
L 9.7575 3.7075 9.7575 3.7075 27 P 0 ;1
L 9.7575 3.7575 9.7575 3.7575 27 P 0 ;1
L 9.7575 3.8075 9.7575 3.8075 27 P 0 ;1
L 9.7575 3.8575 9.7575 3.8575 27 P 0 ;1
L 9.7575 3.9075 9.7575 3.9075 27 P 0 ;1
L 9.7575 3.9575 9.7575 3.9575 27 P 0 ;1
L 9.7575 4.0075 9.7575 4.0075 27 P 0 ;1
L 9.7575 4.0575 9.7575 4.0575 27 P 0 ;1
L 9.7575 4.1075 9.7575 4.1075 27 P 0 ;1
L 9.7575 4.1575 9.7575 4.1575 27 P 0 ;1
L 9.7575 4.2075 9.7575 4.2075 27 P 0 ;1
L 9.7575 4.2575 9.7575 4.2575 27 P 0 ;1
L 9.7575 4.3075 9.7575 4.3075 27 P 0 ;1
L 9.7575 4.3575 9.7575 4.3575 27 P 0 ;1
L 9.7575 4.4075 9.7575 4.4075 27 P 0 ;1
L 9.7575 4.4575 9.7575 4.4575 27 P 0 ;1
L 9.7575 4.5075 9.7575 4.5075 27 P 0 ;1
L 9.7575 5.6575 9.7575 5.6575 27 P 0 ;1
L 9.7575 5.7075 9.7575 5.7075 27 P 0 ;1
L 9.7575 5.7575 9.7575 5.7575 27 P 0 ;1
L 9.7575 5.8075 9.7575 5.8075 27 P 0 ;1
L 9.7575 5.8575 9.7575 5.8575 27 P 0 ;1
L 9.8075 0.1575 9.8075 0.1575 27 P 0 ;1
L 9.8075 0.2075 9.8075 0.2075 27 P 0 ;1
L 9.8075 0.2575 9.8075 0.2575 27 P 0 ;1
L 9.8075 0.3075 9.8075 0.3075 27 P 0 ;1
L 9.8075 0.3575 9.8075 0.3575 27 P 0 ;1
L 9.8075 0.4075 9.8075 0.4075 27 P 0 ;1
L 9.8075 0.4575 9.8075 0.4575 27 P 0 ;1
L 9.8075 0.5075 9.8075 0.5075 27 P 0 ;1
L 9.8075 0.5575 9.8075 0.5575 27 P 0 ;1
L 9.8075 0.6075 9.8075 0.6075 27 P 0 ;1
L 9.8075 0.6575 9.8075 0.6575 27 P 0 ;1
L 9.8075 0.7075 9.8075 0.7075 27 P 0 ;1
L 9.8075 0.7575 9.8075 0.7575 27 P 0 ;1
L 9.8075 0.8075 9.8075 0.8075 27 P 0 ;1
L 9.8075 0.8575 9.8075 0.8575 27 P 0 ;1
L 9.8075 0.9075 9.8075 0.9075 27 P 0 ;1
L 9.8075 0.9575 9.8075 0.9575 27 P 0 ;1
L 9.8075 1.0075 9.8075 1.0075 27 P 0 ;1
L 9.8075 1.0575 9.8075 1.0575 27 P 0 ;1
L 9.8075 1.1075 9.8075 1.1075 27 P 0 ;1
L 9.8075 1.1575 9.8075 1.1575 27 P 0 ;1
L 9.8075 1.2075 9.8075 1.2075 27 P 0 ;1
L 9.8075 1.2575 9.8075 1.2575 27 P 0 ;1
L 9.8075 1.3075 9.8075 1.3075 27 P 0 ;1
L 9.8075 1.3575 9.8075 1.3575 27 P 0 ;1
L 9.8075 1.4075 9.8075 1.4075 27 P 0 ;1
L 9.8075 1.4575 9.8075 1.4575 27 P 0 ;1
L 9.8075 1.5075 9.8075 1.5075 27 P 0 ;1
L 9.8075 1.5575 9.8075 1.5575 27 P 0 ;1
L 9.8075 1.6075 9.8075 1.6075 27 P 0 ;1
L 9.8075 1.6575 9.8075 1.6575 27 P 0 ;1
L 9.8075 1.7075 9.8075 1.7075 27 P 0 ;1
L 9.8075 1.7575 9.8075 1.7575 27 P 0 ;1
L 9.8075 1.8075 9.8075 1.8075 27 P 0 ;1
L 9.8075 1.8575 9.8075 1.8575 27 P 0 ;1
L 9.8075 1.9075 9.8075 1.9075 27 P 0 ;1
L 9.8075 1.9575 9.8075 1.9575 27 P 0 ;1
L 9.8075 2.0075 9.8075 2.0075 27 P 0 ;1
L 9.8075 2.0575 9.8075 2.0575 27 P 0 ;1
L 9.8075 2.1075 9.8075 2.1075 27 P 0 ;1
L 9.8075 2.1575 9.8075 2.1575 27 P 0 ;1
L 9.8075 2.2075 9.8075 2.2075 27 P 0 ;1
L 9.8075 2.2575 9.8075 2.2575 27 P 0 ;1
L 9.8075 2.3075 9.8075 2.3075 27 P 0 ;1
L 9.8075 2.3575 9.8075 2.3575 27 P 0 ;1
L 9.8075 2.4075 9.8075 2.4075 27 P 0 ;1
L 9.8075 2.4575 9.8075 2.4575 27 P 0 ;1
L 9.8075 2.5075 9.8075 2.5075 27 P 0 ;1
L 9.8075 2.5575 9.8075 2.5575 27 P 0 ;1
L 9.8075 2.6075 9.8075 2.6075 27 P 0 ;1
L 9.8075 2.6575 9.8075 2.6575 27 P 0 ;1
L 9.8075 2.7075 9.8075 2.7075 27 P 0 ;1
L 9.8075 2.7575 9.8075 2.7575 27 P 0 ;1
L 9.8075 2.8075 9.8075 2.8075 27 P 0 ;1
L 9.8075 2.8575 9.8075 2.8575 27 P 0 ;1
L 9.8075 2.9075 9.8075 2.9075 27 P 0 ;1
L 9.8075 2.9575 9.8075 2.9575 27 P 0 ;1
L 9.8075 3.0075 9.8075 3.0075 27 P 0 ;1
L 9.8075 3.0575 9.8075 3.0575 27 P 0 ;1
L 9.8075 3.1075 9.8075 3.1075 27 P 0 ;1
L 9.8075 3.1575 9.8075 3.1575 27 P 0 ;1
L 9.8075 3.2075 9.8075 3.2075 27 P 0 ;1
L 9.8075 3.2575 9.8075 3.2575 27 P 0 ;1
L 9.8075 3.3075 9.8075 3.3075 27 P 0 ;1
L 9.8075 3.3575 9.8075 3.3575 27 P 0 ;1
L 9.8075 3.4075 9.8075 3.4075 27 P 0 ;1
L 9.8075 3.4575 9.8075 3.4575 27 P 0 ;1
L 9.8075 3.5075 9.8075 3.5075 27 P 0 ;1
L 9.8075 3.5575 9.8075 3.5575 27 P 0 ;1
L 9.8075 3.6075 9.8075 3.6075 27 P 0 ;1
L 9.8075 3.6575 9.8075 3.6575 27 P 0 ;1
L 9.8075 3.7075 9.8075 3.7075 27 P 0 ;1
L 9.8075 3.7575 9.8075 3.7575 27 P 0 ;1
L 9.8075 3.8075 9.8075 3.8075 27 P 0 ;1
L 9.8075 3.8575 9.8075 3.8575 27 P 0 ;1
L 9.8075 3.9075 9.8075 3.9075 27 P 0 ;1
L 9.8075 3.9575 9.8075 3.9575 27 P 0 ;1
L 9.8075 4.0075 9.8075 4.0075 27 P 0 ;1
L 9.8075 4.0575 9.8075 4.0575 27 P 0 ;1
L 9.8075 4.1075 9.8075 4.1075 27 P 0 ;1
L 9.8075 4.1575 9.8075 4.1575 27 P 0 ;1
L 9.8075 4.2075 9.8075 4.2075 27 P 0 ;1
L 9.8075 4.2575 9.8075 4.2575 27 P 0 ;1
L 9.8075 4.3075 9.8075 4.3075 27 P 0 ;1
L 9.8075 4.3575 9.8075 4.3575 27 P 0 ;1
L 9.8075 4.4075 9.8075 4.4075 27 P 0 ;1
L 9.8075 4.4575 9.8075 4.4575 27 P 0 ;1
L 9.8075 5.6075 9.8075 5.6075 27 P 0 ;1
L 9.8075 5.6575 9.8075 5.6575 27 P 0 ;1
L 9.8075 5.7075 9.8075 5.7075 27 P 0 ;1
L 9.8075 5.7575 9.8075 5.7575 27 P 0 ;1
L 9.8075 5.8075 9.8075 5.8075 27 P 0 ;1
L 9.8075 5.8575 9.8075 5.8575 27 P 0 ;1
L 9.8575 0.1575 9.8575 0.1575 27 P 0 ;1
L 9.8575 0.2075 9.8575 0.2075 27 P 0 ;1
L 9.8575 0.2575 9.8575 0.2575 27 P 0 ;1
L 9.8575 0.3075 9.8575 0.3075 27 P 0 ;1
L 9.8575 0.3575 9.8575 0.3575 27 P 0 ;1
L 9.8575 0.4075 9.8575 0.4075 27 P 0 ;1
L 9.8575 0.4575 9.8575 0.4575 27 P 0 ;1
L 9.8575 0.5075 9.8575 0.5075 27 P 0 ;1
L 9.8575 0.5575 9.8575 0.5575 27 P 0 ;1
L 9.8575 0.6075 9.8575 0.6075 27 P 0 ;1
L 9.8575 0.6575 9.8575 0.6575 27 P 0 ;1
L 9.8575 0.7075 9.8575 0.7075 27 P 0 ;1
L 9.8575 0.7575 9.8575 0.7575 27 P 0 ;1
L 9.8575 0.8075 9.8575 0.8075 27 P 0 ;1
L 9.8575 0.8575 9.8575 0.8575 27 P 0 ;1
L 9.8575 0.9075 9.8575 0.9075 27 P 0 ;1
L 9.8575 0.9575 9.8575 0.9575 27 P 0 ;1
L 9.8575 1.0075 9.8575 1.0075 27 P 0 ;1
L 9.8575 1.0575 9.8575 1.0575 27 P 0 ;1
L 9.8575 1.1075 9.8575 1.1075 27 P 0 ;1
L 9.8575 1.1575 9.8575 1.1575 27 P 0 ;1
L 9.8575 1.2075 9.8575 1.2075 27 P 0 ;1
L 9.8575 1.2575 9.8575 1.2575 27 P 0 ;1
L 9.8575 1.3075 9.8575 1.3075 27 P 0 ;1
L 9.8575 1.3575 9.8575 1.3575 27 P 0 ;1
L 9.8575 1.4075 9.8575 1.4075 27 P 0 ;1
L 9.8575 1.4575 9.8575 1.4575 27 P 0 ;1
L 9.8575 1.5075 9.8575 1.5075 27 P 0 ;1
L 9.8575 1.5575 9.8575 1.5575 27 P 0 ;1
L 9.8575 1.6075 9.8575 1.6075 27 P 0 ;1
L 9.8575 1.6575 9.8575 1.6575 27 P 0 ;1
L 9.8575 1.7075 9.8575 1.7075 27 P 0 ;1
L 9.8575 1.7575 9.8575 1.7575 27 P 0 ;1
L 9.8575 1.8075 9.8575 1.8075 27 P 0 ;1
L 9.8575 1.8575 9.8575 1.8575 27 P 0 ;1
L 9.8575 1.9075 9.8575 1.9075 27 P 0 ;1
L 9.8575 1.9575 9.8575 1.9575 27 P 0 ;1
L 9.8575 2.0075 9.8575 2.0075 27 P 0 ;1
L 9.8575 2.0575 9.8575 2.0575 27 P 0 ;1
L 9.8575 2.1075 9.8575 2.1075 27 P 0 ;1
L 9.8575 2.1575 9.8575 2.1575 27 P 0 ;1
L 9.8575 2.2075 9.8575 2.2075 27 P 0 ;1
L 9.8575 2.2575 9.8575 2.2575 27 P 0 ;1
L 9.8575 2.3075 9.8575 2.3075 27 P 0 ;1
L 9.8575 2.3575 9.8575 2.3575 27 P 0 ;1
L 9.8575 2.4075 9.8575 2.4075 27 P 0 ;1
L 9.8575 2.4575 9.8575 2.4575 27 P 0 ;1
L 9.8575 2.5075 9.8575 2.5075 27 P 0 ;1
L 9.8575 2.5575 9.8575 2.5575 27 P 0 ;1
L 9.8575 2.6075 9.8575 2.6075 27 P 0 ;1
L 9.8575 2.6575 9.8575 2.6575 27 P 0 ;1
L 9.8575 2.7075 9.8575 2.7075 27 P 0 ;1
L 9.8575 2.7575 9.8575 2.7575 27 P 0 ;1
L 9.8575 2.8075 9.8575 2.8075 27 P 0 ;1
L 9.8575 2.8575 9.8575 2.8575 27 P 0 ;1
L 9.8575 2.9075 9.8575 2.9075 27 P 0 ;1
L 9.8575 2.9575 9.8575 2.9575 27 P 0 ;1
L 9.8575 3.0075 9.8575 3.0075 27 P 0 ;1
L 9.8575 3.0575 9.8575 3.0575 27 P 0 ;1
L 9.8575 3.1075 9.8575 3.1075 27 P 0 ;1
L 9.8575 3.1575 9.8575 3.1575 27 P 0 ;1
L 9.8575 3.2075 9.8575 3.2075 27 P 0 ;1
L 9.8575 3.2575 9.8575 3.2575 27 P 0 ;1
L 9.8575 3.3075 9.8575 3.3075 27 P 0 ;1
L 9.8575 3.3575 9.8575 3.3575 27 P 0 ;1
L 9.8575 3.4075 9.8575 3.4075 27 P 0 ;1
L 9.8575 3.4575 9.8575 3.4575 27 P 0 ;1
L 9.8575 3.5075 9.8575 3.5075 27 P 0 ;1
L 9.8575 3.5575 9.8575 3.5575 27 P 0 ;1
L 9.8575 3.6075 9.8575 3.6075 27 P 0 ;1
L 9.8575 3.6575 9.8575 3.6575 27 P 0 ;1
L 9.8575 3.7075 9.8575 3.7075 27 P 0 ;1
L 9.8575 3.7575 9.8575 3.7575 27 P 0 ;1
L 9.8575 3.8075 9.8575 3.8075 27 P 0 ;1
L 9.8575 3.8575 9.8575 3.8575 27 P 0 ;1
L 9.8575 3.9075 9.8575 3.9075 27 P 0 ;1
L 9.8575 3.9575 9.8575 3.9575 27 P 0 ;1
L 9.8575 4.0075 9.8575 4.0075 27 P 0 ;1
L 9.8575 4.0575 9.8575 4.0575 27 P 0 ;1
L 9.8575 4.1075 9.8575 4.1075 27 P 0 ;1
L 9.8575 4.1575 9.8575 4.1575 27 P 0 ;1
L 9.8575 4.2075 9.8575 4.2075 27 P 0 ;1
L 9.8575 4.2575 9.8575 4.2575 27 P 0 ;1
L 9.8575 4.3075 9.8575 4.3075 27 P 0 ;1
L 9.8575 5.5575 9.8575 5.5575 27 P 0 ;1
L 9.8575 5.6075 9.8575 5.6075 27 P 0 ;1
L 9.8575 5.6575 9.8575 5.6575 27 P 0 ;1
L 9.8575 5.7075 9.8575 5.7075 27 P 0 ;1
L 9.8575 5.7575 9.8575 5.7575 27 P 0 ;1
L 9.8575 5.8075 9.8575 5.8075 27 P 0 ;1
L 9.8575 5.8575 9.8575 5.8575 27 P 0 ;1
L 9.9075 0.1575 9.9075 0.1575 27 P 0 ;1
L 9.9075 0.2075 9.9075 0.2075 27 P 0 ;1
L 9.9075 0.2575 9.9075 0.2575 27 P 0 ;1
L 9.9075 0.3075 9.9075 0.3075 27 P 0 ;1
L 9.9075 0.3575 9.9075 0.3575 27 P 0 ;1
L 9.9075 0.4075 9.9075 0.4075 27 P 0 ;1
L 9.9075 0.4575 9.9075 0.4575 27 P 0 ;1
L 9.9075 0.5075 9.9075 0.5075 27 P 0 ;1
L 9.9075 0.5575 9.9075 0.5575 27 P 0 ;1
L 9.9075 0.6075 9.9075 0.6075 27 P 0 ;1
L 9.9075 0.6575 9.9075 0.6575 27 P 0 ;1
L 9.9075 0.7075 9.9075 0.7075 27 P 0 ;1
L 9.9075 0.7575 9.9075 0.7575 27 P 0 ;1
L 9.9075 0.8075 9.9075 0.8075 27 P 0 ;1
L 9.9075 0.8575 9.9075 0.8575 27 P 0 ;1
L 9.9075 0.9075 9.9075 0.9075 27 P 0 ;1
L 9.9075 0.9575 9.9075 0.9575 27 P 0 ;1
L 9.9075 1.0075 9.9075 1.0075 27 P 0 ;1
L 9.9075 1.0575 9.9075 1.0575 27 P 0 ;1
L 9.9075 1.1075 9.9075 1.1075 27 P 0 ;1
L 9.9075 1.1575 9.9075 1.1575 27 P 0 ;1
L 9.9075 1.2075 9.9075 1.2075 27 P 0 ;1
L 9.9075 1.2575 9.9075 1.2575 27 P 0 ;1
L 9.9075 1.3075 9.9075 1.3075 27 P 0 ;1
L 9.9075 1.3575 9.9075 1.3575 27 P 0 ;1
L 9.9075 1.4075 9.9075 1.4075 27 P 0 ;1
L 9.9075 1.4575 9.9075 1.4575 27 P 0 ;1
L 9.9075 1.5075 9.9075 1.5075 27 P 0 ;1
L 9.9075 1.5575 9.9075 1.5575 27 P 0 ;1
L 9.9075 1.6075 9.9075 1.6075 27 P 0 ;1
L 9.9075 1.6575 9.9075 1.6575 27 P 0 ;1
L 9.9075 1.7075 9.9075 1.7075 27 P 0 ;1
L 9.9075 1.7575 9.9075 1.7575 27 P 0 ;1
L 9.9075 1.8075 9.9075 1.8075 27 P 0 ;1
L 9.9075 1.8575 9.9075 1.8575 27 P 0 ;1
L 9.9075 1.9075 9.9075 1.9075 27 P 0 ;1
L 9.9075 1.9575 9.9075 1.9575 27 P 0 ;1
L 9.9075 2.0075 9.9075 2.0075 27 P 0 ;1
L 9.9075 2.0575 9.9075 2.0575 27 P 0 ;1
L 9.9075 2.1075 9.9075 2.1075 27 P 0 ;1
L 9.9075 2.7575 9.9075 2.7575 27 P 0 ;1
L 9.9075 2.8075 9.9075 2.8075 27 P 0 ;1
L 9.9075 3.0075 9.9075 3.0075 27 P 0 ;1
L 9.9075 3.0575 9.9075 3.0575 27 P 0 ;1
L 9.9075 3.1075 9.9075 3.1075 27 P 0 ;1
L 9.9075 3.1575 9.9075 3.1575 27 P 0 ;1
L 9.9075 3.2075 9.9075 3.2075 27 P 0 ;1
L 9.9075 3.2575 9.9075 3.2575 27 P 0 ;1
L 9.9075 3.3075 9.9075 3.3075 27 P 0 ;1
L 9.9075 3.3575 9.9075 3.3575 27 P 0 ;1
L 9.9075 3.4075 9.9075 3.4075 27 P 0 ;1
L 9.9075 3.4575 9.9075 3.4575 27 P 0 ;1
L 9.9075 3.5075 9.9075 3.5075 27 P 0 ;1
L 9.9075 3.5575 9.9075 3.5575 27 P 0 ;1
L 9.9075 3.6075 9.9075 3.6075 27 P 0 ;1
L 9.9075 3.6575 9.9075 3.6575 27 P 0 ;1
L 9.9075 3.7075 9.9075 3.7075 27 P 0 ;1
L 9.9075 3.7575 9.9075 3.7575 27 P 0 ;1
L 9.9075 3.8075 9.9075 3.8075 27 P 0 ;1
L 9.9075 3.8575 9.9075 3.8575 27 P 0 ;1
L 9.9075 3.9075 9.9075 3.9075 27 P 0 ;1
L 9.9075 3.9575 9.9075 3.9575 27 P 0 ;1
L 9.9075 4.0075 9.9075 4.0075 27 P 0 ;1
L 9.9075 4.0575 9.9075 4.0575 27 P 0 ;1
L 9.9075 4.1075 9.9075 4.1075 27 P 0 ;1
L 9.9075 4.1575 9.9075 4.1575 27 P 0 ;1
L 9.9075 4.2075 9.9075 4.2075 27 P 0 ;1
L 9.9075 4.2575 9.9075 4.2575 27 P 0 ;1
L 9.9075 4.3075 9.9075 4.3075 27 P 0 ;1
L 9.9075 5.5075 9.9075 5.5075 27 P 0 ;1
L 9.9075 5.5575 9.9075 5.5575 27 P 0 ;1
L 9.9075 5.6075 9.9075 5.6075 27 P 0 ;1
L 9.9075 5.6575 9.9075 5.6575 27 P 0 ;1
L 9.9075 5.7075 9.9075 5.7075 27 P 0 ;1
L 9.9075 5.7575 9.9075 5.7575 27 P 0 ;1
L 9.9075 5.8075 9.9075 5.8075 27 P 0 ;1
L 9.9075 5.8575 9.9075 5.8575 27 P 0 ;1
L 9.9575 0.1575 9.9575 0.1575 27 P 0 ;1
L 9.9575 0.2075 9.9575 0.2075 27 P 0 ;1
L 9.9575 0.2575 9.9575 0.2575 27 P 0 ;1
L 9.9575 0.3075 9.9575 0.3075 27 P 0 ;1
L 9.9575 0.3575 9.9575 0.3575 27 P 0 ;1
L 9.9575 0.4075 9.9575 0.4075 27 P 0 ;1
L 9.9575 0.4575 9.9575 0.4575 27 P 0 ;1
L 9.9575 0.5075 9.9575 0.5075 27 P 0 ;1
L 9.9575 0.5575 9.9575 0.5575 27 P 0 ;1
L 9.9575 0.6075 9.9575 0.6075 27 P 0 ;1
L 9.9575 0.6575 9.9575 0.6575 27 P 0 ;1
L 9.9575 0.7075 9.9575 0.7075 27 P 0 ;1
L 9.9575 0.7575 9.9575 0.7575 27 P 0 ;1
L 9.9575 0.8075 9.9575 0.8075 27 P 0 ;1
L 9.9575 0.8575 9.9575 0.8575 27 P 0 ;1
L 9.9575 0.9075 9.9575 0.9075 27 P 0 ;1
L 9.9575 0.9575 9.9575 0.9575 27 P 0 ;1
L 9.9575 1.0075 9.9575 1.0075 27 P 0 ;1
L 9.9575 1.0575 9.9575 1.0575 27 P 0 ;1
L 9.9575 1.1075 9.9575 1.1075 27 P 0 ;1
L 9.9575 1.1575 9.9575 1.1575 27 P 0 ;1
L 9.9575 1.2075 9.9575 1.2075 27 P 0 ;1
L 9.9575 1.2575 9.9575 1.2575 27 P 0 ;1
L 9.9575 1.3075 9.9575 1.3075 27 P 0 ;1
L 9.9575 1.3575 9.9575 1.3575 27 P 0 ;1
L 9.9575 1.4075 9.9575 1.4075 27 P 0 ;1
L 9.9575 1.4575 9.9575 1.4575 27 P 0 ;1
L 9.9575 1.5075 9.9575 1.5075 27 P 0 ;1
L 9.9575 1.5575 9.9575 1.5575 27 P 0 ;1
L 9.9575 1.6075 9.9575 1.6075 27 P 0 ;1
L 9.9575 1.6575 9.9575 1.6575 27 P 0 ;1
L 9.9575 1.7075 9.9575 1.7075 27 P 0 ;1
L 9.9575 1.7575 9.9575 1.7575 27 P 0 ;1
L 9.9575 1.8075 9.9575 1.8075 27 P 0 ;1
L 9.9575 1.8575 9.9575 1.8575 27 P 0 ;1
L 9.9575 1.9075 9.9575 1.9075 27 P 0 ;1
L 9.9575 1.9575 9.9575 1.9575 27 P 0 ;1
L 9.9575 2.0075 9.9575 2.0075 27 P 0 ;1
L 9.9575 2.0575 9.9575 2.0575 27 P 0 ;1
L 9.9575 2.1075 9.9575 2.1075 27 P 0 ;1
L 9.9575 2.7575 9.9575 2.7575 27 P 0 ;1
L 9.9575 3.0575 9.9575 3.0575 27 P 0 ;1
L 9.9575 3.1075 9.9575 3.1075 27 P 0 ;1
L 9.9575 3.1575 9.9575 3.1575 27 P 0 ;1
L 9.9575 3.2075 9.9575 3.2075 27 P 0 ;1
L 9.9575 3.2575 9.9575 3.2575 27 P 0 ;1
L 9.9575 3.3075 9.9575 3.3075 27 P 0 ;1
L 9.9575 3.3575 9.9575 3.3575 27 P 0 ;1
L 9.9575 3.4075 9.9575 3.4075 27 P 0 ;1
L 9.9575 3.4575 9.9575 3.4575 27 P 0 ;1
L 9.9575 3.5075 9.9575 3.5075 27 P 0 ;1
L 9.9575 3.5575 9.9575 3.5575 27 P 0 ;1
L 9.9575 3.6075 9.9575 3.6075 27 P 0 ;1
L 9.9575 3.6575 9.9575 3.6575 27 P 0 ;1
L 9.9575 3.7075 9.9575 3.7075 27 P 0 ;1
L 9.9575 3.7575 9.9575 3.7575 27 P 0 ;1
L 9.9575 3.8075 9.9575 3.8075 27 P 0 ;1
L 9.9575 3.8575 9.9575 3.8575 27 P 0 ;1
L 9.9575 3.9075 9.9575 3.9075 27 P 0 ;1
L 9.9575 3.9575 9.9575 3.9575 27 P 0 ;1
L 9.9575 4.0075 9.9575 4.0075 27 P 0 ;1
L 9.9575 4.0575 9.9575 4.0575 27 P 0 ;1
L 9.9575 4.1075 9.9575 4.1075 27 P 0 ;1
L 9.9575 4.1575 9.9575 4.1575 27 P 0 ;1
L 9.9575 4.2075 9.9575 4.2075 27 P 0 ;1
L 9.9575 4.2575 9.9575 4.2575 27 P 0 ;1
L 9.9575 4.3075 9.9575 4.3075 27 P 0 ;1
L 9.9575 5.6075 9.9575 5.6075 27 P 0 ;1
L 9.9575 5.6575 9.9575 5.6575 27 P 0 ;1
L 9.9575 5.7075 9.9575 5.7075 27 P 0 ;1
L 9.9575 5.7575 9.9575 5.7575 27 P 0 ;1
L 9.9575 5.8075 9.9575 5.8075 27 P 0 ;1
L 9.9575 5.8575 9.9575 5.8575 27 P 0 ;1
L 10.0075 0.1575 10.0075 0.1575 27 P 0 ;1
L 10.0075 0.2075 10.0075 0.2075 27 P 0 ;1
L 10.0075 0.2575 10.0075 0.2575 27 P 0 ;1
L 10.0075 0.3075 10.0075 0.3075 27 P 0 ;1
L 10.0075 0.3575 10.0075 0.3575 27 P 0 ;1
L 10.0075 0.4075 10.0075 0.4075 27 P 0 ;1
L 10.0075 0.4575 10.0075 0.4575 27 P 0 ;1
L 10.0075 0.5075 10.0075 0.5075 27 P 0 ;1
L 10.0075 0.5575 10.0075 0.5575 27 P 0 ;1
L 10.0075 0.6075 10.0075 0.6075 27 P 0 ;1
L 10.0075 0.6575 10.0075 0.6575 27 P 0 ;1
L 10.0075 0.7075 10.0075 0.7075 27 P 0 ;1
L 10.0075 0.7575 10.0075 0.7575 27 P 0 ;1
L 10.0075 0.8075 10.0075 0.8075 27 P 0 ;1
L 10.0075 0.8575 10.0075 0.8575 27 P 0 ;1
L 10.0075 0.9075 10.0075 0.9075 27 P 0 ;1
L 10.0075 0.9575 10.0075 0.9575 27 P 0 ;1
L 10.0075 1.0075 10.0075 1.0075 27 P 0 ;1
L 10.0075 1.0575 10.0075 1.0575 27 P 0 ;1
L 10.0075 1.1075 10.0075 1.1075 27 P 0 ;1
L 10.0075 1.1575 10.0075 1.1575 27 P 0 ;1
L 10.0075 1.2075 10.0075 1.2075 27 P 0 ;1
L 10.0075 1.2575 10.0075 1.2575 27 P 0 ;1
L 10.0075 1.3075 10.0075 1.3075 27 P 0 ;1
L 10.0075 1.3575 10.0075 1.3575 27 P 0 ;1
L 10.0075 1.4075 10.0075 1.4075 27 P 0 ;1
L 10.0075 1.4575 10.0075 1.4575 27 P 0 ;1
L 10.0075 1.5075 10.0075 1.5075 27 P 0 ;1
L 10.0075 1.5575 10.0075 1.5575 27 P 0 ;1
L 10.0075 1.6075 10.0075 1.6075 27 P 0 ;1
L 10.0075 1.6575 10.0075 1.6575 27 P 0 ;1
L 10.0075 1.7075 10.0075 1.7075 27 P 0 ;1
L 10.0075 1.7575 10.0075 1.7575 27 P 0 ;1
L 10.0075 1.8075 10.0075 1.8075 27 P 0 ;1
L 10.0075 1.8575 10.0075 1.8575 27 P 0 ;1
L 10.0075 1.9075 10.0075 1.9075 27 P 0 ;1
L 10.0075 1.9575 10.0075 1.9575 27 P 0 ;1
L 10.0075 3.0575 10.0075 3.0575 27 P 0 ;1
L 10.0075 3.1075 10.0075 3.1075 27 P 0 ;1
L 10.0075 3.1575 10.0075 3.1575 27 P 0 ;1
L 10.0075 3.2075 10.0075 3.2075 27 P 0 ;1
L 10.0075 3.2575 10.0075 3.2575 27 P 0 ;1
L 10.0075 3.3075 10.0075 3.3075 27 P 0 ;1
L 10.0075 3.3575 10.0075 3.3575 27 P 0 ;1
L 10.0075 3.4075 10.0075 3.4075 27 P 0 ;1
L 10.0075 3.4575 10.0075 3.4575 27 P 0 ;1
L 10.0075 3.5075 10.0075 3.5075 27 P 0 ;1
L 10.0075 3.5575 10.0075 3.5575 27 P 0 ;1
L 10.0075 3.6075 10.0075 3.6075 27 P 0 ;1
L 10.0075 3.6575 10.0075 3.6575 27 P 0 ;1
L 10.0075 3.7075 10.0075 3.7075 27 P 0 ;1
L 10.0075 3.7575 10.0075 3.7575 27 P 0 ;1
L 10.0075 3.8075 10.0075 3.8075 27 P 0 ;1
L 10.0075 3.8575 10.0075 3.8575 27 P 0 ;1
L 10.0075 3.9075 10.0075 3.9075 27 P 0 ;1
L 10.0075 3.9575 10.0075 3.9575 27 P 0 ;1
L 10.0075 4.0075 10.0075 4.0075 27 P 0 ;1
L 10.0075 4.0575 10.0075 4.0575 27 P 0 ;1
L 10.0075 4.1075 10.0075 4.1075 27 P 0 ;1
L 10.0075 4.1575 10.0075 4.1575 27 P 0 ;1
L 10.0075 4.2075 10.0075 4.2075 27 P 0 ;1
L 10.0075 4.2575 10.0075 4.2575 27 P 0 ;1
L 10.0075 4.3075 10.0075 4.3075 27 P 0 ;1
L 10.0075 4.3575 10.0075 4.3575 27 P 0 ;1
L 10.0075 4.4075 10.0075 4.4075 27 P 0 ;1
L 10.0075 5.6575 10.0075 5.6575 27 P 0 ;1
L 10.0075 5.7075 10.0075 5.7075 27 P 0 ;1
L 10.0075 5.7575 10.0075 5.7575 27 P 0 ;1
L 10.0075 5.8075 10.0075 5.8075 27 P 0 ;1
L 10.0075 5.8575 10.0075 5.8575 27 P 0 ;1
L 10.0575 0.1575 10.0575 0.1575 27 P 0 ;1
L 10.0575 0.2075 10.0575 0.2075 27 P 0 ;1
L 10.0575 0.2575 10.0575 0.2575 27 P 0 ;1
L 10.0575 0.3075 10.0575 0.3075 27 P 0 ;1
L 10.0575 0.3575 10.0575 0.3575 27 P 0 ;1
L 10.0575 0.4075 10.0575 0.4075 27 P 0 ;1
L 10.0575 0.4575 10.0575 0.4575 27 P 0 ;1
L 10.0575 0.5075 10.0575 0.5075 27 P 0 ;1
L 10.0575 0.5575 10.0575 0.5575 27 P 0 ;1
L 10.0575 0.6075 10.0575 0.6075 27 P 0 ;1
L 10.0575 0.6575 10.0575 0.6575 27 P 0 ;1
L 10.0575 0.7075 10.0575 0.7075 27 P 0 ;1
L 10.0575 0.7575 10.0575 0.7575 27 P 0 ;1
L 10.0575 0.8075 10.0575 0.8075 27 P 0 ;1
L 10.0575 0.8575 10.0575 0.8575 27 P 0 ;1
L 10.0575 0.9075 10.0575 0.9075 27 P 0 ;1
L 10.0575 0.9575 10.0575 0.9575 27 P 0 ;1
L 10.0575 1.0075 10.0575 1.0075 27 P 0 ;1
L 10.0575 1.0575 10.0575 1.0575 27 P 0 ;1
L 10.0575 1.1075 10.0575 1.1075 27 P 0 ;1
L 10.0575 1.1575 10.0575 1.1575 27 P 0 ;1
L 10.0575 1.2075 10.0575 1.2075 27 P 0 ;1
L 10.0575 1.2575 10.0575 1.2575 27 P 0 ;1
L 10.0575 1.3075 10.0575 1.3075 27 P 0 ;1
L 10.0575 1.3575 10.0575 1.3575 27 P 0 ;1
L 10.0575 1.4075 10.0575 1.4075 27 P 0 ;1
L 10.0575 1.4575 10.0575 1.4575 27 P 0 ;1
L 10.0575 1.5075 10.0575 1.5075 27 P 0 ;1
L 10.0575 1.5575 10.0575 1.5575 27 P 0 ;1
L 10.0575 1.6075 10.0575 1.6075 27 P 0 ;1
L 10.0575 1.6575 10.0575 1.6575 27 P 0 ;1
L 10.0575 1.7075 10.0575 1.7075 27 P 0 ;1
L 10.0575 1.7575 10.0575 1.7575 27 P 0 ;1
L 10.0575 1.8075 10.0575 1.8075 27 P 0 ;1
L 10.0575 1.8575 10.0575 1.8575 27 P 0 ;1
L 10.0575 1.9075 10.0575 1.9075 27 P 0 ;1
L 10.0575 3.0575 10.0575 3.0575 27 P 0 ;1
L 10.0575 3.1075 10.0575 3.1075 27 P 0 ;1
L 10.0575 3.1575 10.0575 3.1575 27 P 0 ;1
L 10.0575 3.2075 10.0575 3.2075 27 P 0 ;1
L 10.0575 3.2575 10.0575 3.2575 27 P 0 ;1
L 10.0575 3.3075 10.0575 3.3075 27 P 0 ;1
L 10.0575 3.3575 10.0575 3.3575 27 P 0 ;1
L 10.0575 3.4075 10.0575 3.4075 27 P 0 ;1
L 10.0575 3.4575 10.0575 3.4575 27 P 0 ;1
L 10.0575 3.5075 10.0575 3.5075 27 P 0 ;1
L 10.0575 3.5575 10.0575 3.5575 27 P 0 ;1
L 10.0575 3.6075 10.0575 3.6075 27 P 0 ;1
L 10.0575 3.6575 10.0575 3.6575 27 P 0 ;1
L 10.0575 3.7075 10.0575 3.7075 27 P 0 ;1
L 10.0575 3.7575 10.0575 3.7575 27 P 0 ;1
L 10.0575 3.8075 10.0575 3.8075 27 P 0 ;1
L 10.0575 3.8575 10.0575 3.8575 27 P 0 ;1
L 10.0575 3.9075 10.0575 3.9075 27 P 0 ;1
L 10.0575 3.9575 10.0575 3.9575 27 P 0 ;1
L 10.0575 4.0075 10.0575 4.0075 27 P 0 ;1
L 10.0575 4.0575 10.0575 4.0575 27 P 0 ;1
L 10.0575 4.1075 10.0575 4.1075 27 P 0 ;1
L 10.0575 4.1575 10.0575 4.1575 27 P 0 ;1
L 10.0575 4.2075 10.0575 4.2075 27 P 0 ;1
L 10.0575 4.2575 10.0575 4.2575 27 P 0 ;1
L 10.0575 4.3075 10.0575 4.3075 27 P 0 ;1
L 10.0575 4.3575 10.0575 4.3575 27 P 0 ;1
L 10.0575 4.4075 10.0575 4.4075 27 P 0 ;1
L 10.0575 5.7075 10.0575 5.7075 27 P 0 ;1
L 10.0575 5.7575 10.0575 5.7575 27 P 0 ;1
L 10.0575 5.8075 10.0575 5.8075 27 P 0 ;1
L 10.0575 5.8575 10.0575 5.8575 27 P 0 ;1
L 10.1075 0.1575 10.1075 0.1575 27 P 0 ;1
L 10.1075 0.2075 10.1075 0.2075 27 P 0 ;1
L 10.1075 0.2575 10.1075 0.2575 27 P 0 ;1
L 10.1075 0.3075 10.1075 0.3075 27 P 0 ;1
L 10.1075 0.3575 10.1075 0.3575 27 P 0 ;1
L 10.1075 0.4075 10.1075 0.4075 27 P 0 ;1
L 10.1075 0.4575 10.1075 0.4575 27 P 0 ;1
L 10.1075 0.5075 10.1075 0.5075 27 P 0 ;1
L 10.1075 0.5575 10.1075 0.5575 27 P 0 ;1
L 10.1075 0.6075 10.1075 0.6075 27 P 0 ;1
L 10.1075 0.6575 10.1075 0.6575 27 P 0 ;1
L 10.1075 0.7075 10.1075 0.7075 27 P 0 ;1
L 10.1075 0.7575 10.1075 0.7575 27 P 0 ;1
L 10.1075 0.8075 10.1075 0.8075 27 P 0 ;1
L 10.1075 0.8575 10.1075 0.8575 27 P 0 ;1
L 10.1075 0.9075 10.1075 0.9075 27 P 0 ;1
L 10.1075 0.9575 10.1075 0.9575 27 P 0 ;1
L 10.1075 1.0075 10.1075 1.0075 27 P 0 ;1
L 10.1075 1.0575 10.1075 1.0575 27 P 0 ;1
L 10.1075 1.1075 10.1075 1.1075 27 P 0 ;1
L 10.1075 1.1575 10.1075 1.1575 27 P 0 ;1
L 10.1075 1.2075 10.1075 1.2075 27 P 0 ;1
L 10.1075 1.2575 10.1075 1.2575 27 P 0 ;1
L 10.1075 1.3075 10.1075 1.3075 27 P 0 ;1
L 10.1075 1.3575 10.1075 1.3575 27 P 0 ;1
L 10.1075 1.4075 10.1075 1.4075 27 P 0 ;1
L 10.1075 1.4575 10.1075 1.4575 27 P 0 ;1
L 10.1075 1.5075 10.1075 1.5075 27 P 0 ;1
L 10.1075 1.5575 10.1075 1.5575 27 P 0 ;1
L 10.1075 1.6075 10.1075 1.6075 27 P 0 ;1
L 10.1075 1.6575 10.1075 1.6575 27 P 0 ;1
L 10.1075 1.7075 10.1075 1.7075 27 P 0 ;1
L 10.1075 1.7575 10.1075 1.7575 27 P 0 ;1
L 10.1075 1.8075 10.1075 1.8075 27 P 0 ;1
L 10.1075 1.8575 10.1075 1.8575 27 P 0 ;1
L 10.1075 1.9075 10.1075 1.9075 27 P 0 ;1
L 10.1075 3.7575 10.1075 3.7575 27 P 0 ;1
L 10.1075 3.8075 10.1075 3.8075 27 P 0 ;1
L 10.1075 3.8575 10.1075 3.8575 27 P 0 ;1
L 10.1075 3.9075 10.1075 3.9075 27 P 0 ;1
L 10.1075 3.9575 10.1075 3.9575 27 P 0 ;1
L 10.1075 4.0075 10.1075 4.0075 27 P 0 ;1
L 10.1075 4.0575 10.1075 4.0575 27 P 0 ;1
L 10.1075 4.1075 10.1075 4.1075 27 P 0 ;1
L 10.1075 4.1575 10.1075 4.1575 27 P 0 ;1
L 10.1075 4.2075 10.1075 4.2075 27 P 0 ;1
L 10.1075 4.2575 10.1075 4.2575 27 P 0 ;1
L 10.1075 4.3075 10.1075 4.3075 27 P 0 ;1
L 10.1075 4.3575 10.1075 4.3575 27 P 0 ;1
L 10.1075 4.4075 10.1075 4.4075 27 P 0 ;1
L 10.1075 4.8075 10.1075 4.8075 27 P 0 ;1
L 10.1075 4.8575 10.1075 4.8575 27 P 0 ;1
L 10.1075 4.9075 10.1075 4.9075 27 P 0 ;1
L 10.1075 4.9575 10.1075 4.9575 27 P 0 ;1
L 10.1075 5.0075 10.1075 5.0075 27 P 0 ;1
L 10.1075 5.0575 10.1075 5.0575 27 P 0 ;1
L 10.1075 5.1075 10.1075 5.1075 27 P 0 ;1
L 10.1075 5.1575 10.1075 5.1575 27 P 0 ;1
L 10.1075 5.7075 10.1075 5.7075 27 P 0 ;1
L 10.1075 5.7575 10.1075 5.7575 27 P 0 ;1
L 10.1075 5.8075 10.1075 5.8075 27 P 0 ;1
L 10.1075 5.8575 10.1075 5.8575 27 P 0 ;1
L 10.1575 0.1575 10.1575 0.1575 27 P 0 ;1
L 10.1575 0.2075 10.1575 0.2075 27 P 0 ;1
L 10.1575 0.2575 10.1575 0.2575 27 P 0 ;1
L 10.1575 0.3075 10.1575 0.3075 27 P 0 ;1
L 10.1575 0.3575 10.1575 0.3575 27 P 0 ;1
L 10.1575 0.4075 10.1575 0.4075 27 P 0 ;1
L 10.1575 0.4575 10.1575 0.4575 27 P 0 ;1
L 10.1575 0.5075 10.1575 0.5075 27 P 0 ;1
L 10.1575 0.5575 10.1575 0.5575 27 P 0 ;1
L 10.1575 0.6075 10.1575 0.6075 27 P 0 ;1
L 10.1575 0.6575 10.1575 0.6575 27 P 0 ;1
L 10.1575 0.7075 10.1575 0.7075 27 P 0 ;1
L 10.1575 0.7575 10.1575 0.7575 27 P 0 ;1
L 10.1575 0.8075 10.1575 0.8075 27 P 0 ;1
L 10.1575 0.8575 10.1575 0.8575 27 P 0 ;1
L 10.1575 0.9075 10.1575 0.9075 27 P 0 ;1
L 10.1575 0.9575 10.1575 0.9575 27 P 0 ;1
L 10.1575 1.0075 10.1575 1.0075 27 P 0 ;1
L 10.1575 1.0575 10.1575 1.0575 27 P 0 ;1
L 10.1575 1.1075 10.1575 1.1075 27 P 0 ;1
L 10.1575 1.1575 10.1575 1.1575 27 P 0 ;1
L 10.1575 1.2075 10.1575 1.2075 27 P 0 ;1
L 10.1575 1.2575 10.1575 1.2575 27 P 0 ;1
L 10.1575 1.3075 10.1575 1.3075 27 P 0 ;1
L 10.1575 1.3575 10.1575 1.3575 27 P 0 ;1
L 10.1575 1.4075 10.1575 1.4075 27 P 0 ;1
L 10.1575 1.4575 10.1575 1.4575 27 P 0 ;1
L 10.1575 1.5075 10.1575 1.5075 27 P 0 ;1
L 10.1575 1.5575 10.1575 1.5575 27 P 0 ;1
L 10.1575 1.6075 10.1575 1.6075 27 P 0 ;1
L 10.1575 1.6575 10.1575 1.6575 27 P 0 ;1
L 10.1575 1.7075 10.1575 1.7075 27 P 0 ;1
L 10.1575 1.7575 10.1575 1.7575 27 P 0 ;1
L 10.1575 1.8075 10.1575 1.8075 27 P 0 ;1
L 10.1575 1.8575 10.1575 1.8575 27 P 0 ;1
L 10.1575 3.7575 10.1575 3.7575 27 P 0 ;1
L 10.1575 3.8075 10.1575 3.8075 27 P 0 ;1
L 10.1575 3.8575 10.1575 3.8575 27 P 0 ;1
L 10.1575 3.9075 10.1575 3.9075 27 P 0 ;1
L 10.1575 3.9575 10.1575 3.9575 27 P 0 ;1
L 10.1575 4.0075 10.1575 4.0075 27 P 0 ;1
L 10.1575 4.0575 10.1575 4.0575 27 P 0 ;1
L 10.1575 4.1075 10.1575 4.1075 27 P 0 ;1
L 10.1575 4.1575 10.1575 4.1575 27 P 0 ;1
L 10.1575 4.2075 10.1575 4.2075 27 P 0 ;1
L 10.1575 4.2575 10.1575 4.2575 27 P 0 ;1
L 10.1575 4.3075 10.1575 4.3075 27 P 0 ;1
L 10.1575 4.3575 10.1575 4.3575 27 P 0 ;1
L 10.1575 4.4075 10.1575 4.4075 27 P 0 ;1
L 10.1575 4.4575 10.1575 4.4575 27 P 0 ;1
L 10.1575 4.5075 10.1575 4.5075 27 P 0 ;1
L 10.1575 4.5575 10.1575 4.5575 27 P 0 ;1
L 10.1575 4.6075 10.1575 4.6075 27 P 0 ;1
L 10.1575 4.6575 10.1575 4.6575 27 P 0 ;1
L 10.1575 4.7075 10.1575 4.7075 27 P 0 ;1
L 10.1575 4.7575 10.1575 4.7575 27 P 0 ;1
L 10.1575 4.8075 10.1575 4.8075 27 P 0 ;1
L 10.1575 4.8575 10.1575 4.8575 27 P 0 ;1
L 10.1575 4.9075 10.1575 4.9075 27 P 0 ;1
L 10.1575 4.9575 10.1575 4.9575 27 P 0 ;1
L 10.1575 5.0075 10.1575 5.0075 27 P 0 ;1
L 10.1575 5.0575 10.1575 5.0575 27 P 0 ;1
L 10.1575 5.1075 10.1575 5.1075 27 P 0 ;1
L 10.1575 5.1575 10.1575 5.1575 27 P 0 ;1
L 10.1575 5.7575 10.1575 5.7575 27 P 0 ;1
L 10.1575 5.8075 10.1575 5.8075 27 P 0 ;1
L 10.1575 5.8575 10.1575 5.8575 27 P 0 ;1
L 10.2075 0.1575 10.2075 0.1575 27 P 0 ;1
L 10.2075 0.2075 10.2075 0.2075 27 P 0 ;1
L 10.2075 0.2575 10.2075 0.2575 27 P 0 ;1
L 10.2075 0.3075 10.2075 0.3075 27 P 0 ;1
L 10.2075 0.3575 10.2075 0.3575 27 P 0 ;1
L 10.2075 0.4075 10.2075 0.4075 27 P 0 ;1
L 10.2075 0.4575 10.2075 0.4575 27 P 0 ;1
L 10.2075 0.5075 10.2075 0.5075 27 P 0 ;1
L 10.2075 0.5575 10.2075 0.5575 27 P 0 ;1
L 10.2075 0.6075 10.2075 0.6075 27 P 0 ;1
L 10.2075 0.6575 10.2075 0.6575 27 P 0 ;1
L 10.2075 0.7075 10.2075 0.7075 27 P 0 ;1
L 10.2075 0.7575 10.2075 0.7575 27 P 0 ;1
L 10.2075 0.8075 10.2075 0.8075 27 P 0 ;1
L 10.2075 0.8575 10.2075 0.8575 27 P 0 ;1
L 10.2075 0.9075 10.2075 0.9075 27 P 0 ;1
L 10.2075 0.9575 10.2075 0.9575 27 P 0 ;1
L 10.2075 1.0075 10.2075 1.0075 27 P 0 ;1
L 10.2075 1.0575 10.2075 1.0575 27 P 0 ;1
L 10.2075 1.1075 10.2075 1.1075 27 P 0 ;1
L 10.2075 1.1575 10.2075 1.1575 27 P 0 ;1
L 10.2075 1.2075 10.2075 1.2075 27 P 0 ;1
L 10.2075 1.2575 10.2075 1.2575 27 P 0 ;1
L 10.2075 1.3075 10.2075 1.3075 27 P 0 ;1
L 10.2075 1.3575 10.2075 1.3575 27 P 0 ;1
L 10.2075 1.4075 10.2075 1.4075 27 P 0 ;1
L 10.2075 1.4575 10.2075 1.4575 27 P 0 ;1
L 10.2075 1.5075 10.2075 1.5075 27 P 0 ;1
L 10.2075 1.5575 10.2075 1.5575 27 P 0 ;1
L 10.2075 3.7575 10.2075 3.7575 27 P 0 ;1
L 10.2075 3.8075 10.2075 3.8075 27 P 0 ;1
L 10.2075 3.8575 10.2075 3.8575 27 P 0 ;1
L 10.2075 5.7575 10.2075 5.7575 27 P 0 ;1
L 10.2075 5.8075 10.2075 5.8075 27 P 0 ;1
L 10.2075 5.8575 10.2075 5.8575 27 P 0 ;1
L 10.2575 0.1575 10.2575 0.1575 27 P 0 ;1
L 10.2575 0.2075 10.2575 0.2075 27 P 0 ;1
L 10.2575 0.2575 10.2575 0.2575 27 P 0 ;1
L 10.2575 0.3075 10.2575 0.3075 27 P 0 ;1
L 10.2575 0.3575 10.2575 0.3575 27 P 0 ;1
L 10.2575 0.4075 10.2575 0.4075 27 P 0 ;1
L 10.2575 0.4575 10.2575 0.4575 27 P 0 ;1
L 10.2575 0.5075 10.2575 0.5075 27 P 0 ;1
L 10.2575 0.5575 10.2575 0.5575 27 P 0 ;1
L 10.2575 0.6075 10.2575 0.6075 27 P 0 ;1
L 10.2575 0.6575 10.2575 0.6575 27 P 0 ;1
L 10.2575 0.7075 10.2575 0.7075 27 P 0 ;1
L 10.2575 0.7575 10.2575 0.7575 27 P 0 ;1
L 10.2575 0.8075 10.2575 0.8075 27 P 0 ;1
L 10.2575 0.8575 10.2575 0.8575 27 P 0 ;1
L 10.2575 0.9075 10.2575 0.9075 27 P 0 ;1
L 10.2575 0.9575 10.2575 0.9575 27 P 0 ;1
L 10.2575 1.0075 10.2575 1.0075 27 P 0 ;1
L 10.2575 1.0575 10.2575 1.0575 27 P 0 ;1
L 10.2575 1.1075 10.2575 1.1075 27 P 0 ;1
L 10.2575 1.1575 10.2575 1.1575 27 P 0 ;1
L 10.2575 1.2075 10.2575 1.2075 27 P 0 ;1
L 10.2575 1.2575 10.2575 1.2575 27 P 0 ;1
L 10.2575 1.3075 10.2575 1.3075 27 P 0 ;1
L 10.2575 1.3575 10.2575 1.3575 27 P 0 ;1
L 10.2575 1.4075 10.2575 1.4075 27 P 0 ;1
L 10.2575 1.4575 10.2575 1.4575 27 P 0 ;1
L 10.2575 1.5075 10.2575 1.5075 27 P 0 ;1
L 10.2575 1.5575 10.2575 1.5575 27 P 0 ;1
L 10.2575 3.7575 10.2575 3.7575 27 P 0 ;1
L 10.2575 3.8075 10.2575 3.8075 27 P 0 ;1
L 10.2575 5.7575 10.2575 5.7575 27 P 0 ;1
L 10.2575 5.8075 10.2575 5.8075 27 P 0 ;1
L 10.2575 5.8575 10.2575 5.8575 27 P 0 ;1
L 10.3075 0.1575 10.3075 0.1575 27 P 0 ;1
L 10.3075 0.2075 10.3075 0.2075 27 P 0 ;1
L 10.3075 0.2575 10.3075 0.2575 27 P 0 ;1
L 10.3075 0.3075 10.3075 0.3075 27 P 0 ;1
L 10.3075 0.3575 10.3075 0.3575 27 P 0 ;1
L 10.3075 0.4075 10.3075 0.4075 27 P 0 ;1
L 10.3075 0.4575 10.3075 0.4575 27 P 0 ;1
L 10.3075 0.5075 10.3075 0.5075 27 P 0 ;1
L 10.3075 0.5575 10.3075 0.5575 27 P 0 ;1
L 10.3075 0.6075 10.3075 0.6075 27 P 0 ;1
L 10.3075 0.6575 10.3075 0.6575 27 P 0 ;1
L 10.3075 0.7075 10.3075 0.7075 27 P 0 ;1
L 10.3075 0.7575 10.3075 0.7575 27 P 0 ;1
L 10.3075 0.8075 10.3075 0.8075 27 P 0 ;1
L 10.3075 0.8575 10.3075 0.8575 27 P 0 ;1
L 10.3075 0.9075 10.3075 0.9075 27 P 0 ;1
L 10.3075 0.9575 10.3075 0.9575 27 P 0 ;1
L 10.3075 1.0075 10.3075 1.0075 27 P 0 ;1
L 10.3075 1.0575 10.3075 1.0575 27 P 0 ;1
L 10.3075 1.1075 10.3075 1.1075 27 P 0 ;1
L 10.3075 1.1575 10.3075 1.1575 27 P 0 ;1
L 10.3075 1.2075 10.3075 1.2075 27 P 0 ;1
L 10.3075 1.3575 10.3075 1.3575 27 P 0 ;1
L 10.3075 1.4075 10.3075 1.4075 27 P 0 ;1
L 10.3075 3.7575 10.3075 3.7575 27 P 0 ;1
L 10.3075 5.7575 10.3075 5.7575 27 P 0 ;1
L 10.3075 5.8075 10.3075 5.8075 27 P 0 ;1
L 10.3075 5.8575 10.3075 5.8575 27 P 0 ;1
L 10.3575 0.1575 10.3575 0.1575 27 P 0 ;1
L 10.3575 0.2075 10.3575 0.2075 27 P 0 ;1
L 10.3575 0.2575 10.3575 0.2575 27 P 0 ;1
L 10.3575 0.3075 10.3575 0.3075 27 P 0 ;1
L 10.3575 0.3575 10.3575 0.3575 27 P 0 ;1
L 10.3575 0.4075 10.3575 0.4075 27 P 0 ;1
L 10.3575 0.4575 10.3575 0.4575 27 P 0 ;1
L 10.3575 0.5075 10.3575 0.5075 27 P 0 ;1
L 10.3575 0.5575 10.3575 0.5575 27 P 0 ;1
L 10.3575 0.6075 10.3575 0.6075 27 P 0 ;1
L 10.3575 0.6575 10.3575 0.6575 27 P 0 ;1
L 10.3575 0.7075 10.3575 0.7075 27 P 0 ;1
L 10.3575 0.7575 10.3575 0.7575 27 P 0 ;1
L 10.3575 0.8075 10.3575 0.8075 27 P 0 ;1
L 10.3575 0.8575 10.3575 0.8575 27 P 0 ;1
L 10.3575 0.9075 10.3575 0.9075 27 P 0 ;1
L 10.3575 0.9575 10.3575 0.9575 27 P 0 ;1
L 10.3575 1.0075 10.3575 1.0075 27 P 0 ;1
L 10.3575 1.0575 10.3575 1.0575 27 P 0 ;1
L 10.3575 1.1075 10.3575 1.1075 27 P 0 ;1
L 10.3575 1.1575 10.3575 1.1575 27 P 0 ;1
L 10.3575 1.9575 10.3575 1.9575 27 P 0 ;1
L 10.3575 5.7075 10.3575 5.7075 27 P 0 ;1
L 10.3575 5.7575 10.3575 5.7575 27 P 0 ;1
L 10.3575 5.8075 10.3575 5.8075 27 P 0 ;1
L 10.3575 5.8575 10.3575 5.8575 27 P 0 ;1
L 10.4075 0.1575 10.4075 0.1575 27 P 0 ;1
L 10.4075 0.2075 10.4075 0.2075 27 P 0 ;1
L 10.4075 0.2575 10.4075 0.2575 27 P 0 ;1
L 10.4075 0.3075 10.4075 0.3075 27 P 0 ;1
L 10.4075 0.3575 10.4075 0.3575 27 P 0 ;1
L 10.4075 0.4075 10.4075 0.4075 27 P 0 ;1
L 10.4075 0.4575 10.4075 0.4575 27 P 0 ;1
L 10.4075 0.5075 10.4075 0.5075 27 P 0 ;1
L 10.4075 0.5575 10.4075 0.5575 27 P 0 ;1
L 10.4075 0.6075 10.4075 0.6075 27 P 0 ;1
L 10.4075 0.6575 10.4075 0.6575 27 P 0 ;1
L 10.4075 0.7075 10.4075 0.7075 27 P 0 ;1
L 10.4075 0.7575 10.4075 0.7575 27 P 0 ;1
L 10.4075 0.8075 10.4075 0.8075 27 P 0 ;1
L 10.4075 0.8575 10.4075 0.8575 27 P 0 ;1
L 10.4075 0.9075 10.4075 0.9075 27 P 0 ;1
L 10.4075 0.9575 10.4075 0.9575 27 P 0 ;1
L 10.4075 1.0075 10.4075 1.0075 27 P 0 ;1
L 10.4075 1.0575 10.4075 1.0575 27 P 0 ;1
L 10.4075 1.1075 10.4075 1.1075 27 P 0 ;1
L 10.4075 1.1575 10.4075 1.1575 27 P 0 ;1
L 10.4075 1.6575 10.4075 1.6575 27 P 0 ;1
L 10.4075 1.7075 10.4075 1.7075 27 P 0 ;1
L 10.4075 1.7575 10.4075 1.7575 27 P 0 ;1
L 10.4075 1.8075 10.4075 1.8075 27 P 0 ;1
L 10.4075 1.8575 10.4075 1.8575 27 P 0 ;1
L 10.4075 1.9075 10.4075 1.9075 27 P 0 ;1
L 10.4075 1.9575 10.4075 1.9575 27 P 0 ;1
L 10.4075 5.6575 10.4075 5.6575 27 P 0 ;1
L 10.4075 5.7075 10.4075 5.7075 27 P 0 ;1
L 10.4075 5.7575 10.4075 5.7575 27 P 0 ;1
L 10.4075 5.8075 10.4075 5.8075 27 P 0 ;1
L 10.4075 5.8575 10.4075 5.8575 27 P 0 ;1
L 10.4575 0.1575 10.4575 0.1575 27 P 0 ;1
L 10.4575 0.2075 10.4575 0.2075 27 P 0 ;1
L 10.4575 0.2575 10.4575 0.2575 27 P 0 ;1
L 10.4575 0.3075 10.4575 0.3075 27 P 0 ;1
L 10.4575 0.3575 10.4575 0.3575 27 P 0 ;1
L 10.4575 0.4075 10.4575 0.4075 27 P 0 ;1
L 10.4575 0.4575 10.4575 0.4575 27 P 0 ;1
L 10.4575 0.5075 10.4575 0.5075 27 P 0 ;1
L 10.4575 0.5575 10.4575 0.5575 27 P 0 ;1
L 10.4575 0.6075 10.4575 0.6075 27 P 0 ;1
L 10.4575 0.6575 10.4575 0.6575 27 P 0 ;1
L 10.4575 0.7075 10.4575 0.7075 27 P 0 ;1
L 10.4575 0.7575 10.4575 0.7575 27 P 0 ;1
L 10.4575 0.8075 10.4575 0.8075 27 P 0 ;1
L 10.4575 0.8575 10.4575 0.8575 27 P 0 ;1
L 10.4575 0.9075 10.4575 0.9075 27 P 0 ;1
L 10.4575 0.9575 10.4575 0.9575 27 P 0 ;1
L 10.4575 1.0075 10.4575 1.0075 27 P 0 ;1
L 10.4575 1.0575 10.4575 1.0575 27 P 0 ;1
L 10.4575 1.1075 10.4575 1.1075 27 P 0 ;1
L 10.4575 1.1575 10.4575 1.1575 27 P 0 ;1
L 10.4575 1.6075 10.4575 1.6075 27 P 0 ;1
L 10.4575 1.6575 10.4575 1.6575 27 P 0 ;1
L 10.4575 1.7075 10.4575 1.7075 27 P 0 ;1
L 10.4575 1.7575 10.4575 1.7575 27 P 0 ;1
L 10.4575 1.8075 10.4575 1.8075 27 P 0 ;1
L 10.4575 1.8575 10.4575 1.8575 27 P 0 ;1
L 10.4575 1.9075 10.4575 1.9075 27 P 0 ;1
L 10.4575 1.9575 10.4575 1.9575 27 P 0 ;1
L 10.4575 5.6075 10.4575 5.6075 27 P 0 ;1
L 10.4575 5.6575 10.4575 5.6575 27 P 0 ;1
L 10.4575 5.7075 10.4575 5.7075 27 P 0 ;1
L 10.4575 5.7575 10.4575 5.7575 27 P 0 ;1
L 10.4575 5.8075 10.4575 5.8075 27 P 0 ;1
L 10.4575 5.8575 10.4575 5.8575 27 P 0 ;1
L 10.5075 0.1575 10.5075 0.1575 27 P 0 ;1
L 10.5075 0.2075 10.5075 0.2075 27 P 0 ;1
L 10.5075 0.2575 10.5075 0.2575 27 P 0 ;1
L 10.5075 0.3075 10.5075 0.3075 27 P 0 ;1
L 10.5075 0.3575 10.5075 0.3575 27 P 0 ;1
L 10.5075 0.4075 10.5075 0.4075 27 P 0 ;1
L 10.5075 0.4575 10.5075 0.4575 27 P 0 ;1
L 10.5075 0.5075 10.5075 0.5075 27 P 0 ;1
L 10.5075 0.5575 10.5075 0.5575 27 P 0 ;1
L 10.5075 0.6075 10.5075 0.6075 27 P 0 ;1
L 10.5075 0.6575 10.5075 0.6575 27 P 0 ;1
L 10.5075 0.7075 10.5075 0.7075 27 P 0 ;1
L 10.5075 0.7575 10.5075 0.7575 27 P 0 ;1
L 10.5075 0.8075 10.5075 0.8075 27 P 0 ;1
L 10.5075 0.8575 10.5075 0.8575 27 P 0 ;1
L 10.5075 0.9075 10.5075 0.9075 27 P 0 ;1
L 10.5075 0.9575 10.5075 0.9575 27 P 0 ;1
L 10.5075 1.0075 10.5075 1.0075 27 P 0 ;1
L 10.5075 1.0575 10.5075 1.0575 27 P 0 ;1
L 10.5075 1.1075 10.5075 1.1075 27 P 0 ;1
L 10.5075 1.1575 10.5075 1.1575 27 P 0 ;1
L 10.5075 1.2075 10.5075 1.2075 27 P 0 ;1
L 10.5075 1.5575 10.5075 1.5575 27 P 0 ;1
L 10.5075 1.6075 10.5075 1.6075 27 P 0 ;1
L 10.5075 1.6575 10.5075 1.6575 27 P 0 ;1
L 10.5075 1.7075 10.5075 1.7075 27 P 0 ;1
L 10.5075 1.7575 10.5075 1.7575 27 P 0 ;1
L 10.5075 1.8075 10.5075 1.8075 27 P 0 ;1
L 10.5575 0.1575 10.5575 0.1575 27 P 0 ;1
L 10.5575 0.2075 10.5575 0.2075 27 P 0 ;1
L 10.5575 0.2575 10.5575 0.2575 27 P 0 ;1
L 10.5575 0.3075 10.5575 0.3075 27 P 0 ;1
L 10.5575 0.3575 10.5575 0.3575 27 P 0 ;1
L 10.5575 0.4075 10.5575 0.4075 27 P 0 ;1
L 10.5575 0.4575 10.5575 0.4575 27 P 0 ;1
L 10.5575 0.5075 10.5575 0.5075 27 P 0 ;1
L 10.5575 0.5575 10.5575 0.5575 27 P 0 ;1
L 10.5575 0.6075 10.5575 0.6075 27 P 0 ;1
L 10.5575 0.6575 10.5575 0.6575 27 P 0 ;1
L 10.5575 0.7075 10.5575 0.7075 27 P 0 ;1
L 10.5575 0.7575 10.5575 0.7575 27 P 0 ;1
L 10.5575 0.8075 10.5575 0.8075 27 P 0 ;1
L 10.5575 0.8575 10.5575 0.8575 27 P 0 ;1
L 10.5575 0.9075 10.5575 0.9075 27 P 0 ;1
L 10.5575 0.9575 10.5575 0.9575 27 P 0 ;1
L 10.5575 1.0075 10.5575 1.0075 27 P 0 ;1
L 10.5575 1.0575 10.5575 1.0575 27 P 0 ;1
L 10.5575 1.1075 10.5575 1.1075 27 P 0 ;1
L 10.5575 1.1575 10.5575 1.1575 27 P 0 ;1
L 10.5575 1.2075 10.5575 1.2075 27 P 0 ;1
L 10.5575 1.2575 10.5575 1.2575 27 P 0 ;1
L 10.5575 1.3075 10.5575 1.3075 27 P 0 ;1
L 10.5575 1.3575 10.5575 1.3575 27 P 0 ;1
L 10.5575 1.5075 10.5575 1.5075 27 P 0 ;1
L 10.5575 1.5575 10.5575 1.5575 27 P 0 ;1
L 10.5575 1.6075 10.5575 1.6075 27 P 0 ;1
L 10.5575 1.6575 10.5575 1.6575 27 P 0 ;1
L 10.5575 1.7075 10.5575 1.7075 27 P 0 ;1
L 10.5575 1.7575 10.5575 1.7575 27 P 0 ;1
L 10.6075 0.1575 10.6075 0.1575 27 P 0 ;1
L 10.6075 0.2075 10.6075 0.2075 27 P 0 ;1
L 10.6075 0.2575 10.6075 0.2575 27 P 0 ;1
L 10.6075 0.3075 10.6075 0.3075 27 P 0 ;1
L 10.6075 0.3575 10.6075 0.3575 27 P 0 ;1
L 10.6075 0.4075 10.6075 0.4075 27 P 0 ;1
L 10.6075 0.4575 10.6075 0.4575 27 P 0 ;1
L 10.6075 0.5075 10.6075 0.5075 27 P 0 ;1
L 10.6075 0.5575 10.6075 0.5575 27 P 0 ;1
L 10.6075 0.6075 10.6075 0.6075 27 P 0 ;1
L 10.6075 0.6575 10.6075 0.6575 27 P 0 ;1
L 10.6075 0.7075 10.6075 0.7075 27 P 0 ;1
L 10.6075 0.7575 10.6075 0.7575 27 P 0 ;1
L 10.6075 0.8075 10.6075 0.8075 27 P 0 ;1
L 10.6075 0.8575 10.6075 0.8575 27 P 0 ;1
L 10.6075 0.9075 10.6075 0.9075 27 P 0 ;1
L 10.6075 0.9575 10.6075 0.9575 27 P 0 ;1
L 10.6075 1.0075 10.6075 1.0075 27 P 0 ;1
L 10.6075 1.0575 10.6075 1.0575 27 P 0 ;1
L 10.6075 1.1075 10.6075 1.1075 27 P 0 ;1
L 10.6075 1.1575 10.6075 1.1575 27 P 0 ;1
L 10.6075 1.2075 10.6075 1.2075 27 P 0 ;1
L 10.6075 1.2575 10.6075 1.2575 27 P 0 ;1
L 10.6075 1.3075 10.6075 1.3075 27 P 0 ;1
L 10.6075 1.3575 10.6075 1.3575 27 P 0 ;1
L 10.6075 1.4075 10.6075 1.4075 27 P 0 ;1
L 10.6075 1.6075 10.6075 1.6075 27 P 0 ;1
L 10.6075 1.6575 10.6075 1.6575 27 P 0 ;1
L 10.6075 1.7075 10.6075 1.7075 27 P 0 ;1
L 10.6075 1.7575 10.6075 1.7575 27 P 0 ;1
L 10.6575 0.1575 10.6575 0.1575 27 P 0 ;1
L 10.6575 0.2075 10.6575 0.2075 27 P 0 ;1
L 10.6575 0.2575 10.6575 0.2575 27 P 0 ;1
L 10.6575 0.3075 10.6575 0.3075 27 P 0 ;1
L 10.6575 0.3575 10.6575 0.3575 27 P 0 ;1
L 10.6575 0.4075 10.6575 0.4075 27 P 0 ;1
L 10.6575 0.4575 10.6575 0.4575 27 P 0 ;1
L 10.6575 0.5075 10.6575 0.5075 27 P 0 ;1
L 10.6575 0.5575 10.6575 0.5575 27 P 0 ;1
L 10.6575 0.6075 10.6575 0.6075 27 P 0 ;1
L 10.6575 0.6575 10.6575 0.6575 27 P 0 ;1
L 10.6575 0.7075 10.6575 0.7075 27 P 0 ;1
L 10.6575 0.7575 10.6575 0.7575 27 P 0 ;1
L 10.6575 0.8075 10.6575 0.8075 27 P 0 ;1
L 10.6575 0.8575 10.6575 0.8575 27 P 0 ;1
L 10.6575 0.9075 10.6575 0.9075 27 P 0 ;1
L 10.6575 0.9575 10.6575 0.9575 27 P 0 ;1
L 10.6575 1.0075 10.6575 1.0075 27 P 0 ;1
L 10.6575 1.0575 10.6575 1.0575 27 P 0 ;1
L 10.6575 1.1075 10.6575 1.1075 27 P 0 ;1
L 10.6575 1.1575 10.6575 1.1575 27 P 0 ;1
L 10.6575 1.2075 10.6575 1.2075 27 P 0 ;1
L 10.6575 1.2575 10.6575 1.2575 27 P 0 ;1
L 10.6575 1.3075 10.6575 1.3075 27 P 0 ;1
L 10.6575 1.7075 10.6575 1.7075 27 P 0 ;1
L 10.6575 1.7575 10.6575 1.7575 27 P 0 ;1
L 10.7075 0.1575 10.7075 0.1575 27 P 0 ;1
L 10.7075 0.2075 10.7075 0.2075 27 P 0 ;1
L 10.7075 0.2575 10.7075 0.2575 27 P 0 ;1
L 10.7075 0.3075 10.7075 0.3075 27 P 0 ;1
L 10.7075 0.3575 10.7075 0.3575 27 P 0 ;1
L 10.7075 0.4075 10.7075 0.4075 27 P 0 ;1
L 10.7075 0.4575 10.7075 0.4575 27 P 0 ;1
L 10.7075 0.5075 10.7075 0.5075 27 P 0 ;1
L 10.7075 0.5575 10.7075 0.5575 27 P 0 ;1
L 10.7075 0.6075 10.7075 0.6075 27 P 0 ;1
L 10.7075 0.6575 10.7075 0.6575 27 P 0 ;1
L 10.7075 0.7075 10.7075 0.7075 27 P 0 ;1
L 10.7075 0.7575 10.7075 0.7575 27 P 0 ;1
L 10.7075 0.8075 10.7075 0.8075 27 P 0 ;1
L 10.7075 0.8575 10.7075 0.8575 27 P 0 ;1
L 10.7075 0.9075 10.7075 0.9075 27 P 0 ;1
L 10.7075 0.9575 10.7075 0.9575 27 P 0 ;1
L 10.7075 1.0075 10.7075 1.0075 27 P 0 ;1
L 10.7075 1.0575 10.7075 1.0575 27 P 0 ;1
L 10.7075 1.1075 10.7075 1.1075 27 P 0 ;1
L 10.7075 1.1575 10.7075 1.1575 27 P 0 ;1
L 10.7075 1.2075 10.7075 1.2075 27 P 0 ;1
L 10.7075 1.2575 10.7075 1.2575 27 P 0 ;1
L 10.7075 1.7575 10.7075 1.7575 27 P 0 ;1
L 10.7575 0.1575 10.7575 0.1575 27 P 0 ;1
L 10.7575 0.2075 10.7575 0.2075 27 P 0 ;1
L 10.7575 0.2575 10.7575 0.2575 27 P 0 ;1
L 10.7575 0.3075 10.7575 0.3075 27 P 0 ;1
L 10.7575 0.3575 10.7575 0.3575 27 P 0 ;1
L 10.7575 0.4075 10.7575 0.4075 27 P 0 ;1
L 10.7575 0.4575 10.7575 0.4575 27 P 0 ;1
L 10.7575 0.5075 10.7575 0.5075 27 P 0 ;1
L 10.7575 0.5575 10.7575 0.5575 27 P 0 ;1
L 10.7575 0.6075 10.7575 0.6075 27 P 0 ;1
L 10.7575 0.6575 10.7575 0.6575 27 P 0 ;1
L 10.7575 0.7075 10.7575 0.7075 27 P 0 ;1
L 10.7575 0.7575 10.7575 0.7575 27 P 0 ;1
L 10.7575 0.8075 10.7575 0.8075 27 P 0 ;1
L 10.7575 0.8575 10.7575 0.8575 27 P 0 ;1
L 10.7575 0.9075 10.7575 0.9075 27 P 0 ;1
L 10.7575 0.9575 10.7575 0.9575 27 P 0 ;1
L 10.7575 1.0075 10.7575 1.0075 27 P 0 ;1
L 10.7575 1.0575 10.7575 1.0575 27 P 0 ;1
L 10.7575 1.1075 10.7575 1.1075 27 P 0 ;1
L 10.7575 1.1575 10.7575 1.1575 27 P 0 ;1
L 10.7575 1.2075 10.7575 1.2075 27 P 0 ;1
L 10.7575 1.2575 10.7575 1.2575 27 P 0 ;1
L 10.7575 1.7575 10.7575 1.7575 27 P 0 ;1
L 10.8075 0.1575 10.8075 0.1575 27 P 0 ;1
L 10.8075 0.2075 10.8075 0.2075 27 P 0 ;1
L 10.8075 0.2575 10.8075 0.2575 27 P 0 ;1
L 10.8075 0.3075 10.8075 0.3075 27 P 0 ;1
L 10.8075 0.3575 10.8075 0.3575 27 P 0 ;1
L 10.8075 0.4075 10.8075 0.4075 27 P 0 ;1
L 10.8075 0.4575 10.8075 0.4575 27 P 0 ;1
L 10.8075 0.5075 10.8075 0.5075 27 P 0 ;1
L 10.8075 0.5575 10.8075 0.5575 27 P 0 ;1
L 10.8075 0.6075 10.8075 0.6075 27 P 0 ;1
L 10.8075 0.6575 10.8075 0.6575 27 P 0 ;1
L 10.8075 0.7075 10.8075 0.7075 27 P 0 ;1
L 10.8075 0.7575 10.8075 0.7575 27 P 0 ;1
L 10.8075 0.8075 10.8075 0.8075 27 P 0 ;1
L 10.8075 0.8575 10.8075 0.8575 27 P 0 ;1
L 10.8075 0.9075 10.8075 0.9075 27 P 0 ;1
L 10.8075 0.9575 10.8075 0.9575 27 P 0 ;1
L 10.8075 1.0075 10.8075 1.0075 27 P 0 ;1
L 10.8075 1.0575 10.8075 1.0575 27 P 0 ;1
L 10.8075 1.1075 10.8075 1.1075 27 P 0 ;1
L 10.8075 1.1575 10.8075 1.1575 27 P 0 ;1
L 10.8075 1.2075 10.8075 1.2075 27 P 0 ;1
L 10.8075 1.2575 10.8075 1.2575 27 P 0 ;1
L 10.8075 1.7575 10.8075 1.7575 27 P 0 ;1
L 10.8575 0.1575 10.8575 0.1575 27 P 0 ;1
L 10.8575 0.2075 10.8575 0.2075 27 P 0 ;1
L 10.8575 0.2575 10.8575 0.2575 27 P 0 ;1
L 10.8575 0.3075 10.8575 0.3075 27 P 0 ;1
L 10.8575 0.3575 10.8575 0.3575 27 P 0 ;1
L 10.8575 0.4075 10.8575 0.4075 27 P 0 ;1
L 10.8575 0.4575 10.8575 0.4575 27 P 0 ;1
L 10.8575 0.5075 10.8575 0.5075 27 P 0 ;1
L 10.8575 0.5575 10.8575 0.5575 27 P 0 ;1
L 10.8575 0.6075 10.8575 0.6075 27 P 0 ;1
L 10.8575 0.6575 10.8575 0.6575 27 P 0 ;1
L 10.8575 0.7075 10.8575 0.7075 27 P 0 ;1
L 10.8575 0.7575 10.8575 0.7575 27 P 0 ;1
L 10.8575 0.8075 10.8575 0.8075 27 P 0 ;1
L 10.8575 0.8575 10.8575 0.8575 27 P 0 ;1
L 10.8575 0.9075 10.8575 0.9075 27 P 0 ;1
L 10.8575 0.9575 10.8575 0.9575 27 P 0 ;1
L 10.8575 1.0075 10.8575 1.0075 27 P 0 ;1
L 10.8575 1.0575 10.8575 1.0575 27 P 0 ;1
L 10.8575 1.1075 10.8575 1.1075 27 P 0 ;1
L 10.8575 1.1575 10.8575 1.1575 27 P 0 ;1
L 10.8575 1.2075 10.8575 1.2075 27 P 0 ;1
L 10.8575 1.2575 10.8575 1.2575 27 P 0 ;1
L 10.8575 1.7575 10.8575 1.7575 27 P 0 ;1
L 10.9075 0.1575 10.9075 0.1575 27 P 0 ;1
L 10.9075 0.2075 10.9075 0.2075 27 P 0 ;1
L 10.9075 0.2575 10.9075 0.2575 27 P 0 ;1
L 10.9075 0.3075 10.9075 0.3075 27 P 0 ;1
L 10.9075 0.3575 10.9075 0.3575 27 P 0 ;1
L 10.9075 0.4075 10.9075 0.4075 27 P 0 ;1
L 10.9075 0.4575 10.9075 0.4575 27 P 0 ;1
L 10.9075 0.5075 10.9075 0.5075 27 P 0 ;1
L 10.9075 0.5575 10.9075 0.5575 27 P 0 ;1
L 10.9075 0.6075 10.9075 0.6075 27 P 0 ;1
L 10.9075 0.6575 10.9075 0.6575 27 P 0 ;1
L 10.9075 0.7075 10.9075 0.7075 27 P 0 ;1
L 10.9075 0.7575 10.9075 0.7575 27 P 0 ;1
L 10.9075 0.8075 10.9075 0.8075 27 P 0 ;1
L 10.9075 0.8575 10.9075 0.8575 27 P 0 ;1
L 10.9075 0.9075 10.9075 0.9075 27 P 0 ;1
L 10.9075 0.9575 10.9075 0.9575 27 P 0 ;1
L 10.9075 1.0075 10.9075 1.0075 27 P 0 ;1
L 10.9075 1.0575 10.9075 1.0575 27 P 0 ;1
L 10.9075 1.1075 10.9075 1.1075 27 P 0 ;1
L 10.9075 1.1575 10.9075 1.1575 27 P 0 ;1
L 10.9075 1.2075 10.9075 1.2075 27 P 0 ;1
L 10.9075 1.2575 10.9075 1.2575 27 P 0 ;1
L 10.9075 1.7575 10.9075 1.7575 27 P 0 ;1
L 10.9575 0.1575 10.9575 0.1575 27 P 0 ;1
L 10.9575 0.2075 10.9575 0.2075 27 P 0 ;1
L 10.9575 0.2575 10.9575 0.2575 27 P 0 ;1
L 10.9575 0.3075 10.9575 0.3075 27 P 0 ;1
L 10.9575 0.3575 10.9575 0.3575 27 P 0 ;1
L 10.9575 0.4075 10.9575 0.4075 27 P 0 ;1
L 10.9575 0.4575 10.9575 0.4575 27 P 0 ;1
L 10.9575 0.5075 10.9575 0.5075 27 P 0 ;1
L 10.9575 0.5575 10.9575 0.5575 27 P 0 ;1
L 10.9575 0.6075 10.9575 0.6075 27 P 0 ;1
L 10.9575 0.6575 10.9575 0.6575 27 P 0 ;1
L 10.9575 0.7075 10.9575 0.7075 27 P 0 ;1
L 10.9575 0.7575 10.9575 0.7575 27 P 0 ;1
L 10.9575 0.8075 10.9575 0.8075 27 P 0 ;1
L 10.9575 0.8575 10.9575 0.8575 27 P 0 ;1
L 10.9575 0.9075 10.9575 0.9075 27 P 0 ;1
L 10.9575 0.9575 10.9575 0.9575 27 P 0 ;1
L 10.9575 1.0075 10.9575 1.0075 27 P 0 ;1
L 10.9575 1.0575 10.9575 1.0575 27 P 0 ;1
L 10.9575 1.1075 10.9575 1.1075 27 P 0 ;1
L 10.9575 1.1575 10.9575 1.1575 27 P 0 ;1
L 10.9575 1.2075 10.9575 1.2075 27 P 0 ;1
L 10.9575 1.2575 10.9575 1.2575 27 P 0 ;1
L 10.9575 1.7575 10.9575 1.7575 27 P 0 ;1
L 11.0075 0.1575 11.0075 0.1575 27 P 0 ;1
L 11.0075 0.2075 11.0075 0.2075 27 P 0 ;1
L 11.0075 0.2575 11.0075 0.2575 27 P 0 ;1
L 11.0075 0.3075 11.0075 0.3075 27 P 0 ;1
L 11.0075 0.3575 11.0075 0.3575 27 P 0 ;1
L 11.0075 0.4075 11.0075 0.4075 27 P 0 ;1
L 11.0075 0.4575 11.0075 0.4575 27 P 0 ;1
L 11.0075 0.5075 11.0075 0.5075 27 P 0 ;1
L 11.0075 0.5575 11.0075 0.5575 27 P 0 ;1
L 11.0075 0.6075 11.0075 0.6075 27 P 0 ;1
L 11.0075 0.6575 11.0075 0.6575 27 P 0 ;1
L 11.0075 0.7075 11.0075 0.7075 27 P 0 ;1
L 11.0075 0.7575 11.0075 0.7575 27 P 0 ;1
L 11.0075 0.8075 11.0075 0.8075 27 P 0 ;1
L 11.0075 0.8575 11.0075 0.8575 27 P 0 ;1
L 11.0075 0.9075 11.0075 0.9075 27 P 0 ;1
L 11.0075 0.9575 11.0075 0.9575 27 P 0 ;1
L 11.0075 1.0075 11.0075 1.0075 27 P 0 ;1
L 11.0075 1.0575 11.0075 1.0575 27 P 0 ;1
L 11.0075 1.1075 11.0075 1.1075 27 P 0 ;1
L 11.0075 1.1575 11.0075 1.1575 27 P 0 ;1
L 11.0075 1.2075 11.0075 1.2075 27 P 0 ;1
L 11.0075 1.2575 11.0075 1.2575 27 P 0 ;1
L 11.0075 1.3075 11.0075 1.3075 27 P 0 ;1
L 11.0075 1.7075 11.0075 1.7075 27 P 0 ;1
L 11.0075 1.7575 11.0075 1.7575 27 P 0 ;1
L 11.0575 0.1575 11.0575 0.1575 27 P 0 ;1
L 11.0575 0.2075 11.0575 0.2075 27 P 0 ;1
L 11.0575 0.2575 11.0575 0.2575 27 P 0 ;1
L 11.0575 0.3075 11.0575 0.3075 27 P 0 ;1
L 11.0575 0.3575 11.0575 0.3575 27 P 0 ;1
L 11.0575 0.4075 11.0575 0.4075 27 P 0 ;1
L 11.0575 0.4575 11.0575 0.4575 27 P 0 ;1
L 11.0575 0.5075 11.0575 0.5075 27 P 0 ;1
L 11.0575 0.5575 11.0575 0.5575 27 P 0 ;1
L 11.0575 0.6075 11.0575 0.6075 27 P 0 ;1
L 11.0575 0.6575 11.0575 0.6575 27 P 0 ;1
L 11.0575 0.7075 11.0575 0.7075 27 P 0 ;1
L 11.0575 0.7575 11.0575 0.7575 27 P 0 ;1
L 11.0575 0.8075 11.0575 0.8075 27 P 0 ;1
L 11.0575 0.8575 11.0575 0.8575 27 P 0 ;1
L 11.0575 0.9075 11.0575 0.9075 27 P 0 ;1
L 11.0575 0.9575 11.0575 0.9575 27 P 0 ;1
L 11.0575 1.0075 11.0575 1.0075 27 P 0 ;1
L 11.0575 1.0575 11.0575 1.0575 27 P 0 ;1
L 11.0575 1.1075 11.0575 1.1075 27 P 0 ;1
L 11.0575 1.1575 11.0575 1.1575 27 P 0 ;1
L 11.0575 1.2075 11.0575 1.2075 27 P 0 ;1
L 11.0575 1.2575 11.0575 1.2575 27 P 0 ;1
L 11.0575 1.3075 11.0575 1.3075 27 P 0 ;1
L 11.0575 1.3575 11.0575 1.3575 27 P 0 ;1
L 11.0575 1.4075 11.0575 1.4075 27 P 0 ;1
L 11.0575 1.6575 11.0575 1.6575 27 P 0 ;1
L 11.0575 1.7075 11.0575 1.7075 27 P 0 ;1
L 11.0575 1.7575 11.0575 1.7575 27 P 0 ;1
L 11.1075 0.1575 11.1075 0.1575 27 P 0 ;1
L 11.1075 0.2075 11.1075 0.2075 27 P 0 ;1
L 11.1075 0.2575 11.1075 0.2575 27 P 0 ;1
L 11.1075 0.3075 11.1075 0.3075 27 P 0 ;1
L 11.1075 0.3575 11.1075 0.3575 27 P 0 ;1
L 11.1075 0.4075 11.1075 0.4075 27 P 0 ;1
L 11.1075 0.4575 11.1075 0.4575 27 P 0 ;1
L 11.1075 0.5075 11.1075 0.5075 27 P 0 ;1
L 11.1075 0.5575 11.1075 0.5575 27 P 0 ;1
L 11.1075 0.6075 11.1075 0.6075 27 P 0 ;1
L 11.1075 0.6575 11.1075 0.6575 27 P 0 ;1
L 11.1075 0.7075 11.1075 0.7075 27 P 0 ;1
L 11.1075 0.7575 11.1075 0.7575 27 P 0 ;1
L 11.1075 0.8075 11.1075 0.8075 27 P 0 ;1
L 11.1075 0.8575 11.1075 0.8575 27 P 0 ;1
L 11.1075 0.9075 11.1075 0.9075 27 P 0 ;1
L 11.1075 0.9575 11.1075 0.9575 27 P 0 ;1
L 11.1075 1.0075 11.1075 1.0075 27 P 0 ;1
L 11.1075 1.0575 11.1075 1.0575 27 P 0 ;1
L 11.1075 1.1075 11.1075 1.1075 27 P 0 ;1
L 11.1075 1.1575 11.1075 1.1575 27 P 0 ;1
L 11.1075 1.2075 11.1075 1.2075 27 P 0 ;1
L 11.1075 1.2575 11.1075 1.2575 27 P 0 ;1
L 11.1075 1.3075 11.1075 1.3075 27 P 0 ;1
L 11.1075 1.3575 11.1075 1.3575 27 P 0 ;1
L 11.1075 1.4075 11.1075 1.4075 27 P 0 ;1
L 11.1075 1.4575 11.1075 1.4575 27 P 0 ;1
L 11.1075 1.5075 11.1075 1.5075 27 P 0 ;1
L 11.1075 1.5575 11.1075 1.5575 27 P 0 ;1
L 11.1075 1.6075 11.1075 1.6075 27 P 0 ;1
L 11.1075 1.6575 11.1075 1.6575 27 P 0 ;1
L 11.1075 1.7075 11.1075 1.7075 27 P 0 ;1
L 11.1075 1.7575 11.1075 1.7575 27 P 0 ;1
L 11.1575 0.1575 11.1575 0.1575 27 P 0 ;1
L 11.1575 0.2075 11.1575 0.2075 27 P 0 ;1
L 11.1575 0.2575 11.1575 0.2575 27 P 0 ;1
L 11.1575 0.3075 11.1575 0.3075 27 P 0 ;1
L 11.1575 0.3575 11.1575 0.3575 27 P 0 ;1
L 11.1575 0.4075 11.1575 0.4075 27 P 0 ;1
L 11.1575 0.4575 11.1575 0.4575 27 P 0 ;1
L 11.1575 0.5075 11.1575 0.5075 27 P 0 ;1
L 11.1575 0.5575 11.1575 0.5575 27 P 0 ;1
L 11.1575 0.6075 11.1575 0.6075 27 P 0 ;1
L 11.1575 0.6575 11.1575 0.6575 27 P 0 ;1
L 11.1575 0.7075 11.1575 0.7075 27 P 0 ;1
L 11.1575 0.7575 11.1575 0.7575 27 P 0 ;1
L 11.1575 0.8075 11.1575 0.8075 27 P 0 ;1
L 11.1575 0.8575 11.1575 0.8575 27 P 0 ;1
L 11.1575 0.9075 11.1575 0.9075 27 P 0 ;1
L 11.1575 0.9575 11.1575 0.9575 27 P 0 ;1
L 11.1575 1.0075 11.1575 1.0075 27 P 0 ;1
L 11.1575 1.0575 11.1575 1.0575 27 P 0 ;1
L 11.1575 1.1075 11.1575 1.1075 27 P 0 ;1
L 11.1575 1.1575 11.1575 1.1575 27 P 0 ;1
L 11.1575 1.2075 11.1575 1.2075 27 P 0 ;1
L 11.1575 1.2575 11.1575 1.2575 27 P 0 ;1
L 11.1575 1.3075 11.1575 1.3075 27 P 0 ;1
L 11.1575 1.3575 11.1575 1.3575 27 P 0 ;1
L 11.1575 1.4075 11.1575 1.4075 27 P 0 ;1
L 11.1575 1.4575 11.1575 1.4575 27 P 0 ;1
L 11.1575 1.5075 11.1575 1.5075 27 P 0 ;1
L 11.1575 1.5575 11.1575 1.5575 27 P 0 ;1
L 11.1575 1.6075 11.1575 1.6075 27 P 0 ;1
L 11.1575 1.6575 11.1575 1.6575 27 P 0 ;1
L 11.1575 1.7075 11.1575 1.7075 27 P 0 ;1
L 11.1575 1.7575 11.1575 1.7575 27 P 0 ;1
L 11.2075 0.1575 11.2075 0.1575 27 P 0 ;1
L 11.2075 0.2075 11.2075 0.2075 27 P 0 ;1
L 11.2075 0.2575 11.2075 0.2575 27 P 0 ;1
L 11.2075 0.3075 11.2075 0.3075 27 P 0 ;1
L 11.2075 0.3575 11.2075 0.3575 27 P 0 ;1
L 11.2075 0.4075 11.2075 0.4075 27 P 0 ;1
L 11.2075 0.4575 11.2075 0.4575 27 P 0 ;1
L 11.2075 0.5075 11.2075 0.5075 27 P 0 ;1
L 11.2075 0.5575 11.2075 0.5575 27 P 0 ;1
L 11.2075 0.6075 11.2075 0.6075 27 P 0 ;1
L 11.2075 0.6575 11.2075 0.6575 27 P 0 ;1
L 11.2075 0.7075 11.2075 0.7075 27 P 0 ;1
L 11.2075 0.7575 11.2075 0.7575 27 P 0 ;1
L 11.2075 0.8075 11.2075 0.8075 27 P 0 ;1
L 11.2075 0.8575 11.2075 0.8575 27 P 0 ;1
L 11.2075 0.9075 11.2075 0.9075 27 P 0 ;1
L 11.2075 0.9575 11.2075 0.9575 27 P 0 ;1
L 11.2075 1.0075 11.2075 1.0075 27 P 0 ;1
L 11.2075 1.0575 11.2075 1.0575 27 P 0 ;1
L 11.2075 1.1075 11.2075 1.1075 27 P 0 ;1
L 11.2075 1.1575 11.2075 1.1575 27 P 0 ;1
L 11.2075 1.2075 11.2075 1.2075 27 P 0 ;1
L 11.2075 1.2575 11.2075 1.2575 27 P 0 ;1
L 11.2075 1.3075 11.2075 1.3075 27 P 0 ;1
L 11.2075 1.3575 11.2075 1.3575 27 P 0 ;1
L 11.2075 1.4075 11.2075 1.4075 27 P 0 ;1
L 11.2075 1.4575 11.2075 1.4575 27 P 0 ;1
L 11.2075 1.5075 11.2075 1.5075 27 P 0 ;1
L 11.2075 1.5575 11.2075 1.5575 27 P 0 ;1
L 11.2075 1.6075 11.2075 1.6075 27 P 0 ;1
L 11.2075 1.6575 11.2075 1.6575 27 P 0 ;1
L 11.2075 1.7075 11.2075 1.7075 27 P 0 ;1
L 11.2075 1.7575 11.2075 1.7575 27 P 0 ;1
L 11.2075 1.8075 11.2075 1.8075 27 P 0 ;1
L 11.2075 1.8575 11.2075 1.8575 27 P 0 ;1
L 11.2075 1.9075 11.2075 1.9075 27 P 0 ;1
L 11.2075 1.9575 11.2075 1.9575 27 P 0 ;1
L 11.2075 2.0075 11.2075 2.0075 27 P 0 ;1
L 11.2075 2.0575 11.2075 2.0575 27 P 0 ;1
L 11.2075 2.1075 11.2075 2.1075 27 P 0 ;1
L 11.2075 2.1575 11.2075 2.1575 27 P 0 ;1
L 11.2075 2.2075 11.2075 2.2075 27 P 0 ;1
L 11.2075 2.2575 11.2075 2.2575 27 P 0 ;1
L 11.2075 2.3075 11.2075 2.3075 27 P 0 ;1
L 11.2075 2.3575 11.2075 2.3575 27 P 0 ;1
L 11.2075 2.4075 11.2075 2.4075 27 P 0 ;1
L 11.2075 2.4575 11.2075 2.4575 27 P 0 ;1
L 11.2075 2.5075 11.2075 2.5075 27 P 0 ;1
L 11.2075 2.5575 11.2075 2.5575 27 P 0 ;1
L 11.2075 2.6075 11.2075 2.6075 27 P 0 ;1
L 11.2075 2.6575 11.2075 2.6575 27 P 0 ;1
L 11.2075 2.7075 11.2075 2.7075 27 P 0 ;1
L 11.2075 2.7575 11.2075 2.7575 27 P 0 ;1
L 11.2575 0.1575 11.2575 0.1575 27 P 0 ;1
L 11.2575 0.2075 11.2575 0.2075 27 P 0 ;1
L 11.2575 0.2575 11.2575 0.2575 27 P 0 ;1
L 11.2575 0.3075 11.2575 0.3075 27 P 0 ;1
L 11.2575 0.3575 11.2575 0.3575 27 P 0 ;1
L 11.2575 0.4075 11.2575 0.4075 27 P 0 ;1
L 11.2575 0.4575 11.2575 0.4575 27 P 0 ;1
L 11.2575 0.5075 11.2575 0.5075 27 P 0 ;1
L 11.2575 0.5575 11.2575 0.5575 27 P 0 ;1
L 11.2575 0.6075 11.2575 0.6075 27 P 0 ;1
L 11.2575 0.6575 11.2575 0.6575 27 P 0 ;1
L 11.2575 0.7075 11.2575 0.7075 27 P 0 ;1
L 11.2575 0.7575 11.2575 0.7575 27 P 0 ;1
L 11.2575 0.8075 11.2575 0.8075 27 P 0 ;1
L 11.2575 0.8575 11.2575 0.8575 27 P 0 ;1
L 11.2575 0.9075 11.2575 0.9075 27 P 0 ;1
L 11.2575 0.9575 11.2575 0.9575 27 P 0 ;1
L 11.2575 1.0075 11.2575 1.0075 27 P 0 ;1
L 11.2575 1.0575 11.2575 1.0575 27 P 0 ;1
L 11.2575 1.1075 11.2575 1.1075 27 P 0 ;1
L 11.2575 1.1575 11.2575 1.1575 27 P 0 ;1
L 11.2575 1.2075 11.2575 1.2075 27 P 0 ;1
L 11.2575 1.2575 11.2575 1.2575 27 P 0 ;1
L 11.2575 1.3075 11.2575 1.3075 27 P 0 ;1
L 11.2575 1.3575 11.2575 1.3575 27 P 0 ;1
L 11.2575 1.4075 11.2575 1.4075 27 P 0 ;1
L 11.2575 1.4575 11.2575 1.4575 27 P 0 ;1
L 11.2575 1.5075 11.2575 1.5075 27 P 0 ;1
L 11.2575 1.5575 11.2575 1.5575 27 P 0 ;1
L 11.2575 1.6075 11.2575 1.6075 27 P 0 ;1
L 11.2575 1.6575 11.2575 1.6575 27 P 0 ;1
L 11.2575 1.7075 11.2575 1.7075 27 P 0 ;1
L 11.2575 1.7575 11.2575 1.7575 27 P 0 ;1
L 11.2575 1.8075 11.2575 1.8075 27 P 0 ;1
L 11.2575 1.8575 11.2575 1.8575 27 P 0 ;1
L 11.2575 1.9075 11.2575 1.9075 27 P 0 ;1
L 11.2575 1.9575 11.2575 1.9575 27 P 0 ;1
L 11.2575 2.0075 11.2575 2.0075 27 P 0 ;1
L 11.2575 2.0575 11.2575 2.0575 27 P 0 ;1
L 11.2575 2.1075 11.2575 2.1075 27 P 0 ;1
L 11.2575 2.1575 11.2575 2.1575 27 P 0 ;1
L 11.2575 2.2075 11.2575 2.2075 27 P 0 ;1
L 11.2575 2.2575 11.2575 2.2575 27 P 0 ;1
L 11.2575 2.3075 11.2575 2.3075 27 P 0 ;1
L 11.2575 2.3575 11.2575 2.3575 27 P 0 ;1
L 11.2575 2.4075 11.2575 2.4075 27 P 0 ;1
L 11.2575 2.4575 11.2575 2.4575 27 P 0 ;1
L 11.2575 2.5075 11.2575 2.5075 27 P 0 ;1
L 11.2575 2.5575 11.2575 2.5575 27 P 0 ;1
L 11.2575 2.6075 11.2575 2.6075 27 P 0 ;1
L 11.2575 2.6575 11.2575 2.6575 27 P 0 ;1
L 11.2575 2.7075 11.2575 2.7075 27 P 0 ;1
L 11.2575 2.7575 11.2575 2.7575 27 P 0 ;1
L 11.2575 2.8075 11.2575 2.8075 27 P 0 ;1
L 11.3075 0.1575 11.3075 0.1575 27 P 0 ;1
L 11.3075 0.2075 11.3075 0.2075 27 P 0 ;1
L 11.3075 0.2575 11.3075 0.2575 27 P 0 ;1
L 11.3075 0.3075 11.3075 0.3075 27 P 0 ;1
L 11.3075 0.3575 11.3075 0.3575 27 P 0 ;1
L 11.3075 0.4075 11.3075 0.4075 27 P 0 ;1
L 11.3075 0.4575 11.3075 0.4575 27 P 0 ;1
L 11.3075 0.5075 11.3075 0.5075 27 P 0 ;1
L 11.3075 0.5575 11.3075 0.5575 27 P 0 ;1
L 11.3075 0.6075 11.3075 0.6075 27 P 0 ;1
L 11.3075 0.6575 11.3075 0.6575 27 P 0 ;1
L 11.3075 0.7075 11.3075 0.7075 27 P 0 ;1
L 11.3075 0.7575 11.3075 0.7575 27 P 0 ;1
L 11.3075 0.8075 11.3075 0.8075 27 P 0 ;1
L 11.3075 0.8575 11.3075 0.8575 27 P 0 ;1
L 11.3075 0.9075 11.3075 0.9075 27 P 0 ;1
L 11.3075 0.9575 11.3075 0.9575 27 P 0 ;1
L 11.3075 1.0075 11.3075 1.0075 27 P 0 ;1
L 11.3075 1.0575 11.3075 1.0575 27 P 0 ;1
L 11.3075 1.1075 11.3075 1.1075 27 P 0 ;1
L 11.3075 1.1575 11.3075 1.1575 27 P 0 ;1
L 11.3075 1.2075 11.3075 1.2075 27 P 0 ;1
L 11.3075 1.2575 11.3075 1.2575 27 P 0 ;1
L 11.3075 1.3075 11.3075 1.3075 27 P 0 ;1
L 11.3075 1.3575 11.3075 1.3575 27 P 0 ;1
L 11.3075 1.4075 11.3075 1.4075 27 P 0 ;1
L 11.3075 1.4575 11.3075 1.4575 27 P 0 ;1
L 11.3075 1.5075 11.3075 1.5075 27 P 0 ;1
L 11.3075 1.5575 11.3075 1.5575 27 P 0 ;1
L 11.3075 1.6075 11.3075 1.6075 27 P 0 ;1
L 11.3075 1.6575 11.3075 1.6575 27 P 0 ;1
L 11.3075 1.7075 11.3075 1.7075 27 P 0 ;1
L 11.3075 1.7575 11.3075 1.7575 27 P 0 ;1
L 11.3075 1.8075 11.3075 1.8075 27 P 0 ;1
L 11.3075 1.8575 11.3075 1.8575 27 P 0 ;1
L 11.3075 1.9075 11.3075 1.9075 27 P 0 ;1
L 11.3075 1.9575 11.3075 1.9575 27 P 0 ;1
L 11.3075 2.0075 11.3075 2.0075 27 P 0 ;1
L 11.3075 2.0575 11.3075 2.0575 27 P 0 ;1
L 11.3075 2.1075 11.3075 2.1075 27 P 0 ;1
L 11.3075 2.1575 11.3075 2.1575 27 P 0 ;1
L 11.3075 2.2075 11.3075 2.2075 27 P 0 ;1
L 11.3075 2.2575 11.3075 2.2575 27 P 0 ;1
L 11.3075 2.3075 11.3075 2.3075 27 P 0 ;1
L 11.3075 2.3575 11.3075 2.3575 27 P 0 ;1
L 11.3075 2.4075 11.3075 2.4075 27 P 0 ;1
L 11.3075 2.4575 11.3075 2.4575 27 P 0 ;1
L 11.3075 2.5075 11.3075 2.5075 27 P 0 ;1
L 11.3075 2.5575 11.3075 2.5575 27 P 0 ;1
L 11.3075 2.6075 11.3075 2.6075 27 P 0 ;1
L 11.3075 2.6575 11.3075 2.6575 27 P 0 ;1
L 11.3575 0.1575 11.3575 0.1575 27 P 0 ;1
L 11.3575 0.2075 11.3575 0.2075 27 P 0 ;1
L 11.3575 0.2575 11.3575 0.2575 27 P 0 ;1
L 11.3575 0.3075 11.3575 0.3075 27 P 0 ;1
L 11.3575 0.3575 11.3575 0.3575 27 P 0 ;1
L 11.3575 0.4075 11.3575 0.4075 27 P 0 ;1
L 11.3575 0.4575 11.3575 0.4575 27 P 0 ;1
L 11.3575 0.5075 11.3575 0.5075 27 P 0 ;1
L 11.3575 0.5575 11.3575 0.5575 27 P 0 ;1
L 11.3575 0.6075 11.3575 0.6075 27 P 0 ;1
L 11.3575 0.6575 11.3575 0.6575 27 P 0 ;1
L 11.3575 0.7075 11.3575 0.7075 27 P 0 ;1
L 11.3575 0.7575 11.3575 0.7575 27 P 0 ;1
L 11.3575 0.8075 11.3575 0.8075 27 P 0 ;1
L 11.3575 0.8575 11.3575 0.8575 27 P 0 ;1
L 11.3575 0.9075 11.3575 0.9075 27 P 0 ;1
L 11.3575 0.9575 11.3575 0.9575 27 P 0 ;1
L 11.3575 1.0075 11.3575 1.0075 27 P 0 ;1
L 11.3575 1.0575 11.3575 1.0575 27 P 0 ;1
L 11.3575 1.1075 11.3575 1.1075 27 P 0 ;1
L 11.3575 1.1575 11.3575 1.1575 27 P 0 ;1
L 11.3575 1.2075 11.3575 1.2075 27 P 0 ;1
L 11.3575 1.2575 11.3575 1.2575 27 P 0 ;1
L 11.3575 1.3075 11.3575 1.3075 27 P 0 ;1
L 11.3575 1.3575 11.3575 1.3575 27 P 0 ;1
L 11.3575 1.4075 11.3575 1.4075 27 P 0 ;1
L 11.3575 1.4575 11.3575 1.4575 27 P 0 ;1
L 11.3575 1.5075 11.3575 1.5075 27 P 0 ;1
L 11.3575 1.5575 11.3575 1.5575 27 P 0 ;1
L 11.3575 1.6075 11.3575 1.6075 27 P 0 ;1
L 11.3575 1.6575 11.3575 1.6575 27 P 0 ;1
L 11.3575 1.7075 11.3575 1.7075 27 P 0 ;1
L 11.3575 1.7575 11.3575 1.7575 27 P 0 ;1
L 11.3575 1.8075 11.3575 1.8075 27 P 0 ;1
L 11.3575 1.8575 11.3575 1.8575 27 P 0 ;1
L 11.3575 1.9075 11.3575 1.9075 27 P 0 ;1
L 11.3575 1.9575 11.3575 1.9575 27 P 0 ;1
L 11.3575 2.0075 11.3575 2.0075 27 P 0 ;1
L 11.3575 2.0575 11.3575 2.0575 27 P 0 ;1
L 11.3575 2.1075 11.3575 2.1075 27 P 0 ;1
L 11.3575 2.1575 11.3575 2.1575 27 P 0 ;1
L 11.3575 2.2075 11.3575 2.2075 27 P 0 ;1
L 11.3575 2.2575 11.3575 2.2575 27 P 0 ;1
L 11.3575 2.3075 11.3575 2.3075 27 P 0 ;1
L 11.3575 2.3575 11.3575 2.3575 27 P 0 ;1
L 11.3575 2.4075 11.3575 2.4075 27 P 0 ;1
L 11.3575 2.4575 11.3575 2.4575 27 P 0 ;1
L 11.3575 2.5075 11.3575 2.5075 27 P 0 ;1
L 11.3575 2.5575 11.3575 2.5575 27 P 0 ;1
L 11.3575 2.6075 11.3575 2.6075 27 P 0 ;1
L 11.3575 3.3575 11.3575 3.3575 27 P 0 ;1
L 11.3575 3.4075 11.3575 3.4075 27 P 0 ;1
L 11.3575 3.4575 11.3575 3.4575 27 P 0 ;1
L 11.3575 3.5075 11.3575 3.5075 27 P 0 ;1
L 11.3575 3.5575 11.3575 3.5575 27 P 0 ;1
L 11.3575 3.6075 11.3575 3.6075 27 P 0 ;1
L 11.3575 3.6575 11.3575 3.6575 27 P 0 ;1
L 11.3575 3.7075 11.3575 3.7075 27 P 0 ;1
L 11.3575 3.7575 11.3575 3.7575 27 P 0 ;1
L 11.3575 3.8075 11.3575 3.8075 27 P 0 ;1
L 11.3575 3.8575 11.3575 3.8575 27 P 0 ;1
L 11.3575 3.9075 11.3575 3.9075 27 P 0 ;1
L 11.3575 3.9575 11.3575 3.9575 27 P 0 ;1
L 11.3575 4.0075 11.3575 4.0075 27 P 0 ;1
L 11.3575 4.0575 11.3575 4.0575 27 P 0 ;1
L 11.3575 4.1075 11.3575 4.1075 27 P 0 ;1
L 11.3575 4.1575 11.3575 4.1575 27 P 0 ;1
L 11.3575 4.2075 11.3575 4.2075 27 P 0 ;1
L 11.3575 4.2575 11.3575 4.2575 27 P 0 ;1
L 11.3575 4.3075 11.3575 4.3075 27 P 0 ;1
L 11.3575 4.3575 11.3575 4.3575 27 P 0 ;1
L 11.3575 4.4075 11.3575 4.4075 27 P 0 ;1
L 11.3575 4.4575 11.3575 4.4575 27 P 0 ;1
L 11.3575 4.5075 11.3575 4.5075 27 P 0 ;1
L 11.3575 4.5575 11.3575 4.5575 27 P 0 ;1
L 11.3575 4.6075 11.3575 4.6075 27 P 0 ;1
L 11.3575 4.6575 11.3575 4.6575 27 P 0 ;1
L 11.4075 0.1575 11.4075 0.1575 27 P 0 ;1
L 11.4075 0.2075 11.4075 0.2075 27 P 0 ;1
L 11.4075 0.2575 11.4075 0.2575 27 P 0 ;1
L 11.4075 0.3075 11.4075 0.3075 27 P 0 ;1
L 11.4075 0.3575 11.4075 0.3575 27 P 0 ;1
L 11.4075 0.4075 11.4075 0.4075 27 P 0 ;1
L 11.4075 0.4575 11.4075 0.4575 27 P 0 ;1
L 11.4075 0.5075 11.4075 0.5075 27 P 0 ;1
L 11.4075 0.5575 11.4075 0.5575 27 P 0 ;1
L 11.4075 0.6075 11.4075 0.6075 27 P 0 ;1
L 11.4075 0.6575 11.4075 0.6575 27 P 0 ;1
L 11.4075 0.7075 11.4075 0.7075 27 P 0 ;1
L 11.4075 0.7575 11.4075 0.7575 27 P 0 ;1
L 11.4075 0.8075 11.4075 0.8075 27 P 0 ;1
L 11.4075 0.8575 11.4075 0.8575 27 P 0 ;1
L 11.4075 0.9075 11.4075 0.9075 27 P 0 ;1
L 11.4075 0.9575 11.4075 0.9575 27 P 0 ;1
L 11.4075 1.0075 11.4075 1.0075 27 P 0 ;1
L 11.4075 1.0575 11.4075 1.0575 27 P 0 ;1
L 11.4075 1.1075 11.4075 1.1075 27 P 0 ;1
L 11.4075 1.1575 11.4075 1.1575 27 P 0 ;1
L 11.4075 1.2075 11.4075 1.2075 27 P 0 ;1
L 11.4075 1.2575 11.4075 1.2575 27 P 0 ;1
L 11.4075 1.3075 11.4075 1.3075 27 P 0 ;1
L 11.4075 1.3575 11.4075 1.3575 27 P 0 ;1
L 11.4075 1.5075 11.4075 1.5075 27 P 0 ;1
L 11.4075 2.1575 11.4075 2.1575 27 P 0 ;1
L 11.4075 2.2075 11.4075 2.2075 27 P 0 ;1
L 11.4075 2.2575 11.4075 2.2575 27 P 0 ;1
L 11.4075 2.3075 11.4075 2.3075 27 P 0 ;1
L 11.4075 3.4075 11.4075 3.4075 27 P 0 ;1
L 11.4075 3.4575 11.4075 3.4575 27 P 0 ;1
L 11.4075 3.5075 11.4075 3.5075 27 P 0 ;1
L 11.4075 3.5575 11.4075 3.5575 27 P 0 ;1
L 11.4075 3.6075 11.4075 3.6075 27 P 0 ;1
L 11.4075 3.6575 11.4075 3.6575 27 P 0 ;1
L 11.4075 3.7075 11.4075 3.7075 27 P 0 ;1
L 11.4075 3.7575 11.4075 3.7575 27 P 0 ;1
L 11.4075 3.8075 11.4075 3.8075 27 P 0 ;1
L 11.4075 3.8575 11.4075 3.8575 27 P 0 ;1
L 11.4075 3.9075 11.4075 3.9075 27 P 0 ;1
L 11.4075 3.9575 11.4075 3.9575 27 P 0 ;1
L 11.4075 4.0075 11.4075 4.0075 27 P 0 ;1
L 11.4075 4.0575 11.4075 4.0575 27 P 0 ;1
L 11.4075 4.1075 11.4075 4.1075 27 P 0 ;1
L 11.4075 4.1575 11.4075 4.1575 27 P 0 ;1
L 11.4075 4.2075 11.4075 4.2075 27 P 0 ;1
L 11.4075 4.2575 11.4075 4.2575 27 P 0 ;1
L 11.4075 4.3075 11.4075 4.3075 27 P 0 ;1
L 11.4075 4.3575 11.4075 4.3575 27 P 0 ;1
L 11.4075 4.4075 11.4075 4.4075 27 P 0 ;1
L 11.4075 4.4575 11.4075 4.4575 27 P 0 ;1
L 11.4075 4.5075 11.4075 4.5075 27 P 0 ;1
L 11.4075 4.5575 11.4075 4.5575 27 P 0 ;1
L 11.4075 4.6075 11.4075 4.6075 27 P 0 ;1
L 11.4075 4.6575 11.4075 4.6575 27 P 0 ;1
L 11.4575 0.1575 11.4575 0.1575 27 P 0 ;1
L 11.4575 0.2075 11.4575 0.2075 27 P 0 ;1
L 11.4575 0.2575 11.4575 0.2575 27 P 0 ;1
L 11.4575 0.3075 11.4575 0.3075 27 P 0 ;1
L 11.4575 0.3575 11.4575 0.3575 27 P 0 ;1
L 11.4575 0.4075 11.4575 0.4075 27 P 0 ;1
L 11.4575 0.4575 11.4575 0.4575 27 P 0 ;1
L 11.4575 0.5075 11.4575 0.5075 27 P 0 ;1
L 11.4575 0.5575 11.4575 0.5575 27 P 0 ;1
L 11.4575 0.6075 11.4575 0.6075 27 P 0 ;1
L 11.4575 0.6575 11.4575 0.6575 27 P 0 ;1
L 11.4575 0.7075 11.4575 0.7075 27 P 0 ;1
L 11.4575 0.7575 11.4575 0.7575 27 P 0 ;1
L 11.4575 0.8075 11.4575 0.8075 27 P 0 ;1
L 11.4575 0.8575 11.4575 0.8575 27 P 0 ;1
L 11.4575 0.9075 11.4575 0.9075 27 P 0 ;1
L 11.4575 0.9575 11.4575 0.9575 27 P 0 ;1
L 11.4575 1.0075 11.4575 1.0075 27 P 0 ;1
L 11.4575 1.0575 11.4575 1.0575 27 P 0 ;1
L 11.4575 1.1075 11.4575 1.1075 27 P 0 ;1
L 11.4575 1.1575 11.4575 1.1575 27 P 0 ;1
L 11.4575 1.2075 11.4575 1.2075 27 P 0 ;1
L 11.4575 1.2575 11.4575 1.2575 27 P 0 ;1
L 11.4575 1.3075 11.4575 1.3075 27 P 0 ;1
L 11.4575 2.2075 11.4575 2.2075 27 P 0 ;1
L 11.4575 2.2575 11.4575 2.2575 27 P 0 ;1
L 11.4575 3.4075 11.4575 3.4075 27 P 0 ;1
L 11.4575 3.4575 11.4575 3.4575 27 P 0 ;1
L 11.4575 3.5075 11.4575 3.5075 27 P 0 ;1
L 11.4575 3.5575 11.4575 3.5575 27 P 0 ;1
L 11.4575 3.6075 11.4575 3.6075 27 P 0 ;1
L 11.4575 3.6575 11.4575 3.6575 27 P 0 ;1
L 11.4575 3.7075 11.4575 3.7075 27 P 0 ;1
L 11.4575 3.7575 11.4575 3.7575 27 P 0 ;1
L 11.4575 3.8075 11.4575 3.8075 27 P 0 ;1
L 11.4575 3.8575 11.4575 3.8575 27 P 0 ;1
L 11.4575 3.9075 11.4575 3.9075 27 P 0 ;1
L 11.4575 3.9575 11.4575 3.9575 27 P 0 ;1
L 11.4575 4.0075 11.4575 4.0075 27 P 0 ;1
L 11.4575 4.0575 11.4575 4.0575 27 P 0 ;1
L 11.4575 4.1075 11.4575 4.1075 27 P 0 ;1
L 11.4575 4.1575 11.4575 4.1575 27 P 0 ;1
L 11.4575 4.2075 11.4575 4.2075 27 P 0 ;1
L 11.4575 4.2575 11.4575 4.2575 27 P 0 ;1
L 11.4575 4.3075 11.4575 4.3075 27 P 0 ;1
L 11.4575 4.3575 11.4575 4.3575 27 P 0 ;1
L 11.4575 4.4075 11.4575 4.4075 27 P 0 ;1
L 11.4575 4.4575 11.4575 4.4575 27 P 0 ;1
L 11.4575 4.5075 11.4575 4.5075 27 P 0 ;1
L 11.4575 4.5575 11.4575 4.5575 27 P 0 ;1
L 11.4575 4.6075 11.4575 4.6075 27 P 0 ;1
L 11.4575 4.6575 11.4575 4.6575 27 P 0 ;1
L 11.5075 0.1575 11.5075 0.1575 27 P 0 ;1
L 11.5075 0.2075 11.5075 0.2075 27 P 0 ;1
L 11.5075 0.2575 11.5075 0.2575 27 P 0 ;1
L 11.5075 0.3075 11.5075 0.3075 27 P 0 ;1
L 11.5075 0.3575 11.5075 0.3575 27 P 0 ;1
L 11.5075 0.4075 11.5075 0.4075 27 P 0 ;1
L 11.5075 0.4575 11.5075 0.4575 27 P 0 ;1
L 11.5075 0.5075 11.5075 0.5075 27 P 0 ;1
L 11.5075 0.5575 11.5075 0.5575 27 P 0 ;1
L 11.5075 0.6075 11.5075 0.6075 27 P 0 ;1
L 11.5075 0.6575 11.5075 0.6575 27 P 0 ;1
L 11.5075 0.7075 11.5075 0.7075 27 P 0 ;1
L 11.5075 0.7575 11.5075 0.7575 27 P 0 ;1
L 11.5075 0.8075 11.5075 0.8075 27 P 0 ;1
L 11.5075 0.8575 11.5075 0.8575 27 P 0 ;1
L 11.5075 0.9075 11.5075 0.9075 27 P 0 ;1
L 11.5075 0.9575 11.5075 0.9575 27 P 0 ;1
L 11.5075 1.0075 11.5075 1.0075 27 P 0 ;1
L 11.5075 1.0575 11.5075 1.0575 27 P 0 ;1
L 11.5075 1.1075 11.5075 1.1075 27 P 0 ;1
L 11.5075 1.1575 11.5075 1.1575 27 P 0 ;1
L 11.5075 1.2075 11.5075 1.2075 27 P 0 ;1
L 11.5075 1.2575 11.5075 1.2575 27 P 0 ;1
L 11.5075 1.3075 11.5075 1.3075 27 P 0 ;1
L 11.5075 2.2075 11.5075 2.2075 27 P 0 ;1
L 11.5075 2.2575 11.5075 2.2575 27 P 0 ;1
L 11.5075 3.4075 11.5075 3.4075 27 P 0 ;1
L 11.5075 3.4575 11.5075 3.4575 27 P 0 ;1
L 11.5075 3.5075 11.5075 3.5075 27 P 0 ;1
L 11.5075 3.5575 11.5075 3.5575 27 P 0 ;1
L 11.5075 3.6075 11.5075 3.6075 27 P 0 ;1
L 11.5075 3.6575 11.5075 3.6575 27 P 0 ;1
L 11.5075 3.7075 11.5075 3.7075 27 P 0 ;1
L 11.5075 3.7575 11.5075 3.7575 27 P 0 ;1
L 11.5075 3.8075 11.5075 3.8075 27 P 0 ;1
L 11.5075 3.8575 11.5075 3.8575 27 P 0 ;1
L 11.5075 3.9075 11.5075 3.9075 27 P 0 ;1
L 11.5075 3.9575 11.5075 3.9575 27 P 0 ;1
L 11.5075 4.0075 11.5075 4.0075 27 P 0 ;1
L 11.5075 4.0575 11.5075 4.0575 27 P 0 ;1
L 11.5075 4.1075 11.5075 4.1075 27 P 0 ;1
L 11.5075 4.1575 11.5075 4.1575 27 P 0 ;1
L 11.5075 4.2075 11.5075 4.2075 27 P 0 ;1
L 11.5075 4.2575 11.5075 4.2575 27 P 0 ;1
L 11.5075 4.3075 11.5075 4.3075 27 P 0 ;1
L 11.5075 4.3575 11.5075 4.3575 27 P 0 ;1
L 11.5075 4.4075 11.5075 4.4075 27 P 0 ;1
L 11.5075 4.4575 11.5075 4.4575 27 P 0 ;1
L 11.5075 4.5075 11.5075 4.5075 27 P 0 ;1
L 11.5075 4.5575 11.5075 4.5575 27 P 0 ;1
L 11.5075 4.6075 11.5075 4.6075 27 P 0 ;1
L 11.5075 4.6575 11.5075 4.6575 27 P 0 ;1
L 11.5575 0.1575 11.5575 0.1575 27 P 0 ;1
L 11.5575 0.2075 11.5575 0.2075 27 P 0 ;1
L 11.5575 0.2575 11.5575 0.2575 27 P 0 ;1
L 11.5575 0.3075 11.5575 0.3075 27 P 0 ;1
L 11.5575 0.3575 11.5575 0.3575 27 P 0 ;1
L 11.5575 0.4075 11.5575 0.4075 27 P 0 ;1
L 11.5575 0.4575 11.5575 0.4575 27 P 0 ;1
L 11.5575 0.5075 11.5575 0.5075 27 P 0 ;1
L 11.5575 0.5575 11.5575 0.5575 27 P 0 ;1
L 11.5575 0.6075 11.5575 0.6075 27 P 0 ;1
L 11.5575 0.6575 11.5575 0.6575 27 P 0 ;1
L 11.5575 0.7075 11.5575 0.7075 27 P 0 ;1
L 11.5575 0.7575 11.5575 0.7575 27 P 0 ;1
L 11.5575 0.8075 11.5575 0.8075 27 P 0 ;1
L 11.5575 0.8575 11.5575 0.8575 27 P 0 ;1
L 11.5575 0.9075 11.5575 0.9075 27 P 0 ;1
L 11.5575 0.9575 11.5575 0.9575 27 P 0 ;1
L 11.5575 1.0075 11.5575 1.0075 27 P 0 ;1
L 11.5575 1.0575 11.5575 1.0575 27 P 0 ;1
L 11.5575 1.1075 11.5575 1.1075 27 P 0 ;1
L 11.5575 1.1575 11.5575 1.1575 27 P 0 ;1
L 11.5575 1.2075 11.5575 1.2075 27 P 0 ;1
L 11.5575 1.2575 11.5575 1.2575 27 P 0 ;1
L 11.5575 1.3075 11.5575 1.3075 27 P 0 ;1
L 11.5575 2.2075 11.5575 2.2075 27 P 0 ;1
L 11.5575 2.2575 11.5575 2.2575 27 P 0 ;1
L 11.5575 3.0075 11.5575 3.0075 27 P 0 ;1
L 11.5575 3.0575 11.5575 3.0575 27 P 0 ;1
L 11.5575 3.1075 11.5575 3.1075 27 P 0 ;1
L 11.5575 3.1575 11.5575 3.1575 27 P 0 ;1
L 11.5575 3.2075 11.5575 3.2075 27 P 0 ;1
L 11.5575 3.2575 11.5575 3.2575 27 P 0 ;1
L 11.5575 3.3075 11.5575 3.3075 27 P 0 ;1
L 11.5575 3.3575 11.5575 3.3575 27 P 0 ;1
L 11.5575 3.4075 11.5575 3.4075 27 P 0 ;1
L 11.5575 3.4575 11.5575 3.4575 27 P 0 ;1
L 11.5575 3.5075 11.5575 3.5075 27 P 0 ;1
L 11.5575 3.5575 11.5575 3.5575 27 P 0 ;1
L 11.5575 3.6075 11.5575 3.6075 27 P 0 ;1
L 11.5575 3.6575 11.5575 3.6575 27 P 0 ;1
L 11.5575 3.7075 11.5575 3.7075 27 P 0 ;1
L 11.5575 3.7575 11.5575 3.7575 27 P 0 ;1
L 11.5575 3.8075 11.5575 3.8075 27 P 0 ;1
L 11.5575 3.8575 11.5575 3.8575 27 P 0 ;1
L 11.5575 3.9075 11.5575 3.9075 27 P 0 ;1
L 11.5575 3.9575 11.5575 3.9575 27 P 0 ;1
L 11.5575 4.0075 11.5575 4.0075 27 P 0 ;1
L 11.5575 4.0575 11.5575 4.0575 27 P 0 ;1
L 11.5575 4.1075 11.5575 4.1075 27 P 0 ;1
L 11.5575 4.1575 11.5575 4.1575 27 P 0 ;1
L 11.5575 4.2075 11.5575 4.2075 27 P 0 ;1
L 11.5575 4.2575 11.5575 4.2575 27 P 0 ;1
L 11.5575 4.3075 11.5575 4.3075 27 P 0 ;1
L 11.5575 4.3575 11.5575 4.3575 27 P 0 ;1
L 11.5575 4.4075 11.5575 4.4075 27 P 0 ;1
L 11.5575 4.4575 11.5575 4.4575 27 P 0 ;1
L 11.5575 4.5075 11.5575 4.5075 27 P 0 ;1
L 11.5575 4.5575 11.5575 4.5575 27 P 0 ;1
L 11.5575 4.6075 11.5575 4.6075 27 P 0 ;1
L 11.5575 4.6575 11.5575 4.6575 27 P 0 ;1
L 11.6075 0.1575 11.6075 0.1575 27 P 0 ;1
L 11.6075 0.2075 11.6075 0.2075 27 P 0 ;1
L 11.6075 0.2575 11.6075 0.2575 27 P 0 ;1
L 11.6075 0.3075 11.6075 0.3075 27 P 0 ;1
L 11.6075 0.3575 11.6075 0.3575 27 P 0 ;1
L 11.6075 0.4075 11.6075 0.4075 27 P 0 ;1
L 11.6075 0.4575 11.6075 0.4575 27 P 0 ;1
L 11.6075 0.5075 11.6075 0.5075 27 P 0 ;1
L 11.6075 0.5575 11.6075 0.5575 27 P 0 ;1
L 11.6075 0.6075 11.6075 0.6075 27 P 0 ;1
L 11.6075 0.6575 11.6075 0.6575 27 P 0 ;1
L 11.6075 0.7075 11.6075 0.7075 27 P 0 ;1
L 11.6075 0.7575 11.6075 0.7575 27 P 0 ;1
L 11.6075 0.8075 11.6075 0.8075 27 P 0 ;1
L 11.6075 0.8575 11.6075 0.8575 27 P 0 ;1
L 11.6075 0.9075 11.6075 0.9075 27 P 0 ;1
L 11.6075 0.9575 11.6075 0.9575 27 P 0 ;1
L 11.6075 1.0075 11.6075 1.0075 27 P 0 ;1
L 11.6075 1.0575 11.6075 1.0575 27 P 0 ;1
L 11.6075 1.1075 11.6075 1.1075 27 P 0 ;1
L 11.6075 1.1575 11.6075 1.1575 27 P 0 ;1
L 11.6075 1.2075 11.6075 1.2075 27 P 0 ;1
L 11.6075 1.2575 11.6075 1.2575 27 P 0 ;1
L 11.6075 1.3075 11.6075 1.3075 27 P 0 ;1
L 11.6075 3.0075 11.6075 3.0075 27 P 0 ;1
L 11.6075 3.0575 11.6075 3.0575 27 P 0 ;1
L 11.6075 3.1075 11.6075 3.1075 27 P 0 ;1
L 11.6075 3.1575 11.6075 3.1575 27 P 0 ;1
L 11.6075 3.2075 11.6075 3.2075 27 P 0 ;1
L 11.6075 3.2575 11.6075 3.2575 27 P 0 ;1
L 11.6075 3.3075 11.6075 3.3075 27 P 0 ;1
L 11.6075 3.3575 11.6075 3.3575 27 P 0 ;1
L 11.6075 3.4075 11.6075 3.4075 27 P 0 ;1
L 11.6075 3.4575 11.6075 3.4575 27 P 0 ;1
L 11.6075 3.5075 11.6075 3.5075 27 P 0 ;1
L 11.6075 3.5575 11.6075 3.5575 27 P 0 ;1
L 11.6075 3.6075 11.6075 3.6075 27 P 0 ;1
L 11.6075 3.6575 11.6075 3.6575 27 P 0 ;1
L 11.6075 3.7075 11.6075 3.7075 27 P 0 ;1
L 11.6075 3.7575 11.6075 3.7575 27 P 0 ;1
L 11.6075 3.8075 11.6075 3.8075 27 P 0 ;1
L 11.6075 3.8575 11.6075 3.8575 27 P 0 ;1
L 11.6075 3.9075 11.6075 3.9075 27 P 0 ;1
L 11.6075 3.9575 11.6075 3.9575 27 P 0 ;1
L 11.6075 4.0075 11.6075 4.0075 27 P 0 ;1
L 11.6075 4.0575 11.6075 4.0575 27 P 0 ;1
L 11.6075 4.1075 11.6075 4.1075 27 P 0 ;1
L 11.6075 4.1575 11.6075 4.1575 27 P 0 ;1
L 11.6075 4.2075 11.6075 4.2075 27 P 0 ;1
L 11.6075 4.2575 11.6075 4.2575 27 P 0 ;1
L 11.6075 4.3075 11.6075 4.3075 27 P 0 ;1
L 11.6075 4.3575 11.6075 4.3575 27 P 0 ;1
L 11.6075 4.4075 11.6075 4.4075 27 P 0 ;1
L 11.6075 4.4575 11.6075 4.4575 27 P 0 ;1
L 11.6075 4.5075 11.6075 4.5075 27 P 0 ;1
L 11.6075 4.5575 11.6075 4.5575 27 P 0 ;1
L 11.6075 4.6075 11.6075 4.6075 27 P 0 ;1
L 11.6075 4.6575 11.6075 4.6575 27 P 0 ;1
L 11.6575 0.1575 11.6575 0.1575 27 P 0 ;1
L 11.6575 0.2075 11.6575 0.2075 27 P 0 ;1
L 11.6575 0.2575 11.6575 0.2575 27 P 0 ;1
L 11.6575 0.3075 11.6575 0.3075 27 P 0 ;1
L 11.6575 0.3575 11.6575 0.3575 27 P 0 ;1
L 11.6575 0.4075 11.6575 0.4075 27 P 0 ;1
L 11.6575 0.4575 11.6575 0.4575 27 P 0 ;1
L 11.6575 0.5075 11.6575 0.5075 27 P 0 ;1
L 11.6575 0.5575 11.6575 0.5575 27 P 0 ;1
L 11.6575 0.6075 11.6575 0.6075 27 P 0 ;1
L 11.6575 0.6575 11.6575 0.6575 27 P 0 ;1
L 11.6575 0.7075 11.6575 0.7075 27 P 0 ;1
L 11.6575 0.7575 11.6575 0.7575 27 P 0 ;1
L 11.6575 0.8075 11.6575 0.8075 27 P 0 ;1
L 11.6575 0.8575 11.6575 0.8575 27 P 0 ;1
L 11.6575 0.9075 11.6575 0.9075 27 P 0 ;1
L 11.6575 0.9575 11.6575 0.9575 27 P 0 ;1
L 11.6575 1.0075 11.6575 1.0075 27 P 0 ;1
L 11.6575 1.0575 11.6575 1.0575 27 P 0 ;1
L 11.6575 1.1075 11.6575 1.1075 27 P 0 ;1
L 11.6575 1.1575 11.6575 1.1575 27 P 0 ;1
L 11.6575 1.2075 11.6575 1.2075 27 P 0 ;1
L 11.6575 1.2575 11.6575 1.2575 27 P 0 ;1
L 11.6575 1.3075 11.6575 1.3075 27 P 0 ;1
L 11.6575 1.3575 11.6575 1.3575 27 P 0 ;1
L 11.6575 3.0075 11.6575 3.0075 27 P 0 ;1
L 11.6575 3.0575 11.6575 3.0575 27 P 0 ;1
L 11.6575 3.1075 11.6575 3.1075 27 P 0 ;1
L 11.6575 3.1575 11.6575 3.1575 27 P 0 ;1
L 11.6575 3.2075 11.6575 3.2075 27 P 0 ;1
L 11.6575 3.2575 11.6575 3.2575 27 P 0 ;1
L 11.6575 3.3075 11.6575 3.3075 27 P 0 ;1
L 11.6575 3.3575 11.6575 3.3575 27 P 0 ;1
L 11.6575 3.4075 11.6575 3.4075 27 P 0 ;1
L 11.6575 3.4575 11.6575 3.4575 27 P 0 ;1
L 11.6575 3.5075 11.6575 3.5075 27 P 0 ;1
L 11.6575 3.5575 11.6575 3.5575 27 P 0 ;1
L 11.6575 3.6075 11.6575 3.6075 27 P 0 ;1
L 11.6575 3.6575 11.6575 3.6575 27 P 0 ;1
L 11.6575 3.7075 11.6575 3.7075 27 P 0 ;1
L 11.6575 3.7575 11.6575 3.7575 27 P 0 ;1
L 11.6575 3.8075 11.6575 3.8075 27 P 0 ;1
L 11.6575 3.8575 11.6575 3.8575 27 P 0 ;1
L 11.6575 3.9075 11.6575 3.9075 27 P 0 ;1
L 11.6575 3.9575 11.6575 3.9575 27 P 0 ;1
L 11.6575 4.0075 11.6575 4.0075 27 P 0 ;1
L 11.6575 4.0575 11.6575 4.0575 27 P 0 ;1
L 11.6575 4.1075 11.6575 4.1075 27 P 0 ;1
L 11.6575 4.1575 11.6575 4.1575 27 P 0 ;1
L 11.6575 4.2075 11.6575 4.2075 27 P 0 ;1
L 11.6575 4.2575 11.6575 4.2575 27 P 0 ;1
L 11.6575 4.3075 11.6575 4.3075 27 P 0 ;1
L 11.6575 4.3575 11.6575 4.3575 27 P 0 ;1
L 11.6575 4.4075 11.6575 4.4075 27 P 0 ;1
L 11.6575 4.4575 11.6575 4.4575 27 P 0 ;1
L 11.6575 4.5075 11.6575 4.5075 27 P 0 ;1
L 11.6575 4.5575 11.6575 4.5575 27 P 0 ;1
L 11.6575 4.6075 11.6575 4.6075 27 P 0 ;1
L 11.6575 4.6575 11.6575 4.6575 27 P 0 ;1
L 11.7075 0.1575 11.7075 0.1575 27 P 0 ;1
L 11.7075 0.2075 11.7075 0.2075 27 P 0 ;1
L 11.7075 0.2575 11.7075 0.2575 27 P 0 ;1
L 11.7075 0.3075 11.7075 0.3075 27 P 0 ;1
L 11.7075 0.3575 11.7075 0.3575 27 P 0 ;1
L 11.7075 0.4075 11.7075 0.4075 27 P 0 ;1
L 11.7075 0.4575 11.7075 0.4575 27 P 0 ;1
L 11.7075 0.5075 11.7075 0.5075 27 P 0 ;1
L 11.7075 0.5575 11.7075 0.5575 27 P 0 ;1
L 11.7075 0.6075 11.7075 0.6075 27 P 0 ;1
L 11.7075 0.6575 11.7075 0.6575 27 P 0 ;1
L 11.7075 0.7075 11.7075 0.7075 27 P 0 ;1
L 11.7075 0.7575 11.7075 0.7575 27 P 0 ;1
L 11.7075 0.8075 11.7075 0.8075 27 P 0 ;1
L 11.7075 0.8575 11.7075 0.8575 27 P 0 ;1
L 11.7075 0.9075 11.7075 0.9075 27 P 0 ;1
L 11.7075 0.9575 11.7075 0.9575 27 P 0 ;1
L 11.7075 1.0075 11.7075 1.0075 27 P 0 ;1
L 11.7075 1.0575 11.7075 1.0575 27 P 0 ;1
L 11.7075 1.1075 11.7075 1.1075 27 P 0 ;1
L 11.7075 1.1575 11.7075 1.1575 27 P 0 ;1
L 11.7075 1.2075 11.7075 1.2075 27 P 0 ;1
L 11.7075 1.2575 11.7075 1.2575 27 P 0 ;1
L 11.7075 1.3075 11.7075 1.3075 27 P 0 ;1
L 11.7075 1.3575 11.7075 1.3575 27 P 0 ;1
L 11.7075 2.7575 11.7075 2.7575 27 P 0 ;1
L 11.7075 2.9575 11.7075 2.9575 27 P 0 ;1
L 11.7075 3.0075 11.7075 3.0075 27 P 0 ;1
L 11.7075 3.0575 11.7075 3.0575 27 P 0 ;1
L 11.7075 3.1075 11.7075 3.1075 27 P 0 ;1
L 11.7075 3.1575 11.7075 3.1575 27 P 0 ;1
L 11.7075 3.2075 11.7075 3.2075 27 P 0 ;1
L 11.7075 3.2575 11.7075 3.2575 27 P 0 ;1
L 11.7075 3.3075 11.7075 3.3075 27 P 0 ;1
L 11.7075 3.3575 11.7075 3.3575 27 P 0 ;1
L 11.7075 3.4075 11.7075 3.4075 27 P 0 ;1
L 11.7075 3.4575 11.7075 3.4575 27 P 0 ;1
L 11.7075 3.5075 11.7075 3.5075 27 P 0 ;1
L 11.7075 3.5575 11.7075 3.5575 27 P 0 ;1
L 11.7075 3.6075 11.7075 3.6075 27 P 0 ;1
L 11.7075 3.6575 11.7075 3.6575 27 P 0 ;1
L 11.7075 3.7075 11.7075 3.7075 27 P 0 ;1
L 11.7075 3.7575 11.7075 3.7575 27 P 0 ;1
L 11.7075 3.8075 11.7075 3.8075 27 P 0 ;1
L 11.7075 3.8575 11.7075 3.8575 27 P 0 ;1
L 11.7075 3.9075 11.7075 3.9075 27 P 0 ;1
L 11.7075 3.9575 11.7075 3.9575 27 P 0 ;1
L 11.7075 4.0075 11.7075 4.0075 27 P 0 ;1
L 11.7075 4.0575 11.7075 4.0575 27 P 0 ;1
L 11.7075 4.1075 11.7075 4.1075 27 P 0 ;1
L 11.7075 4.1575 11.7075 4.1575 27 P 0 ;1
L 11.7075 4.2075 11.7075 4.2075 27 P 0 ;1
L 11.7075 4.2575 11.7075 4.2575 27 P 0 ;1
L 11.7075 4.3075 11.7075 4.3075 27 P 0 ;1
L 11.7075 4.3575 11.7075 4.3575 27 P 0 ;1
L 11.7075 4.4075 11.7075 4.4075 27 P 0 ;1
L 11.7075 4.4575 11.7075 4.4575 27 P 0 ;1
L 11.7075 4.5075 11.7075 4.5075 27 P 0 ;1
L 11.7075 4.5575 11.7075 4.5575 27 P 0 ;1
L 11.7075 4.6075 11.7075 4.6075 27 P 0 ;1
L 11.7075 4.6575 11.7075 4.6575 27 P 0 ;1
L 11.7075 4.7075 11.7075 4.7075 27 P 0 ;1
L 11.7575 0.1575 11.7575 0.1575 27 P 0 ;1
L 11.7575 0.2075 11.7575 0.2075 27 P 0 ;1
L 11.7575 0.2575 11.7575 0.2575 27 P 0 ;1
L 11.7575 0.3075 11.7575 0.3075 27 P 0 ;1
L 11.7575 0.3575 11.7575 0.3575 27 P 0 ;1
L 11.7575 0.4075 11.7575 0.4075 27 P 0 ;1
L 11.7575 0.4575 11.7575 0.4575 27 P 0 ;1
L 11.7575 0.5075 11.7575 0.5075 27 P 0 ;1
L 11.7575 0.5575 11.7575 0.5575 27 P 0 ;1
L 11.7575 0.6075 11.7575 0.6075 27 P 0 ;1
L 11.7575 0.6575 11.7575 0.6575 27 P 0 ;1
L 11.7575 0.7075 11.7575 0.7075 27 P 0 ;1
L 11.7575 0.7575 11.7575 0.7575 27 P 0 ;1
L 11.7575 0.8075 11.7575 0.8075 27 P 0 ;1
L 11.7575 0.8575 11.7575 0.8575 27 P 0 ;1
L 11.7575 0.9075 11.7575 0.9075 27 P 0 ;1
L 11.7575 0.9575 11.7575 0.9575 27 P 0 ;1
L 11.7575 1.0075 11.7575 1.0075 27 P 0 ;1
L 11.7575 1.0575 11.7575 1.0575 27 P 0 ;1
L 11.7575 1.1075 11.7575 1.1075 27 P 0 ;1
L 11.7575 1.1575 11.7575 1.1575 27 P 0 ;1
L 11.7575 1.2075 11.7575 1.2075 27 P 0 ;1
L 11.7575 1.2575 11.7575 1.2575 27 P 0 ;1
L 11.7575 1.3075 11.7575 1.3075 27 P 0 ;1
L 11.7575 1.3575 11.7575 1.3575 27 P 0 ;1
L 11.7575 2.7575 11.7575 2.7575 27 P 0 ;1
L 11.7575 2.9075 11.7575 2.9075 27 P 0 ;1
L 11.7575 2.9575 11.7575 2.9575 27 P 0 ;1
L 11.7575 3.0075 11.7575 3.0075 27 P 0 ;1
L 11.7575 3.0575 11.7575 3.0575 27 P 0 ;1
L 11.7575 3.1075 11.7575 3.1075 27 P 0 ;1
L 11.7575 3.1575 11.7575 3.1575 27 P 0 ;1
L 11.7575 3.2075 11.7575 3.2075 27 P 0 ;1
L 11.7575 3.2575 11.7575 3.2575 27 P 0 ;1
L 11.7575 3.3075 11.7575 3.3075 27 P 0 ;1
L 11.7575 3.3575 11.7575 3.3575 27 P 0 ;1
L 11.7575 3.4075 11.7575 3.4075 27 P 0 ;1
L 11.7575 3.4575 11.7575 3.4575 27 P 0 ;1
L 11.7575 3.5075 11.7575 3.5075 27 P 0 ;1
L 11.7575 3.5575 11.7575 3.5575 27 P 0 ;1
L 11.7575 3.6075 11.7575 3.6075 27 P 0 ;1
L 11.7575 3.6575 11.7575 3.6575 27 P 0 ;1
L 11.7575 3.7075 11.7575 3.7075 27 P 0 ;1
L 11.7575 3.7575 11.7575 3.7575 27 P 0 ;1
L 11.7575 3.8075 11.7575 3.8075 27 P 0 ;1
L 11.7575 3.8575 11.7575 3.8575 27 P 0 ;1
L 11.7575 3.9075 11.7575 3.9075 27 P 0 ;1
L 11.7575 3.9575 11.7575 3.9575 27 P 0 ;1
L 11.7575 4.0075 11.7575 4.0075 27 P 0 ;1
L 11.7575 4.0575 11.7575 4.0575 27 P 0 ;1
L 11.7575 4.1075 11.7575 4.1075 27 P 0 ;1
L 11.7575 4.1575 11.7575 4.1575 27 P 0 ;1
L 11.7575 4.2075 11.7575 4.2075 27 P 0 ;1
L 11.7575 4.2575 11.7575 4.2575 27 P 0 ;1
L 11.7575 4.3075 11.7575 4.3075 27 P 0 ;1
L 11.7575 4.3575 11.7575 4.3575 27 P 0 ;1
L 11.7575 4.4075 11.7575 4.4075 27 P 0 ;1
L 11.7575 4.4575 11.7575 4.4575 27 P 0 ;1
L 11.7575 4.5075 11.7575 4.5075 27 P 0 ;1
L 11.7575 4.5575 11.7575 4.5575 27 P 0 ;1
L 11.7575 4.6075 11.7575 4.6075 27 P 0 ;1
L 11.7575 4.6575 11.7575 4.6575 27 P 0 ;1
L 11.8075 0.1575 11.8075 0.1575 27 P 0 ;1
L 11.8075 0.2075 11.8075 0.2075 27 P 0 ;1
L 11.8075 0.2575 11.8075 0.2575 27 P 0 ;1
L 11.8075 0.3075 11.8075 0.3075 27 P 0 ;1
L 11.8075 0.3575 11.8075 0.3575 27 P 0 ;1
L 11.8075 0.4075 11.8075 0.4075 27 P 0 ;1
L 11.8075 0.4575 11.8075 0.4575 27 P 0 ;1
L 11.8075 0.5075 11.8075 0.5075 27 P 0 ;1
L 11.8075 0.5575 11.8075 0.5575 27 P 0 ;1
L 11.8075 0.6075 11.8075 0.6075 27 P 0 ;1
L 11.8075 0.6575 11.8075 0.6575 27 P 0 ;1
L 11.8075 0.7075 11.8075 0.7075 27 P 0 ;1
L 11.8075 0.7575 11.8075 0.7575 27 P 0 ;1
L 11.8075 0.8075 11.8075 0.8075 27 P 0 ;1
L 11.8075 0.8575 11.8075 0.8575 27 P 0 ;1
L 11.8075 0.9075 11.8075 0.9075 27 P 0 ;1
L 11.8075 0.9575 11.8075 0.9575 27 P 0 ;1
L 11.8075 1.0075 11.8075 1.0075 27 P 0 ;1
L 11.8075 1.0575 11.8075 1.0575 27 P 0 ;1
L 11.8075 1.1075 11.8075 1.1075 27 P 0 ;1
L 11.8075 1.1575 11.8075 1.1575 27 P 0 ;1
L 11.8075 1.2075 11.8075 1.2075 27 P 0 ;1
L 11.8075 1.2575 11.8075 1.2575 27 P 0 ;1
L 11.8075 1.3075 11.8075 1.3075 27 P 0 ;1
L 11.8075 1.3575 11.8075 1.3575 27 P 0 ;1
L 11.8075 1.4075 11.8075 1.4075 27 P 0 ;1
L 11.8075 2.7575 11.8075 2.7575 27 P 0 ;1
L 11.8075 2.9575 11.8075 2.9575 27 P 0 ;1
L 11.8075 3.0075 11.8075 3.0075 27 P 0 ;1
L 11.8075 3.0575 11.8075 3.0575 27 P 0 ;1
L 11.8075 3.1075 11.8075 3.1075 27 P 0 ;1
L 11.8075 3.1575 11.8075 3.1575 27 P 0 ;1
L 11.8075 3.2075 11.8075 3.2075 27 P 0 ;1
L 11.8075 3.2575 11.8075 3.2575 27 P 0 ;1
L 11.8075 3.3075 11.8075 3.3075 27 P 0 ;1
L 11.8075 3.3575 11.8075 3.3575 27 P 0 ;1
L 11.8075 3.4075 11.8075 3.4075 27 P 0 ;1
L 11.8075 3.4575 11.8075 3.4575 27 P 0 ;1
L 11.8075 3.5075 11.8075 3.5075 27 P 0 ;1
L 11.8075 3.5575 11.8075 3.5575 27 P 0 ;1
L 11.8075 3.6075 11.8075 3.6075 27 P 0 ;1
L 11.8075 3.6575 11.8075 3.6575 27 P 0 ;1
L 11.8075 3.7075 11.8075 3.7075 27 P 0 ;1
L 11.8075 3.7575 11.8075 3.7575 27 P 0 ;1
L 11.8075 3.8075 11.8075 3.8075 27 P 0 ;1
L 11.8075 3.8575 11.8075 3.8575 27 P 0 ;1
L 11.8075 3.9075 11.8075 3.9075 27 P 0 ;1
L 11.8075 3.9575 11.8075 3.9575 27 P 0 ;1
L 11.8075 4.0075 11.8075 4.0075 27 P 0 ;1
L 11.8075 4.0575 11.8075 4.0575 27 P 0 ;1
L 11.8075 4.1075 11.8075 4.1075 27 P 0 ;1
L 11.8075 4.1575 11.8075 4.1575 27 P 0 ;1
L 11.8075 4.2075 11.8075 4.2075 27 P 0 ;1
L 11.8075 4.2575 11.8075 4.2575 27 P 0 ;1
L 11.8075 4.3075 11.8075 4.3075 27 P 0 ;1
L 11.8075 4.3575 11.8075 4.3575 27 P 0 ;1
L 11.8075 4.5575 11.8075 4.5575 27 P 0 ;1
L 11.8075 4.6075 11.8075 4.6075 27 P 0 ;1
L 11.8075 4.6575 11.8075 4.6575 27 P 0 ;1
L 11.8575 0.1575 11.8575 0.1575 27 P 0 ;1
L 11.8575 0.4075 11.8575 0.4075 27 P 0 ;1
L 11.8575 0.4575 11.8575 0.4575 27 P 0 ;1
L 11.8575 0.5075 11.8575 0.5075 27 P 0 ;1
L 11.8575 0.5575 11.8575 0.5575 27 P 0 ;1
L 11.8575 0.6075 11.8575 0.6075 27 P 0 ;1
L 11.8575 0.6575 11.8575 0.6575 27 P 0 ;1
L 11.8575 0.7075 11.8575 0.7075 27 P 0 ;1
L 11.8575 0.7575 11.8575 0.7575 27 P 0 ;1
L 11.8575 0.8075 11.8575 0.8075 27 P 0 ;1
L 11.8575 0.8575 11.8575 0.8575 27 P 0 ;1
L 11.8575 0.9075 11.8575 0.9075 27 P 0 ;1
L 11.8575 0.9575 11.8575 0.9575 27 P 0 ;1
L 11.8575 1.0075 11.8575 1.0075 27 P 0 ;1
L 11.8575 1.0575 11.8575 1.0575 27 P 0 ;1
L 11.8575 1.1075 11.8575 1.1075 27 P 0 ;1
L 11.8575 1.1575 11.8575 1.1575 27 P 0 ;1
L 11.8575 1.2075 11.8575 1.2075 27 P 0 ;1
L 11.8575 1.2575 11.8575 1.2575 27 P 0 ;1
L 11.8575 1.3075 11.8575 1.3075 27 P 0 ;1
L 11.8575 1.3575 11.8575 1.3575 27 P 0 ;1
L 11.8575 1.4075 11.8575 1.4075 27 P 0 ;1
L 11.8575 1.4575 11.8575 1.4575 27 P 0 ;1
L 11.8575 1.5075 11.8575 1.5075 27 P 0 ;1
L 11.8575 1.5575 11.8575 1.5575 27 P 0 ;1
L 11.8575 1.7575 11.8575 1.7575 27 P 0 ;1
L 11.8575 1.8075 11.8575 1.8075 27 P 0 ;1
L 11.8575 1.8575 11.8575 1.8575 27 P 0 ;1
L 11.8575 1.9075 11.8575 1.9075 27 P 0 ;1
L 11.8575 1.9575 11.8575 1.9575 27 P 0 ;1
L 11.8575 2.0075 11.8575 2.0075 27 P 0 ;1
L 11.8575 2.0575 11.8575 2.0575 27 P 0 ;1
L 11.8575 2.1075 11.8575 2.1075 27 P 0 ;1
L 11.8575 2.3575 11.8575 2.3575 27 P 0 ;1
L 11.8575 2.4075 11.8575 2.4075 27 P 0 ;1
L 11.8575 2.4575 11.8575 2.4575 27 P 0 ;1
L 11.8575 2.5075 11.8575 2.5075 27 P 0 ;1
L 11.8575 2.5575 11.8575 2.5575 27 P 0 ;1
L 11.8575 2.6075 11.8575 2.6075 27 P 0 ;1
L 11.8575 2.6575 11.8575 2.6575 27 P 0 ;1
L 11.8575 2.7075 11.8575 2.7075 27 P 0 ;1
L 11.8575 2.7575 11.8575 2.7575 27 P 0 ;1
L 11.8575 2.9575 11.8575 2.9575 27 P 0 ;1
L 11.8575 3.0075 11.8575 3.0075 27 P 0 ;1
L 11.8575 3.0575 11.8575 3.0575 27 P 0 ;1
L 11.8575 3.1075 11.8575 3.1075 27 P 0 ;1
L 11.8575 3.1575 11.8575 3.1575 27 P 0 ;1
L 11.8575 3.2075 11.8575 3.2075 27 P 0 ;1
L 11.8575 3.2575 11.8575 3.2575 27 P 0 ;1
L 11.8575 3.3075 11.8575 3.3075 27 P 0 ;1
L 11.8575 3.3575 11.8575 3.3575 27 P 0 ;1
L 11.8575 3.4075 11.8575 3.4075 27 P 0 ;1
L 11.8575 3.4575 11.8575 3.4575 27 P 0 ;1
L 11.8575 3.5075 11.8575 3.5075 27 P 0 ;1
L 11.8575 3.5575 11.8575 3.5575 27 P 0 ;1
L 11.8575 3.6075 11.8575 3.6075 27 P 0 ;1
L 11.8575 3.6575 11.8575 3.6575 27 P 0 ;1
L 11.8575 3.7075 11.8575 3.7075 27 P 0 ;1
L 11.8575 3.7575 11.8575 3.7575 27 P 0 ;1
L 11.8575 3.8075 11.8575 3.8075 27 P 0 ;1
L 11.8575 3.8575 11.8575 3.8575 27 P 0 ;1
L 11.8575 3.9075 11.8575 3.9075 27 P 0 ;1
L 11.8575 3.9575 11.8575 3.9575 27 P 0 ;1
L 11.8575 4.0075 11.8575 4.0075 27 P 0 ;1
L 11.8575 4.0575 11.8575 4.0575 27 P 0 ;1
L 11.8575 4.1075 11.8575 4.1075 27 P 0 ;1
L 11.8575 4.1575 11.8575 4.1575 27 P 0 ;1
L 11.8575 4.2075 11.8575 4.2075 27 P 0 ;1
L 11.8575 4.2575 11.8575 4.2575 27 P 0 ;1
L 11.8575 4.3075 11.8575 4.3075 27 P 0 ;1
L 11.8575 4.3575 11.8575 4.3575 27 P 0 ;1
L 11.8575 4.5575 11.8575 4.5575 27 P 0 ;1
L 11.8575 4.6075 11.8575 4.6075 27 P 0 ;1
L 11.8575 4.6575 11.8575 4.6575 27 P 0 ;1
L 11.9075 0.4575 11.9075 0.4575 27 P 0 ;1
L 11.9075 0.5075 11.9075 0.5075 27 P 0 ;1
L 11.9075 0.5575 11.9075 0.5575 27 P 0 ;1
L 11.9075 0.6075 11.9075 0.6075 27 P 0 ;1
L 11.9075 0.6575 11.9075 0.6575 27 P 0 ;1
L 11.9075 0.7075 11.9075 0.7075 27 P 0 ;1
L 11.9075 0.7575 11.9075 0.7575 27 P 0 ;1
L 11.9075 0.8075 11.9075 0.8075 27 P 0 ;1
L 11.9075 0.8575 11.9075 0.8575 27 P 0 ;1
L 11.9075 0.9075 11.9075 0.9075 27 P 0 ;1
L 11.9075 0.9575 11.9075 0.9575 27 P 0 ;1
L 11.9075 1.0075 11.9075 1.0075 27 P 0 ;1
L 11.9075 1.0575 11.9075 1.0575 27 P 0 ;1
L 11.9075 1.1075 11.9075 1.1075 27 P 0 ;1
L 11.9075 1.1575 11.9075 1.1575 27 P 0 ;1
L 11.9075 1.2075 11.9075 1.2075 27 P 0 ;1
L 11.9075 1.2575 11.9075 1.2575 27 P 0 ;1
L 11.9075 1.3075 11.9075 1.3075 27 P 0 ;1
L 11.9075 1.3575 11.9075 1.3575 27 P 0 ;1
L 11.9075 1.4075 11.9075 1.4075 27 P 0 ;1
L 11.9075 1.6575 11.9075 1.6575 27 P 0 ;1
L 11.9075 1.7075 11.9075 1.7075 27 P 0 ;1
L 11.9075 1.7575 11.9075 1.7575 27 P 0 ;1
L 11.9075 1.8075 11.9075 1.8075 27 P 0 ;1
L 11.9075 1.8575 11.9075 1.8575 27 P 0 ;1
L 11.9075 1.9075 11.9075 1.9075 27 P 0 ;1
L 11.9075 1.9575 11.9075 1.9575 27 P 0 ;1
L 11.9075 2.0075 11.9075 2.0075 27 P 0 ;1
L 11.9075 2.0575 11.9075 2.0575 27 P 0 ;1
L 11.9075 2.1075 11.9075 2.1075 27 P 0 ;1
L 11.9075 2.3575 11.9075 2.3575 27 P 0 ;1
L 11.9075 2.4075 11.9075 2.4075 27 P 0 ;1
L 11.9075 2.4575 11.9075 2.4575 27 P 0 ;1
L 11.9075 2.5075 11.9075 2.5075 27 P 0 ;1
L 11.9075 2.6575 11.9075 2.6575 27 P 0 ;1
L 11.9075 2.7075 11.9075 2.7075 27 P 0 ;1
L 11.9075 2.7575 11.9075 2.7575 27 P 0 ;1
L 11.9075 2.9575 11.9075 2.9575 27 P 0 ;1
L 11.9075 3.0075 11.9075 3.0075 27 P 0 ;1
L 11.9075 3.0575 11.9075 3.0575 27 P 0 ;1
L 11.9075 3.1075 11.9075 3.1075 27 P 0 ;1
L 11.9075 3.1575 11.9075 3.1575 27 P 0 ;1
L 11.9075 3.2075 11.9075 3.2075 27 P 0 ;1
L 11.9075 3.2575 11.9075 3.2575 27 P 0 ;1
L 11.9075 3.3075 11.9075 3.3075 27 P 0 ;1
L 11.9075 3.3575 11.9075 3.3575 27 P 0 ;1
L 11.9075 3.4075 11.9075 3.4075 27 P 0 ;1
L 11.9075 3.4575 11.9075 3.4575 27 P 0 ;1
L 11.9075 3.5075 11.9075 3.5075 27 P 0 ;1
L 11.9075 3.5575 11.9075 3.5575 27 P 0 ;1
L 11.9075 3.6075 11.9075 3.6075 27 P 0 ;1
L 11.9075 3.6575 11.9075 3.6575 27 P 0 ;1
L 11.9075 3.7075 11.9075 3.7075 27 P 0 ;1
L 11.9075 3.7575 11.9075 3.7575 27 P 0 ;1
L 11.9075 3.8075 11.9075 3.8075 27 P 0 ;1
L 11.9075 3.8575 11.9075 3.8575 27 P 0 ;1
L 11.9075 3.9075 11.9075 3.9075 27 P 0 ;1
L 11.9075 3.9575 11.9075 3.9575 27 P 0 ;1
L 11.9075 4.0075 11.9075 4.0075 27 P 0 ;1
L 11.9075 4.0575 11.9075 4.0575 27 P 0 ;1
L 11.9075 4.3575 11.9075 4.3575 27 P 0 ;1
L 11.9075 4.5575 11.9075 4.5575 27 P 0 ;1
L 11.9075 4.6075 11.9075 4.6075 27 P 0 ;1
L 11.9075 4.6575 11.9075 4.6575 27 P 0 ;1
L 11.9575 0.4575 11.9575 0.4575 27 P 0 ;1
L 11.9575 0.5075 11.9575 0.5075 27 P 0 ;1
L 11.9575 0.5575 11.9575 0.5575 27 P 0 ;1
L 11.9575 0.6075 11.9575 0.6075 27 P 0 ;1
L 11.9575 0.6575 11.9575 0.6575 27 P 0 ;1
L 11.9575 0.7075 11.9575 0.7075 27 P 0 ;1
L 11.9575 0.7575 11.9575 0.7575 27 P 0 ;1
L 11.9575 0.8075 11.9575 0.8075 27 P 0 ;1
L 11.9575 0.8575 11.9575 0.8575 27 P 0 ;1
L 11.9575 0.9075 11.9575 0.9075 27 P 0 ;1
L 11.9575 0.9575 11.9575 0.9575 27 P 0 ;1
L 11.9575 1.0075 11.9575 1.0075 27 P 0 ;1
L 11.9575 1.0575 11.9575 1.0575 27 P 0 ;1
L 11.9575 1.1075 11.9575 1.1075 27 P 0 ;1
L 11.9575 1.1575 11.9575 1.1575 27 P 0 ;1
L 11.9575 1.2075 11.9575 1.2075 27 P 0 ;1
L 11.9575 1.2575 11.9575 1.2575 27 P 0 ;1
L 11.9575 1.3075 11.9575 1.3075 27 P 0 ;1
L 11.9575 1.7075 11.9575 1.7075 27 P 0 ;1
L 11.9575 1.7575 11.9575 1.7575 27 P 0 ;1
L 11.9575 1.8075 11.9575 1.8075 27 P 0 ;1
L 11.9575 1.8575 11.9575 1.8575 27 P 0 ;1
L 11.9575 1.9075 11.9575 1.9075 27 P 0 ;1
L 11.9575 1.9575 11.9575 1.9575 27 P 0 ;1
L 11.9575 2.0075 11.9575 2.0075 27 P 0 ;1
L 11.9575 2.0575 11.9575 2.0575 27 P 0 ;1
L 11.9575 2.1075 11.9575 2.1075 27 P 0 ;1
L 11.9575 2.1575 11.9575 2.1575 27 P 0 ;1
L 11.9575 2.2075 11.9575 2.2075 27 P 0 ;1
L 11.9575 2.2575 11.9575 2.2575 27 P 0 ;1
L 11.9575 2.3075 11.9575 2.3075 27 P 0 ;1
L 11.9575 2.3575 11.9575 2.3575 27 P 0 ;1
L 11.9575 2.4075 11.9575 2.4075 27 P 0 ;1
L 11.9575 2.4575 11.9575 2.4575 27 P 0 ;1
L 11.9575 2.7075 11.9575 2.7075 27 P 0 ;1
L 11.9575 2.7575 11.9575 2.7575 27 P 0 ;1
L 11.9575 2.8075 11.9575 2.8075 27 P 0 ;1
L 11.9575 2.8575 11.9575 2.8575 27 P 0 ;1
L 11.9575 2.9075 11.9575 2.9075 27 P 0 ;1
L 11.9575 2.9575 11.9575 2.9575 27 P 0 ;1
L 11.9575 3.0075 11.9575 3.0075 27 P 0 ;1
L 11.9575 3.0575 11.9575 3.0575 27 P 0 ;1
L 11.9575 3.1075 11.9575 3.1075 27 P 0 ;1
L 11.9575 3.1575 11.9575 3.1575 27 P 0 ;1
L 11.9575 3.2075 11.9575 3.2075 27 P 0 ;1
L 11.9575 3.2575 11.9575 3.2575 27 P 0 ;1
L 11.9575 3.3075 11.9575 3.3075 27 P 0 ;1
L 11.9575 3.3575 11.9575 3.3575 27 P 0 ;1
L 11.9575 3.4075 11.9575 3.4075 27 P 0 ;1
L 11.9575 3.4575 11.9575 3.4575 27 P 0 ;1
L 11.9575 3.5075 11.9575 3.5075 27 P 0 ;1
L 11.9575 3.5575 11.9575 3.5575 27 P 0 ;1
L 11.9575 3.6075 11.9575 3.6075 27 P 0 ;1
L 11.9575 3.6575 11.9575 3.6575 27 P 0 ;1
L 11.9575 3.7075 11.9575 3.7075 27 P 0 ;1
L 11.9575 3.7575 11.9575 3.7575 27 P 0 ;1
L 11.9575 3.8075 11.9575 3.8075 27 P 0 ;1
L 11.9575 3.8575 11.9575 3.8575 27 P 0 ;1
L 11.9575 3.9075 11.9575 3.9075 27 P 0 ;1
L 11.9575 3.9575 11.9575 3.9575 27 P 0 ;1
L 11.9575 4.0075 11.9575 4.0075 27 P 0 ;1
L 11.9575 4.4075 11.9575 4.4075 27 P 0 ;1
L 11.9575 4.5075 11.9575 4.5075 27 P 0 ;1
L 11.9575 4.5575 11.9575 4.5575 27 P 0 ;1
L 11.9575 4.6075 11.9575 4.6075 27 P 0 ;1
L 11.9575 4.6575 11.9575 4.6575 27 P 0 ;1
L 12.0075 0.4575 12.0075 0.4575 27 P 0 ;1
L 12.0075 0.5075 12.0075 0.5075 27 P 0 ;1
L 12.0075 0.5575 12.0075 0.5575 27 P 0 ;1
L 12.0075 0.6075 12.0075 0.6075 27 P 0 ;1
L 12.0075 0.6575 12.0075 0.6575 27 P 0 ;1
L 12.0075 0.7075 12.0075 0.7075 27 P 0 ;1
L 12.0075 0.7575 12.0075 0.7575 27 P 0 ;1
L 12.0075 0.8075 12.0075 0.8075 27 P 0 ;1
L 12.0075 0.8575 12.0075 0.8575 27 P 0 ;1
L 12.0075 0.9075 12.0075 0.9075 27 P 0 ;1
L 12.0075 0.9575 12.0075 0.9575 27 P 0 ;1
L 12.0075 1.0075 12.0075 1.0075 27 P 0 ;1
L 12.0075 1.0575 12.0075 1.0575 27 P 0 ;1
L 12.0075 1.1075 12.0075 1.1075 27 P 0 ;1
L 12.0075 1.1575 12.0075 1.1575 27 P 0 ;1
L 12.0075 1.2075 12.0075 1.2075 27 P 0 ;1
L 12.0075 1.2575 12.0075 1.2575 27 P 0 ;1
L 12.0075 1.3075 12.0075 1.3075 27 P 0 ;1
L 12.0075 1.7575 12.0075 1.7575 27 P 0 ;1
L 12.0075 1.8075 12.0075 1.8075 27 P 0 ;1
L 12.0075 1.8575 12.0075 1.8575 27 P 0 ;1
L 12.0075 1.9075 12.0075 1.9075 27 P 0 ;1
L 12.0075 1.9575 12.0075 1.9575 27 P 0 ;1
L 12.0075 2.0075 12.0075 2.0075 27 P 0 ;1
L 12.0075 2.0575 12.0075 2.0575 27 P 0 ;1
L 12.0075 2.1075 12.0075 2.1075 27 P 0 ;1
L 12.0075 2.1575 12.0075 2.1575 27 P 0 ;1
L 12.0075 2.2075 12.0075 2.2075 27 P 0 ;1
L 12.0075 2.2575 12.0075 2.2575 27 P 0 ;1
L 12.0075 2.3075 12.0075 2.3075 27 P 0 ;1
L 12.0075 2.3575 12.0075 2.3575 27 P 0 ;1
L 12.0075 2.4075 12.0075 2.4075 27 P 0 ;1
L 12.0075 2.7575 12.0075 2.7575 27 P 0 ;1
L 12.0075 2.8075 12.0075 2.8075 27 P 0 ;1
L 12.0075 2.8575 12.0075 2.8575 27 P 0 ;1
L 12.0075 2.9075 12.0075 2.9075 27 P 0 ;1
L 12.0075 2.9575 12.0075 2.9575 27 P 0 ;1
L 12.0075 3.0075 12.0075 3.0075 27 P 0 ;1
L 12.0075 3.0575 12.0075 3.0575 27 P 0 ;1
L 12.0075 3.1075 12.0075 3.1075 27 P 0 ;1
L 12.0075 3.1575 12.0075 3.1575 27 P 0 ;1
L 12.0075 3.2075 12.0075 3.2075 27 P 0 ;1
L 12.0075 3.2575 12.0075 3.2575 27 P 0 ;1
L 12.0075 3.3075 12.0075 3.3075 27 P 0 ;1
L 12.0075 3.3575 12.0075 3.3575 27 P 0 ;1
L 12.0075 3.4075 12.0075 3.4075 27 P 0 ;1
L 12.0075 3.4575 12.0075 3.4575 27 P 0 ;1
L 12.0075 3.5075 12.0075 3.5075 27 P 0 ;1
L 12.0075 3.5575 12.0075 3.5575 27 P 0 ;1
L 12.0075 3.6075 12.0075 3.6075 27 P 0 ;1
L 12.0075 3.6575 12.0075 3.6575 27 P 0 ;1
L 12.0075 3.7075 12.0075 3.7075 27 P 0 ;1
L 12.0075 3.7575 12.0075 3.7575 27 P 0 ;1
L 12.0075 3.8075 12.0075 3.8075 27 P 0 ;1
L 12.0075 3.8575 12.0075 3.8575 27 P 0 ;1
L 12.0075 3.9075 12.0075 3.9075 27 P 0 ;1
L 12.0075 3.9575 12.0075 3.9575 27 P 0 ;1
L 12.0075 4.4575 12.0075 4.4575 27 P 0 ;1
L 12.0075 4.5075 12.0075 4.5075 27 P 0 ;1
L 12.0075 4.5575 12.0075 4.5575 27 P 0 ;1
L 12.0075 4.6075 12.0075 4.6075 27 P 0 ;1
L 12.0075 4.6575 12.0075 4.6575 27 P 0 ;1
L 12.0575 0.4575 12.0575 0.4575 27 P 0 ;1
L 12.0575 0.5075 12.0575 0.5075 27 P 0 ;1
L 12.0575 0.5575 12.0575 0.5575 27 P 0 ;1
L 12.0575 0.6075 12.0575 0.6075 27 P 0 ;1
L 12.0575 0.6575 12.0575 0.6575 27 P 0 ;1
L 12.0575 0.7075 12.0575 0.7075 27 P 0 ;1
L 12.0575 0.7575 12.0575 0.7575 27 P 0 ;1
L 12.0575 0.8075 12.0575 0.8075 27 P 0 ;1
L 12.0575 0.8575 12.0575 0.8575 27 P 0 ;1
L 12.0575 0.9075 12.0575 0.9075 27 P 0 ;1
L 12.0575 0.9575 12.0575 0.9575 27 P 0 ;1
L 12.0575 1.0075 12.0575 1.0075 27 P 0 ;1
L 12.0575 1.0575 12.0575 1.0575 27 P 0 ;1
L 12.0575 1.1075 12.0575 1.1075 27 P 0 ;1
L 12.0575 1.1575 12.0575 1.1575 27 P 0 ;1
L 12.0575 1.2075 12.0575 1.2075 27 P 0 ;1
L 12.0575 1.2575 12.0575 1.2575 27 P 0 ;1
L 12.0575 1.8075 12.0575 1.8075 27 P 0 ;1
L 12.0575 1.8575 12.0575 1.8575 27 P 0 ;1
L 12.0575 1.9075 12.0575 1.9075 27 P 0 ;1
L 12.0575 1.9575 12.0575 1.9575 27 P 0 ;1
L 12.0575 2.0075 12.0575 2.0075 27 P 0 ;1
L 12.0575 2.0575 12.0575 2.0575 27 P 0 ;1
L 12.0575 2.1075 12.0575 2.1075 27 P 0 ;1
L 12.0575 2.1575 12.0575 2.1575 27 P 0 ;1
L 12.0575 2.2075 12.0575 2.2075 27 P 0 ;1
L 12.0575 2.2575 12.0575 2.2575 27 P 0 ;1
L 12.0575 2.3075 12.0575 2.3075 27 P 0 ;1
L 12.0575 2.3575 12.0575 2.3575 27 P 0 ;1
L 12.0575 2.4075 12.0575 2.4075 27 P 0 ;1
L 12.0575 2.7575 12.0575 2.7575 27 P 0 ;1
L 12.0575 2.8075 12.0575 2.8075 27 P 0 ;1
L 12.0575 2.8575 12.0575 2.8575 27 P 0 ;1
L 12.0575 2.9075 12.0575 2.9075 27 P 0 ;1
L 12.0575 2.9575 12.0575 2.9575 27 P 0 ;1
L 12.0575 3.0075 12.0575 3.0075 27 P 0 ;1
L 12.0575 3.0575 12.0575 3.0575 27 P 0 ;1
L 12.0575 3.1075 12.0575 3.1075 27 P 0 ;1
L 12.0575 3.1575 12.0575 3.1575 27 P 0 ;1
L 12.0575 3.2075 12.0575 3.2075 27 P 0 ;1
L 12.0575 3.2575 12.0575 3.2575 27 P 0 ;1
L 12.0575 3.3075 12.0575 3.3075 27 P 0 ;1
L 12.0575 3.3575 12.0575 3.3575 27 P 0 ;1
L 12.0575 3.4075 12.0575 3.4075 27 P 0 ;1
L 12.0575 3.4575 12.0575 3.4575 27 P 0 ;1
L 12.0575 3.5075 12.0575 3.5075 27 P 0 ;1
L 12.0575 3.5575 12.0575 3.5575 27 P 0 ;1
L 12.0575 3.6075 12.0575 3.6075 27 P 0 ;1
L 12.0575 3.6575 12.0575 3.6575 27 P 0 ;1
L 12.0575 3.7075 12.0575 3.7075 27 P 0 ;1
L 12.0575 3.7575 12.0575 3.7575 27 P 0 ;1
L 12.0575 3.8075 12.0575 3.8075 27 P 0 ;1
L 12.0575 3.8575 12.0575 3.8575 27 P 0 ;1
L 12.0575 3.9075 12.0575 3.9075 27 P 0 ;1
L 12.0575 3.9575 12.0575 3.9575 27 P 0 ;1
L 12.0575 4.4575 12.0575 4.4575 27 P 0 ;1
L 12.0575 4.5075 12.0575 4.5075 27 P 0 ;1
L 12.0575 4.5575 12.0575 4.5575 27 P 0 ;1
L 12.0575 4.6075 12.0575 4.6075 27 P 0 ;1
L 12.0575 4.6575 12.0575 4.6575 27 P 0 ;1
L 12.0575 4.7075 12.0575 4.7075 27 P 0 ;1
L 12.1075 0.1575 12.1075 0.1575 27 P 0 ;1
L 12.1075 0.4575 12.1075 0.4575 27 P 0 ;1
L 12.1075 0.5075 12.1075 0.5075 27 P 0 ;1
L 12.1075 0.5575 12.1075 0.5575 27 P 0 ;1
L 12.1075 0.6075 12.1075 0.6075 27 P 0 ;1
L 12.1075 0.6575 12.1075 0.6575 27 P 0 ;1
L 12.1075 0.7075 12.1075 0.7075 27 P 0 ;1
L 12.1075 0.7575 12.1075 0.7575 27 P 0 ;1
L 12.1075 0.8075 12.1075 0.8075 27 P 0 ;1
L 12.1075 0.8575 12.1075 0.8575 27 P 0 ;1
L 12.1075 0.9075 12.1075 0.9075 27 P 0 ;1
L 12.1075 0.9575 12.1075 0.9575 27 P 0 ;1
L 12.1075 1.0075 12.1075 1.0075 27 P 0 ;1
L 12.1075 1.0575 12.1075 1.0575 27 P 0 ;1
L 12.1075 1.1075 12.1075 1.1075 27 P 0 ;1
L 12.1075 1.1575 12.1075 1.1575 27 P 0 ;1
L 12.1075 1.2075 12.1075 1.2075 27 P 0 ;1
L 12.1075 1.2575 12.1075 1.2575 27 P 0 ;1
L 12.1075 1.8075 12.1075 1.8075 27 P 0 ;1
L 12.1075 1.8575 12.1075 1.8575 27 P 0 ;1
L 12.1075 1.9075 12.1075 1.9075 27 P 0 ;1
L 12.1075 1.9575 12.1075 1.9575 27 P 0 ;1
L 12.1075 2.0075 12.1075 2.0075 27 P 0 ;1
L 12.1075 2.0575 12.1075 2.0575 27 P 0 ;1
L 12.1075 2.1075 12.1075 2.1075 27 P 0 ;1
L 12.1075 2.1575 12.1075 2.1575 27 P 0 ;1
L 12.1075 2.2075 12.1075 2.2075 27 P 0 ;1
L 12.1075 2.2575 12.1075 2.2575 27 P 0 ;1
L 12.1075 2.3075 12.1075 2.3075 27 P 0 ;1
L 12.1075 2.3575 12.1075 2.3575 27 P 0 ;1
L 12.1075 2.4075 12.1075 2.4075 27 P 0 ;1
L 12.1075 2.7575 12.1075 2.7575 27 P 0 ;1
L 12.1075 2.8075 12.1075 2.8075 27 P 0 ;1
L 12.1075 2.8575 12.1075 2.8575 27 P 0 ;1
L 12.1075 2.9075 12.1075 2.9075 27 P 0 ;1
L 12.1075 2.9575 12.1075 2.9575 27 P 0 ;1
L 12.1075 3.0075 12.1075 3.0075 27 P 0 ;1
L 12.1075 3.0575 12.1075 3.0575 27 P 0 ;1
L 12.1075 3.1075 12.1075 3.1075 27 P 0 ;1
L 12.1075 3.1575 12.1075 3.1575 27 P 0 ;1
L 12.1075 3.2075 12.1075 3.2075 27 P 0 ;1
L 12.1075 3.2575 12.1075 3.2575 27 P 0 ;1
L 12.1075 3.3075 12.1075 3.3075 27 P 0 ;1
L 12.1075 3.3575 12.1075 3.3575 27 P 0 ;1
L 12.1075 3.4075 12.1075 3.4075 27 P 0 ;1
L 12.1075 3.4575 12.1075 3.4575 27 P 0 ;1
L 12.1075 3.5075 12.1075 3.5075 27 P 0 ;1
L 12.1075 3.5575 12.1075 3.5575 27 P 0 ;1
L 12.1075 3.6075 12.1075 3.6075 27 P 0 ;1
L 12.1075 3.6575 12.1075 3.6575 27 P 0 ;1
L 12.1075 3.7075 12.1075 3.7075 27 P 0 ;1
L 12.1075 3.7575 12.1075 3.7575 27 P 0 ;1
L 12.1075 3.8075 12.1075 3.8075 27 P 0 ;1
L 12.1075 3.8575 12.1075 3.8575 27 P 0 ;1
L 12.1075 3.9075 12.1075 3.9075 27 P 0 ;1
L 12.1075 3.9575 12.1075 3.9575 27 P 0 ;1
L 12.1075 4.4575 12.1075 4.4575 27 P 0 ;1
L 12.1075 4.5075 12.1075 4.5075 27 P 0 ;1
L 12.1075 4.5575 12.1075 4.5575 27 P 0 ;1
L 12.1075 4.6075 12.1075 4.6075 27 P 0 ;1
L 12.1075 4.6575 12.1075 4.6575 27 P 0 ;1
L 12.1075 4.7075 12.1075 4.7075 27 P 0 ;1
L 12.1075 4.7575 12.1075 4.7575 27 P 0 ;1
L 12.1075 4.8075 12.1075 4.8075 27 P 0 ;1
L 12.1575 0.1575 12.1575 0.1575 27 P 0 ;1
L 12.1575 0.4075 12.1575 0.4075 27 P 0 ;1
L 12.1575 0.4575 12.1575 0.4575 27 P 0 ;1
L 12.1575 0.5075 12.1575 0.5075 27 P 0 ;1
L 12.1575 0.5575 12.1575 0.5575 27 P 0 ;1
L 12.1575 0.6075 12.1575 0.6075 27 P 0 ;1
L 12.1575 0.6575 12.1575 0.6575 27 P 0 ;1
L 12.1575 0.7075 12.1575 0.7075 27 P 0 ;1
L 12.1575 0.7575 12.1575 0.7575 27 P 0 ;1
L 12.1575 0.8075 12.1575 0.8075 27 P 0 ;1
L 12.1575 0.8575 12.1575 0.8575 27 P 0 ;1
L 12.1575 0.9075 12.1575 0.9075 27 P 0 ;1
L 12.1575 0.9575 12.1575 0.9575 27 P 0 ;1
L 12.1575 1.0075 12.1575 1.0075 27 P 0 ;1
L 12.1575 1.0575 12.1575 1.0575 27 P 0 ;1
L 12.1575 1.1075 12.1575 1.1075 27 P 0 ;1
L 12.1575 1.1575 12.1575 1.1575 27 P 0 ;1
L 12.1575 1.2075 12.1575 1.2075 27 P 0 ;1
L 12.1575 1.2575 12.1575 1.2575 27 P 0 ;1
L 12.1575 1.8075 12.1575 1.8075 27 P 0 ;1
L 12.1575 1.8575 12.1575 1.8575 27 P 0 ;1
L 12.1575 1.9075 12.1575 1.9075 27 P 0 ;1
L 12.1575 1.9575 12.1575 1.9575 27 P 0 ;1
L 12.1575 2.0075 12.1575 2.0075 27 P 0 ;1
L 12.1575 2.0575 12.1575 2.0575 27 P 0 ;1
L 12.1575 2.1075 12.1575 2.1075 27 P 0 ;1
L 12.1575 2.1575 12.1575 2.1575 27 P 0 ;1
L 12.1575 2.2075 12.1575 2.2075 27 P 0 ;1
L 12.1575 2.2575 12.1575 2.2575 27 P 0 ;1
L 12.1575 2.3075 12.1575 2.3075 27 P 0 ;1
L 12.1575 2.3575 12.1575 2.3575 27 P 0 ;1
L 12.1575 2.4075 12.1575 2.4075 27 P 0 ;1
L 12.1575 2.4575 12.1575 2.4575 27 P 0 ;1
L 12.1575 2.7075 12.1575 2.7075 27 P 0 ;1
L 12.1575 2.7575 12.1575 2.7575 27 P 0 ;1
L 12.1575 2.8075 12.1575 2.8075 27 P 0 ;1
L 12.1575 2.8575 12.1575 2.8575 27 P 0 ;1
L 12.1575 2.9075 12.1575 2.9075 27 P 0 ;1
L 12.1575 2.9575 12.1575 2.9575 27 P 0 ;1
L 12.1575 3.0075 12.1575 3.0075 27 P 0 ;1
L 12.1575 3.0575 12.1575 3.0575 27 P 0 ;1
L 12.1575 3.1075 12.1575 3.1075 27 P 0 ;1
L 12.1575 3.1575 12.1575 3.1575 27 P 0 ;1
L 12.1575 3.2075 12.1575 3.2075 27 P 0 ;1
L 12.1575 3.2575 12.1575 3.2575 27 P 0 ;1
L 12.1575 3.3075 12.1575 3.3075 27 P 0 ;1
L 12.1575 3.3575 12.1575 3.3575 27 P 0 ;1
L 12.1575 3.4075 12.1575 3.4075 27 P 0 ;1
L 12.1575 3.4575 12.1575 3.4575 27 P 0 ;1
L 12.1575 3.5075 12.1575 3.5075 27 P 0 ;1
L 12.1575 3.5575 12.1575 3.5575 27 P 0 ;1
L 12.1575 3.6075 12.1575 3.6075 27 P 0 ;1
L 12.1575 3.6575 12.1575 3.6575 27 P 0 ;1
L 12.1575 3.7075 12.1575 3.7075 27 P 0 ;1
L 12.1575 3.7575 12.1575 3.7575 27 P 0 ;1
L 12.1575 3.8075 12.1575 3.8075 27 P 0 ;1
L 12.1575 3.8575 12.1575 3.8575 27 P 0 ;1
L 12.1575 3.9075 12.1575 3.9075 27 P 0 ;1
L 12.1575 3.9575 12.1575 3.9575 27 P 0 ;1
L 12.1575 4.4575 12.1575 4.4575 27 P 0 ;1
L 12.1575 4.5075 12.1575 4.5075 27 P 0 ;1
L 12.1575 4.5575 12.1575 4.5575 27 P 0 ;1
L 12.1575 4.6075 12.1575 4.6075 27 P 0 ;1
L 12.1575 4.6575 12.1575 4.6575 27 P 0 ;1
L 12.1575 4.7075 12.1575 4.7075 27 P 0 ;1
L 12.1575 4.7575 12.1575 4.7575 27 P 0 ;1
L 12.1575 4.8075 12.1575 4.8075 27 P 0 ;1
L 12.2075 0.4575 12.2075 0.4575 27 P 0 ;1
L 12.2075 0.5075 12.2075 0.5075 27 P 0 ;1
L 12.2075 0.5575 12.2075 0.5575 27 P 0 ;1
L 12.2075 0.6075 12.2075 0.6075 27 P 0 ;1
L 12.2075 0.6575 12.2075 0.6575 27 P 0 ;1
L 12.2075 0.7075 12.2075 0.7075 27 P 0 ;1
L 12.2075 0.7575 12.2075 0.7575 27 P 0 ;1
L 12.2075 0.8075 12.2075 0.8075 27 P 0 ;1
L 12.2075 0.8575 12.2075 0.8575 27 P 0 ;1
L 12.2075 0.9075 12.2075 0.9075 27 P 0 ;1
L 12.2075 0.9575 12.2075 0.9575 27 P 0 ;1
L 12.2075 1.0075 12.2075 1.0075 27 P 0 ;1
L 12.2075 1.0575 12.2075 1.0575 27 P 0 ;1
L 12.2075 1.1075 12.2075 1.1075 27 P 0 ;1
L 12.2075 1.1575 12.2075 1.1575 27 P 0 ;1
L 12.2075 1.2075 12.2075 1.2075 27 P 0 ;1
L 12.2075 1.2575 12.2075 1.2575 27 P 0 ;1
L 12.2075 1.7575 12.2075 1.7575 27 P 0 ;1
L 12.2075 1.8075 12.2075 1.8075 27 P 0 ;1
L 12.2075 1.8575 12.2075 1.8575 27 P 0 ;1
L 12.2075 1.9075 12.2075 1.9075 27 P 0 ;1
L 12.2075 1.9575 12.2075 1.9575 27 P 0 ;1
L 12.2075 2.0075 12.2075 2.0075 27 P 0 ;1
L 12.2075 2.0575 12.2075 2.0575 27 P 0 ;1
L 12.2075 2.1075 12.2075 2.1075 27 P 0 ;1
L 12.2075 2.1575 12.2075 2.1575 27 P 0 ;1
L 12.2075 2.2075 12.2075 2.2075 27 P 0 ;1
L 12.2075 2.2575 12.2075 2.2575 27 P 0 ;1
L 12.2075 2.3075 12.2075 2.3075 27 P 0 ;1
L 12.2075 2.3575 12.2075 2.3575 27 P 0 ;1
L 12.2075 2.4075 12.2075 2.4075 27 P 0 ;1
L 12.2075 2.4575 12.2075 2.4575 27 P 0 ;1
L 12.2075 2.5075 12.2075 2.5075 27 P 0 ;1
L 12.2075 2.5575 12.2075 2.5575 27 P 0 ;1
L 12.2075 2.6075 12.2075 2.6075 27 P 0 ;1
L 12.2075 2.6575 12.2075 2.6575 27 P 0 ;1
L 12.2075 2.7075 12.2075 2.7075 27 P 0 ;1
L 12.2075 2.7575 12.2075 2.7575 27 P 0 ;1
L 12.2075 2.8075 12.2075 2.8075 27 P 0 ;1
L 12.2075 2.8575 12.2075 2.8575 27 P 0 ;1
L 12.2075 2.9075 12.2075 2.9075 27 P 0 ;1
L 12.2075 2.9575 12.2075 2.9575 27 P 0 ;1
L 12.2075 3.0075 12.2075 3.0075 27 P 0 ;1
L 12.2075 3.0575 12.2075 3.0575 27 P 0 ;1
L 12.2075 3.1075 12.2075 3.1075 27 P 0 ;1
L 12.2075 3.1575 12.2075 3.1575 27 P 0 ;1
L 12.2075 3.2075 12.2075 3.2075 27 P 0 ;1
L 12.2075 3.2575 12.2075 3.2575 27 P 0 ;1
L 12.2075 3.3075 12.2075 3.3075 27 P 0 ;1
L 12.2075 3.3575 12.2075 3.3575 27 P 0 ;1
L 12.2075 3.4075 12.2075 3.4075 27 P 0 ;1
L 12.2075 3.4575 12.2075 3.4575 27 P 0 ;1
L 12.2075 3.5075 12.2075 3.5075 27 P 0 ;1
L 12.2075 3.5575 12.2075 3.5575 27 P 0 ;1
L 12.2075 3.6075 12.2075 3.6075 27 P 0 ;1
L 12.2075 3.6575 12.2075 3.6575 27 P 0 ;1
L 12.2075 3.7075 12.2075 3.7075 27 P 0 ;1
L 12.2075 3.7575 12.2075 3.7575 27 P 0 ;1
L 12.2075 3.8075 12.2075 3.8075 27 P 0 ;1
L 12.2075 3.8575 12.2075 3.8575 27 P 0 ;1
L 12.2075 3.9075 12.2075 3.9075 27 P 0 ;1
L 12.2075 3.9575 12.2075 3.9575 27 P 0 ;1
L 12.2075 4.4575 12.2075 4.4575 27 P 0 ;1
L 12.2075 4.5075 12.2075 4.5075 27 P 0 ;1
L 12.2075 4.5575 12.2075 4.5575 27 P 0 ;1
L 12.2075 4.6075 12.2075 4.6075 27 P 0 ;1
L 12.2075 4.6575 12.2075 4.6575 27 P 0 ;1
L 12.2075 4.7075 12.2075 4.7075 27 P 0 ;1
L 12.2075 4.7575 12.2075 4.7575 27 P 0 ;1
L 12.2075 4.8075 12.2075 4.8075 27 P 0 ;1
L 12.2575 0.4575 12.2575 0.4575 27 P 0 ;1
L 12.2575 0.5075 12.2575 0.5075 27 P 0 ;1
L 12.2575 0.5575 12.2575 0.5575 27 P 0 ;1
L 12.2575 0.6075 12.2575 0.6075 27 P 0 ;1
L 12.2575 0.6575 12.2575 0.6575 27 P 0 ;1
L 12.2575 0.7075 12.2575 0.7075 27 P 0 ;1
L 12.2575 0.7575 12.2575 0.7575 27 P 0 ;1
L 12.2575 0.8075 12.2575 0.8075 27 P 0 ;1
L 12.2575 0.8575 12.2575 0.8575 27 P 0 ;1
L 12.2575 0.9075 12.2575 0.9075 27 P 0 ;1
L 12.2575 0.9575 12.2575 0.9575 27 P 0 ;1
L 12.2575 1.0075 12.2575 1.0075 27 P 0 ;1
L 12.2575 1.0575 12.2575 1.0575 27 P 0 ;1
L 12.2575 1.1075 12.2575 1.1075 27 P 0 ;1
L 12.2575 1.1575 12.2575 1.1575 27 P 0 ;1
L 12.2575 1.2075 12.2575 1.2075 27 P 0 ;1
L 12.2575 1.2575 12.2575 1.2575 27 P 0 ;1
L 12.2575 1.3075 12.2575 1.3075 27 P 0 ;1
L 12.2575 1.7575 12.2575 1.7575 27 P 0 ;1
L 12.2575 1.8075 12.2575 1.8075 27 P 0 ;1
L 12.2575 1.8575 12.2575 1.8575 27 P 0 ;1
L 12.2575 1.9075 12.2575 1.9075 27 P 0 ;1
L 12.2575 1.9575 12.2575 1.9575 27 P 0 ;1
L 12.2575 2.0075 12.2575 2.0075 27 P 0 ;1
L 12.2575 2.0575 12.2575 2.0575 27 P 0 ;1
L 12.2575 2.1075 12.2575 2.1075 27 P 0 ;1
L 12.2575 2.2575 12.2575 2.2575 27 P 0 ;1
L 12.2575 2.3075 12.2575 2.3075 27 P 0 ;1
L 12.2575 2.3575 12.2575 2.3575 27 P 0 ;1
L 12.2575 2.4075 12.2575 2.4075 27 P 0 ;1
L 12.2575 2.4575 12.2575 2.4575 27 P 0 ;1
L 12.2575 2.5075 12.2575 2.5075 27 P 0 ;1
L 12.2575 2.5575 12.2575 2.5575 27 P 0 ;1
L 12.2575 2.6075 12.2575 2.6075 27 P 0 ;1
L 12.2575 2.6575 12.2575 2.6575 27 P 0 ;1
L 12.2575 2.7075 12.2575 2.7075 27 P 0 ;1
L 12.2575 2.7575 12.2575 2.7575 27 P 0 ;1
L 12.2575 2.8075 12.2575 2.8075 27 P 0 ;1
L 12.2575 2.8575 12.2575 2.8575 27 P 0 ;1
L 12.2575 2.9075 12.2575 2.9075 27 P 0 ;1
L 12.2575 2.9575 12.2575 2.9575 27 P 0 ;1
L 12.2575 3.0075 12.2575 3.0075 27 P 0 ;1
L 12.2575 3.0575 12.2575 3.0575 27 P 0 ;1
L 12.2575 3.1075 12.2575 3.1075 27 P 0 ;1
L 12.2575 3.1575 12.2575 3.1575 27 P 0 ;1
L 12.2575 3.2075 12.2575 3.2075 27 P 0 ;1
L 12.2575 3.2575 12.2575 3.2575 27 P 0 ;1
L 12.2575 3.3075 12.2575 3.3075 27 P 0 ;1
L 12.2575 3.3575 12.2575 3.3575 27 P 0 ;1
L 12.2575 3.4075 12.2575 3.4075 27 P 0 ;1
L 12.2575 3.4575 12.2575 3.4575 27 P 0 ;1
L 12.2575 3.5075 12.2575 3.5075 27 P 0 ;1
L 12.2575 3.5575 12.2575 3.5575 27 P 0 ;1
L 12.2575 3.6075 12.2575 3.6075 27 P 0 ;1
L 12.2575 3.6575 12.2575 3.6575 27 P 0 ;1
L 12.2575 3.7075 12.2575 3.7075 27 P 0 ;1
L 12.2575 3.7575 12.2575 3.7575 27 P 0 ;1
L 12.2575 3.8075 12.2575 3.8075 27 P 0 ;1
L 12.2575 3.8575 12.2575 3.8575 27 P 0 ;1
L 12.2575 3.9075 12.2575 3.9075 27 P 0 ;1
L 12.2575 3.9575 12.2575 3.9575 27 P 0 ;1
L 12.2575 4.4075 12.2575 4.4075 27 P 0 ;1
L 12.2575 4.4575 12.2575 4.4575 27 P 0 ;1
L 12.2575 4.5075 12.2575 4.5075 27 P 0 ;1
L 12.2575 4.5575 12.2575 4.5575 27 P 0 ;1
L 12.2575 4.6075 12.2575 4.6075 27 P 0 ;1
L 12.2575 4.6575 12.2575 4.6575 27 P 0 ;1
L 12.2575 4.7075 12.2575 4.7075 27 P 0 ;1
L 12.2575 4.7575 12.2575 4.7575 27 P 0 ;1
L 12.2575 4.8075 12.2575 4.8075 27 P 0 ;1
L 12.3075 0.4575 12.3075 0.4575 27 P 0 ;1
L 12.3075 0.5075 12.3075 0.5075 27 P 0 ;1
L 12.3075 0.5575 12.3075 0.5575 27 P 0 ;1
L 12.3075 0.6075 12.3075 0.6075 27 P 0 ;1
L 12.3075 0.6575 12.3075 0.6575 27 P 0 ;1
L 12.3075 0.7075 12.3075 0.7075 27 P 0 ;1
L 12.3075 0.7575 12.3075 0.7575 27 P 0 ;1
L 12.3075 0.8075 12.3075 0.8075 27 P 0 ;1
L 12.3075 0.8575 12.3075 0.8575 27 P 0 ;1
L 12.3075 0.9075 12.3075 0.9075 27 P 0 ;1
L 12.3075 0.9575 12.3075 0.9575 27 P 0 ;1
L 12.3075 1.0075 12.3075 1.0075 27 P 0 ;1
L 12.3075 1.0575 12.3075 1.0575 27 P 0 ;1
L 12.3075 1.1075 12.3075 1.1075 27 P 0 ;1
L 12.3075 1.1575 12.3075 1.1575 27 P 0 ;1
L 12.3075 1.2075 12.3075 1.2075 27 P 0 ;1
L 12.3075 1.2575 12.3075 1.2575 27 P 0 ;1
L 12.3075 1.3075 12.3075 1.3075 27 P 0 ;1
L 12.3075 1.3575 12.3075 1.3575 27 P 0 ;1
L 12.3075 1.7075 12.3075 1.7075 27 P 0 ;1
L 12.3075 1.7575 12.3075 1.7575 27 P 0 ;1
L 12.3075 1.8075 12.3075 1.8075 27 P 0 ;1
L 12.3075 1.8575 12.3075 1.8575 27 P 0 ;1
L 12.3075 1.9075 12.3075 1.9075 27 P 0 ;1
L 12.3075 1.9575 12.3075 1.9575 27 P 0 ;1
L 12.3075 2.0075 12.3075 2.0075 27 P 0 ;1
L 12.3075 2.0575 12.3075 2.0575 27 P 0 ;1
L 12.3075 2.3075 12.3075 2.3075 27 P 0 ;1
L 12.3075 2.3575 12.3075 2.3575 27 P 0 ;1
L 12.3075 2.4075 12.3075 2.4075 27 P 0 ;1
L 12.3075 2.4575 12.3075 2.4575 27 P 0 ;1
L 12.3075 2.5075 12.3075 2.5075 27 P 0 ;1
L 12.3075 2.5575 12.3075 2.5575 27 P 0 ;1
L 12.3075 2.6075 12.3075 2.6075 27 P 0 ;1
L 12.3075 2.6575 12.3075 2.6575 27 P 0 ;1
L 12.3075 2.7075 12.3075 2.7075 27 P 0 ;1
L 12.3075 2.7575 12.3075 2.7575 27 P 0 ;1
L 12.3075 2.8075 12.3075 2.8075 27 P 0 ;1
L 12.3075 2.8575 12.3075 2.8575 27 P 0 ;1
L 12.3075 2.9075 12.3075 2.9075 27 P 0 ;1
L 12.3075 2.9575 12.3075 2.9575 27 P 0 ;1
L 12.3075 3.0075 12.3075 3.0075 27 P 0 ;1
L 12.3075 3.0575 12.3075 3.0575 27 P 0 ;1
L 12.3075 3.1075 12.3075 3.1075 27 P 0 ;1
L 12.3075 3.1575 12.3075 3.1575 27 P 0 ;1
L 12.3075 3.2075 12.3075 3.2075 27 P 0 ;1
L 12.3075 3.2575 12.3075 3.2575 27 P 0 ;1
L 12.3075 3.3075 12.3075 3.3075 27 P 0 ;1
L 12.3075 3.3575 12.3075 3.3575 27 P 0 ;1
L 12.3075 3.4075 12.3075 3.4075 27 P 0 ;1
L 12.3075 3.4575 12.3075 3.4575 27 P 0 ;1
L 12.3075 3.5075 12.3075 3.5075 27 P 0 ;1
L 12.3075 3.5575 12.3075 3.5575 27 P 0 ;1
L 12.3075 3.6075 12.3075 3.6075 27 P 0 ;1
L 12.3075 3.6575 12.3075 3.6575 27 P 0 ;1
L 12.3075 3.7075 12.3075 3.7075 27 P 0 ;1
L 12.3075 3.7575 12.3075 3.7575 27 P 0 ;1
L 12.3075 3.8075 12.3075 3.8075 27 P 0 ;1
L 12.3075 3.8575 12.3075 3.8575 27 P 0 ;1
L 12.3075 3.9075 12.3075 3.9075 27 P 0 ;1
L 12.3075 3.9575 12.3075 3.9575 27 P 0 ;1
L 12.3075 4.0075 12.3075 4.0075 27 P 0 ;1
L 12.3075 4.4075 12.3075 4.4075 27 P 0 ;1
L 12.3075 4.4575 12.3075 4.4575 27 P 0 ;1
L 12.3075 4.5075 12.3075 4.5075 27 P 0 ;1
L 12.3075 4.5575 12.3075 4.5575 27 P 0 ;1
L 12.3075 4.6075 12.3075 4.6075 27 P 0 ;1
L 12.3075 4.6575 12.3075 4.6575 27 P 0 ;1
L 12.3075 4.7075 12.3075 4.7075 27 P 0 ;1
L 12.3075 4.7575 12.3075 4.7575 27 P 0 ;1
L 12.3075 4.8075 12.3075 4.8075 27 P 0 ;1
L 12.3075 4.8575 12.3075 4.8575 27 P 0 ;1
L 12.3575 0.1575 12.3575 0.1575 27 P 0 ;1
L 12.3575 0.4575 12.3575 0.4575 27 P 0 ;1
L 12.3575 0.5075 12.3575 0.5075 27 P 0 ;1
L 12.3575 0.5575 12.3575 0.5575 27 P 0 ;1
L 12.3575 0.6075 12.3575 0.6075 27 P 0 ;1
L 12.3575 0.6575 12.3575 0.6575 27 P 0 ;1
L 12.3575 0.7075 12.3575 0.7075 27 P 0 ;1
L 12.3575 0.7575 12.3575 0.7575 27 P 0 ;1
L 12.3575 0.8075 12.3575 0.8075 27 P 0 ;1
L 12.3575 0.8575 12.3575 0.8575 27 P 0 ;1
L 12.3575 0.9075 12.3575 0.9075 27 P 0 ;1
L 12.3575 0.9575 12.3575 0.9575 27 P 0 ;1
L 12.3575 1.0075 12.3575 1.0075 27 P 0 ;1
L 12.3575 1.0575 12.3575 1.0575 27 P 0 ;1
L 12.3575 1.1075 12.3575 1.1075 27 P 0 ;1
L 12.3575 1.1575 12.3575 1.1575 27 P 0 ;1
L 12.3575 1.2075 12.3575 1.2075 27 P 0 ;1
L 12.3575 1.2575 12.3575 1.2575 27 P 0 ;1
L 12.3575 1.3075 12.3575 1.3075 27 P 0 ;1
L 12.3575 1.3575 12.3575 1.3575 27 P 0 ;1
L 12.3575 1.4075 12.3575 1.4075 27 P 0 ;1
L 12.3575 1.4575 12.3575 1.4575 27 P 0 ;1
L 12.3575 1.6075 12.3575 1.6075 27 P 0 ;1
L 12.3575 1.6575 12.3575 1.6575 27 P 0 ;1
L 12.3575 1.7075 12.3575 1.7075 27 P 0 ;1
L 12.3575 1.7575 12.3575 1.7575 27 P 0 ;1
L 12.3575 1.8075 12.3575 1.8075 27 P 0 ;1
L 12.3575 1.8575 12.3575 1.8575 27 P 0 ;1
L 12.3575 1.9075 12.3575 1.9075 27 P 0 ;1
L 12.3575 1.9575 12.3575 1.9575 27 P 0 ;1
L 12.3575 2.0075 12.3575 2.0075 27 P 0 ;1
L 12.3575 2.0575 12.3575 2.0575 27 P 0 ;1
L 12.3575 2.3075 12.3575 2.3075 27 P 0 ;1
L 12.3575 2.3575 12.3575 2.3575 27 P 0 ;1
L 12.3575 2.4075 12.3575 2.4075 27 P 0 ;1
L 12.3575 2.4575 12.3575 2.4575 27 P 0 ;1
L 12.3575 2.5075 12.3575 2.5075 27 P 0 ;1
L 12.3575 2.5575 12.3575 2.5575 27 P 0 ;1
L 12.3575 2.6075 12.3575 2.6075 27 P 0 ;1
L 12.3575 2.6575 12.3575 2.6575 27 P 0 ;1
L 12.3575 2.7075 12.3575 2.7075 27 P 0 ;1
L 12.3575 2.7575 12.3575 2.7575 27 P 0 ;1
L 12.3575 2.8075 12.3575 2.8075 27 P 0 ;1
L 12.3575 2.8575 12.3575 2.8575 27 P 0 ;1
L 12.3575 2.9075 12.3575 2.9075 27 P 0 ;1
L 12.3575 2.9575 12.3575 2.9575 27 P 0 ;1
L 12.3575 3.0075 12.3575 3.0075 27 P 0 ;1
L 12.3575 3.0575 12.3575 3.0575 27 P 0 ;1
L 12.3575 3.1075 12.3575 3.1075 27 P 0 ;1
L 12.3575 3.1575 12.3575 3.1575 27 P 0 ;1
L 12.3575 3.2075 12.3575 3.2075 27 P 0 ;1
L 12.3575 3.2575 12.3575 3.2575 27 P 0 ;1
L 12.3575 3.3075 12.3575 3.3075 27 P 0 ;1
L 12.3575 3.3575 12.3575 3.3575 27 P 0 ;1
L 12.3575 3.4075 12.3575 3.4075 27 P 0 ;1
L 12.3575 3.4575 12.3575 3.4575 27 P 0 ;1
L 12.3575 3.5075 12.3575 3.5075 27 P 0 ;1
L 12.3575 3.5575 12.3575 3.5575 27 P 0 ;1
L 12.3575 3.6075 12.3575 3.6075 27 P 0 ;1
L 12.3575 3.6575 12.3575 3.6575 27 P 0 ;1
L 12.3575 3.7075 12.3575 3.7075 27 P 0 ;1
L 12.3575 3.7575 12.3575 3.7575 27 P 0 ;1
L 12.3575 3.8075 12.3575 3.8075 27 P 0 ;1
L 12.3575 3.8575 12.3575 3.8575 27 P 0 ;1
L 12.3575 3.9075 12.3575 3.9075 27 P 0 ;1
L 12.3575 3.9575 12.3575 3.9575 27 P 0 ;1
L 12.3575 4.0075 12.3575 4.0075 27 P 0 ;1
L 12.3575 4.0575 12.3575 4.0575 27 P 0 ;1
L 12.3575 4.1075 12.3575 4.1075 27 P 0 ;1
L 12.3575 4.3075 12.3575 4.3075 27 P 0 ;1
L 12.3575 4.3575 12.3575 4.3575 27 P 0 ;1
L 12.3575 4.4075 12.3575 4.4075 27 P 0 ;1
L 12.3575 4.4575 12.3575 4.4575 27 P 0 ;1
L 12.3575 4.5075 12.3575 4.5075 27 P 0 ;1
L 12.3575 4.5575 12.3575 4.5575 27 P 0 ;1
L 12.3575 4.6075 12.3575 4.6075 27 P 0 ;1
L 12.3575 4.6575 12.3575 4.6575 27 P 0 ;1
L 12.3575 4.7075 12.3575 4.7075 27 P 0 ;1
L 12.3575 4.7575 12.3575 4.7575 27 P 0 ;1
L 12.3575 4.8075 12.3575 4.8075 27 P 0 ;1
L 12.3575 4.8575 12.3575 4.8575 27 P 0 ;1
L 12.3575 4.9075 12.3575 4.9075 27 P 0 ;1
L 12.3575 4.9575 12.3575 4.9575 27 P 0 ;1
L 12.3575 5.0075 12.3575 5.0075 27 P 0 ;1
L 12.4075 0.1575 12.4075 0.1575 27 P 0 ;1
L 12.4075 0.2075 12.4075 0.2075 27 P 0 ;1
L 12.4075 0.3575 12.4075 0.3575 27 P 0 ;1
L 12.4075 0.4075 12.4075 0.4075 27 P 0 ;1
L 12.4075 0.4575 12.4075 0.4575 27 P 0 ;1
L 12.4075 0.5075 12.4075 0.5075 27 P 0 ;1
L 12.4075 0.5575 12.4075 0.5575 27 P 0 ;1
L 12.4075 0.6075 12.4075 0.6075 27 P 0 ;1
L 12.4075 0.6575 12.4075 0.6575 27 P 0 ;1
L 12.4075 0.7075 12.4075 0.7075 27 P 0 ;1
L 12.4075 0.7575 12.4075 0.7575 27 P 0 ;1
L 12.4075 0.8075 12.4075 0.8075 27 P 0 ;1
L 12.4075 0.8575 12.4075 0.8575 27 P 0 ;1
L 12.4075 0.9075 12.4075 0.9075 27 P 0 ;1
L 12.4075 0.9575 12.4075 0.9575 27 P 0 ;1
L 12.4075 1.0075 12.4075 1.0075 27 P 0 ;1
L 12.4075 1.0575 12.4075 1.0575 27 P 0 ;1
L 12.4075 1.1075 12.4075 1.1075 27 P 0 ;1
L 12.4075 1.1575 12.4075 1.1575 27 P 0 ;1
L 12.4075 1.2075 12.4075 1.2075 27 P 0 ;1
L 12.4075 1.2575 12.4075 1.2575 27 P 0 ;1
L 12.4075 1.3075 12.4075 1.3075 27 P 0 ;1
L 12.4075 1.3575 12.4075 1.3575 27 P 0 ;1
L 12.4075 1.4075 12.4075 1.4075 27 P 0 ;1
L 12.4075 1.4575 12.4075 1.4575 27 P 0 ;1
L 12.4075 1.5075 12.4075 1.5075 27 P 0 ;1
L 12.4075 1.5575 12.4075 1.5575 27 P 0 ;1
L 12.4075 1.6075 12.4075 1.6075 27 P 0 ;1
L 12.4075 1.6575 12.4075 1.6575 27 P 0 ;1
L 12.4075 1.7075 12.4075 1.7075 27 P 0 ;1
L 12.4075 1.7575 12.4075 1.7575 27 P 0 ;1
L 12.4075 1.8075 12.4075 1.8075 27 P 0 ;1
L 12.4075 1.8575 12.4075 1.8575 27 P 0 ;1
L 12.4075 1.9075 12.4075 1.9075 27 P 0 ;1
L 12.4075 1.9575 12.4075 1.9575 27 P 0 ;1
L 12.4075 2.0075 12.4075 2.0075 27 P 0 ;1
L 12.4075 2.0575 12.4075 2.0575 27 P 0 ;1
L 12.4075 2.1075 12.4075 2.1075 27 P 0 ;1
L 12.4075 2.3075 12.4075 2.3075 27 P 0 ;1
L 12.4075 2.3575 12.4075 2.3575 27 P 0 ;1
L 12.4075 2.4075 12.4075 2.4075 27 P 0 ;1
L 12.4075 2.4575 12.4075 2.4575 27 P 0 ;1
L 12.4075 2.5075 12.4075 2.5075 27 P 0 ;1
L 12.4075 2.5575 12.4075 2.5575 27 P 0 ;1
L 12.4075 2.6075 12.4075 2.6075 27 P 0 ;1
L 12.4075 2.6575 12.4075 2.6575 27 P 0 ;1
L 12.4075 2.7075 12.4075 2.7075 27 P 0 ;1
L 12.4075 2.7575 12.4075 2.7575 27 P 0 ;1
L 12.4075 2.8075 12.4075 2.8075 27 P 0 ;1
L 12.4075 2.8575 12.4075 2.8575 27 P 0 ;1
L 12.4075 2.9075 12.4075 2.9075 27 P 0 ;1
L 12.4075 2.9575 12.4075 2.9575 27 P 0 ;1
L 12.4075 3.0075 12.4075 3.0075 27 P 0 ;1
L 12.4075 3.0575 12.4075 3.0575 27 P 0 ;1
L 12.4075 3.1075 12.4075 3.1075 27 P 0 ;1
L 12.4075 3.1575 12.4075 3.1575 27 P 0 ;1
L 12.4075 3.2075 12.4075 3.2075 27 P 0 ;1
L 12.4075 3.2575 12.4075 3.2575 27 P 0 ;1
L 12.4075 3.3075 12.4075 3.3075 27 P 0 ;1
L 12.4075 3.3575 12.4075 3.3575 27 P 0 ;1
L 12.4075 3.4075 12.4075 3.4075 27 P 0 ;1
L 12.4075 3.4575 12.4075 3.4575 27 P 0 ;1
L 12.4075 3.5075 12.4075 3.5075 27 P 0 ;1
L 12.4075 3.5575 12.4075 3.5575 27 P 0 ;1
L 12.4075 3.6075 12.4075 3.6075 27 P 0 ;1
L 12.4075 3.6575 12.4075 3.6575 27 P 0 ;1
L 12.4075 3.7075 12.4075 3.7075 27 P 0 ;1
L 12.4075 3.7575 12.4075 3.7575 27 P 0 ;1
L 12.4075 3.8075 12.4075 3.8075 27 P 0 ;1
L 12.4075 3.8575 12.4075 3.8575 27 P 0 ;1
L 12.4075 3.9075 12.4075 3.9075 27 P 0 ;1
L 12.4075 3.9575 12.4075 3.9575 27 P 0 ;1
L 12.4075 4.0075 12.4075 4.0075 27 P 0 ;1
L 12.4075 4.0575 12.4075 4.0575 27 P 0 ;1
L 12.4075 4.1075 12.4075 4.1075 27 P 0 ;1
L 12.4075 4.1575 12.4075 4.1575 27 P 0 ;1
L 12.4075 4.2075 12.4075 4.2075 27 P 0 ;1
L 12.4075 4.2575 12.4075 4.2575 27 P 0 ;1
L 12.4075 4.3075 12.4075 4.3075 27 P 0 ;1
L 12.4075 4.3575 12.4075 4.3575 27 P 0 ;1
L 12.4075 4.4075 12.4075 4.4075 27 P 0 ;1
L 12.4075 4.4575 12.4075 4.4575 27 P 0 ;1
L 12.4075 4.5075 12.4075 4.5075 27 P 0 ;1
L 12.4075 4.5575 12.4075 4.5575 27 P 0 ;1
L 12.4075 4.6075 12.4075 4.6075 27 P 0 ;1
L 12.4075 4.6575 12.4075 4.6575 27 P 0 ;1
L 12.4075 4.7075 12.4075 4.7075 27 P 0 ;1
L 12.4075 4.7575 12.4075 4.7575 27 P 0 ;1
L 12.4075 4.8075 12.4075 4.8075 27 P 0 ;1
L 12.4075 4.8575 12.4075 4.8575 27 P 0 ;1
L 12.4075 4.9075 12.4075 4.9075 27 P 0 ;1
L 12.4075 4.9575 12.4075 4.9575 27 P 0 ;1
L 12.4075 5.0075 12.4075 5.0075 27 P 0 ;1
L 12.4075 5.0575 12.4075 5.0575 27 P 0 ;1
L 12.4575 0.1575 12.4575 0.1575 27 P 0 ;1
L 12.4575 0.2075 12.4575 0.2075 27 P 0 ;1
L 12.4575 0.2575 12.4575 0.2575 27 P 0 ;1
L 12.4575 0.3075 12.4575 0.3075 27 P 0 ;1
L 12.4575 0.3575 12.4575 0.3575 27 P 0 ;1
L 12.4575 0.4075 12.4575 0.4075 27 P 0 ;1
L 12.4575 0.4575 12.4575 0.4575 27 P 0 ;1
L 12.4575 0.5075 12.4575 0.5075 27 P 0 ;1
L 12.4575 0.5575 12.4575 0.5575 27 P 0 ;1
L 12.4575 0.6075 12.4575 0.6075 27 P 0 ;1
L 12.4575 0.8075 12.4575 0.8075 27 P 0 ;1
L 12.4575 0.8575 12.4575 0.8575 27 P 0 ;1
L 12.4575 0.9075 12.4575 0.9075 27 P 0 ;1
L 12.4575 0.9575 12.4575 0.9575 27 P 0 ;1
L 12.4575 1.0075 12.4575 1.0075 27 P 0 ;1
L 12.4575 1.0575 12.4575 1.0575 27 P 0 ;1
L 12.4575 1.1075 12.4575 1.1075 27 P 0 ;1
L 12.4575 1.1575 12.4575 1.1575 27 P 0 ;1
L 12.4575 1.2075 12.4575 1.2075 27 P 0 ;1
L 12.4575 1.2575 12.4575 1.2575 27 P 0 ;1
L 12.4575 1.3075 12.4575 1.3075 27 P 0 ;1
L 12.4575 1.3575 12.4575 1.3575 27 P 0 ;1
L 12.4575 1.4575 12.4575 1.4575 27 P 0 ;1
L 12.4575 1.6075 12.4575 1.6075 27 P 0 ;1
L 12.4575 1.8075 12.4575 1.8075 27 P 0 ;1
L 12.4575 2.0075 12.4575 2.0075 27 P 0 ;1
L 12.4575 2.1575 12.4575 2.1575 27 P 0 ;1
L 12.4575 2.5575 12.4575 2.5575 27 P 0 ;1
L 12.4575 2.7075 12.4575 2.7075 27 P 0 ;1
L 12.4575 2.9575 12.4575 2.9575 27 P 0 ;1
L 12.4575 3.1075 12.4575 3.1075 27 P 0 ;1
L 12.4575 3.2575 12.4575 3.2575 27 P 0 ;1
L 12.4575 3.5075 12.4575 3.5075 27 P 0 ;1
L 12.4575 3.6575 12.4575 3.6575 27 P 0 ;1
L 12.4575 3.8075 12.4575 3.8075 27 P 0 ;1
L 12.4575 4.0575 12.4575 4.0575 27 P 0 ;1
L 12.4575 4.2075 12.4575 4.2075 27 P 0 ;1
L 12.4575 4.3575 12.4575 4.3575 27 P 0 ;1
L 12.4575 4.6075 12.4575 4.6075 27 P 0 ;1
L 12.4575 4.7075 12.4575 4.7075 27 P 0 ;1
L 12.4575 4.7575 12.4575 4.7575 27 P 0 ;1
L 12.4575 4.8075 12.4575 4.8075 27 P 0 ;1
L 12.4575 4.8575 12.4575 4.8575 27 P 0 ;1
L 12.4575 4.9075 12.4575 4.9075 27 P 0 ;1
L 12.4575 4.9575 12.4575 4.9575 27 P 0 ;1
L 12.4575 5.0075 12.4575 5.0075 27 P 0 ;1
L 12.4575 5.0575 12.4575 5.0575 27 P 0 ;1
L 12.5075 0.1575 12.5075 0.1575 27 P 0 ;1
L 12.5075 0.2075 12.5075 0.2075 27 P 0 ;1
L 12.5075 0.2575 12.5075 0.2575 27 P 0 ;1
L 12.5075 0.3075 12.5075 0.3075 27 P 0 ;1
L 12.5075 0.3575 12.5075 0.3575 27 P 0 ;1
L 12.5075 0.4075 12.5075 0.4075 27 P 0 ;1
L 12.5075 0.4575 12.5075 0.4575 27 P 0 ;1
L 12.5075 0.5075 12.5075 0.5075 27 P 0 ;1
L 12.5075 0.5575 12.5075 0.5575 27 P 0 ;1
L 12.5075 0.9075 12.5075 0.9075 27 P 0 ;1
L 12.5075 0.9575 12.5075 0.9575 27 P 0 ;1
L 12.5075 1.0075 12.5075 1.0075 27 P 0 ;1
L 12.5075 1.0575 12.5075 1.0575 27 P 0 ;1
L 12.5075 1.1075 12.5075 1.1075 27 P 0 ;1
L 12.5075 1.1575 12.5075 1.1575 27 P 0 ;1
L 12.5075 1.2075 12.5075 1.2075 27 P 0 ;1
L 12.5075 1.2575 12.5075 1.2575 27 P 0 ;1
L 12.5075 1.3075 12.5075 1.3075 27 P 0 ;1
L 12.5075 4.7575 12.5075 4.7575 27 P 0 ;1
L 12.5075 4.8075 12.5075 4.8075 27 P 0 ;1
L 12.5075 4.8575 12.5075 4.8575 27 P 0 ;1
L 12.5075 4.9075 12.5075 4.9075 27 P 0 ;1
L 12.5075 4.9575 12.5075 4.9575 27 P 0 ;1
L 12.5575 0.1575 12.5575 0.1575 27 P 0 ;1
L 12.5575 0.2075 12.5575 0.2075 27 P 0 ;1
L 12.5575 0.2575 12.5575 0.2575 27 P 0 ;1
L 12.5575 0.3075 12.5575 0.3075 27 P 0 ;1
L 12.5575 0.3575 12.5575 0.3575 27 P 0 ;1
L 12.5575 1.0075 12.5575 1.0075 27 P 0 ;1
L 12.5575 1.0575 12.5575 1.0575 27 P 0 ;1
L 12.5575 1.1075 12.5575 1.1075 27 P 0 ;1
L 12.5575 1.1575 12.5575 1.1575 27 P 0 ;1
L 12.5575 1.2075 12.5575 1.2075 27 P 0 ;1
L 12.5575 1.2575 12.5575 1.2575 27 P 0 ;1
L 12.5575 4.7575 12.5575 4.7575 27 P 0 ;1
L 12.5575 4.8075 12.5575 4.8075 27 P 0 ;1
L 12.5575 4.8575 12.5575 4.8575 27 P 0 ;1
L 12.6075 0.1575 12.6075 0.1575 27 P 0 ;1
L 12.6075 0.2075 12.6075 0.2075 27 P 0 ;1
L 12.6075 0.2575 12.6075 0.2575 27 P 0 ;1
L 12.6075 0.3075 12.6075 0.3075 27 P 0 ;1
L 12.6075 1.1075 12.6075 1.1075 27 P 0 ;1
L 12.6075 1.1575 12.6075 1.1575 27 P 0 ;1
L 12.6075 1.2075 12.6075 1.2075 27 P 0 ;1
L 12.6075 1.2575 12.6075 1.2575 27 P 0 ;1
L 12.6075 5.5575 12.6075 5.5575 27 P 0 ;1
L 12.6075 5.6075 12.6075 5.6075 27 P 0 ;1
L 12.6075 5.6575 12.6075 5.6575 27 P 0 ;1
L 12.6075 5.7075 12.6075 5.7075 27 P 0 ;1
L 12.6075 5.7575 12.6075 5.7575 27 P 0 ;1
L 12.6075 5.8075 12.6075 5.8075 27 P 0 ;1
L 12.6075 5.8575 12.6075 5.8575 27 P 0 ;1
L 12.6575 0.1575 12.6575 0.1575 27 P 0 ;1
L 12.6575 0.2075 12.6575 0.2075 27 P 0 ;1
L 12.6575 0.2575 12.6575 0.2575 27 P 0 ;1
L 12.6575 0.3075 12.6575 0.3075 27 P 0 ;1
L 12.6575 1.1075 12.6575 1.1075 27 P 0 ;1
L 12.6575 1.1575 12.6575 1.1575 27 P 0 ;1
L 12.6575 1.2075 12.6575 1.2075 27 P 0 ;1
L 12.6575 1.2575 12.6575 1.2575 27 P 0 ;1
L 12.6575 5.6075 12.6575 5.6075 27 P 0 ;1
L 12.6575 5.6575 12.6575 5.6575 27 P 0 ;1
L 12.6575 5.7075 12.6575 5.7075 27 P 0 ;1
L 12.6575 5.7575 12.6575 5.7575 27 P 0 ;1
L 12.6575 5.8075 12.6575 5.8075 27 P 0 ;1
L 12.6575 5.8575 12.6575 5.8575 27 P 0 ;1
L 12.7075 0.1575 12.7075 0.1575 27 P 0 ;1
L 12.7075 0.2075 12.7075 0.2075 27 P 0 ;1
L 12.7075 0.2575 12.7075 0.2575 27 P 0 ;1
L 12.7075 0.3075 12.7075 0.3075 27 P 0 ;1
L 12.7075 1.1075 12.7075 1.1075 27 P 0 ;1
L 12.7075 1.1575 12.7075 1.1575 27 P 0 ;1
L 12.7075 1.2075 12.7075 1.2075 27 P 0 ;1
L 12.7075 1.2575 12.7075 1.2575 27 P 0 ;1
L 12.7075 5.6075 12.7075 5.6075 27 P 0 ;1
L 12.7075 5.6575 12.7075 5.6575 27 P 0 ;1
L 12.7075 5.7075 12.7075 5.7075 27 P 0 ;1
L 12.7075 5.7575 12.7075 5.7575 27 P 0 ;1
L 12.7075 5.8075 12.7075 5.8075 27 P 0 ;1
L 12.7075 5.8575 12.7075 5.8575 27 P 0 ;1
L 12.7575 0.1575 12.7575 0.1575 27 P 0 ;1
L 12.7575 0.2075 12.7575 0.2075 27 P 0 ;1
L 12.7575 0.2575 12.7575 0.2575 27 P 0 ;1
L 12.7575 0.3075 12.7575 0.3075 27 P 0 ;1
L 12.7575 1.1075 12.7575 1.1075 27 P 0 ;1
L 12.7575 1.1575 12.7575 1.1575 27 P 0 ;1
L 12.7575 1.2075 12.7575 1.2075 27 P 0 ;1
L 12.7575 1.2575 12.7575 1.2575 27 P 0 ;1
L 12.7575 5.6075 12.7575 5.6075 27 P 0 ;1
L 12.7575 5.6575 12.7575 5.6575 27 P 0 ;1
L 12.7575 5.7075 12.7575 5.7075 27 P 0 ;1
L 12.7575 5.7575 12.7575 5.7575 27 P 0 ;1
L 12.7575 5.8075 12.7575 5.8075 27 P 0 ;1
L 12.7575 5.8575 12.7575 5.8575 27 P 0 ;1

### steps/drc/layers/legc/features
#
#Feature symbol names
#
$0 r2
$1 r5
$2 r6
$3 r7.87
$4 r8
$5 r10
$6 r11.81
$7 r13.78
$8 r15

#
#Feature attribute names
#
@0 .nomenclature
@1 .string
@2 .string_angle

#
#Feature attribute text strings
#
&0 PWR CONN
&1 CPU1_NV_BOT
&2 CPU1_NV_TOP
&3 CPU0_NV_BOT
&4 CPU0_NV_TOP
&5 Sideband CONN
&6 ICT
&7 FVS
&8 Label
&9 ID
&10 GPU1
&11 GPU0
&12 Rework 123
&13 VENDOR
&14 P/N:0101FFS00-000-G
&15 REV:X00
&16 MADE IN _____
&17 H11
&18 H14
&19 H10
&20 H13
&21 H15
&22 H16
&23 GPU0_H0
&24 GPU1_H1
&25 J_GPU_PWR
&26 10
&27 18
&28 9
&29 H20
&30 H21
&31 H9
&32 H19
&33 H18
&34 H17
&35 H25
&36 H26
&37 H27
&38 H28
&39 J_CP0_NVLINK_BOTTOM
&40 A1
&41 B1
&42 B37
&43 A37
&44 J_CP1_NVLINK_BOTTOM
&45 J_CP0_NVLINK_TOP
&46 J_CP1_NVLINK_TOP
&47 LED_GPU_PWR_PG
&48 A
&49 C
&50 SW1
&51 SW3
&52 1
&53 2
&54 ON
&55 U45
&56 SW2
&57 3
&58 4
&59 PSTL2
&60 PSTR15
&61 PSTR10
&62 PSTU1
&63 14
&64 23
&65 24
&66 28
&67 PSTC3
&68 PSTC20
&69 PSTL1
&70 U101
&71 J_PCIE3
&72 A12
&73 B2
&74 A2
&75 B82
&76 A81
&77 A82
&78 A13
&79 B12
&80 B13
&81 B81
&82 J_PCIE4
&83 Z45S_IN_L12
&84 Z45S_IN_L10
&85 Z45S_IN_L5
&86 Z45S_IN_L3
&87 Z45S_IN_L1
&88 Z85D_IN_L12
&89 Z85D_IN_L10
&90 Z85D_IN_L1
&91 Z85D_IN_L3
&92 Z85D_IN_L5
&93 SHEET
&94 TITLE
&95 SCALE 1:1
&96 LAYER
&97 OF
&98 ART
&99 SILK SCREEN ( TOP )
&100 -
&101 Barreleye G2 SXM2-Riser
&102 DATE OCT/27/2017
&103 FD13
&104 FD14
&105 FD15
&106 FD2
&107 FD7
&108 FD8
&109 FD9
&110 H24
&111 H23
&112 H22
&113 H4
&114 H3
&115 H1
&116 H2
&117 R1618
&118 R1627
&119 R1613
&120 R1612
&121 R1620
&122 R1616
&123 R1615
&124 R1623
&125 R1621
&126 R1625
&127 R1619
&128 R1614
&129 R1626
&130 R1607
&131 R1602
&132 R1601
&133 R1609
&134 R1608
&135 R1606
&136 R1605
&137 R1598
&138 R1596
&139 R1604
&140 R1603
&141 R1599
&142 R1597
&143 PSTR35
&144 PSTR6
&145 PSTR9
&146 PSTR13
&147 PSTR16
&148 PSTR3
&149 PSTR4
&150 PSTR2
&151 R1579
&152 R1578
&153 R1577
&154 R1591
&155 R1590
&156 R1589
&157 R1588
&158 R1585
&159 R1584
&160 R1583
&161 R1582
&162 R1581
&163 R1576
&164 R1575
&165 R73
&166 R1489
&167 R804
&168 R721
&169 R1524
&170 R1523
&171 R1510
&172 R1509
&173 R1508
&174 R1500
&175 R1499
&176 R1498
&177 R1480
&178 R1479
&179 R1476
&180 R1475
&181 R1495
&182 R1488
&183 R1485
&184 R1484
&185 R1483
&186 R1482
&187 R1473
&188 R1491
&189 R738
&190 R737
&191 R722
&192 R1520
&193 R1519
&194 R1518
&195 R1507
&196 R1506
&197 R1497
&198 R1496
&199 L9
&200 L10
&201 CE8
&202 CE7
&203 CE6
&204 CE2
&205 CE1
&206 PSTC26
&207 PSTC33
&208 PSTC34
&209 PSTC29
&210 PSTC14
&211 PSTC15
&212 PSTC28
&213 PSTC5
&214 PSTC11
&215 PSTC6
&216 C409
&217 C410
&218 C412
&219 C414
&220 C2243
&221 C2242
&222 C2246
&223 C2245
&224 C2244
&225 C2239
&226 C2240
&227 C2241
&228 PSTC22
&229 PSTC13
&230 PSTC2
&231 PSTC12
&232 PSTC21
&233 PSTC8
&234 PSTC1
&235 C2238
&236 C2188
&237 C413
&238 C411
&239 C2192
&240 C2190
&241 C2186
&242 C2185
&243 C2173
&244 C2172
&245 C2236
&246 C2197
&247 C2196
&248 C2195
&249 C2194
&250 C2193
&251 C2191
&252 C2189
&253 C2174
&254 Q1
&255 D
&256 G
&257 S
&258 U177
&259 U176
&260 U175
&261 U174
&262 U165
&263 U173
&264 U164
&265 U170
&266 U171
&267 J16
&268 J17
&269 J_SIDEBAND
&270 21
&271 22
&272 J_NVLINK_GPU0
&273 5
&274 6
&275 7
&276 8
&277 11
&278 12
&279 13
&280 15
&281 16
&282 17
&283 19
&284 20
&285 B
&286 E
&287 F
&288 H
&289 J
&290 K
&291 25
&292 26
&293 27
&294 29
&295 30
&296 31
&297 32
&298 33
&299 34
&300 35
&301 36
&302 37
&303 38
&304 39
&305 40
&306 J_NVLINK_GPU1
&307 J_PEX_GPU0
&308 J_PEX_GPU1

#
#Layer features
#
L 1.88908002 -1.91246004 1.89293002 -1.91246004 0 P 0 
L 1.89126998 -1.91146004 1.89656998 -1.91146004 0 P 0 
L 1.89393996 -1.91046004 1.9155 -1.91046004 0 P 0 
L 1.91593996 -1.91246004 1.92048996 -1.91246004 0 P 0 
L 1.9126 -1.91146004 1.9184 -1.91146004 0 P 0 
L 1.89763002 -1.90946004 1.91016998 -1.90946004 0 P 0 
L 1.89053002 -1.96001004 1.8974 -1.96001004 0 P 0 
L 1.89053002 -1.95901004 1.8974 -1.95901004 0 P 0 
L 1.89053002 -1.95801004 1.8974 -1.95801004 0 P 0 
L 1.89053002 -1.95701004 1.8974 -1.95701004 0 P 0 
L 1.89053002 -1.95601004 1.8974 -1.95601004 0 P 0 
L 1.89053002 -1.95501004 1.8974 -1.95501004 0 P 0 
L 1.89053002 -1.95401004 1.8974 -1.95401004 0 P 0 
L 1.89053002 -1.95301004 1.89741004 -1.95301004 0 P 0 
L 1.89053002 -1.95201004 1.89741998 -1.95201004 0 P 0 
L 1.89053002 -1.95101004 1.89743996 -1.95101004 0 P 0 
L 1.89053002 -1.95001004 1.89745 -1.95001004 0 P 0 
L 1.89053002 -1.94901004 1.89746004 -1.94901004 0 P 0 
L 1.89053002 -1.94801004 1.89753002 -1.94801004 0 P 0 
L 1.89053002 -1.94701004 1.8977 -1.94701004 0 P 0 
L 1.89053002 -1.94601004 1.89798002 -1.94601004 0 P 0 
L 1.89053002 -1.94501004 1.89861004 -1.94501004 0 P 0 
L 1.89053002 -1.94401004 1.90005 -1.94401004 0 P 0 
L 1.89053002 -1.94301004 1.9113 -1.94301004 0 P 0 
L 1.89053002 -1.94201004 1.91168002 -1.94201004 0 P 0 
L 1.89053002 -1.94101004 1.91246998 -1.94101004 0 P 0 
L 1.89053002 -1.94001004 1.90093996 -1.94001004 0 P 0 
L 1.89053002 -1.93901004 1.89856004 -1.93901004 0 P 0 
L 1.89053002 -1.93801004 1.89786998 -1.93801004 0 P 0 
L 1.89053002 -1.93701004 1.89753996 -1.93701004 0 P 0 
L 1.89053002 -1.93601004 1.89746998 -1.93601004 0 P 0 
L 1.89053002 -1.93501004 1.89743996 -1.93501004 0 P 0 
L 1.89053002 -1.93401004 1.89741998 -1.93401004 0 P 0 
L 1.89053002 -1.93301004 1.8974 -1.93301004 0 P 0 
L 1.89053002 -1.93201004 1.8974 -1.93201004 0 P 0 
L 1.89053002 -1.93101004 1.8974 -1.93101004 0 P 0 
L 1.89053002 -1.93001004 1.8974 -1.93001004 0 P 0 
L 1.89053002 -1.92901004 1.8974 -1.92901004 0 P 0 
L 1.89053002 -1.92801004 1.89753002 -1.92801004 0 P 0 
L 1.89053002 -1.92701004 1.89793996 -1.92701004 0 P 0 
L 1.89053002 -1.92601004 1.91713002 -1.92601004 0 P 0 
L 1.89053002 -1.92501004 1.91628996 -1.92501004 0 P 0 
L 1.89053002 -1.92401004 1.91513996 -1.92401004 0 P 0 
L 1.89053002 -1.92301004 1.91321998 -1.92301004 0 P 0 
L 1.89053002 -1.92201004 1.90551004 -1.92201004 0 P 0 
L 1.89438996 -1.97246004 1.91331004 -1.97246004 0 P 0 
L 1.89106998 -1.97146004 1.89973002 -1.97146004 0 P 0 
L 1.88878002 -1.97046004 1.8949 -1.97046004 0 P 0 
L 1.88698002 -1.96946004 1.89206998 -1.96946004 0 P 0 
L 1.88546004 -1.96846004 1.88986998 -1.96846004 0 P 0 
L 1.88416998 -1.96746004 1.88808996 -1.96746004 0 P 0 
L 1.88288002 -1.96646004 1.88655 -1.96646004 0 P 0 
L 1.88176998 -1.96546004 1.88518002 -1.96546004 0 P 0 
L 1.88068996 -1.96446004 1.88393996 -1.96446004 0 P 0 
L 1.87968996 -1.96346004 1.88286004 -1.96346004 0 P 0 
L 1.87878002 -1.96246004 1.88186004 -1.96246004 0 P 0 
L 1.8786 -1.92046004 1.88126998 -1.92046004 0 P 0 
L 1.87946998 -1.91946004 1.88223002 -1.91946004 0 P 0 
L 1.88048002 -1.91846004 1.88321004 -1.91846004 0 P 0 
L 1.88153996 -1.91746004 1.88436998 -1.91746004 0 P 0 
L 1.88273002 -1.91646004 1.88558996 -1.91646004 0 P 0 
L 1.88406004 -1.91546004 1.88696998 -1.91546004 0 P 0 
L 1.88548996 -1.91446004 1.88853002 -1.91446004 0 P 0 
L 1.88718002 -1.91346004 1.89041998 -1.91346004 0 P 0 
L 1.90896004 -1.92963996 1.90921998 -1.92991998 0 P 0 
L 1.90921998 -1.92991998 1.90945 -1.93021998 0 P 0 
L 1.90945 -1.93021998 1.90966004 -1.93053002 0 P 0 
L 1.90966004 -1.93053002 1.90983002 -1.93086004 0 P 0 
L 1.90983002 -1.93086004 1.90998002 -1.93121004 0 P 0 
L 1.90998002 -1.93121004 1.9101 -1.93156998 0 P 0 
L 1.9101 -1.93156998 1.91018996 -1.93193996 0 P 0 
L 1.91018996 -1.93193996 1.91023996 -1.93231004 0 P 0 
L 1.91023996 -1.93231004 1.91026998 -1.93265 0 P 0 
L 1.91026998 -1.93265 1.91026004 -1.93298002 0 P 0 
L 1.91026004 -1.93298002 1.91023002 -1.93331004 0 P 0 
L 1.91023002 -1.93331004 1.91016998 -1.93363996 0 P 0 
L 1.91016998 -1.93363996 1.91008996 -1.93396004 0 P 0 
L 1.91008996 -1.93396004 1.90998002 -1.93428002 0 P 0 
L 1.90998002 -1.93428002 1.90983996 -1.93458002 0 P 0 
L 1.90983996 -1.93458002 1.90968996 -1.93486998 0 P 0 
L 1.90968996 -1.93486998 1.90951004 -1.93516004 0 P 0 
L 1.90951004 -1.93516004 1.90921004 -1.93556004 0 P 0 
L 1.90921004 -1.93556004 1.90888002 -1.93593002 0 P 0 
L 1.90888002 -1.93593002 1.90853002 -1.93626998 0 P 0 
L 1.90853002 -1.93626998 1.90815 -1.93658996 0 P 0 
L 1.90815 -1.93658996 1.90773996 -1.93686998 0 P 0 
L 1.90773996 -1.93686998 1.90731998 -1.93711998 0 P 0 
L 1.90731998 -1.93711998 1.90686998 -1.93733996 0 P 0 
L 1.90686998 -1.93733996 1.90615 -1.93761004 0 P 0 
L 1.90615 -1.93761004 1.90541998 -1.93783002 0 P 0 
L 1.90541998 -1.93783002 1.90466004 -1.93798002 0 P 0 
L 1.90466004 -1.93798002 1.9039 -1.93808002 0 P 0 
L 1.9039 -1.93808002 1.90311998 -1.9381 0 P 0 
L 1.90311998 -1.9381 1.90196004 -1.93808002 0 P 0 
L 1.90196004 -1.93808002 1.90078996 -1.93798996 0 P 0 
L 1.90078996 -1.93798996 1.90068002 -1.93798002 0 P 0 
L 1.90068002 -1.93798002 1.90058002 -1.93795 0 P 0 
L 1.90058002 -1.93795 1.90046998 -1.93791998 0 P 0 
L 1.90046998 -1.93791998 1.90038002 -1.93788002 0 P 0 
L 1.90038002 -1.93788002 1.90028002 -1.93783002 0 P 0 
L 1.90028002 -1.93783002 1.90018996 -1.93778002 0 P 0 
L 1.90018996 -1.93778002 1.9001 -1.93771004 0 P 0 
L 1.9001 -1.93771004 1.90001998 -1.93763996 0 P 0 
L 1.90001998 -1.93763996 1.89988002 -1.93748002 0 P 0 
L 1.89988002 -1.93748002 1.89978002 -1.93733996 0 P 0 
L 1.89978002 -1.93733996 1.89961998 -1.93703996 0 P 0 
L 1.89961998 -1.93703996 1.89956998 -1.93688002 0 P 0 
L 1.89956998 -1.93688002 1.89951998 -1.93671004 0 P 0 
L 1.89951998 -1.93671004 1.89948996 -1.93655 0 P 0 
L 1.89948996 -1.93655 1.89946998 -1.93636998 0 P 0 
L 1.89946998 -1.93636998 1.8994 -1.93323002 0 P 0 
L 1.8994 -1.93323002 1.8994 -1.92833002 0 P 0 
L 1.8994 -1.92833002 1.90353996 -1.92833002 0 P 0 
L 1.90353996 -1.92833002 1.90436998 -1.92835 0 P 0 
L 1.90436998 -1.92835 1.9052 -1.92843002 0 P 0 
L 1.9052 -1.92843002 1.90603002 -1.92853996 0 P 0 
L 1.90603002 -1.92853996 1.90683996 -1.92871004 0 P 0 
L 1.90683996 -1.92871004 1.90751004 -1.9289 0 P 0 
L 1.90751004 -1.9289 1.90818002 -1.92913002 0 P 0 
L 1.90818002 -1.92913002 1.90851998 -1.92928996 0 P 0 
L 1.90851998 -1.92928996 1.90868002 -1.92938996 0 P 0 
L 1.90868002 -1.92938996 1.90883002 -1.92951004 0 P 0 
L 1.90883002 -1.92951004 1.90896004 -1.92963996 0 P 0 
L 1.91188996 -1.96001004 1.91638996 -1.96001004 0 P 0 
L 1.91156998 -1.95901004 1.91926998 -1.95901004 0 P 0 
L 1.91125 -1.95801004 1.91891998 -1.95801004 0 P 0 
L 1.91091998 -1.95701004 1.91853002 -1.95701004 0 P 0 
L 1.9106 -1.95601004 1.91811004 -1.95601004 0 P 0 
L 1.91025 -1.95501004 1.91765 -1.95501004 0 P 0 
L 1.90988996 -1.95401004 1.91718996 -1.95401004 0 P 0 
L 1.90953002 -1.95301004 1.91673002 -1.95301004 0 P 0 
L 1.90918002 -1.95201004 1.91626998 -1.95201004 0 P 0 
L 1.90881998 -1.95101004 1.91576004 -1.95101004 0 P 0 
L 1.90841004 -1.95001004 1.91523996 -1.95001004 0 P 0 
L 1.90793996 -1.94901004 1.91471004 -1.94901004 0 P 0 
L 1.90738996 -1.94801004 1.91418002 -1.94801004 0 P 0 
L 1.90676998 -1.94701004 1.9136 -1.94701004 0 P 0 
L 1.90598996 -1.94601004 1.91261004 -1.94601004 0 P 0 
L 1.90495 -1.94501004 1.91175 -1.94501004 0 P 0 
L 1.90325 -1.94401004 1.91133002 -1.94401004 0 P 0 
L 1.90456004 -1.94001004 1.91383002 -1.94001004 0 P 0 
L 1.90801004 -1.93901004 1.91523002 -1.93901004 0 P 0 
L 1.90956998 -1.93801004 1.91635 -1.93801004 0 P 0 
L 1.9106 -1.93701004 1.91718002 -1.93701004 0 P 0 
L 1.91133996 -1.93601004 1.91781004 -1.93601004 0 P 0 
L 1.91183996 -1.93501004 1.91826004 -1.93501004 0 P 0 
L 1.91213002 -1.93401004 1.9186 -1.93401004 0 P 0 
L 1.91226004 -1.93301004 1.9188 -1.93301004 0 P 0 
L 1.91221998 -1.93201004 1.9189 -1.93201004 0 P 0 
L 1.91201998 -1.93101004 1.9189 -1.93101004 0 P 0 
L 1.91163996 -1.93001004 1.91878996 -1.93001004 0 P 0 
L 1.91105 -1.92901004 1.91856998 -1.92901004 0 P 0 
L 1.91013996 -1.92801004 1.91823002 -1.92801004 0 P 0 
L 1.90816998 -1.92701004 1.91776004 -1.92701004 0 P 0 
L 1.90313996 -1.94011004 1.90316998 -1.9401 0 P 0 
L 1.90316998 -1.9401 1.9032 -1.9401 0 P 0 
L 1.9032 -1.9401 1.90398002 -1.94006998 0 P 0 
L 1.90398002 -1.94006998 1.90406004 -1.94006998 0 P 0 
L 1.90406004 -1.94006998 1.90413996 -1.94006004 0 P 0 
L 1.90413996 -1.94006004 1.9049 -1.93996998 0 P 0 
L 1.9049 -1.93996998 1.90493996 -1.93996004 0 P 0 
L 1.90493996 -1.93996004 1.90498996 -1.93996004 0 P 0 
L 1.90498996 -1.93996004 1.90506998 -1.93993996 0 P 0 
L 1.90506998 -1.93993996 1.90581998 -1.93978002 0 P 0 
L 1.90581998 -1.93978002 1.90586004 -1.93978002 0 P 0 
L 1.90586004 -1.93978002 1.90593996 -1.93976004 0 P 0 
L 1.90593996 -1.93976004 1.90596998 -1.93973996 0 P 0 
L 1.90596998 -1.93973996 1.90671004 -1.93953002 0 P 0 
L 1.90671004 -1.93953002 1.90678996 -1.93951004 0 P 0 
L 1.90678996 -1.93951004 1.90758996 -1.93921004 0 P 0 
L 1.90758996 -1.93921004 1.90766004 -1.93916998 0 P 0 
L 1.90766004 -1.93916998 1.9077 -1.93915 0 P 0 
L 1.9077 -1.93915 1.90773996 -1.93913996 0 P 0 
L 1.90773996 -1.93913996 1.90818996 -1.93891998 0 P 0 
L 1.90818996 -1.93891998 1.90821998 -1.9389 0 P 0 
L 1.90821998 -1.9389 1.90826004 -1.93888996 0 P 0 
L 1.90826004 -1.93888996 1.90828996 -1.93886998 0 P 0 
L 1.90828996 -1.93886998 1.90833002 -1.93885 0 P 0 
L 1.90833002 -1.93885 1.90875 -1.9386 0 P 0 
L 1.90875 -1.9386 1.90883002 -1.93856004 0 P 0 
L 1.90883002 -1.93856004 1.90888996 -1.93851004 0 P 0 
L 1.90888996 -1.93851004 1.90928996 -1.93823002 0 P 0 
L 1.90928996 -1.93823002 1.90933002 -1.9382 0 P 0 
L 1.90933002 -1.9382 1.90936004 -1.93818002 0 P 0 
L 1.90936004 -1.93818002 1.90938996 -1.93815 0 P 0 
L 1.90938996 -1.93815 1.90941998 -1.93813002 0 P 0 
L 1.90941998 -1.93813002 1.9098 -1.93781998 0 P 0 
L 1.9098 -1.93781998 1.90986004 -1.93776004 0 P 0 
L 1.90986004 -1.93776004 1.90988996 -1.93773996 0 P 0 
L 1.90988996 -1.93773996 1.90991998 -1.93771004 0 P 0 
L 1.90991998 -1.93771004 1.91028002 -1.93736004 0 P 0 
L 1.91028002 -1.93736004 1.91038996 -1.93725 0 P 0 
L 1.91038996 -1.93725 1.91071004 -1.93688002 0 P 0 
L 1.91071004 -1.93688002 1.91073996 -1.93685 0 P 0 
L 1.91073996 -1.93685 1.91116004 -1.9363 0 P 0 
L 1.91116004 -1.9363 1.9112 -1.93623002 0 P 0 
L 1.9112 -1.93623002 1.91138002 -1.93595 0 P 0 
L 1.91138002 -1.93595 1.9114 -1.93591004 0 P 0 
L 1.9114 -1.93591004 1.91143996 -1.93585 0 P 0 
L 1.91143996 -1.93585 1.91146004 -1.93581004 0 P 0 
L 1.91146004 -1.93581004 1.91161004 -1.93551998 0 P 0 
L 1.91161004 -1.93551998 1.91163002 -1.93548996 0 P 0 
L 1.91163002 -1.93548996 1.91165 -1.93545 0 P 0 
L 1.91165 -1.93545 1.91166004 -1.93541004 0 P 0 
L 1.91166004 -1.93541004 1.91168002 -1.93538002 0 P 0 
L 1.91168002 -1.93538002 1.91181004 -1.93506998 0 P 0 
L 1.91181004 -1.93506998 1.91183996 -1.935 0 P 0 
L 1.91183996 -1.935 1.91186004 -1.93496004 0 P 0 
L 1.91186004 -1.93496004 1.91186998 -1.93493002 0 P 0 
L 1.91186998 -1.93493002 1.91198002 -1.93461004 0 P 0 
L 1.91198002 -1.93461004 1.91198996 -1.93456998 0 P 0 
L 1.91198996 -1.93456998 1.912 -1.93453996 0 P 0 
L 1.912 -1.93453996 1.9121 -1.93413996 0 P 0 
L 1.9121 -1.93413996 1.91211998 -1.9341 0 P 0 
L 1.91211998 -1.9341 1.91211998 -1.93406004 0 P 0 
L 1.91211998 -1.93406004 1.91213002 -1.93401998 0 P 0 
L 1.91213002 -1.93401998 1.91213996 -1.93398996 0 P 0 
L 1.91213996 -1.93398996 1.9122 -1.93366004 0 P 0 
L 1.9122 -1.93366004 1.91221004 -1.93358002 0 P 0 
L 1.91221004 -1.93358002 1.91221004 -1.93353996 0 P 0 
L 1.91221004 -1.93353996 1.91221998 -1.9335 0 P 0 
L 1.91221998 -1.9335 1.91225 -1.93316998 0 P 0 
L 1.91225 -1.93316998 1.91226004 -1.93308996 0 P 0 
L 1.91226004 -1.93308996 1.91226004 -1.93268002 0 P 0 
L 1.91226004 -1.93268002 1.91226998 -1.93263996 0 P 0 
L 1.91226998 -1.93263996 1.91226998 -1.9326 0 P 0 
L 1.91226998 -1.9326 1.91226004 -1.93251998 0 P 0 
L 1.91226004 -1.93251998 1.91223996 -1.93218996 0 P 0 
L 1.91223996 -1.93218996 1.91223996 -1.93215 0 P 0 
L 1.91223996 -1.93215 1.91223002 -1.9321 0 P 0 
L 1.91223002 -1.9321 1.91223002 -1.93206004 0 P 0 
L 1.91223002 -1.93206004 1.91221998 -1.93201998 0 P 0 
L 1.91221998 -1.93201998 1.91216998 -1.93163996 0 P 0 
L 1.91216998 -1.93163996 1.91216004 -1.9316 0 P 0 
L 1.91216004 -1.9316 1.91213996 -1.93151004 0 P 0 
L 1.91213996 -1.93151004 1.91213002 -1.93146998 0 P 0 
L 1.91213002 -1.93146998 1.91205 -1.93111004 0 P 0 
L 1.91205 -1.93111004 1.91203996 -1.93106004 0 P 0 
L 1.91203996 -1.93106004 1.91203002 -1.93101998 0 P 0 
L 1.91203002 -1.93101998 1.91201004 -1.93098002 0 P 0 
L 1.91201004 -1.93098002 1.912 -1.93093996 0 P 0 
L 1.912 -1.93093996 1.91188002 -1.93058002 0 P 0 
L 1.91188002 -1.93058002 1.91186998 -1.93053996 0 P 0 
L 1.91186998 -1.93053996 1.91185 -1.9305 0 P 0 
L 1.91185 -1.9305 1.91183996 -1.93046004 0 P 0 
L 1.91183996 -1.93046004 1.91181998 -1.93043002 0 P 0 
L 1.91181998 -1.93043002 1.91166998 -1.93008002 0 P 0 
L 1.91166998 -1.93008002 1.91166004 -1.93003996 0 P 0 
L 1.91166004 -1.93003996 1.9116 -1.92991998 0 P 0 
L 1.9116 -1.92991998 1.91141998 -1.92958996 0 P 0 
L 1.91141998 -1.92958996 1.9114 -1.92955 0 P 0 
L 1.9114 -1.92955 1.91138002 -1.92951998 0 P 0 
L 1.91138002 -1.92951998 1.91133002 -1.92945 0 P 0 
L 1.91133002 -1.92945 1.91113002 -1.92913002 0 P 0 
L 1.91113002 -1.92913002 1.91111004 -1.92908996 0 P 0 
L 1.91111004 -1.92908996 1.91108996 -1.92906004 0 P 0 
L 1.91108996 -1.92906004 1.91106004 -1.92901998 0 P 0 
L 1.91106004 -1.92901998 1.91103002 -1.92898996 0 P 0 
L 1.91103002 -1.92898996 1.9108 -1.92868996 0 P 0 
L 1.9108 -1.92868996 1.91076998 -1.92866004 0 P 0 
L 1.91076998 -1.92866004 1.91075 -1.92861998 0 P 0 
L 1.91075 -1.92861998 1.91068996 -1.92856004 0 P 0 
L 1.91068996 -1.92856004 1.91043002 -1.92828002 0 P 0 
L 1.91043002 -1.92828002 1.91035 -1.9282 0 P 0 
L 1.91035 -1.9282 1.91033002 -1.92816998 0 P 0 
L 1.91033002 -1.92816998 1.91018996 -1.92803996 0 P 0 
L 1.91018996 -1.92803996 1.91018002 -1.92803996 0 P 0 
L 1.91018002 -1.92803996 1.91016004 -1.92801998 0 P 0 
L 1.91016004 -1.92801998 1.91011998 -1.92798996 0 P 0 
L 1.91011998 -1.92798996 1.91006004 -1.92793002 0 P 0 
L 1.91006004 -1.92793002 1.90991004 -1.92781998 0 P 0 
L 1.90991004 -1.92781998 1.90988002 -1.9278 0 P 0 
L 1.90988002 -1.9278 1.90983996 -1.92776998 0 P 0 
L 1.90983996 -1.92776998 1.90976998 -1.92771998 0 P 0 
L 1.90976998 -1.92771998 1.90961004 -1.92761998 0 P 0 
L 1.90961004 -1.92761998 1.90953996 -1.92756998 0 P 0 
L 1.90953996 -1.92756998 1.9095 -1.92755 0 P 0 
L 1.9095 -1.92755 1.90946998 -1.92753002 0 P 0 
L 1.90946998 -1.92753002 1.9093 -1.92743996 0 P 0 
L 1.9093 -1.92743996 1.90926004 -1.92741998 0 P 0 
L 1.90926004 -1.92741998 1.90923002 -1.9274 0 P 0 
L 1.90923002 -1.9274 1.90915 -1.92736998 0 P 0 
L 1.90915 -1.92736998 1.90896998 -1.92728996 0 P 0 
L 1.90896998 -1.92728996 1.90893996 -1.92728002 0 P 0 
L 1.90893996 -1.92728002 1.9089 -1.92726004 0 P 0 
L 1.9089 -1.92726004 1.90886998 -1.92725 0 P 0 
L 1.90886998 -1.92725 1.90883002 -1.92723996 0 P 0 
L 1.90883002 -1.92723996 1.90816004 -1.92701004 0 P 0 
L 1.90816004 -1.92701004 1.90813996 -1.927 0 P 0 
L 1.90813996 -1.927 1.9081 -1.92698996 0 P 0 
L 1.9081 -1.92698996 1.90803996 -1.92696998 0 P 0 
L 1.90803996 -1.92696998 1.90736998 -1.92678002 0 P 0 
L 1.90736998 -1.92678002 1.90723996 -1.92675 0 P 0 
L 1.90723996 -1.92675 1.90643002 -1.92658996 0 P 0 
L 1.90643002 -1.92658996 1.90636998 -1.92656998 0 P 0 
L 1.90636998 -1.92656998 1.90633996 -1.92656998 0 P 0 
L 1.90633996 -1.92656998 1.90631004 -1.92656004 0 P 0 
L 1.90631004 -1.92656004 1.90548996 -1.92645 0 P 0 
L 1.90548996 -1.92645 1.90543996 -1.92643996 0 P 0 
L 1.90543996 -1.92643996 1.9054 -1.92643002 0 P 0 
L 1.9054 -1.92643002 1.90538002 -1.92643002 0 P 0 
L 1.90538002 -1.92643002 1.90455 -1.92636004 0 P 0 
L 1.90455 -1.92636004 1.90443002 -1.92636004 0 P 0 
L 1.90443002 -1.92636004 1.9036 -1.92633002 0 P 0 
L 1.9036 -1.92633002 1.8994 -1.92633002 0 P 0 
L 1.8994 -1.92633002 1.89798002 -1.92691004 0 P 0 
L 1.89798002 -1.92691004 1.8974 -1.92833002 0 P 0 
L 1.8974 -1.92833002 1.8974 -1.93328002 0 P 0 
L 1.8974 -1.93328002 1.89748002 -1.93643002 0 P 0 
L 1.89748002 -1.93643002 1.89748002 -1.93656004 0 P 0 
L 1.89748002 -1.93656004 1.8975 -1.93673002 0 P 0 
L 1.8975 -1.93673002 1.89751004 -1.93681004 0 P 0 
L 1.89751004 -1.93681004 1.89751998 -1.9369 0 P 0 
L 1.89751998 -1.9369 1.89755 -1.93706004 0 P 0 
L 1.89755 -1.93706004 1.89758002 -1.93718996 0 P 0 
L 1.89758002 -1.93718996 1.89758996 -1.93723002 0 P 0 
L 1.89758996 -1.93723002 1.89763002 -1.9374 0 P 0 
L 1.89763002 -1.9374 1.89763996 -1.93743996 0 P 0 
L 1.89763996 -1.93743996 1.89766004 -1.93748002 0 P 0 
L 1.89766004 -1.93748002 1.89768002 -1.93756004 0 P 0 
L 1.89768002 -1.93756004 1.89773996 -1.93771998 0 P 0 
L 1.89773996 -1.93771998 1.89776004 -1.93776004 0 P 0 
L 1.89776004 -1.93776004 1.89776998 -1.9378 0 P 0 
L 1.89776998 -1.9378 1.89781004 -1.93788002 0 P 0 
L 1.89781004 -1.93788002 1.89788002 -1.93803996 0 P 0 
L 1.89788002 -1.93803996 1.8979 -1.93808002 0 P 0 
L 1.8979 -1.93808002 1.89791998 -1.93811004 0 P 0 
L 1.89791998 -1.93811004 1.89796004 -1.93818996 0 P 0 
L 1.89796004 -1.93818996 1.89803996 -1.93833996 0 P 0 
L 1.89803996 -1.93833996 1.89813996 -1.93848002 0 P 0 
L 1.89813996 -1.93848002 1.89823002 -1.93861998 0 P 0 
L 1.89823002 -1.93861998 1.89828002 -1.93868996 0 P 0 
L 1.89828002 -1.93868996 1.89831004 -1.93873002 0 P 0 
L 1.89831004 -1.93873002 1.89833996 -1.93876004 0 P 0 
L 1.89833996 -1.93876004 1.8984 -1.93883996 0 P 0 
L 1.8984 -1.93883996 1.89848996 -1.93893002 0 P 0 
L 1.89848996 -1.93893002 1.89851004 -1.93896004 0 P 0 
L 1.89851004 -1.93896004 1.89868002 -1.93913002 0 P 0 
L 1.89868002 -1.93913002 1.89871004 -1.93915 0 P 0 
L 1.89871004 -1.93915 1.89878996 -1.93921998 0 P 0 
L 1.89878996 -1.93921998 1.89885 -1.93928002 0 P 0 
L 1.89885 -1.93928002 1.89888002 -1.9393 0 P 0 
L 1.89888002 -1.9393 1.89891998 -1.93931998 0 P 0 
L 1.89891998 -1.93931998 1.89901004 -1.93938996 0 P 0 
L 1.89901004 -1.93938996 1.89903996 -1.93941004 0 P 0 
L 1.89903996 -1.93941004 1.89906998 -1.93943996 0 P 0 
L 1.89906998 -1.93943996 1.8991 -1.93946004 0 P 0 
L 1.8991 -1.93946004 1.89913996 -1.93948002 0 P 0 
L 1.89913996 -1.93948002 1.89923002 -1.93953996 0 P 0 
L 1.89923002 -1.93953996 1.89926998 -1.93956004 0 P 0 
L 1.89926998 -1.93956004 1.8993 -1.93958002 0 P 0 
L 1.8993 -1.93958002 1.89933996 -1.9396 0 P 0 
L 1.89933996 -1.9396 1.89936998 -1.93961004 0 P 0 
L 1.89936998 -1.93961004 1.89938002 -1.93961004 0 P 0 
L 1.89938002 -1.93961004 1.89946998 -1.93966004 0 P 0 
L 1.89946998 -1.93966004 1.89953996 -1.9397 0 P 0 
L 1.89953996 -1.9397 1.89971998 -1.93976998 0 P 0 
L 1.89971998 -1.93976998 1.89975 -1.93978996 0 P 0 
L 1.89975 -1.93978996 1.89978996 -1.9398 0 P 0 
L 1.89978996 -1.9398 1.89986998 -1.93983002 0 P 0 
L 1.89986998 -1.93983002 1.89996998 -1.93986004 0 P 0 
L 1.89996998 -1.93986004 1.90001004 -1.93986998 0 P 0 
L 1.90001004 -1.93986998 1.90005 -1.93988996 0 P 0 
L 1.90005 -1.93988996 1.90013002 -1.9399 0 P 0 
L 1.90013002 -1.9399 1.90023002 -1.93993002 0 P 0 
L 1.90023002 -1.93993002 1.90023996 -1.93993002 0 P 0 
L 1.90023996 -1.93993002 1.90028002 -1.93993996 0 P 0 
L 1.90028002 -1.93993996 1.90031004 -1.93995 0 P 0 
L 1.90031004 -1.93995 1.90036004 -1.93995 0 P 0 
L 1.90036004 -1.93995 1.9004 -1.93996004 0 P 0 
L 1.9004 -1.93996004 1.9005 -1.93996998 0 P 0 
L 1.9005 -1.93996998 1.90061004 -1.93998996 0 P 0 
L 1.90061004 -1.93998996 1.90063996 -1.93998996 0 P 0 
L 1.90063996 -1.93998996 1.90181004 -1.94006998 0 P 0 
L 1.90181004 -1.94006998 1.90183996 -1.94008002 0 P 0 
L 1.90183996 -1.94008002 1.90191004 -1.94008002 0 P 0 
L 1.90191004 -1.94008002 1.90308002 -1.9401 0 P 0 
L 1.90308002 -1.9401 1.90311004 -1.9401 0 P 0 
L 1.90311004 -1.9401 1.90313996 -1.94011004 0 P 0 
L 1.90841004 -1.97146004 1.91683996 -1.97146004 0 P 0 
L 1.9135 -1.97046004 1.91931004 -1.97046004 0 P 0 
L 1.91655 -1.96946004 1.92131004 -1.96946004 0 P 0 
L 1.91891998 -1.96846004 1.92301004 -1.96846004 0 P 0 
L 1.92088996 -1.96746004 1.9245 -1.96746004 0 P 0 
L 1.92251004 -1.96646004 1.9258 -1.96646004 0 P 0 
L 1.92391004 -1.96546004 1.92696004 -1.96546004 0 P 0 
L 1.92513002 -1.96446004 1.92803002 -1.96446004 0 P 0 
L 1.9262 -1.96346004 1.92898996 -1.96346004 0 P 0 
L 1.92713996 -1.96246004 1.92986004 -1.96246004 0 P 0 
L 1.928 -1.96146004 1.93068996 -1.96146004 0 P 0 
L 1.92878002 -1.96046004 1.93143002 -1.96046004 0 P 0 
L 1.92951004 -1.95946004 1.93216004 -1.95946004 0 P 0 
L 1.93016998 -1.95846004 1.93278996 -1.95846004 0 P 0 
L 1.93078002 -1.95746004 1.93341004 -1.95746004 0 P 0 
L 1.93133002 -1.95646004 1.93396004 -1.95646004 0 P 0 
L 1.93185 -1.95546004 1.93448996 -1.95546004 0 P 0 
L 1.93231004 -1.95446004 1.93495 -1.95446004 0 P 0 
L 1.93275 -1.95346004 1.93541004 -1.95346004 0 P 0 
L 1.93311998 -1.95246004 1.93586004 -1.95246004 0 P 0 
L 1.93348002 -1.95146004 1.93628996 -1.95146004 0 P 0 
L 1.93376998 -1.95046004 1.93666004 -1.95046004 0 P 0 
L 1.93405 -1.94946004 1.93693002 -1.94946004 0 P 0 
L 1.93428002 -1.94846004 1.93715 -1.94846004 0 P 0 
L 1.93446998 -1.94746004 1.93733002 -1.94746004 0 P 0 
L 1.93466004 -1.94646004 1.93743002 -1.94646004 0 P 0 
L 1.93478996 -1.94546004 1.93748996 -1.94546004 0 P 0 
L 1.9349 -1.94446998 1.93751998 -1.94446998 0 P 0 
L 1.93496998 -1.94346004 1.93755 -1.94346004 0 P 0 
L 1.93501998 -1.94246004 1.93758002 -1.94246004 0 P 0 
L 1.93505 -1.94146998 1.93758996 -1.94146998 0 P 0 
L 1.93503002 -1.94046004 1.93755 -1.94046004 0 P 0 
L 1.935 -1.93946004 1.93751998 -1.93946004 0 P 0 
L 1.93491998 -1.93846004 1.93748002 -1.93846004 0 P 0 
L 1.93481004 -1.93746004 1.93738996 -1.93746004 0 P 0 
L 1.93468996 -1.93646004 1.93726998 -1.93646004 0 P 0 
L 1.93451004 -1.93546004 1.93716004 -1.93546004 0 P 0 
L 1.93433002 -1.93446004 1.93703996 -1.93446004 0 P 0 
L 1.93408996 -1.93346004 1.93685 -1.93346004 0 P 0 
L 1.93383002 -1.93246004 1.93666004 -1.93246004 0 P 0 
L 1.93353002 -1.93146004 1.93638996 -1.93146004 0 P 0 
L 1.9332 -1.93046004 1.93611998 -1.93046004 0 P 0 
L 1.93283996 -1.92946004 1.93576998 -1.92946004 0 P 0 
L 1.93241004 -1.92846004 1.93541004 -1.92846004 0 P 0 
L 1.93198996 -1.92746004 1.93498002 -1.92746004 0 P 0 
L 1.93146998 -1.92646004 1.93451004 -1.92646004 0 P 0 
L 1.93096004 -1.92546004 1.93398002 -1.92546004 0 P 0 
L 1.93035 -1.92446998 1.93338002 -1.92446998 0 P 0 
L 1.92973002 -1.92346004 1.93275 -1.92346004 0 P 0 
L 1.92903002 -1.92246004 1.93201004 -1.92246004 0 P 0 
L 1.92831004 -1.92146004 1.93125 -1.92146004 0 P 0 
L 1.92746998 -1.92046004 1.93041004 -1.92046004 0 P 0 
L 1.92661004 -1.91946004 1.92948996 -1.91946004 0 P 0 
L 1.92558996 -1.91846004 1.92851004 -1.91846004 0 P 0 
L 1.9245 -1.91746004 1.92741998 -1.91746004 0 P 0 
L 1.92328996 -1.91646004 1.92621998 -1.91646004 0 P 0 
L 1.92188002 -1.91546004 1.92491998 -1.91546004 0 P 0 
L 1.92026004 -1.91446004 1.92358996 -1.91446004 0 P 0 
L 1.91835 -1.91346004 1.92208002 -1.91346004 0 P 0 
L 1.82446998 -2.08323996 1.87608002 -2.08323996 0 P 0 
L 1.82403002 -2.08223996 1.87601004 -2.08223996 0 P 0 
L 1.8234 -2.08123996 1.87591004 -2.08123996 0 P 0 
L 1.82256004 -2.08023996 1.87578002 -2.08023996 0 P 0 
L 1.82166004 -2.07923996 1.87558996 -2.07923996 0 P 0 
L 1.82061998 -2.07823996 1.87533002 -2.07823996 0 P 0 
L 1.81946004 -2.07723996 1.87498996 -2.07723996 0 P 0 
L 1.81818002 -2.07623996 1.8746 -2.07623996 0 P 0 
L 1.8168 -2.07523996 1.87416998 -2.07523996 0 P 0 
L 1.81541998 -2.07423996 1.87371004 -2.07423996 0 P 0 
L 1.81403002 -2.07323996 1.87316998 -2.07323996 0 P 0 
L 1.81265 -2.07223996 1.87261004 -2.07223996 0 P 0 
L 1.81126998 -2.07123996 1.87196004 -2.07123996 0 P 0 
L 1.80986004 -2.07023996 1.87128002 -2.07023996 0 P 0 
L 1.80843996 -2.06923996 1.87051998 -2.06923996 0 P 0 
L 1.80703002 -2.06823996 1.8697 -2.06823996 0 P 0 
L 1.80561004 -2.06723996 1.86883002 -2.06723996 0 P 0 
L 1.8042 -2.06623996 1.86796004 -2.06623996 0 P 0 
L 1.80278002 -2.06523996 1.86705 -2.06523996 0 P 0 
L 1.80136004 -2.06423996 1.86608002 -2.06423996 0 P 0 
L 1.79995 -2.06323996 1.8651 -2.06323996 0 P 0 
L 1.79865 -2.06223996 1.86411004 -2.06223996 0 P 0 
L 1.79735 -2.06123996 1.86301998 -2.06123996 0 P 0 
L 1.79605 -2.06023996 1.86193002 -2.06023996 0 P 0 
L 1.79475 -2.05923996 1.86083996 -2.05923996 0 P 0 
L 1.79345 -2.05823996 1.85966998 -2.05823996 0 P 0 
L 1.79215 -2.05723996 1.85846004 -2.05723996 0 P 0 
L 1.79088002 -2.05623996 1.85726004 -2.05623996 0 P 0 
L 1.78971998 -2.05523996 1.85598996 -2.05523996 0 P 0 
L 1.78856004 -2.05423996 1.85461998 -2.05423996 0 P 0 
L 1.7874 -2.05323996 1.85326004 -2.05323996 0 P 0 
L 1.78623002 -2.05223996 1.8519 -2.05223996 0 P 0 
L 1.78506998 -2.05123996 1.85053996 -2.05123996 0 P 0 
L 1.78398002 -2.05023996 1.84918002 -2.05023996 0 P 0 
L 1.783 -2.04923996 1.84781004 -2.04923996 0 P 0 
L 1.87086004 -2.03023996 1.87535 -2.03023996 0 P 0 
L 1.91633002 -1.91473002 1.9183 -1.91565 0 P 0 
L 1.9183 -1.91565 1.92018996 -1.91673002 0 P 0 
L 1.92018996 -1.91673002 1.92196998 -1.91796998 0 P 0 
L 1.92196998 -1.91796998 1.92365 -1.91936004 0 P 0 
L 1.92365 -1.91936004 1.9252 -1.92088002 0 P 0 
L 1.9252 -1.92088002 1.92661004 -1.92253996 0 P 0 
L 1.92661004 -1.92253996 1.92795 -1.92436998 0 P 0 
L 1.92795 -1.92436998 1.92913996 -1.9263 0 P 0 
L 1.92913996 -1.9263 1.93018002 -1.92831998 0 P 0 
L 1.93018002 -1.92831998 1.93106998 -1.93041004 0 P 0 
L 1.93106998 -1.93041004 1.93178996 -1.93256004 0 P 0 
L 1.93178996 -1.93256004 1.93236004 -1.93476004 0 P 0 
L 1.93236004 -1.93476004 1.93276004 -1.93703996 0 P 0 
L 1.93276004 -1.93703996 1.93298996 -1.93933996 0 P 0 
L 1.93298996 -1.93933996 1.93306004 -1.94165 0 P 0 
L 1.93306004 -1.94165 1.93295 -1.94396998 0 P 0 
L 1.93295 -1.94396998 1.93268002 -1.94626004 0 P 0 
L 1.93268002 -1.94626004 1.93223002 -1.94853996 0 P 0 
L 1.93223002 -1.94853996 1.93161998 -1.95071998 0 P 0 
L 1.93161998 -1.95071998 1.93085 -1.95285 0 P 0 
L 1.93085 -1.95285 1.92991004 -1.95491004 0 P 0 
L 1.92991004 -1.95491004 1.92881004 -1.95688996 0 P 0 
L 1.92881004 -1.95688996 1.92756004 -1.95878002 0 P 0 
L 1.92756004 -1.95878002 1.92616004 -1.96056998 0 P 0 
L 1.92616004 -1.96056998 1.92493996 -1.9619 0 P 0 
L 1.92493996 -1.9619 1.92361998 -1.96313996 0 P 0 
L 1.92361998 -1.96313996 1.9222 -1.96426004 0 P 0 
L 1.9222 -1.96426004 1.9207 -1.96526998 0 P 0 
L 1.9207 -1.96526998 1.91911004 -1.96616998 0 P 0 
L 1.91911004 -1.96616998 1.91686998 -1.96721004 0 P 0 
L 1.91686998 -1.96721004 1.91456004 -1.96806998 0 P 0 
L 1.91456004 -1.96806998 1.91218996 -1.96876004 0 P 0 
L 1.91218996 -1.96876004 1.90975 -1.96926998 0 P 0 
L 1.90975 -1.96926998 1.90725 -1.9696 0 P 0 
L 1.90725 -1.9696 1.90473002 -1.96973996 0 P 0 
L 1.90473002 -1.96973996 1.9022 -1.96968996 0 P 0 
L 1.9022 -1.96968996 1.89966998 -1.96945 0 P 0 
L 1.89966998 -1.96945 1.89778002 -1.96913002 0 P 0 
L 1.89778002 -1.96913002 1.89591998 -1.96868996 0 P 0 
L 1.89591998 -1.96868996 1.8941 -1.96811004 0 P 0 
L 1.8941 -1.96811004 1.89231004 -1.96741004 0 P 0 
L 1.89231004 -1.96741004 1.89058002 -1.96658002 0 P 0 
L 1.89058002 -1.96658002 1.88875 -1.96553996 0 P 0 
L 1.88875 -1.96553996 1.88698996 -1.96435 0 P 0 
L 1.88698996 -1.96435 1.88533996 -1.96303002 0 P 0 
L 1.88533996 -1.96303002 1.88378996 -1.9616 0 P 0 
L 1.88378996 -1.9616 1.88235 -1.96003996 0 P 0 
L 1.88235 -1.96003996 1.88103002 -1.95838996 0 P 0 
L 1.88103002 -1.95838996 1.87983996 -1.95663002 0 P 0 
L 1.87983996 -1.95663002 1.87861998 -1.95446998 0 P 0 
L 1.87861998 -1.95446998 1.87758002 -1.9522 0 P 0 
L 1.87758002 -1.9522 1.87673996 -1.94986004 0 P 0 
L 1.87673996 -1.94986004 1.8761 -1.94745 0 P 0 
L 1.8761 -1.94745 1.87568002 -1.945 0 P 0 
L 1.87568002 -1.945 1.87546004 -1.94248996 0 P 0 
L 1.87546004 -1.94248996 1.87546004 -1.93998996 0 P 0 
L 1.87546004 -1.93998996 1.87566998 -1.93748996 0 P 0 
L 1.87566998 -1.93748996 1.87608996 -1.93501998 0 P 0 
L 1.87608996 -1.93501998 1.87671998 -1.9326 0 P 0 
L 1.87671998 -1.9326 1.87755 -1.93023002 0 P 0 
L 1.87755 -1.93023002 1.8786 -1.92793002 0 P 0 
L 1.8786 -1.92793002 1.87981998 -1.92575 0 P 0 
L 1.87981998 -1.92575 1.88123002 -1.92368002 0 P 0 
L 1.88123002 -1.92368002 1.88281004 -1.92175 0 P 0 
L 1.88281004 -1.92175 1.88455 -1.91996004 0 P 0 
L 1.88455 -1.91996004 1.88643002 -1.91831998 0 P 0 
L 1.88643002 -1.91831998 1.88845 -1.91686004 0 P 0 
L 1.88845 -1.91686004 1.88986998 -1.91598996 0 P 0 
L 1.88986998 -1.91598996 1.89135 -1.91523002 0 P 0 
L 1.89135 -1.91523002 1.89288002 -1.91458996 0 P 0 
L 1.89288002 -1.91458996 1.89446998 -1.91406004 0 P 0 
L 1.89446998 -1.91406004 1.89688996 -1.91343996 0 P 0 
L 1.89688996 -1.91343996 1.89935 -1.91298996 0 P 0 
L 1.89935 -1.91298996 1.90183996 -1.91271004 0 P 0 
L 1.90183996 -1.91271004 1.9044 -1.91261004 0 P 0 
L 1.9044 -1.91261004 1.90695 -1.91268002 0 P 0 
L 1.90695 -1.91268002 1.90948996 -1.91291998 0 P 0 
L 1.90948996 -1.91291998 1.91181998 -1.91331998 0 P 0 
L 1.91181998 -1.91331998 1.91408996 -1.91393002 0 P 0 
L 1.91408996 -1.91393002 1.91633002 -1.91473002 0 P 0 
L 1.89498002 -1.90801998 1.8922 -1.90893002 0 P 0 
L 1.8922 -1.90893002 1.88948002 -1.91003002 0 P 0 
L 1.88948002 -1.91003002 1.88686004 -1.91133002 0 P 0 
L 1.88686004 -1.91133002 1.88431004 -1.91283996 0 P 0 
L 1.88431004 -1.91283996 1.88201004 -1.91446004 0 P 0 
L 1.88201004 -1.91446004 1.87985 -1.91626998 0 P 0 
L 1.87985 -1.91626998 1.87785 -1.91826004 0 P 0 
L 1.87785 -1.91826004 1.87601998 -1.92041004 0 P 0 
L 1.87601998 -1.92041004 1.87441004 -1.92266998 0 P 0 
L 1.87441004 -1.92266998 1.87298996 -1.92505 0 P 0 
L 1.87298996 -1.92505 1.87178002 -1.92756004 0 P 0 
L 1.87178002 -1.92756004 1.87078996 -1.93015 0 P 0 
L 1.87078996 -1.93015 1.87 -1.93286998 0 P 0 
L 1.87 -1.93286998 1.86943996 -1.93563996 0 P 0 
L 1.86943996 -1.93563996 1.86908996 -1.93845 0 P 0 
L 1.86908996 -1.93845 1.86898002 -1.94128996 0 P 0 
L 1.86898002 -1.94128996 1.86911998 -1.94485 0 P 0 
L 1.86911998 -1.94485 1.86953996 -1.94841004 0 P 0 
L 1.86953996 -1.94841004 1.86996004 -1.95048996 0 P 0 
L 1.86996004 -1.95048996 1.87053002 -1.95251998 0 P 0 
L 1.87053002 -1.95251998 1.87125 -1.95451998 0 P 0 
L 1.87125 -1.95451998 1.87211004 -1.95643002 0 P 0 
L 1.87211004 -1.95643002 1.8731 -1.95826004 0 P 0 
L 1.8731 -1.95826004 1.87423996 -1.96001998 0 P 0 
L 1.87423996 -1.96001998 1.87636998 -1.96278996 0 P 0 
L 1.87636998 -1.96278996 1.87871998 -1.96536998 0 P 0 
L 1.87871998 -1.96536998 1.88145 -1.96788002 0 P 0 
L 1.88145 -1.96788002 1.88436998 -1.97015 0 P 0 
L 1.88436998 -1.97015 1.88621004 -1.97135 0 P 0 
L 1.88621004 -1.97135 1.88813002 -1.97238002 0 P 0 
L 1.88813002 -1.97238002 1.89013002 -1.97326004 0 P 0 
L 1.89013002 -1.97326004 1.89228002 -1.97398996 0 P 0 
L 1.89228002 -1.97398996 1.89446998 -1.97455 0 P 0 
L 1.89446998 -1.97455 1.89671004 -1.97493996 0 P 0 
L 1.89671004 -1.97493996 1.90076998 -1.97533996 0 P 0 
L 1.90076998 -1.97533996 1.90485 -1.97546998 0 P 0 
L 1.90485 -1.97546998 1.90821004 -1.97531998 0 P 0 
L 1.90821004 -1.97531998 1.91153996 -1.97488996 0 P 0 
L 1.91153996 -1.97488996 1.91481998 -1.97418996 0 P 0 
L 1.91481998 -1.97418996 1.9171 -1.9735 0 P 0 
L 1.9171 -1.9735 1.91933002 -1.97266004 0 P 0 
L 1.91933002 -1.97266004 1.92148002 -1.97166004 0 P 0 
L 1.92148002 -1.97166004 1.92356998 -1.97048996 0 P 0 
L 1.92356998 -1.97048996 1.92553996 -1.96918996 0 P 0 
L 1.92553996 -1.96918996 1.92741004 -1.96773996 0 P 0 
L 1.92741004 -1.96773996 1.92916004 -1.96616998 0 P 0 
L 1.92916004 -1.96616998 1.93081004 -1.96446004 0 P 0 
L 1.93081004 -1.96446004 1.93236998 -1.96256998 0 P 0 
L 1.93236998 -1.96256998 1.93381004 -1.96058996 0 P 0 
L 1.93381004 -1.96058996 1.93511998 -1.95851004 0 P 0 
L 1.93511998 -1.95851004 1.93628996 -1.95633996 0 P 0 
L 1.93628996 -1.95633996 1.93803996 -1.95251998 0 P 0 
L 1.93803996 -1.95251998 1.93858002 -1.95101998 0 P 0 
L 1.93858002 -1.95101998 1.93898996 -1.94948002 0 P 0 
L 1.93898996 -1.94948002 1.93928996 -1.94786998 0 P 0 
L 1.93928996 -1.94786998 1.93946004 -1.94625 0 P 0 
L 1.93946004 -1.94625 1.9396 -1.94178002 0 P 0 
L 1.9396 -1.94178002 1.93946004 -1.93803996 0 P 0 
L 1.93946004 -1.93803996 1.93905 -1.9343 0 P 0 
L 1.93905 -1.9343 1.93863996 -1.93213996 0 P 0 
L 1.93863996 -1.93213996 1.93808002 -1.93001998 0 P 0 
L 1.93808002 -1.93001998 1.93736004 -1.92795 0 P 0 
L 1.93736004 -1.92795 1.93653002 -1.92601004 0 P 0 
L 1.93653002 -1.92601004 1.93555 -1.92415 0 P 0 
L 1.93555 -1.92415 1.93441998 -1.92236004 0 P 0 
L 1.93441998 -1.92236004 1.9331 -1.92056004 0 P 0 
L 1.9331 -1.92056004 1.93166998 -1.91885 0 P 0 
L 1.93166998 -1.91885 1.93011998 -1.91723002 0 P 0 
L 1.93011998 -1.91723002 1.92896004 -1.91615 0 P 0 
L 1.92896004 -1.91615 1.92775 -1.91511004 0 P 0 
L 1.92775 -1.91511004 1.92493002 -1.91295 0 P 0 
L 1.92493002 -1.91295 1.9221 -1.91108002 0 P 0 
L 1.9221 -1.91108002 1.92095 -1.91043002 0 P 0 
L 1.92095 -1.91043002 1.91975 -1.90985 0 P 0 
L 1.91975 -1.90985 1.91796004 -1.90913996 0 P 0 
L 1.91796004 -1.90913996 1.91613002 -1.90856004 0 P 0 
L 1.91613002 -1.90856004 1.91423996 -1.9081 0 P 0 
L 1.91423996 -1.9081 1.91086004 -1.90751998 0 P 0 
L 1.91086004 -1.90751998 1.90743002 -1.90716004 0 P 0 
L 1.90743002 -1.90716004 1.90401004 -1.90701004 0 P 0 
L 1.90401004 -1.90701004 1.90058002 -1.90708002 0 P 0 
L 1.90058002 -1.90708002 1.8987 -1.90726004 0 P 0 
L 1.8987 -1.90726004 1.89683002 -1.90756998 0 P 0 
L 1.89683002 -1.90756998 1.89498002 -1.90801998 0 P 0 
L 1.86643002 -2.02923996 1.87525 -2.02923996 0 P 0 
L 1.86176998 -2.02823996 1.87515 -2.02823996 0 P 0 
L 1.85588996 -2.02723996 1.87505 -2.02723996 0 P 0 
L 1.78365 -2.00523996 1.87281004 -2.00523996 0 P 0 
L 1.78451004 -2.00423996 1.87271004 -2.00423996 0 P 0 
L 1.78546998 -2.00323996 1.87261004 -2.00323996 0 P 0 
L 1.78655 -2.00223996 1.8725 -2.00223996 0 P 0 
L 1.78776004 -2.00123996 1.8724 -2.00123996 0 P 0 
L 1.78915 -2.00023996 1.8723 -2.00023996 0 P 0 
L 1.79078996 -1.99923996 1.8722 -1.99923996 0 P 0 
L 1.79263996 -1.99823996 1.87208996 -1.99823996 0 P 0 
L 1.79458996 -1.99723996 1.87198996 -1.99723996 0 P 0 
L 1.79686998 -1.99623996 1.87188002 -1.99623996 0 P 0 
L 1.79946004 -1.99523996 1.87178002 -1.99523996 0 P 0 
L 1.80231004 -1.99423996 1.86961998 -1.99423996 0 P 0 
L 1.80596004 -1.99323996 1.86218002 -1.99323996 0 P 0 
L 1.81051004 -1.99223996 1.85398002 -1.99223996 0 P 0 
L 1.81676004 -1.99123996 1.84395 -1.99123996 0 P 0 
L 1.87786998 -1.96146004 1.88093996 -1.96146004 0 P 0 
L 1.8771 -1.96046004 1.88013002 -1.96046004 0 P 0 
L 1.87633996 -1.95946004 1.87933996 -1.95946004 0 P 0 
L 1.87561998 -1.95846004 1.87866998 -1.95846004 0 P 0 
L 1.87496998 -1.95746004 1.87801998 -1.95746004 0 P 0 
L 1.8744 -1.95646004 1.87745 -1.95646004 0 P 0 
L 1.87386998 -1.95546004 1.87688002 -1.95546004 0 P 0 
L 1.87341998 -1.95446004 1.87641998 -1.95446004 0 P 0 
L 1.87298996 -1.95346004 1.87596004 -1.95346004 0 P 0 
L 1.87263002 -1.95246004 1.87555 -1.95246004 0 P 0 
L 1.87231004 -1.95146004 1.87518996 -1.95146004 0 P 0 
L 1.87203002 -1.95046004 1.87483002 -1.95046004 0 P 0 
L 1.87178996 -1.94946004 1.87456998 -1.94946004 0 P 0 
L 1.87158996 -1.94846004 1.87431004 -1.94846004 0 P 0 
L 1.87143996 -1.94746004 1.87408002 -1.94746004 0 P 0 
L 1.87133002 -1.94646004 1.8739 -1.94646004 0 P 0 
L 1.87121004 -1.94546004 1.87373002 -1.94546004 0 P 0 
L 1.8711 -1.94446998 1.87361998 -1.94446998 0 P 0 
L 1.87106998 -1.94346004 1.87353996 -1.94346004 0 P 0 
L 1.87103002 -1.94246004 1.87346004 -1.94246004 0 P 0 
L 1.87098996 -1.94146998 1.87346004 -1.94146998 0 P 0 
L 1.87101004 -1.94046004 1.87346004 -1.94046004 0 P 0 
L 1.87106004 -1.93946004 1.87348996 -1.93946004 0 P 0 
L 1.87111004 -1.93846004 1.87358002 -1.93846004 0 P 0 
L 1.87123002 -1.93746004 1.87366004 -1.93746004 0 P 0 
L 1.87135 -1.93646004 1.87381998 -1.93646004 0 P 0 
L 1.87151004 -1.93546004 1.87398996 -1.93546004 0 P 0 
L 1.87171998 -1.93446004 1.87416998 -1.93446004 0 P 0 
L 1.87191998 -1.93346004 1.87443002 -1.93346004 0 P 0 
L 1.8722 -1.93246004 1.87468996 -1.93246004 0 P 0 
L 1.87248996 -1.93146004 1.875 -1.93146004 0 P 0 
L 1.87281004 -1.93046004 1.87535 -1.93046004 0 P 0 
L 1.87318996 -1.92946004 1.87571004 -1.92946004 0 P 0 
L 1.87356998 -1.92846004 1.87616004 -1.92846004 0 P 0 
L 1.87405 -1.92746004 1.87661004 -1.92746004 0 P 0 
L 1.87453002 -1.92646004 1.87711998 -1.92646004 0 P 0 
L 1.87506998 -1.92546004 1.87768996 -1.92546004 0 P 0 
L 1.87566004 -1.92446998 1.87826998 -1.92446998 0 P 0 
L 1.87628996 -1.92346004 1.87896004 -1.92346004 0 P 0 
L 1.87701004 -1.92246004 1.87963996 -1.92246004 0 P 0 
L 1.87775 -1.92146004 1.88046004 -1.92146004 0 P 0 
L 1.90483996 -1.97346004 1.9009 -1.97333996 0 P 0 
L 1.9009 -1.97333996 1.89698002 -1.97295 0 P 0 
L 1.89698002 -1.97295 1.89488996 -1.97258996 0 P 0 
L 1.89488996 -1.97258996 1.89285 -1.97206998 0 P 0 
L 1.89285 -1.97206998 1.89086004 -1.97138996 0 P 0 
L 1.89086004 -1.97138996 1.889 -1.97058002 0 P 0 
L 1.889 -1.97058002 1.88723002 -1.96961998 0 P 0 
L 1.88723002 -1.96961998 1.88553002 -1.96851998 0 P 0 
L 1.88553002 -1.96851998 1.88273996 -1.96636004 0 P 0 
L 1.88273996 -1.96636004 1.88013996 -1.96396004 0 P 0 
L 1.88013996 -1.96396004 1.8779 -1.9615 0 P 0 
L 1.8779 -1.9615 1.87588002 -1.95886998 0 P 0 
L 1.87588002 -1.95886998 1.87483002 -1.95723996 0 P 0 
L 1.87483002 -1.95723996 1.8739 -1.95553996 0 P 0 
L 1.8739 -1.95553996 1.87311004 -1.95376998 0 P 0 
L 1.87311004 -1.95376998 1.87243002 -1.95191004 0 P 0 
L 1.87243002 -1.95191004 1.8719 -1.95001998 0 P 0 
L 1.8719 -1.95001998 1.87151998 -1.9481 0 P 0 
L 1.87151998 -1.9481 1.87111004 -1.94468996 0 P 0 
L 1.87111004 -1.94468996 1.87098002 -1.94128996 0 P 0 
L 1.87098002 -1.94128996 1.87108996 -1.93861004 0 P 0 
L 1.87108996 -1.93861004 1.87141004 -1.93596998 0 P 0 
L 1.87141004 -1.93596998 1.87195 -1.93335 0 P 0 
L 1.87195 -1.93335 1.87268996 -1.93078996 0 P 0 
L 1.87268996 -1.93078996 1.87361998 -1.92835 0 P 0 
L 1.87361998 -1.92835 1.87475 -1.926 0 P 0 
L 1.87475 -1.926 1.87608996 -1.92376004 0 P 0 
L 1.87608996 -1.92376004 1.8776 -1.92163996 0 P 0 
L 1.8776 -1.92163996 1.87931998 -1.91961998 0 P 0 
L 1.87931998 -1.91961998 1.8812 -1.91775 0 P 0 
L 1.8812 -1.91775 1.88323002 -1.91605 0 P 0 
L 1.88323002 -1.91605 1.8854 -1.91451998 0 P 0 
L 1.8854 -1.91451998 1.88781004 -1.91308996 0 P 0 
L 1.88781004 -1.91308996 1.89031004 -1.91186004 0 P 0 
L 1.89031004 -1.91186004 1.89288002 -1.9108 0 P 0 
L 1.89288002 -1.9108 1.89553002 -1.90995 0 P 0 
L 1.89553002 -1.90995 1.89723002 -1.90953002 0 P 0 
L 1.89723002 -1.90953002 1.89896004 -1.90923996 0 P 0 
L 1.89896004 -1.90923996 1.90068996 -1.90908002 0 P 0 
L 1.90068996 -1.90908002 1.90398996 -1.90901004 0 P 0 
L 1.90398996 -1.90901004 1.90728002 -1.90915 0 P 0 
L 1.90728002 -1.90915 1.91058996 -1.90951004 0 P 0 
L 1.91058996 -1.90951004 1.91383996 -1.91006004 0 P 0 
L 1.91383996 -1.91006004 1.91558996 -1.91048996 0 P 0 
L 1.91558996 -1.91048996 1.91728996 -1.91101998 0 P 0 
L 1.91728996 -1.91101998 1.91895 -1.91168002 0 P 0 
L 1.91895 -1.91168002 1.92001998 -1.9122 0 P 0 
L 1.92001998 -1.9122 1.92105 -1.91278996 0 P 0 
L 1.92105 -1.91278996 1.92376998 -1.91458002 0 P 0 
L 1.92376998 -1.91458002 1.92648996 -1.91666998 0 P 0 
L 1.92648996 -1.91666998 1.92763002 -1.91763996 0 P 0 
L 1.92763002 -1.91763996 1.92871004 -1.91865 0 P 0 
L 1.92871004 -1.91865 1.93018002 -1.92018996 0 P 0 
L 1.93018002 -1.92018996 1.93153002 -1.9218 0 P 0 
L 1.93153002 -1.9218 1.93276998 -1.92348996 0 P 0 
L 1.93276998 -1.92348996 1.93381004 -1.92515 0 P 0 
L 1.93381004 -1.92515 1.93471998 -1.92686998 0 P 0 
L 1.93471998 -1.92686998 1.9355 -1.92866998 0 P 0 
L 1.9355 -1.92866998 1.93616998 -1.93061004 0 P 0 
L 1.93616998 -1.93061004 1.93668996 -1.93258002 0 P 0 
L 1.93668996 -1.93258002 1.93706998 -1.93458996 0 P 0 
L 1.93706998 -1.93458996 1.93746998 -1.93818996 0 P 0 
L 1.93746998 -1.93818996 1.9376 -1.94178996 0 P 0 
L 1.9376 -1.94178996 1.93746004 -1.94611004 0 P 0 
L 1.93746004 -1.94611004 1.93731004 -1.94758996 0 P 0 
L 1.93731004 -1.94758996 1.93705 -1.94903996 0 P 0 
L 1.93705 -1.94903996 1.93666998 -1.95041998 0 P 0 
L 1.93666998 -1.95041998 1.93618002 -1.95176004 0 P 0 
L 1.93618002 -1.95176004 1.9345 -1.95545 0 P 0 
L 1.9345 -1.95545 1.93338996 -1.9575 0 P 0 
L 1.93338996 -1.9575 1.93216004 -1.95946998 0 P 0 
L 1.93216004 -1.95946998 1.93078996 -1.96133996 0 P 0 
L 1.93078996 -1.96133996 1.92931004 -1.96311998 0 P 0 
L 1.92931004 -1.96311998 1.92776998 -1.96473002 0 P 0 
L 1.92776998 -1.96473002 1.92613002 -1.96621004 0 P 0 
L 1.92613002 -1.96621004 1.92438002 -1.96756004 0 P 0 
L 1.92438002 -1.96756004 1.92253002 -1.96878002 0 P 0 
L 1.92253002 -1.96878002 1.92056998 -1.96986998 0 P 0 
L 1.92056998 -1.96986998 1.91855 -1.97081998 0 P 0 
L 1.91855 -1.97081998 1.91646004 -1.97161004 0 P 0 
L 1.91646004 -1.97161004 1.91433002 -1.97223996 0 P 0 
L 1.91433002 -1.97223996 1.9112 -1.97291004 0 P 0 
L 1.9112 -1.97291004 1.90803996 -1.97331998 0 P 0 
L 1.90803996 -1.97331998 1.90483996 -1.97346004 0 P 0 
L 1.90476004 -1.97173996 1.9048 -1.97173996 0 P 0 
L 1.9048 -1.97173996 1.90483996 -1.97173002 0 P 0 
L 1.90483996 -1.97173002 1.90736004 -1.9716 0 P 0 
L 1.90736004 -1.9716 1.9074 -1.97158996 0 P 0 
L 1.9074 -1.97158996 1.90746998 -1.97158996 0 P 0 
L 1.90746998 -1.97158996 1.90751004 -1.97158002 0 P 0 
L 1.90751004 -1.97158002 1.91001004 -1.97126004 0 P 0 
L 1.91001004 -1.97126004 1.91005 -1.97125 0 P 0 
L 1.91005 -1.97125 1.91008002 -1.97123996 0 P 0 
L 1.91008002 -1.97123996 1.91011998 -1.97123996 0 P 0 
L 1.91011998 -1.97123996 1.91016004 -1.97123002 0 P 0 
L 1.91016004 -1.97123002 1.9126 -1.97071998 0 P 0 
L 1.9126 -1.97071998 1.9126 -1.97071004 0 P 0 
L 1.9126 -1.97071004 1.91266998 -1.97071004 0 P 0 
L 1.91266998 -1.97071004 1.91271004 -1.97068996 0 P 0 
L 1.91271004 -1.97068996 1.91275 -1.97068002 0 P 0 
L 1.91275 -1.97068002 1.91511998 -1.96998996 0 P 0 
L 1.91511998 -1.96998996 1.91515 -1.96998996 0 P 0 
L 1.91515 -1.96998996 1.91518996 -1.96996998 0 P 0 
L 1.91518996 -1.96996998 1.91523002 -1.96996004 0 P 0 
L 1.91523002 -1.96996004 1.91526004 -1.96995 0 P 0 
L 1.91526004 -1.96995 1.91756998 -1.96908002 0 P 0 
L 1.91756998 -1.96908002 1.91761004 -1.96906998 0 P 0 
L 1.91761004 -1.96906998 1.91768002 -1.96903996 0 P 0 
L 1.91768002 -1.96903996 1.91771004 -1.96901998 0 P 0 
L 1.91771004 -1.96901998 1.91995 -1.96798002 0 P 0 
L 1.91995 -1.96798002 1.92001998 -1.96795 0 P 0 
L 1.92001998 -1.96795 1.92005 -1.96793002 0 P 0 
L 1.92005 -1.96793002 1.92008996 -1.96791004 0 P 0 
L 1.92008996 -1.96791004 1.92168002 -1.96701998 0 P 0 
L 1.92168002 -1.96701998 1.92171998 -1.967 0 P 0 
L 1.92171998 -1.967 1.92175 -1.96698002 0 P 0 
L 1.92175 -1.96698002 1.92178996 -1.96695 0 P 0 
L 1.92178996 -1.96695 1.92181998 -1.96693002 0 P 0 
L 1.92181998 -1.96693002 1.92331998 -1.96591998 0 P 0 
L 1.92331998 -1.96591998 1.92336004 -1.9659 0 P 0 
L 1.92336004 -1.9659 1.92341998 -1.96586004 0 P 0 
L 1.92341998 -1.96586004 1.92345 -1.96583002 0 P 0 
L 1.92345 -1.96583002 1.92486004 -1.9647 0 P 0 
L 1.92486004 -1.9647 1.92493002 -1.96465 0 P 0 
L 1.92493002 -1.96465 1.92496004 -1.96463002 0 P 0 
L 1.92496004 -1.96463002 1.92498996 -1.9646 0 P 0 
L 1.92498996 -1.9646 1.92631004 -1.96336998 0 P 0 
L 1.92631004 -1.96336998 1.9264 -1.96328002 0 P 0 
L 1.9264 -1.96328002 1.92641998 -1.96325 0 P 0 
L 1.92641998 -1.96325 1.92763996 -1.96191998 0 P 0 
L 1.92763996 -1.96191998 1.92766998 -1.96188996 0 P 0 
L 1.92766998 -1.96188996 1.92768996 -1.96186004 0 P 0 
L 1.92768996 -1.96186004 1.92771998 -1.96183002 0 P 0 
L 1.92771998 -1.96183002 1.92773996 -1.9618 0 P 0 
L 1.92773996 -1.9618 1.92913996 -1.96001004 0 P 0 
L 1.92913996 -1.96001004 1.92918996 -1.95995 0 P 0 
L 1.92918996 -1.95995 1.92921004 -1.95991004 0 P 0 
L 1.92921004 -1.95991004 1.92923002 -1.95988002 0 P 0 
L 1.92923002 -1.95988002 1.93048002 -1.95798996 0 P 0 
L 1.93048002 -1.95798996 1.93051998 -1.95793002 0 P 0 
L 1.93051998 -1.95793002 1.93053996 -1.95788996 0 P 0 
L 1.93053996 -1.95788996 1.93056004 -1.95786004 0 P 0 
L 1.93056004 -1.95786004 1.93166004 -1.95588002 0 P 0 
L 1.93166004 -1.95588002 1.93171004 -1.95576998 0 P 0 
L 1.93171004 -1.95576998 1.93173002 -1.95573996 0 P 0 
L 1.93173002 -1.95573996 1.93266998 -1.95366998 0 P 0 
L 1.93266998 -1.95366998 1.93271004 -1.95356998 0 P 0 
L 1.93271004 -1.95356998 1.93273002 -1.95353002 0 P 0 
L 1.93273002 -1.95353002 1.9335 -1.9514 0 P 0 
L 1.9335 -1.9514 1.93351004 -1.95136998 0 P 0 
L 1.93351004 -1.95136998 1.93353002 -1.95133002 0 P 0 
L 1.93353002 -1.95133002 1.93355 -1.95125 0 P 0 
L 1.93355 -1.95125 1.93416004 -1.94906998 0 P 0 
L 1.93416004 -1.94906998 1.93416998 -1.94903002 0 P 0 
L 1.93416998 -1.94903002 1.93418002 -1.949 0 P 0 
L 1.93418002 -1.949 1.93418002 -1.94896004 0 P 0 
L 1.93418002 -1.94896004 1.93418996 -1.94891998 0 P 0 
L 1.93418996 -1.94891998 1.93463996 -1.94665 0 P 0 
L 1.93463996 -1.94665 1.93463996 -1.94661004 0 P 0 
L 1.93463996 -1.94661004 1.93465 -1.94656998 0 P 0 
L 1.93465 -1.94656998 1.93466004 -1.9465 0 P 0 
L 1.93466004 -1.9465 1.93493996 -1.9442 0 P 0 
L 1.93493996 -1.9442 1.93493996 -1.94413002 0 P 0 
L 1.93493996 -1.94413002 1.93495 -1.94408996 0 P 0 
L 1.93495 -1.94408996 1.93495 -1.94406004 0 P 0 
L 1.93495 -1.94406004 1.93505 -1.94173996 0 P 0 
L 1.93505 -1.94173996 1.93506004 -1.94171004 0 P 0 
L 1.93506004 -1.94171004 1.93506004 -1.9416 0 P 0 
L 1.93506004 -1.9416 1.93498996 -1.93928996 0 P 0 
L 1.93498996 -1.93928996 1.93498996 -1.93921004 0 P 0 
L 1.93498996 -1.93921004 1.93498002 -1.93913996 0 P 0 
L 1.93498002 -1.93913996 1.93475 -1.93683996 0 P 0 
L 1.93475 -1.93683996 1.93473996 -1.93676998 0 P 0 
L 1.93473996 -1.93676998 1.93473002 -1.93673002 0 P 0 
L 1.93473002 -1.93673002 1.93473002 -1.93668996 0 P 0 
L 1.93473002 -1.93668996 1.93433002 -1.93441004 0 P 0 
L 1.93433002 -1.93441004 1.93431998 -1.93436998 0 P 0 
L 1.93431998 -1.93436998 1.93431004 -1.93433996 0 P 0 
L 1.93431004 -1.93433996 1.93428996 -1.93426004 0 P 0 
L 1.93428996 -1.93426004 1.93373002 -1.93206004 0 P 0 
L 1.93373002 -1.93206004 1.93368996 -1.93191998 0 P 0 
L 1.93368996 -1.93191998 1.93296004 -1.92976998 0 P 0 
L 1.93296004 -1.92976998 1.93293996 -1.9297 0 P 0 
L 1.93293996 -1.9297 1.93291004 -1.92963002 0 P 0 
L 1.93291004 -1.92963002 1.93201998 -1.92753996 0 P 0 
L 1.93201998 -1.92753996 1.93196998 -1.92743002 0 P 0 
L 1.93196998 -1.92743002 1.93196004 -1.9274 0 P 0 
L 1.93196004 -1.9274 1.93091998 -1.92538996 0 P 0 
L 1.93091998 -1.92538996 1.9309 -1.92536004 0 P 0 
L 1.9309 -1.92536004 1.93088002 -1.92531998 0 P 0 
L 1.93088002 -1.92531998 1.93086004 -1.92528996 0 P 0 
L 1.93086004 -1.92528996 1.93083996 -1.92525 0 P 0 
L 1.93083996 -1.92525 1.92965 -1.92331998 0 P 0 
L 1.92965 -1.92331998 1.92956998 -1.9232 0 P 0 
L 1.92956998 -1.9232 1.92823002 -1.92136004 0 P 0 
L 1.92823002 -1.92136004 1.92818002 -1.9213 0 P 0 
L 1.92818002 -1.9213 1.92816004 -1.92126998 0 P 0 
L 1.92816004 -1.92126998 1.92813002 -1.92123996 0 P 0 
L 1.92813002 -1.92123996 1.92671998 -1.91958002 0 P 0 
L 1.92671998 -1.91958002 1.9266 -1.91946004 0 P 0 
L 1.9266 -1.91946004 1.92505 -1.91793002 0 P 0 
L 1.92505 -1.91793002 1.92498996 -1.91786998 0 P 0 
L 1.92498996 -1.91786998 1.92493002 -1.91781998 0 P 0 
L 1.92493002 -1.91781998 1.92325 -1.91643002 0 P 0 
L 1.92325 -1.91643002 1.92318996 -1.91636998 0 P 0 
L 1.92318996 -1.91636998 1.92311998 -1.91631998 0 P 0 
L 1.92311998 -1.91631998 1.92133002 -1.91508002 0 P 0 
L 1.92133002 -1.91508002 1.92126004 -1.91503996 0 P 0 
L 1.92126004 -1.91503996 1.92121998 -1.91501004 0 P 0 
L 1.92121998 -1.91501004 1.92118002 -1.91498996 0 P 0 
L 1.92118002 -1.91498996 1.91928996 -1.91391004 0 P 0 
L 1.91928996 -1.91391004 1.91926004 -1.91388996 0 P 0 
L 1.91926004 -1.91388996 1.91913996 -1.91383002 0 P 0 
L 1.91913996 -1.91383002 1.91716998 -1.91291004 0 P 0 
L 1.91716998 -1.91291004 1.91711998 -1.91288996 0 P 0 
L 1.91711998 -1.91288996 1.91705 -1.91286004 0 P 0 
L 1.91705 -1.91286004 1.917 -1.91285 0 P 0 
L 1.917 -1.91285 1.91476998 -1.91203996 0 P 0 
L 1.91476998 -1.91203996 1.91468996 -1.91201998 0 P 0 
L 1.91468996 -1.91201998 1.91465 -1.912 0 P 0 
L 1.91465 -1.912 1.9146 -1.91198996 0 P 0 
L 1.9146 -1.91198996 1.91233002 -1.91138996 0 P 0 
L 1.91233002 -1.91138996 1.91228002 -1.91138002 0 P 0 
L 1.91228002 -1.91138002 1.91223996 -1.91136998 0 P 0 
L 1.91223996 -1.91136998 1.91216004 -1.91136004 0 P 0 
L 1.91216004 -1.91136004 1.90983002 -1.91095 0 P 0 
L 1.90983002 -1.91095 1.9098 -1.91093996 0 P 0 
L 1.9098 -1.91093996 1.90976004 -1.91093996 0 P 0 
L 1.90976004 -1.91093996 1.90971998 -1.91093002 0 P 0 
L 1.90971998 -1.91093002 1.90968002 -1.91093002 0 P 0 
L 1.90968002 -1.91093002 1.90713996 -1.91068996 0 P 0 
L 1.90713996 -1.91068996 1.9071 -1.91068002 0 P 0 
L 1.9071 -1.91068002 1.907 -1.91068002 0 P 0 
L 1.907 -1.91068002 1.90445 -1.91061004 0 P 0 
L 1.90445 -1.91061004 1.90431004 -1.91061004 0 P 0 
L 1.90431004 -1.91061004 1.90176004 -1.91071004 0 P 0 
L 1.90176004 -1.91071004 1.90173002 -1.91071998 0 P 0 
L 1.90173002 -1.91071998 1.90166004 -1.91071998 0 P 0 
L 1.90166004 -1.91071998 1.90161998 -1.91073002 0 P 0 
L 1.90161998 -1.91073002 1.89913002 -1.911 0 P 0 
L 1.89913002 -1.911 1.89906004 -1.91101004 0 P 0 
L 1.89906004 -1.91101004 1.89901998 -1.91101998 0 P 0 
L 1.89901998 -1.91101998 1.89898996 -1.91101998 0 P 0 
L 1.89898996 -1.91101998 1.89653002 -1.91146998 0 P 0 
L 1.89653002 -1.91146998 1.8965 -1.91148002 0 P 0 
L 1.8965 -1.91148002 1.89646004 -1.91148002 0 P 0 
L 1.89646004 -1.91148002 1.8964 -1.9115 0 P 0 
L 1.8964 -1.9115 1.89396998 -1.91211998 0 P 0 
L 1.89396998 -1.91211998 1.89393996 -1.91213002 0 P 0 
L 1.89393996 -1.91213002 1.89383002 -1.91216004 0 P 0 
L 1.89383002 -1.91216004 1.89225 -1.91268996 0 P 0 
L 1.89225 -1.91268996 1.89218002 -1.91271998 0 P 0 
L 1.89218002 -1.91271998 1.89211004 -1.91273996 0 P 0 
L 1.89211004 -1.91273996 1.8921 -1.91273996 0 P 0 
L 1.8921 -1.91273996 1.89058002 -1.91338996 0 P 0 
L 1.89058002 -1.91338996 1.89043996 -1.91345 0 P 0 
L 1.89043996 -1.91345 1.88896004 -1.91421004 0 P 0 
L 1.88896004 -1.91421004 1.88893002 -1.91423002 0 P 0 
L 1.88893002 -1.91423002 1.8889 -1.91423996 0 P 0 
L 1.8889 -1.91423996 1.88886004 -1.91426004 0 P 0 
L 1.88886004 -1.91426004 1.88883002 -1.91428002 0 P 0 
L 1.88883002 -1.91428002 1.88741004 -1.91515 0 P 0 
L 1.88741004 -1.91515 1.88733996 -1.91518996 0 P 0 
L 1.88733996 -1.91518996 1.88728002 -1.91523996 0 P 0 
L 1.88728002 -1.91523996 1.88526004 -1.9167 0 P 0 
L 1.88526004 -1.9167 1.88521998 -1.91673002 0 P 0 
L 1.88521998 -1.91673002 1.88518996 -1.91675 0 P 0 
L 1.88518996 -1.91675 1.88516004 -1.91678002 0 P 0 
L 1.88516004 -1.91678002 1.88511998 -1.91681004 0 P 0 
L 1.88511998 -1.91681004 1.88323002 -1.91845 0 P 0 
L 1.88323002 -1.91845 1.8832 -1.91846998 0 P 0 
L 1.8832 -1.91846998 1.88311004 -1.91856004 0 P 0 
L 1.88311004 -1.91856004 1.88136998 -1.92036004 0 P 0 
L 1.88136998 -1.92036004 1.88128002 -1.92045 0 P 0 
L 1.88128002 -1.92045 1.88125 -1.92048996 0 P 0 
L 1.88125 -1.92048996 1.87968002 -1.92241998 0 P 0 
L 1.87968002 -1.92241998 1.87965 -1.92245 0 P 0 
L 1.87965 -1.92245 1.87961998 -1.92248996 0 P 0 
L 1.87961998 -1.92248996 1.87956998 -1.92256004 0 P 0 
L 1.87956998 -1.92256004 1.87816998 -1.92461998 0 P 0 
L 1.87816998 -1.92461998 1.8781 -1.92473002 0 P 0 
L 1.8781 -1.92473002 1.87808002 -1.92476998 0 P 0 
L 1.87808002 -1.92476998 1.87685 -1.92695 0 P 0 
L 1.87685 -1.92695 1.87683002 -1.92698996 0 P 0 
L 1.87683002 -1.92698996 1.87681004 -1.92701998 0 P 0 
L 1.87681004 -1.92701998 1.87678996 -1.92706998 0 P 0 
L 1.87678996 -1.92706998 1.87676998 -1.92711004 0 P 0 
L 1.87676998 -1.92711004 1.87573002 -1.92941004 0 P 0 
L 1.87573002 -1.92941004 1.87571004 -1.92945 0 P 0 
L 1.87571004 -1.92945 1.8757 -1.92948996 0 P 0 
L 1.8757 -1.92948996 1.87568002 -1.92951998 0 P 0 
L 1.87568002 -1.92951998 1.87566998 -1.92956998 0 P 0 
L 1.87566998 -1.92956998 1.87483996 -1.93193002 0 P 0 
L 1.87483996 -1.93193002 1.87481004 -1.93201004 0 P 0 
L 1.87481004 -1.93201004 1.87478996 -1.93208996 0 P 0 
L 1.87478996 -1.93208996 1.87416004 -1.93451998 0 P 0 
L 1.87416004 -1.93451998 1.87413996 -1.93456004 0 P 0 
L 1.87413996 -1.93456004 1.87413002 -1.9346 0 P 0 
L 1.87413002 -1.9346 1.87413002 -1.93463996 0 P 0 
L 1.87413002 -1.93463996 1.87411998 -1.93468002 0 P 0 
L 1.87411998 -1.93468002 1.8737 -1.93715 0 P 0 
L 1.8737 -1.93715 1.87368996 -1.93718996 0 P 0 
L 1.87368996 -1.93718996 1.87368002 -1.93723996 0 P 0 
L 1.87368002 -1.93723996 1.87368002 -1.93731998 0 P 0 
L 1.87368002 -1.93731998 1.87346998 -1.93981998 0 P 0 
L 1.87346998 -1.93981998 1.87346004 -1.93986004 0 P 0 
L 1.87346004 -1.93986004 1.87346004 -1.94258002 0 P 0 
L 1.87346004 -1.94258002 1.87346998 -1.94266004 0 P 0 
L 1.87346998 -1.94266004 1.87368002 -1.94516998 0 P 0 
L 1.87368002 -1.94516998 1.87368996 -1.94521004 0 P 0 
L 1.87368996 -1.94521004 1.87368996 -1.94525 0 P 0 
L 1.87368996 -1.94525 1.87371004 -1.94533996 0 P 0 
L 1.87371004 -1.94533996 1.87413996 -1.94778996 0 P 0 
L 1.87413996 -1.94778996 1.87413996 -1.94783996 0 P 0 
L 1.87413996 -1.94783996 1.87416998 -1.94796004 0 P 0 
L 1.87416998 -1.94796004 1.87481004 -1.95036998 0 P 0 
L 1.87481004 -1.95036998 1.87483996 -1.95048996 0 P 0 
L 1.87483996 -1.95048996 1.87486004 -1.95053002 0 P 0 
L 1.87486004 -1.95053002 1.8757 -1.95288002 0 P 0 
L 1.8757 -1.95288002 1.87571004 -1.95291998 0 P 0 
L 1.87571004 -1.95291998 1.87575 -1.953 0 P 0 
L 1.87575 -1.953 1.87576004 -1.95303996 0 P 0 
L 1.87576004 -1.95303996 1.8768 -1.9553 0 P 0 
L 1.8768 -1.9553 1.87686004 -1.95541998 0 P 0 
L 1.87686004 -1.95541998 1.87688002 -1.95545 0 P 0 
L 1.87688002 -1.95545 1.8781 -1.95761004 0 P 0 
L 1.8781 -1.95761004 1.87811998 -1.95761004 0 P 0 
L 1.87811998 -1.95761004 1.8781 -1.95761998 0 P 0 
L 1.8781 -1.95761998 1.87813996 -1.95768996 0 P 0 
L 1.87813996 -1.95768996 1.87816998 -1.95771998 0 P 0 
L 1.87816998 -1.95771998 1.87818996 -1.95775 0 P 0 
L 1.87818996 -1.95775 1.87938002 -1.95951004 0 P 0 
L 1.87938002 -1.95951004 1.87943996 -1.9596 0 P 0 
L 1.87943996 -1.9596 1.87946998 -1.95963002 0 P 0 
L 1.87946998 -1.95963002 1.88078002 -1.96128996 0 P 0 
L 1.88078002 -1.96128996 1.88081004 -1.96131998 0 P 0 
L 1.88081004 -1.96131998 1.88083002 -1.96135 0 P 0 
L 1.88083002 -1.96135 1.88086004 -1.96136998 0 P 0 
L 1.88086004 -1.96136998 1.88088002 -1.9614 0 P 0 
L 1.88088002 -1.9614 1.88231998 -1.96295 0 P 0 
L 1.88231998 -1.96295 1.88233996 -1.96298002 0 P 0 
L 1.88233996 -1.96298002 1.8824 -1.96303996 0 P 0 
L 1.8824 -1.96303996 1.88243002 -1.96306004 0 P 0 
L 1.88243002 -1.96306004 1.88398002 -1.9645 0 P 0 
L 1.88398002 -1.9645 1.88401004 -1.96451998 0 P 0 
L 1.88401004 -1.96451998 1.88403002 -1.96455 0 P 0 
L 1.88403002 -1.96455 1.88406998 -1.96458002 0 P 0 
L 1.88406998 -1.96458002 1.88408996 -1.9646 0 P 0 
L 1.88408996 -1.9646 1.88575 -1.96591004 0 P 0 
L 1.88575 -1.96591004 1.88578002 -1.96593996 0 P 0 
L 1.88578002 -1.96593996 1.88586998 -1.966 0 P 0 
L 1.88586998 -1.966 1.88761998 -1.96718996 0 P 0 
L 1.88761998 -1.96718996 1.88766004 -1.96721004 0 P 0 
L 1.88766004 -1.96721004 1.88775 -1.96726998 0 P 0 
L 1.88775 -1.96726998 1.88958996 -1.96831998 0 P 0 
L 1.88958996 -1.96831998 1.88965 -1.96836004 0 P 0 
L 1.88965 -1.96836004 1.88968002 -1.96836998 0 P 0 
L 1.88968002 -1.96836998 1.88971998 -1.96838996 0 P 0 
L 1.88971998 -1.96838996 1.89145 -1.96921998 0 P 0 
L 1.89145 -1.96921998 1.89151004 -1.96925 0 P 0 
L 1.89151004 -1.96925 1.89155 -1.96926004 0 P 0 
L 1.89155 -1.96926004 1.89158002 -1.96926998 0 P 0 
L 1.89158002 -1.96926998 1.89336004 -1.96996998 0 P 0 
L 1.89336004 -1.96996998 1.89336004 -1.96998002 0 P 0 
L 1.89336004 -1.96998002 1.89346004 -1.97001004 0 P 0 
L 1.89346004 -1.97001004 1.89348996 -1.97001998 0 P 0 
L 1.89348996 -1.97001998 1.89531998 -1.9706 0 P 0 
L 1.89531998 -1.9706 1.89536004 -1.97061004 0 P 0 
L 1.89536004 -1.97061004 1.89541998 -1.97063002 0 P 0 
L 1.89541998 -1.97063002 1.89546004 -1.97063002 0 P 0 
L 1.89546004 -1.97063002 1.89731998 -1.97108002 0 P 0 
L 1.89731998 -1.97108002 1.89741998 -1.9711 0 P 0 
L 1.89741998 -1.9711 1.89746004 -1.9711 0 P 0 
L 1.89746004 -1.9711 1.89746004 -1.97111004 0 P 0 
L 1.89746004 -1.97111004 1.89933996 -1.97141998 0 P 0 
L 1.89933996 -1.97141998 1.89936998 -1.97143002 0 P 0 
L 1.89936998 -1.97143002 1.89941004 -1.97143002 0 P 0 
L 1.89941004 -1.97143002 1.89945 -1.97143996 0 P 0 
L 1.89945 -1.97143996 1.89948002 -1.97143996 0 P 0 
L 1.89948002 -1.97143996 1.90201004 -1.97168002 0 P 0 
L 1.90201004 -1.97168002 1.90205 -1.97168002 0 P 0 
L 1.90205 -1.97168002 1.90208996 -1.97168996 0 P 0 
L 1.90208996 -1.97168996 1.90216004 -1.97168996 0 P 0 
L 1.90216004 -1.97168996 1.90468996 -1.97173996 0 P 0 
L 1.90468996 -1.97173996 1.90476004 -1.97173996 0 P 0 
L 1.80616004 -2.12823996 1.83348996 -2.12823996 0 P 0 
L 1.79591998 -2.12723996 1.8396 -2.12723996 0 P 0 
L 1.78818002 -2.12623996 1.84465 -2.12623996 0 P 0 
L 1.82003996 -2.09123996 1.87618996 -2.09123996 0 P 0 
L 1.82198996 -2.09023996 1.8762 -2.09023996 0 P 0 
L 1.82325 -2.08923996 1.8762 -2.08923996 0 P 0 
L 1.82411998 -2.08823996 1.87618996 -2.08823996 0 P 0 
L 1.82463002 -2.08723996 1.87616998 -2.08723996 0 P 0 
L 1.82488002 -2.08623996 1.87615 -2.08623996 0 P 0 
L 1.82493002 -2.08523996 1.87613002 -2.08523996 0 P 0 
L 1.82476998 -2.08423996 1.87611004 -2.08423996 0 P 0 
L 1.64846004 -2.08295 1.73316998 -2.08295 0 P 0 
L 1.64811998 -2.08195 1.73356998 -2.08195 0 P 0 
L 1.64776998 -2.08095 1.73398002 -2.08095 0 P 0 
L 1.64743002 -2.07995 1.73438002 -2.07995 0 P 0 
L 1.64708996 -2.07895 1.73478996 -2.07895 0 P 0 
L 1.64673996 -2.07795 1.7352 -2.07795 0 P 0 
L 1.6464 -2.07695 1.7356 -2.07695 0 P 0 
L 1.64605 -2.07595 1.73601004 -2.07595 0 P 0 
L 1.64571004 -2.07495 1.73641004 -2.07495 0 P 0 
L 1.64536004 -2.07395 1.73681004 -2.07395 0 P 0 
L 1.64501998 -2.07295 1.73721998 -2.07295 0 P 0 
L 1.64466998 -2.07195 1.73761998 -2.07195 0 P 0 
L 1.64433002 -2.07095 1.73803002 -2.07095 0 P 0 
L 1.64398002 -2.06995 1.69251004 -2.06995 0 P 0 
L 1.69583002 -2.06995 1.73843996 -2.06995 0 P 0 
L 1.64363002 -2.06895 1.69168002 -2.06895 0 P 0 
L 1.69671998 -2.06895 1.73883996 -2.06895 0 P 0 
L 1.64328996 -2.06795 1.69136004 -2.06795 0 P 0 
L 1.69708996 -2.06795 1.73925 -2.06795 0 P 0 
L 1.64293996 -2.06695 1.69108002 -2.06695 0 P 0 
L 1.69738002 -2.06695 1.73965 -2.06695 0 P 0 
L 1.64258996 -2.06595 1.6908 -2.06595 0 P 0 
L 1.69768002 -2.06595 1.74006004 -2.06595 0 P 0 
L 1.64223996 -2.06495 1.69051998 -2.06495 0 P 0 
L 1.69796998 -2.06495 1.74046004 -2.06495 0 P 0 
L 1.6419 -2.06395 1.69023002 -2.06395 0 P 0 
L 1.69826998 -2.06395 1.74086004 -2.06395 0 P 0 
L 1.64155 -2.06295 1.68996004 -2.06295 0 P 0 
L 1.69856004 -2.06295 1.74126998 -2.06295 0 P 0 
L 1.6412 -2.06195 1.68966998 -2.06195 0 P 0 
L 1.69886004 -2.06195 1.74168002 -2.06195 0 P 0 
L 1.64085 -2.06095 1.68938996 -2.06095 0 P 0 
L 1.69915 -2.06095 1.74208002 -2.06095 0 P 0 
L 1.6405 -2.05995 1.68911004 -2.05995 0 P 0 
L 1.69945 -2.05995 1.74248002 -2.05995 0 P 0 
L 1.64016004 -2.05895 1.68883002 -2.05895 0 P 0 
L 1.69973996 -2.05895 1.74288996 -2.05895 0 P 0 
L 1.63981004 -2.05795 1.68855 -2.05795 0 P 0 
L 1.70003996 -2.05795 1.74328996 -2.05795 0 P 0 
L 1.63946004 -2.05695 1.68826998 -2.05695 0 P 0 
L 1.70033002 -2.05695 1.7437 -2.05695 0 P 0 
L 1.63911004 -2.05595 1.68798996 -2.05595 0 P 0 
L 1.70063002 -2.05595 1.7441 -2.05595 0 P 0 
L 1.63876998 -2.05495 1.68771004 -2.05495 0 P 0 
L 1.70091998 -2.05495 1.74451004 -2.05495 0 P 0 
L 1.63841998 -2.05395 1.68741998 -2.05395 0 P 0 
L 1.70121998 -2.05395 1.74491004 -2.05395 0 P 0 
L 1.63806998 -2.05295 1.68713996 -2.05295 0 P 0 
L 1.70151004 -2.05295 1.74531004 -2.05295 0 P 0 
L 1.63771998 -2.05195 1.68686004 -2.05195 0 P 0 
L 1.70181004 -2.05195 1.74571998 -2.05195 0 P 0 
L 1.63738002 -2.05095 1.68658002 -2.05095 0 P 0 
L 1.7021 -2.05095 1.74611998 -2.05095 0 P 0 
L 1.63703002 -2.04995 1.6863 -2.04995 0 P 0 
L 1.7024 -2.04995 1.74653002 -2.04995 0 P 0 
L 1.63668002 -2.04895 1.68601998 -2.04895 0 P 0 
L 1.70268996 -2.04895 1.74693002 -2.04895 0 P 0 
L 1.63633002 -2.04795 1.68573996 -2.04795 0 P 0 
L 1.70298996 -2.04795 1.74733002 -2.04795 0 P 0 
L 1.63598002 -2.04695 1.68546004 -2.04695 0 P 0 
L 1.70328002 -2.04695 1.74773996 -2.04695 0 P 0 
L 1.63563996 -2.04595 1.68518002 -2.04595 0 P 0 
L 1.70358002 -2.04595 1.74813996 -2.04595 0 P 0 
L 1.63528996 -2.04495 1.6849 -2.04495 0 P 0 
L 1.70386998 -2.04495 1.74855 -2.04495 0 P 0 
L 1.63493996 -2.04395 1.68461004 -2.04395 0 P 0 
L 1.70416998 -2.04395 1.74895 -2.04395 0 P 0 
L 1.63458996 -2.04295 1.68433002 -2.04295 0 P 0 
L 1.70446004 -2.04295 1.74936004 -2.04295 0 P 0 
L 1.63425 -2.04195 1.68405 -2.04195 0 P 0 
L 1.70475 -2.04195 1.74976004 -2.04195 0 P 0 
L 1.6339 -2.04095 1.68376998 -2.04095 0 P 0 
L 1.70503002 -2.04095 1.75016004 -2.04095 0 P 0 
L 1.63355 -2.03995 1.68348996 -2.03995 0 P 0 
L 1.70531998 -2.03995 1.75056998 -2.03995 0 P 0 
L 1.6332 -2.03895 1.68321004 -2.03895 0 P 0 
L 1.7056 -2.03895 1.75096998 -2.03895 0 P 0 
L 1.63286004 -2.03795 1.68293002 -2.03795 0 P 0 
L 1.70588996 -2.03795 1.75138002 -2.03795 0 P 0 
L 1.63251004 -2.03695 1.68266004 -2.03695 0 P 0 
L 1.70618002 -2.03695 1.75178002 -2.03695 0 P 0 
L 1.63216004 -2.03595 1.68238002 -2.03595 0 P 0 
L 1.70646998 -2.03595 1.75218996 -2.03595 0 P 0 
L 1.63181004 -2.03495 1.6821 -2.03495 0 P 0 
L 1.70675 -2.03495 1.75258996 -2.03495 0 P 0 
L 1.63146998 -2.03395 1.68183002 -2.03395 0 P 0 
L 1.70703996 -2.03395 1.75298996 -2.03395 0 P 0 
L 1.63111998 -2.03295 1.68155 -2.03295 0 P 0 
L 1.70733002 -2.03295 1.7534 -2.03295 0 P 0 
L 1.63076998 -2.03195 1.68126998 -2.03195 0 P 0 
L 1.70761004 -2.03195 1.75381004 -2.03195 0 P 0 
L 1.63041998 -2.03095 1.68098996 -2.03095 0 P 0 
L 1.7079 -2.03095 1.75421004 -2.03095 0 P 0 
L 1.63006998 -2.02995 1.68071004 -2.02995 0 P 0 
L 1.70818996 -2.02995 1.75461004 -2.02995 0 P 0 
L 1.62973002 -2.02895 1.68043996 -2.02895 0 P 0 
L 1.70846998 -2.02895 1.75501998 -2.02895 0 P 0 
L 1.62938002 -2.02795 1.68016004 -2.02795 0 P 0 
L 1.70876004 -2.02795 1.75541998 -2.02795 0 P 0 
L 1.62903002 -2.02695 1.67988002 -2.02695 0 P 0 
L 1.70905 -2.02695 1.75583002 -2.02695 0 P 0 
L 1.62868002 -2.02595 1.6796 -2.02595 0 P 0 
L 1.70933996 -2.02595 1.75623002 -2.02595 0 P 0 
L 1.62831004 -2.02495 1.67933002 -2.02495 0 P 0 
L 1.70961998 -2.02495 1.75663996 -2.02495 0 P 0 
L 1.62793996 -2.02395 1.67905 -2.02395 0 P 0 
L 1.70991004 -2.02395 1.75703996 -2.02395 0 P 0 
L 1.62756998 -2.02295 1.67876998 -2.02295 0 P 0 
L 1.7102 -2.02295 1.75743996 -2.02295 0 P 0 
L 1.6272 -2.02195 1.6785 -2.02195 0 P 0 
L 1.71048002 -2.02195 1.75785 -2.02195 0 P 0 
L 1.62683002 -2.02095 1.67821998 -2.02095 0 P 0 
L 1.71076004 -2.02095 1.75825 -2.02095 0 P 0 
L 1.62646998 -2.01995 1.67793996 -2.01995 0 P 0 
L 1.71101004 -2.01995 1.75866004 -2.01995 0 P 0 
L 1.6261 -2.01895 1.67766004 -2.01895 0 P 0 
L 1.71126998 -2.01895 1.75906004 -2.01895 0 P 0 
L 1.62573002 -2.01795 1.67738996 -2.01795 0 P 0 
L 1.71151998 -2.01795 1.75946998 -2.01795 0 P 0 
L 1.62536004 -2.01695 1.67711004 -2.01695 0 P 0 
L 1.71176998 -2.01695 1.75986998 -2.01695 0 P 0 
L 1.62498996 -2.01595 1.67683002 -2.01595 0 P 0 
L 1.71203002 -2.01595 1.76026998 -2.01595 0 P 0 
L 1.62461998 -2.01495 1.67656004 -2.01495 0 P 0 
L 1.71228002 -2.01495 1.76068002 -2.01495 0 P 0 
L 1.62425 -2.01395 1.67628002 -2.01395 0 P 0 
L 1.71253996 -2.01395 1.76108002 -2.01395 0 P 0 
L 1.62388002 -2.01295 1.67601998 -2.01295 0 P 0 
L 1.71278996 -2.01295 1.76148996 -2.01295 0 P 0 
L 1.62351004 -2.01195 1.67576998 -2.01195 0 P 0 
L 1.71305 -2.01195 1.76188996 -2.01195 0 P 0 
L 1.62313996 -2.01095 1.67551998 -2.01095 0 P 0 
L 1.7133 -2.01095 1.76228996 -2.01095 0 P 0 
L 1.62276998 -2.00995 1.67528002 -2.00995 0 P 0 
L 1.71355 -2.00995 1.7627 -2.00995 0 P 0 
L 1.6224 -2.00895 1.67503002 -2.00895 0 P 0 
L 1.71381004 -2.00895 1.7631 -2.00895 0 P 0 
L 1.62203002 -2.00795 1.67478996 -2.00795 0 P 0 
L 1.71406004 -2.00795 1.76351004 -2.00795 0 P 0 
L 1.62166004 -2.00695 1.67453996 -2.00695 0 P 0 
L 1.71431004 -2.00695 1.76391004 -2.00695 0 P 0 
L 1.62128996 -2.00595 1.67428996 -2.00595 0 P 0 
L 1.71453996 -2.00595 1.76431998 -2.00595 0 P 0 
L 1.62091004 -2.00495 1.67405 -2.00495 0 P 0 
L 1.71476998 -2.00495 1.76471998 -2.00495 0 P 0 
L 1.62051998 -2.00395 1.6738 -2.00395 0 P 0 
L 1.715 -2.00395 1.76511998 -2.00395 0 P 0 
L 1.62013002 -2.00295 1.67355 -2.00295 0 P 0 
L 1.71523002 -2.00295 1.76553002 -2.00295 0 P 0 
L 1.61973996 -2.00195 1.67331004 -2.00195 0 P 0 
L 1.71546004 -2.00195 1.76593996 -2.00195 0 P 0 
L 1.61935 -2.00095 1.67306004 -2.00095 0 P 0 
L 1.71568996 -2.00095 1.76633996 -2.00095 0 P 0 
L 1.61896004 -1.99995 1.67283996 -1.99995 0 P 0 
L 1.71591998 -1.99995 1.76673996 -1.99995 0 P 0 
L 1.61856998 -1.99895 1.67261998 -1.99895 0 P 0 
L 1.71613996 -1.99895 1.76715 -1.99895 0 P 0 
L 1.71638002 -1.99795 1.76755 -1.99795 0 P 0 
L 1.7166 -1.99695 1.76796004 -1.99695 0 P 0 
L 1.71683002 -1.99595 1.76836004 -1.99595 0 P 0 
L 1.71866998 -1.99495 1.76876998 -1.99495 0 P 0 
L 1.78213996 -2.04823996 1.84641998 -2.04823996 0 P 0 
L 1.78138002 -2.04723996 1.84498996 -2.04723996 0 P 0 
L 1.78071004 -2.04623996 1.84356004 -2.04623996 0 P 0 
L 1.7801 -2.04523996 1.84213996 -2.04523996 0 P 0 
L 1.77956004 -2.04423996 1.84071004 -2.04423996 0 P 0 
L 1.77908996 -2.04323996 1.83928002 -2.04323996 0 P 0 
L 1.77866004 -2.04223996 1.83786004 -2.04223996 0 P 0 
L 1.77831004 -2.04123996 1.83658996 -2.04123996 0 P 0 
L 1.77796004 -2.04023996 1.83536004 -2.04023996 0 P 0 
L 1.77761004 -2.03923996 1.83428002 -2.03923996 0 P 0 
L 1.77733996 -2.03823996 1.83321998 -2.03823996 0 P 0 
L 1.77706998 -2.03723996 1.83236998 -2.03723996 0 P 0 
L 1.7768 -2.03623996 1.83171004 -2.03623996 0 P 0 
L 1.7766 -2.03523996 1.83121004 -2.03523996 0 P 0 
L 1.77641004 -2.03423996 1.83085 -2.03423996 0 P 0 
L 1.77621004 -2.03323996 1.83071004 -2.03323996 0 P 0 
L 1.77608002 -2.03223996 1.83076998 -2.03223996 0 P 0 
L 1.77596004 -2.03123996 1.83106004 -2.03123996 0 P 0 
L 1.77583996 -2.03023996 1.83158996 -2.03023996 0 P 0 
L 1.77576004 -2.02923996 1.83238002 -2.02923996 0 P 0 
L 1.7757 -2.02823996 1.83356998 -2.02823996 0 P 0 
L 1.7757 -2.02723996 1.83591998 -2.02723996 0 P 0 
L 1.77571998 -2.02623996 1.87495 -2.02623996 0 P 0 
L 1.7758 -2.02523996 1.87485 -2.02523996 0 P 0 
L 1.77588996 -2.02423996 1.87475 -2.02423996 0 P 0 
L 1.77605 -2.02323996 1.87465 -2.02323996 0 P 0 
L 1.77621004 -2.02223996 1.87455 -2.02223996 0 P 0 
L 1.7764 -2.02123996 1.87445 -2.02123996 0 P 0 
L 1.77665 -2.02023996 1.87433996 -2.02023996 0 P 0 
L 1.7769 -2.01923996 1.87425 -2.01923996 0 P 0 
L 1.7772 -2.01823996 1.87413996 -2.01823996 0 P 0 
L 1.77753002 -2.01723996 1.87405 -2.01723996 0 P 0 
L 1.77786004 -2.01623996 1.87393996 -2.01623996 0 P 0 
L 1.77823002 -2.01523996 1.87383996 -2.01523996 0 P 0 
L 1.77863996 -2.01423996 1.87373996 -2.01423996 0 P 0 
L 1.77903996 -2.01323996 1.87363996 -2.01323996 0 P 0 
L 1.7795 -2.01223996 1.87353996 -2.01223996 0 P 0 
L 1.77998996 -2.01123996 1.87343996 -2.01123996 0 P 0 
L 1.78046998 -2.01023996 1.87333002 -2.01023996 0 P 0 
L 1.78103996 -2.00923996 1.87323002 -2.00923996 0 P 0 
L 1.78161004 -2.00823996 1.87311998 -2.00823996 0 P 0 
L 1.78221004 -2.00723996 1.87301998 -2.00723996 0 P 0 
L 1.78288002 -2.00623996 1.87291998 -2.00623996 0 P 0 
L 1.64213996 -2.14795 1.70566004 -2.14795 0 P 0 
L 1.64518996 -2.14695 1.7062 -2.14695 0 P 0 
L 1.64728996 -2.14595 1.70673996 -2.14595 0 P 0 
L 1.64906998 -2.14495 1.70728002 -2.14495 0 P 0 
L 1.65058002 -2.14395 1.70783002 -2.14395 0 P 0 
L 1.6519 -2.14295 1.70836998 -2.14295 0 P 0 
L 1.65311998 -2.14195 1.70881998 -2.14195 0 P 0 
L 1.65416998 -2.14095 1.70926998 -2.14095 0 P 0 
L 1.65508996 -2.13995 1.70973002 -2.13995 0 P 0 
L 1.65588002 -2.13895 1.71018002 -2.13895 0 P 0 
L 1.65658002 -2.13795 1.71063002 -2.13795 0 P 0 
L 1.65726998 -2.13695 1.71108996 -2.13695 0 P 0 
L 1.65791998 -2.13595 1.71153996 -2.13595 0 P 0 
L 1.65853002 -2.13495 1.71198996 -2.13495 0 P 0 
L 1.65913002 -2.13395 1.71245 -2.13395 0 P 0 
L 1.65968002 -2.13295 1.7129 -2.13295 0 P 0 
L 1.66021998 -2.13195 1.71331004 -2.13195 0 P 0 
L 1.66071998 -2.13095 1.71371998 -2.13095 0 P 0 
L 1.66121004 -2.12995 1.71411998 -2.12995 0 P 0 
L 1.66166998 -2.12895 1.71453002 -2.12895 0 P 0 
L 1.66201004 -2.12795 1.71493996 -2.12795 0 P 0 
L 1.66223996 -2.12695 1.71533996 -2.12695 0 P 0 
L 1.66235 -2.12595 1.71575 -2.12595 0 P 0 
L 1.66236004 -2.12495 1.71615 -2.12495 0 P 0 
L 1.66228002 -2.12395 1.71656004 -2.12395 0 P 0 
L 1.66211998 -2.12295 1.71696004 -2.12295 0 P 0 
L 1.66188002 -2.12195 1.71736004 -2.12195 0 P 0 
L 1.66156004 -2.12095 1.71776998 -2.12095 0 P 0 
L 1.66121004 -2.11995 1.71818002 -2.11995 0 P 0 
L 1.66086998 -2.11895 1.71858002 -2.11895 0 P 0 
L 1.66053002 -2.11795 1.71898996 -2.11795 0 P 0 
L 1.66018002 -2.11695 1.71938996 -2.11695 0 P 0 
L 1.65983996 -2.11595 1.7198 -2.11595 0 P 0 
L 1.65948996 -2.11495 1.7202 -2.11495 0 P 0 
L 1.65913996 -2.11395 1.72061004 -2.11395 0 P 0 
L 1.6588 -2.11295 1.72101004 -2.11295 0 P 0 
L 1.65846004 -2.11195 1.72141998 -2.11195 0 P 0 
L 1.65811004 -2.11095 1.72181998 -2.11095 0 P 0 
L 1.65776998 -2.10995 1.72223002 -2.10995 0 P 0 
L 1.65741998 -2.10895 1.72263002 -2.10895 0 P 0 
L 1.65708002 -2.10795 1.72303996 -2.10795 0 P 0 
L 1.65673002 -2.10695 1.72343996 -2.10695 0 P 0 
L 1.65638996 -2.10595 1.72385 -2.10595 0 P 0 
L 1.65605 -2.10495 1.72425 -2.10495 0 P 0 
L 1.6557 -2.10395 1.72466004 -2.10395 0 P 0 
L 1.65536004 -2.10295 1.72506998 -2.10295 0 P 0 
L 1.65501004 -2.10195 1.72546998 -2.10195 0 P 0 
L 1.65466998 -2.10095 1.72588002 -2.10095 0 P 0 
L 1.65431998 -2.09995 1.72628002 -2.09995 0 P 0 
L 1.65398002 -2.09895 1.72668996 -2.09895 0 P 0 
L 1.65363002 -2.09795 1.72708996 -2.09795 0 P 0 
L 1.65328996 -2.09695 1.72748996 -2.09695 0 P 0 
L 1.65293996 -2.09595 1.7279 -2.09595 0 P 0 
L 1.6526 -2.09495 1.72831004 -2.09495 0 P 0 
L 1.65225 -2.09395 1.72871004 -2.09395 0 P 0 
L 1.65191004 -2.09295 1.72911998 -2.09295 0 P 0 
L 1.65156998 -2.09195 1.72951998 -2.09195 0 P 0 
L 1.65121998 -2.09095 1.72993002 -2.09095 0 P 0 
L 1.65088002 -2.08995 1.73033002 -2.08995 0 P 0 
L 1.65053002 -2.08895 1.73073996 -2.08895 0 P 0 
L 1.65018996 -2.08795 1.73113996 -2.08795 0 P 0 
L 1.64983996 -2.08695 1.73155 -2.08695 0 P 0 
L 1.6495 -2.08595 1.73195 -2.08595 0 P 0 
L 1.64915 -2.08495 1.73236004 -2.08495 0 P 0 
L 1.64881004 -2.08395 1.73276004 -2.08395 0 P 0 
L 1.81726998 -1.98915 1.81196004 -1.9899 0 P 0 
L 1.81196004 -1.9899 1.80668996 -1.99096998 0 P 0 
L 1.80668996 -1.99096998 1.8019 -1.99226004 0 P 0 
L 1.8019 -1.99226004 1.79718996 -1.99391004 0 P 0 
L 1.79718996 -1.99391004 1.79316004 -1.99568002 0 P 0 
L 1.79316004 -1.99568002 1.78926998 -1.99778002 0 P 0 
L 1.78926998 -1.99778002 1.78771004 -1.99878002 0 P 0 
L 1.78771004 -1.99878002 1.78623002 -1.99988002 0 P 0 
L 1.78623002 -1.99988002 1.78481004 -2.00108002 0 P 0 
L 1.78481004 -2.00108002 1.78346998 -2.00238996 0 P 0 
L 1.78346998 -2.00238996 1.78228996 -2.00371998 0 P 0 
L 1.78228996 -2.00371998 1.78121004 -2.00513002 0 P 0 
L 1.78121004 -2.00513002 1.78023002 -2.00661004 0 P 0 
L 1.78023002 -2.00661004 1.77868002 -2.00933996 0 P 0 
L 1.77868002 -2.00933996 1.77731998 -2.01216998 0 P 0 
L 1.77731998 -2.01216998 1.77611004 -2.01516004 0 P 0 
L 1.77611004 -2.01516004 1.77508996 -2.01823002 0 P 0 
L 1.77508996 -2.01823002 1.77436998 -2.02111004 0 P 0 
L 1.77436998 -2.02111004 1.77388996 -2.02406004 0 P 0 
L 1.77388996 -2.02406004 1.77371998 -2.02603996 0 P 0 
L 1.77371998 -2.02603996 1.77368996 -2.02801998 0 P 0 
L 1.77368996 -2.02801998 1.7738 -2.03001998 0 P 0 
L 1.7738 -2.03001998 1.7742 -2.03338996 0 P 0 
L 1.7742 -2.03338996 1.77485 -2.03671004 0 P 0 
L 1.77485 -2.03671004 1.77573002 -2.03993996 0 P 0 
L 1.77573002 -2.03993996 1.77683996 -2.04308002 0 P 0 
L 1.77683996 -2.04308002 1.7776 -2.04481998 0 P 0 
L 1.7776 -2.04481998 1.7785 -2.04648996 0 P 0 
L 1.7785 -2.04648996 1.77953002 -2.04808996 0 P 0 
L 1.77953002 -2.04808996 1.78061004 -2.04953996 0 P 0 
L 1.78061004 -2.04953996 1.78181004 -2.05091004 0 P 0 
L 1.78181004 -2.05091004 1.78311004 -2.05218996 0 P 0 
L 1.78311004 -2.05218996 1.78988996 -2.05801998 0 P 0 
L 1.78988996 -2.05801998 1.79883996 -2.06491004 0 P 0 
L 1.79883996 -2.06491004 1.80976998 -2.07261004 0 P 0 
L 1.80976998 -2.07261004 1.81753002 -2.07823002 0 P 0 
L 1.81753002 -2.07823002 1.81896998 -2.07943002 0 P 0 
L 1.81896998 -2.07943002 1.82033002 -2.08073002 0 P 0 
L 1.82033002 -2.08073002 1.82156998 -2.08213996 0 P 0 
L 1.82156998 -2.08213996 1.82186004 -2.08251004 0 P 0 
L 1.82186004 -2.08251004 1.82211004 -2.0829 0 P 0 
L 1.82211004 -2.0829 1.82233002 -2.08331004 0 P 0 
L 1.82233002 -2.08331004 1.82253002 -2.08373996 0 P 0 
L 1.82253002 -2.08373996 1.82268002 -2.08418002 0 P 0 
L 1.82268002 -2.08418002 1.82281004 -2.08463002 0 P 0 
L 1.82281004 -2.08463002 1.8229 -2.0851 0 P 0 
L 1.8229 -2.0851 1.82293002 -2.08533996 0 P 0 
L 1.82293002 -2.08533996 1.82293996 -2.08558996 0 P 0 
L 1.82293996 -2.08558996 1.82291998 -2.08583996 0 P 0 
L 1.82291998 -2.08583996 1.82288002 -2.08608002 0 P 0 
L 1.82288002 -2.08608002 1.82283002 -2.08631998 0 P 0 
L 1.82283002 -2.08631998 1.82275 -2.08656004 0 P 0 
L 1.82275 -2.08656004 1.82265 -2.08678996 0 P 0 
L 1.82265 -2.08678996 1.82253996 -2.087 0 P 0 
L 1.82253996 -2.087 1.8224 -2.08721004 0 P 0 
L 1.8224 -2.08721004 1.82225 -2.08741004 0 P 0 
L 1.82225 -2.08741004 1.82208996 -2.08758996 0 P 0 
L 1.82208996 -2.08758996 1.8216 -2.08803996 0 P 0 
L 1.8216 -2.08803996 1.82106998 -2.08845 0 P 0 
L 1.82106998 -2.08845 1.82051004 -2.08881004 0 P 0 
L 1.82051004 -2.08881004 1.81991998 -2.08911998 0 P 0 
L 1.81991998 -2.08911998 1.81931004 -2.08936998 0 P 0 
L 1.81931004 -2.08936998 1.81868002 -2.08958002 0 P 0 
L 1.81868002 -2.08958002 1.81803002 -2.08973002 0 P 0 
L 1.81803002 -2.08973002 1.81736004 -2.08981998 0 P 0 
L 1.81736004 -2.08981998 1.81293002 -2.09001998 0 P 0 
L 1.81293002 -2.09001998 1.80846998 -2.08986004 0 P 0 
L 1.80846998 -2.08986004 1.80256998 -2.08923002 0 P 0 
L 1.80256998 -2.08923002 1.79668002 -2.08818996 0 P 0 
L 1.79668002 -2.08818996 1.78223002 -2.08458002 0 P 0 
L 1.78223002 -2.08458002 1.77788996 -2.08338002 0 P 0 
L 1.77788996 -2.08338002 1.77415 -2.08246004 0 P 0 
L 1.77415 -2.08246004 1.77095 -2.08175 0 P 0 
L 1.77095 -2.08175 1.7709 -2.08173996 0 P 0 
L 1.7709 -2.08173996 1.77076998 -2.08173996 0 P 0 
L 1.77076998 -2.08173996 1.77068996 -2.08176004 0 P 0 
L 1.77068996 -2.08176004 1.77053002 -2.08183996 0 P 0 
L 1.77053002 -2.08183996 1.77043002 -2.08193996 0 P 0 
L 1.77043002 -2.08193996 1.77036998 -2.08201998 0 P 0 
L 1.77036998 -2.08201998 1.77031998 -2.08211998 0 P 0 
L 1.77031998 -2.08211998 1.7703 -2.08216998 0 P 0 
L 1.7703 -2.08216998 1.77028996 -2.08223002 0 P 0 
L 1.77028996 -2.08223002 1.77028002 -2.08228002 0 P 0 
L 1.77028002 -2.08228002 1.77028002 -2.08238996 0 P 0 
L 1.77028002 -2.08238996 1.77056998 -2.08838996 0 P 0 
L 1.77056998 -2.08838996 1.77096004 -2.09526004 0 P 0 
L 1.77096004 -2.09526004 1.77153996 -2.1033 0 P 0 
L 1.77153996 -2.1033 1.77236004 -2.11291004 0 P 0 
L 1.77236004 -2.11291004 1.77311004 -2.1194 0 P 0 
L 1.77311004 -2.1194 1.77383002 -2.12398002 0 P 0 
L 1.77383002 -2.12398002 1.77386004 -2.12411004 0 P 0 
L 1.77386004 -2.12411004 1.7739 -2.12423002 0 P 0 
L 1.7739 -2.12423002 1.77395 -2.12436004 0 P 0 
L 1.77395 -2.12436004 1.77401004 -2.12448002 0 P 0 
L 1.77401004 -2.12448002 1.77408002 -2.12458996 0 P 0 
L 1.77408002 -2.12458996 1.77416004 -2.1247 0 P 0 
L 1.77416004 -2.1247 1.77425 -2.1248 0 P 0 
L 1.77425 -2.1248 1.77435 -2.12488996 0 P 0 
L 1.77435 -2.12488996 1.77445 -2.12496998 0 P 0 
L 1.77445 -2.12496998 1.77456998 -2.12505 0 P 0 
L 1.77456998 -2.12505 1.77571004 -2.12568996 0 P 0 
L 1.77571004 -2.12568996 1.7769 -2.12623996 0 P 0 
L 1.7769 -2.12623996 1.77813002 -2.12668996 0 P 0 
L 1.77813002 -2.12668996 1.7794 -2.12703996 0 P 0 
L 1.7794 -2.12703996 1.78068996 -2.12728996 0 P 0 
L 1.78068996 -2.12728996 1.79791998 -2.12951004 0 P 0 
L 1.79791998 -2.12951004 1.81536004 -2.13106004 0 P 0 
L 1.81536004 -2.13106004 1.82125 -2.13123996 0 P 0 
L 1.82125 -2.13123996 1.82716004 -2.13098996 0 P 0 
L 1.82716004 -2.13098996 1.83583996 -2.12998002 0 P 0 
L 1.83583996 -2.12998002 1.84445 -2.12836004 0 P 0 
L 1.84445 -2.12836004 1.84911998 -2.12711004 0 P 0 
L 1.84911998 -2.12711004 1.85366004 -2.12548002 0 P 0 
L 1.85366004 -2.12548002 1.85806998 -2.12348002 0 P 0 
L 1.85806998 -2.12348002 1.86078996 -2.12196998 0 P 0 
L 1.86078996 -2.12196998 1.8634 -2.12026998 0 P 0 
L 1.8634 -2.12026998 1.86586998 -2.11836998 0 P 0 
L 1.86586998 -2.11836998 1.86821004 -2.11628002 0 P 0 
L 1.86821004 -2.11628002 1.87026004 -2.11413002 0 P 0 
L 1.87026004 -2.11413002 1.8721 -2.11181998 0 P 0 
L 1.8721 -2.11181998 1.87375 -2.10936004 0 P 0 
L 1.87375 -2.10936004 1.87516998 -2.10673996 0 P 0 
L 1.87516998 -2.10673996 1.87605 -2.10483996 0 P 0 
L 1.87605 -2.10483996 1.87683996 -2.10291004 0 P 0 
L 1.87683996 -2.10291004 1.8772 -2.10188002 0 P 0 
L 1.8772 -2.10188002 1.87748996 -2.10083002 0 P 0 
L 1.87748996 -2.10083002 1.87771004 -2.09976998 0 P 0 
L 1.87771004 -2.09976998 1.87798002 -2.09788996 0 P 0 
L 1.87798002 -2.09788996 1.87811998 -2.09601004 0 P 0 
L 1.87811998 -2.09601004 1.87821004 -2.08966998 0 P 0 
L 1.87821004 -2.08966998 1.8781 -2.08353996 0 P 0 
L 1.8781 -2.08353996 1.87798002 -2.08166004 0 P 0 
L 1.87798002 -2.08166004 1.87773002 -2.07976998 0 P 0 
L 1.87773002 -2.07976998 1.87753002 -2.07873996 0 P 0 
L 1.87753002 -2.07873996 1.87726998 -2.07773996 0 P 0 
L 1.87726998 -2.07773996 1.87695 -2.07673996 0 P 0 
L 1.87695 -2.07673996 1.87628996 -2.07505 0 P 0 
L 1.87628996 -2.07505 1.87553002 -2.07338002 0 P 0 
L 1.87553002 -2.07338002 1.87441004 -2.07133996 0 P 0 
L 1.87441004 -2.07133996 1.87313996 -2.06938002 0 P 0 
L 1.87313996 -2.06938002 1.87171004 -2.06751004 0 P 0 
L 1.87171004 -2.06751004 1.8688 -2.06416004 0 P 0 
L 1.8688 -2.06416004 1.86566998 -2.06095 0 P 0 
L 1.86566998 -2.06095 1.86181998 -2.05741998 0 P 0 
L 1.86181998 -2.05741998 1.85778002 -2.05406998 0 P 0 
L 1.85778002 -2.05406998 1.84833996 -2.04715 0 P 0 
L 1.84833996 -2.04715 1.83913996 -2.0407 0 P 0 
L 1.83913996 -2.0407 1.83686004 -2.0389 0 P 0 
L 1.83686004 -2.0389 1.83471998 -2.03691998 0 P 0 
L 1.83471998 -2.03691998 1.83428002 -2.03643002 0 P 0 
L 1.83428002 -2.03643002 1.83386998 -2.0359 0 P 0 
L 1.83386998 -2.0359 1.83351004 -2.03535 0 P 0 
L 1.83351004 -2.03535 1.83318996 -2.03476004 0 P 0 
L 1.83318996 -2.03476004 1.83291998 -2.03415 0 P 0 
L 1.83291998 -2.03415 1.83283996 -2.03393996 0 P 0 
L 1.83283996 -2.03393996 1.83278002 -2.03371004 0 P 0 
L 1.83278002 -2.03371004 1.83273002 -2.03348996 0 P 0 
L 1.83273002 -2.03348996 1.83271004 -2.03326004 0 P 0 
L 1.83271004 -2.03326004 1.8327 -2.03303002 0 P 0 
L 1.8327 -2.03303002 1.83271004 -2.0328 0 P 0 
L 1.83271004 -2.0328 1.83275 -2.03258002 0 P 0 
L 1.83275 -2.03258002 1.83278996 -2.03235 0 P 0 
L 1.83278996 -2.03235 1.83286004 -2.03213002 0 P 0 
L 1.83286004 -2.03213002 1.83293996 -2.03191998 0 P 0 
L 1.83293996 -2.03191998 1.83305 -2.03171004 0 P 0 
L 1.83305 -2.03171004 1.83325 -2.03135 0 P 0 
L 1.83325 -2.03135 1.83348996 -2.03101998 0 P 0 
L 1.83348996 -2.03101998 1.83375 -2.03071004 0 P 0 
L 1.83375 -2.03071004 1.83403002 -2.03041004 0 P 0 
L 1.83403002 -2.03041004 1.83433996 -2.03015 0 P 0 
L 1.83433996 -2.03015 1.83466998 -2.02991004 0 P 0 
L 1.83466998 -2.02991004 1.83501998 -2.02968996 0 P 0 
L 1.83501998 -2.02968996 1.83538002 -2.02951004 0 P 0 
L 1.83538002 -2.02951004 1.83576004 -2.02936004 0 P 0 
L 1.83576004 -2.02936004 1.83615 -2.02923996 0 P 0 
L 1.83615 -2.02923996 1.83655 -2.02915 0 P 0 
L 1.83655 -2.02915 1.8392 -2.02873996 0 P 0 
L 1.8392 -2.02873996 1.84188002 -2.0285 0 P 0 
L 1.84188002 -2.0285 1.84458002 -2.02841004 0 P 0 
L 1.84458002 -2.02841004 1.84993996 -2.02858002 0 P 0 
L 1.84993996 -2.02858002 1.85526998 -2.02916004 0 P 0 
L 1.85526998 -2.02916004 1.86155 -2.03023002 0 P 0 
L 1.86155 -2.03023002 1.86778002 -2.03158002 0 P 0 
L 1.86778002 -2.03158002 1.8713 -2.03238996 0 P 0 
L 1.8713 -2.03238996 1.87428996 -2.03303002 0 P 0 
L 1.87428996 -2.03303002 1.8769 -2.03356004 0 P 0 
L 1.8769 -2.03356004 1.87691998 -2.03356998 0 P 0 
L 1.87691998 -2.03356998 1.87696004 -2.03356998 0 P 0 
L 1.87696004 -2.03356998 1.87696998 -2.03356004 0 P 0 
L 1.87696998 -2.03356004 1.87701004 -2.03356004 0 P 0 
L 1.87701004 -2.03356004 1.87703996 -2.03353996 0 P 0 
L 1.87703996 -2.03353996 1.87706004 -2.03353002 0 P 0 
L 1.87706004 -2.03353002 1.87706998 -2.03351998 0 P 0 
L 1.87706998 -2.03351998 1.87708996 -2.03351004 0 P 0 
L 1.87708996 -2.03351004 1.8771 -2.03348996 0 P 0 
L 1.8771 -2.03348996 1.87711004 -2.03348002 0 P 0 
L 1.87711004 -2.03348002 1.87721998 -2.0333 0 P 0 
L 1.87721998 -2.0333 1.87731998 -2.0331 0 P 0 
L 1.87731998 -2.0331 1.8774 -2.0329 0 P 0 
L 1.8774 -2.0329 1.87746004 -2.03268996 0 P 0 
L 1.87746004 -2.03268996 1.87751004 -2.03248002 0 P 0 
L 1.87751004 -2.03248002 1.87753002 -2.03226998 0 P 0 
L 1.87753002 -2.03226998 1.87753996 -2.03205 0 P 0 
L 1.87753996 -2.03205 1.87753002 -2.03183002 0 P 0 
L 1.87753002 -2.03183002 1.87565 -2.01323996 0 P 0 
L 1.87565 -2.01323996 1.87371004 -1.99451998 0 P 0 
L 1.87371004 -1.99451998 1.8737 -1.99438996 0 P 0 
L 1.8737 -1.99438996 1.87366998 -1.99426998 0 P 0 
L 1.87366998 -1.99426998 1.87363002 -1.99415 0 P 0 
L 1.87363002 -1.99415 1.87358002 -1.99403002 0 P 0 
L 1.87358002 -1.99403002 1.87351998 -1.99391004 0 P 0 
L 1.87351998 -1.99391004 1.87346004 -1.9938 0 P 0 
L 1.87346004 -1.9938 1.87338002 -1.9937 0 P 0 
L 1.87338002 -1.9937 1.87328996 -1.9936 0 P 0 
L 1.87328996 -1.9936 1.8732 -1.99351004 0 P 0 
L 1.8732 -1.99351004 1.8731 -1.99343002 0 P 0 
L 1.8731 -1.99343002 1.87298996 -1.99335 0 P 0 
L 1.87298996 -1.99335 1.87248002 -1.99305 0 P 0 
L 1.87248002 -1.99305 1.87193996 -1.99278002 0 P 0 
L 1.87193996 -1.99278002 1.87136998 -1.99256998 0 P 0 
L 1.87136998 -1.99256998 1.87078996 -1.99241004 0 P 0 
L 1.87078996 -1.99241004 1.8702 -1.9923 0 P 0 
L 1.8702 -1.9923 1.85876004 -1.99076004 0 P 0 
L 1.85876004 -1.99076004 1.84691998 -1.98943002 0 P 0 
L 1.84691998 -1.98943002 1.83693002 -1.98876004 0 P 0 
L 1.83693002 -1.98876004 1.8318 -1.98863002 0 P 0 
L 1.8318 -1.98863002 1.82623002 -1.98866998 0 P 0 
L 1.82623002 -1.98866998 1.82106004 -1.98883996 0 P 0 
L 1.82106004 -1.98883996 1.81726998 -1.98915 0 P 0 
L 1.78061004 -2.12523996 1.84838002 -2.12523996 0 P 0 
L 1.77733002 -2.12423996 1.85121004 -2.12423996 0 P 0 
L 1.77573996 -2.12323996 1.85376998 -2.12323996 0 P 0 
L 1.77558002 -2.12223996 1.85596998 -2.12223996 0 P 0 
L 1.77541998 -2.12123996 1.85798996 -2.12123996 0 P 0 
L 1.77526998 -2.12023996 1.85978996 -2.12023996 0 P 0 
L 1.77511004 -2.11923996 1.86131998 -2.11923996 0 P 0 
L 1.77498996 -2.11823996 1.86276004 -2.11823996 0 P 0 
L 1.77486998 -2.11723996 1.86406998 -2.11723996 0 P 0 
L 1.77475 -2.11623996 1.86526004 -2.11623996 0 P 0 
L 1.77463996 -2.11523996 1.86638002 -2.11523996 0 P 0 
L 1.77451998 -2.11423996 1.8674 -2.11423996 0 P 0 
L 1.77441004 -2.11323996 1.86835 -2.11323996 0 P 0 
L 1.77431004 -2.11223996 1.86921004 -2.11223996 0 P 0 
L 1.77421998 -2.11123996 1.87001004 -2.11123996 0 P 0 
L 1.77413996 -2.11023996 1.87075 -2.11023996 0 P 0 
L 1.77405 -2.10923996 1.87141998 -2.10923996 0 P 0 
L 1.77396998 -2.10823996 1.87208002 -2.10823996 0 P 0 
L 1.77388002 -2.10723996 1.87261998 -2.10723996 0 P 0 
L 1.7738 -2.10623996 1.87316998 -2.10623996 0 P 0 
L 1.77371004 -2.10523996 1.87366004 -2.10523996 0 P 0 
L 1.77363002 -2.10423996 1.87411998 -2.10423996 0 P 0 
L 1.77353996 -2.10323996 1.87453996 -2.10323996 0 P 0 
L 1.77346998 -2.10223996 1.87495 -2.10223996 0 P 0 
L 1.7734 -2.10123996 1.8753 -2.10123996 0 P 0 
L 1.77333002 -2.10023996 1.87556998 -2.10023996 0 P 0 
L 1.77325 -2.09923996 1.87576998 -2.09923996 0 P 0 
L 1.77318002 -2.09823996 1.87591998 -2.09823996 0 P 0 
L 1.77311004 -2.09723996 1.87603002 -2.09723996 0 P 0 
L 1.77303996 -2.09623996 1.8761 -2.09623996 0 P 0 
L 1.77296998 -2.09523996 1.87613002 -2.09523996 0 P 0 
L 1.77291004 -2.09423996 1.87613996 -2.09423996 0 P 0 
L 1.77285 -2.09323996 1.87616004 -2.09323996 0 P 0 
L 1.77278996 -2.09223996 1.87616998 -2.09223996 0 P 0 
L 1.77273002 -2.09123996 1.80256998 -2.09123996 0 P 0 
L 1.77268002 -2.09023996 1.7968 -2.09023996 0 P 0 
L 1.77261998 -2.08923996 1.79263002 -2.08923996 0 P 0 
L 1.77256004 -2.08823996 1.78861998 -2.08823996 0 P 0 
L 1.77251004 -2.08723996 1.7846 -2.08723996 0 P 0 
L 1.77246004 -2.08623996 1.7807 -2.08623996 0 P 0 
L 1.77241998 -2.08523996 1.77705 -2.08523996 0 P 0 
L 1.77236998 -2.08423996 1.77293996 -2.08423996 0 P 0 
L 1.62463996 -2.18195 1.65948996 -2.18195 0 P 0 
L 1.61963996 -2.18095 1.66483002 -2.18095 0 P 0 
L 1.61818002 -1.99795 1.6724 -1.99795 0 P 0 
L 1.61778996 -1.99695 1.67218002 -1.99695 0 P 0 
L 1.6174 -1.99595 1.67196004 -1.99595 0 P 0 
L 1.61701004 -1.99495 1.67173996 -1.99495 0 P 0 
L 1.61391998 -2.15695 1.70026004 -2.15695 0 P 0 
L 1.61386004 -2.15595 1.70088002 -2.15595 0 P 0 
L 1.61381004 -2.15495 1.70151004 -2.15495 0 P 0 
L 1.61375 -2.15395 1.70213996 -2.15395 0 P 0 
L 1.6137 -2.15295 1.70276004 -2.15295 0 P 0 
L 1.61365 -2.15195 1.70338996 -2.15195 0 P 0 
L 1.6136 -2.15095 1.70401004 -2.15095 0 P 0 
L 1.61355 -2.14995 1.70456998 -2.14995 0 P 0 
L 1.61348996 -2.14895 1.70511998 -2.14895 0 P 0 
L 1.61343996 -2.14795 1.61738002 -2.14795 0 P 0 
L 1.55341004 -2.08286998 1.60538002 -2.08286998 0 P 0 
L 1.55286004 -2.08186998 1.60526998 -2.08186998 0 P 0 
L 1.5521 -2.08086998 1.6051 -2.08086998 0 P 0 
L 1.55126998 -2.07986998 1.6049 -2.07986998 0 P 0 
L 1.55033996 -2.07886998 1.60463996 -2.07886998 0 P 0 
L 1.54928996 -2.07786998 1.60433002 -2.07786998 0 P 0 
L 1.54806998 -2.07686998 1.60398996 -2.07686998 0 P 0 
L 1.5467 -2.07586998 1.60356998 -2.07586998 0 P 0 
L 1.54531004 -2.07486998 1.6031 -2.07486998 0 P 0 
L 1.54391004 -2.07386998 1.60258996 -2.07386998 0 P 0 
L 1.54251004 -2.07286998 1.60201004 -2.07286998 0 P 0 
L 1.54111998 -2.07186998 1.60138002 -2.07186998 0 P 0 
L 1.53971998 -2.07086998 1.60068002 -2.07086998 0 P 0 
L 1.53833002 -2.06986998 1.59993002 -2.06986998 0 P 0 
L 1.53693002 -2.06886998 1.59908002 -2.06886998 0 P 0 
L 1.53556004 -2.06786998 1.59821004 -2.06786998 0 P 0 
L 1.53418996 -2.06686998 1.59733996 -2.06686998 0 P 0 
L 1.53281998 -2.06586998 1.59646998 -2.06586998 0 P 0 
L 1.53145 -2.06486998 1.5955 -2.06486998 0 P 0 
L 1.53008002 -2.06386998 1.59453002 -2.06386998 0 P 0 
L 1.52871004 -2.06286998 1.59356004 -2.06286998 0 P 0 
L 1.52733996 -2.06186998 1.59253002 -2.06186998 0 P 0 
L 1.52596998 -2.06086998 1.59145 -2.06086998 0 P 0 
L 1.5246 -2.05986998 1.59038002 -2.05986998 0 P 0 
L 1.52323002 -2.05886998 1.5893 -2.05886998 0 P 0 
L 1.52186004 -2.05786998 1.58813996 -2.05786998 0 P 0 
L 1.52053996 -2.05686998 1.58696004 -2.05686998 0 P 0 
L 1.51935 -2.05586998 1.58576998 -2.05586998 0 P 0 
L 1.51816004 -2.05486998 1.58456998 -2.05486998 0 P 0 
L 1.51706998 -2.05386998 1.58321004 -2.05386998 0 P 0 
L 1.51603996 -2.05286998 1.58185 -2.05286998 0 P 0 
L 1.51501998 -2.05186998 1.58048996 -2.05186998 0 P 0 
L 1.51408996 -2.05086998 1.57913002 -2.05086998 0 P 0 
L 1.5132 -2.04986998 1.57776998 -2.04986998 0 P 0 
L 1.51231998 -2.04886998 1.57641998 -2.04886998 0 P 0 
L 1.51151004 -2.04786998 1.57505 -2.04786998 0 P 0 
L 1.51075 -2.04686998 1.57365 -2.04686998 0 P 0 
L 1.51008002 -2.04586998 1.57223002 -2.04586998 0 P 0 
L 1.50945 -2.04486998 1.57081004 -2.04486998 0 P 0 
L 1.50888002 -2.04386998 1.56938996 -2.04386998 0 P 0 
L 1.50836004 -2.04286998 1.56796998 -2.04286998 0 P 0 
L 1.5079 -2.04186998 1.56655 -2.04186998 0 P 0 
L 1.50748002 -2.04086998 1.56518996 -2.04086998 0 P 0 
L 1.50708996 -2.03986998 1.564 -2.03986998 0 P 0 
L 1.50676004 -2.03886998 1.56296998 -2.03886998 0 P 0 
L 1.50641998 -2.03786998 1.56206004 -2.03786998 0 P 0 
L 1.50616998 -2.03686998 1.56125 -2.03686998 0 P 0 
L 1.50591004 -2.03586998 1.56066998 -2.03586998 0 P 0 
L 1.5057 -2.03486998 1.56031998 -2.03486998 0 P 0 
L 1.50551998 -2.03386998 1.56016004 -2.03386998 0 P 0 
L 1.50533996 -2.03286998 1.56016998 -2.03286998 0 P 0 
L 1.50523996 -2.03186998 1.56036004 -2.03186998 0 P 0 
L 1.50513002 -2.03086998 1.56071998 -2.03086998 0 P 0 
L 1.50506998 -2.02986998 1.56131004 -2.02986998 0 P 0 
L 1.50503996 -2.02886998 1.5622 -2.02886998 0 P 0 
L 1.50501004 -2.02786998 1.56355 -2.02786998 0 P 0 
L 1.50501998 -2.02686998 1.5657 -2.02686998 0 P 0 
L 1.50506998 -2.02586998 1.60378996 -2.02586998 0 P 0 
L 1.50511998 -2.02486998 1.60371004 -2.02486998 0 P 0 
L 1.50521004 -2.02386998 1.60363996 -2.02386998 0 P 0 
L 1.50533996 -2.02286998 1.60356998 -2.02286998 0 P 0 
L 1.50546998 -2.02186998 1.6035 -2.02186998 0 P 0 
L 1.50563996 -2.02086998 1.60343002 -2.02086998 0 P 0 
L 1.50585 -2.01986998 1.60336004 -2.01986998 0 P 0 
L 1.50606004 -2.01886998 1.60328996 -2.01886998 0 P 0 
L 1.50633002 -2.01786998 1.60321998 -2.01786998 0 P 0 
L 1.50661998 -2.01686998 1.60315 -2.01686998 0 P 0 
L 1.50691004 -2.01586998 1.60308002 -2.01586998 0 P 0 
L 1.50726998 -2.01486998 1.603 -2.01486998 0 P 0 
L 1.50766004 -2.01386998 1.60293002 -2.01386998 0 P 0 
L 1.50808996 -2.01286998 1.60285 -2.01286998 0 P 0 
L 1.50856998 -2.01186998 1.60278002 -2.01186998 0 P 0 
L 1.50908996 -2.01086998 1.6027 -2.01086998 0 P 0 
L 1.50966004 -2.00986998 1.60261998 -2.00986998 0 P 0 
L 1.51028996 -2.00886998 1.60255 -2.00886998 0 P 0 
L 1.51096998 -2.00786998 1.60246998 -2.00786998 0 P 0 
L 1.51171998 -2.00686998 1.6024 -2.00686998 0 P 0 
L 1.51253996 -2.00586998 1.60233002 -2.00586998 0 P 0 
L 1.51343996 -2.00486998 1.60225 -2.00486998 0 P 0 
L 1.5144 -2.00386998 1.60218002 -2.00386998 0 P 0 
L 1.51551998 -2.00286998 1.6021 -2.00286998 0 P 0 
L 1.51663996 -2.00186998 1.60203002 -2.00186998 0 P 0 
L 1.51795 -2.00086998 1.60195 -2.00086998 0 P 0 
L 1.51928996 -1.99986998 1.60183996 -1.99986998 0 P 0 
L 1.52086998 -1.99886998 1.60173002 -1.99886998 0 P 0 
L 1.52258996 -1.99786998 1.60156998 -1.99786998 0 P 0 
L 1.52451004 -1.99686998 1.60138996 -1.99686998 0 P 0 
L 1.52686998 -1.99586998 1.60106998 -1.99586998 0 P 0 
L 1.52976004 -1.99486998 1.59943996 -1.99486998 0 P 0 
L 1.53283002 -1.99386998 1.59543002 -1.99386998 0 P 0 
L 1.53678996 -1.99286998 1.59003996 -1.99286998 0 P 0 
L 1.54173996 -1.99186998 1.58073996 -1.99186998 0 P 0 
L 1.55036998 -1.99086998 1.56493002 -1.99086998 0 P 0 
L 1.6036 -2.03086998 1.60413996 -2.03086998 0 P 0 
L 1.59891004 -2.02986998 1.60406998 -2.02986998 0 P 0 
L 1.59435 -2.02886998 1.604 -2.02886998 0 P 0 
L 1.58838996 -2.02786998 1.60393002 -2.02786998 0 P 0 
L 1.57981004 -2.02686998 1.60386004 -2.02686998 0 P 0 
L 1.54575 -1.98923996 1.53931998 -1.99021998 0 P 0 
L 1.53931998 -1.99021998 1.53298996 -1.99171998 0 P 0 
L 1.53298996 -1.99171998 1.52678996 -1.99373996 0 P 0 
L 1.52678996 -1.99373996 1.52376998 -1.995 0 P 0 
L 1.52376998 -1.995 1.52086998 -1.99651004 0 P 0 
L 1.52086998 -1.99651004 1.5181 -1.99826004 0 P 0 
L 1.5181 -1.99826004 1.51548002 -2.00023002 0 P 0 
L 1.51548002 -2.00023002 1.51301004 -2.00243002 0 P 0 
L 1.51301004 -2.00243002 1.51128996 -2.00423002 0 P 0 
L 1.51128996 -2.00423002 1.50971998 -2.00616004 0 P 0 
L 1.50971998 -2.00616004 1.50831004 -2.00821004 0 P 0 
L 1.50831004 -2.00821004 1.50706998 -2.01036998 0 P 0 
L 1.50706998 -2.01036998 1.50598996 -2.01261998 0 P 0 
L 1.50598996 -2.01261998 1.50508996 -2.01496998 0 P 0 
L 1.50508996 -2.01496998 1.5042 -2.01801004 0 P 0 
L 1.5042 -2.01801004 1.50355 -2.02111004 0 P 0 
L 1.50355 -2.02111004 1.50313996 -2.02426004 0 P 0 
L 1.50313996 -2.02426004 1.50298996 -2.02743002 0 P 0 
L 1.50298996 -2.02743002 1.50308996 -2.03063002 0 P 0 
L 1.50308996 -2.03063002 1.50338002 -2.03326998 0 P 0 
L 1.50338002 -2.03326998 1.50385 -2.03588002 0 P 0 
L 1.50385 -2.03588002 1.50451004 -2.03845 0 P 0 
L 1.50451004 -2.03845 1.50535 -2.04096998 0 P 0 
L 1.50535 -2.04096998 1.50633002 -2.0433 0 P 0 
L 1.50633002 -2.0433 1.5075 -2.04553002 0 P 0 
L 1.5075 -2.04553002 1.50883996 -2.04766998 0 P 0 
L 1.50883996 -2.04766998 1.51036998 -2.04968996 0 P 0 
L 1.51036998 -2.04968996 1.51323002 -2.05291998 0 P 0 
L 1.51323002 -2.05291998 1.51631998 -2.05593996 0 P 0 
L 1.51631998 -2.05593996 1.51961998 -2.05871004 0 P 0 
L 1.51961998 -2.05871004 1.53591004 -2.0706 0 P 0 
L 1.53591004 -2.0706 1.54668002 -2.07831004 0 P 0 
L 1.54668002 -2.07831004 1.54793996 -2.07933996 0 P 0 
L 1.54793996 -2.07933996 1.54911998 -2.08046998 0 P 0 
L 1.54911998 -2.08046998 1.55021004 -2.08168002 0 P 0 
L 1.55021004 -2.08168002 1.5512 -2.08298996 0 P 0 
L 1.5512 -2.08298996 1.55136004 -2.08323002 0 P 0 
L 1.55136004 -2.08323002 1.5515 -2.08348002 0 P 0 
L 1.5515 -2.08348002 1.55161004 -2.08373996 0 P 0 
L 1.55161004 -2.08373996 1.5517 -2.08401998 0 P 0 
L 1.5517 -2.08401998 1.55176998 -2.0843 0 P 0 
L 1.55176998 -2.0843 1.55181004 -2.08458002 0 P 0 
L 1.55181004 -2.08458002 1.55183002 -2.08486998 0 P 0 
L 1.55183002 -2.08486998 1.55181998 -2.08516004 0 P 0 
L 1.55181998 -2.08516004 1.55178996 -2.08545 0 P 0 
L 1.55178996 -2.08545 1.55173996 -2.08573002 0 P 0 
L 1.55173996 -2.08573002 1.55166004 -2.086 0 P 0 
L 1.55166004 -2.086 1.55156004 -2.08628002 0 P 0 
L 1.55156004 -2.08628002 1.55136998 -2.08666998 0 P 0 
L 1.55136998 -2.08666998 1.55115 -2.08703996 0 P 0 
L 1.55115 -2.08703996 1.5509 -2.08738996 0 P 0 
L 1.5509 -2.08738996 1.55063002 -2.08771998 0 P 0 
L 1.55063002 -2.08771998 1.55033002 -2.08803002 0 P 0 
L 1.55033002 -2.08803002 1.55 -2.08831004 0 P 0 
L 1.55 -2.08831004 1.54966004 -2.08856004 0 P 0 
L 1.54966004 -2.08856004 1.54928996 -2.08878996 0 P 0 
L 1.54928996 -2.08878996 1.5489 -2.08898996 0 P 0 
L 1.5489 -2.08898996 1.54786004 -2.08941004 0 P 0 
L 1.54786004 -2.08941004 1.54678996 -2.08973996 0 P 0 
L 1.54678996 -2.08973996 1.54568002 -2.08998002 0 P 0 
L 1.54568002 -2.08998002 1.54456998 -2.09011998 0 P 0 
L 1.54456998 -2.09011998 1.54343996 -2.09016998 0 P 0 
L 1.54343996 -2.09016998 1.53906998 -2.09003002 0 P 0 
L 1.53906998 -2.09003002 1.53468002 -2.08961998 0 P 0 
L 1.53468002 -2.08961998 1.52908996 -2.08878996 0 P 0 
L 1.52908996 -2.08878996 1.52351004 -2.08766004 0 P 0 
L 1.52351004 -2.08766004 1.51005 -2.08418996 0 P 0 
L 1.51005 -2.08418996 1.50631004 -2.08318002 0 P 0 
L 1.50631004 -2.08318002 1.50308002 -2.08238996 0 P 0 
L 1.50308002 -2.08238996 1.50033996 -2.08183002 0 P 0 
L 1.50033996 -2.08183002 1.5003 -2.08181998 0 P 0 
L 1.5003 -2.08181998 1.50016004 -2.08181998 0 P 0 
L 1.50016004 -2.08181998 1.50011998 -2.08183002 0 P 0 
L 1.50011998 -2.08183002 1.50006998 -2.08183996 0 P 0 
L 1.50006998 -2.08183996 1.50003002 -2.08186004 0 P 0 
L 1.50003002 -2.08186004 1.49998996 -2.08186998 0 P 0 
L 1.49998996 -2.08186998 1.49995 -2.08188996 0 P 0 
L 1.49995 -2.08188996 1.49991004 -2.08191998 0 P 0 
L 1.49991004 -2.08191998 1.49988002 -2.08195 0 P 0 
L 1.49988002 -2.08195 1.49983996 -2.08198002 0 P 0 
L 1.49983996 -2.08198002 1.4997 -2.08213996 0 P 0 
L 1.4997 -2.08213996 1.49956004 -2.08231998 0 P 0 
L 1.49956004 -2.08231998 1.49943996 -2.0825 0 P 0 
L 1.49943996 -2.0825 1.49933996 -2.0827 0 P 0 
L 1.49933996 -2.0827 1.49925 -2.0829 0 P 0 
L 1.49925 -2.0829 1.49918996 -2.08311004 0 P 0 
L 1.49918996 -2.08311004 1.49913996 -2.08333002 0 P 0 
L 1.49913996 -2.08333002 1.49911004 -2.08355 0 P 0 
L 1.49911004 -2.08355 1.4991 -2.08376998 0 P 0 
L 1.4991 -2.08376998 1.49911004 -2.08398996 0 P 0 
L 1.49911004 -2.08398996 1.50071004 -2.10395 0 P 0 
L 1.50071004 -2.10395 1.5024 -2.12403996 0 P 0 
L 1.5024 -2.12403996 1.50241998 -2.12418002 0 P 0 
L 1.50241998 -2.12418002 1.50246004 -2.12431004 0 P 0 
L 1.50246004 -2.12431004 1.50248996 -2.12445 0 P 0 
L 1.50248996 -2.12445 1.50255 -2.12456998 0 P 0 
L 1.50255 -2.12456998 1.50261004 -2.1247 0 P 0 
L 1.50261004 -2.1247 1.50276998 -2.12491998 0 P 0 
L 1.50276998 -2.12491998 1.50286004 -2.12501998 0 P 0 
L 1.50286004 -2.12501998 1.50296998 -2.12511998 0 P 0 
L 1.50296998 -2.12511998 1.50308002 -2.12521004 0 P 0 
L 1.50308002 -2.12521004 1.50318996 -2.12528002 0 P 0 
L 1.50318996 -2.12528002 1.50331998 -2.12535 0 P 0 
L 1.50331998 -2.12535 1.50343996 -2.1254 0 P 0 
L 1.50343996 -2.1254 1.50391998 -2.12556004 0 P 0 
L 1.50391998 -2.12556004 1.5044 -2.12568996 0 P 0 
L 1.5044 -2.12568996 1.50848002 -2.12648996 0 P 0 
L 1.50848002 -2.12648996 1.51328996 -2.12738002 0 P 0 
L 1.51328996 -2.12738002 1.51873996 -2.12833996 0 P 0 
L 1.51873996 -2.12833996 1.52606004 -2.12945 0 P 0 
L 1.52606004 -2.12945 1.53343996 -2.13023002 0 P 0 
L 1.53343996 -2.13023002 1.54886998 -2.13086998 0 P 0 
L 1.54886998 -2.13086998 1.56305 -2.1303 0 P 0 
L 1.56305 -2.1303 1.56666004 -2.12988996 0 P 0 
L 1.56666004 -2.12988996 1.57023002 -2.12926998 0 P 0 
L 1.57023002 -2.12926998 1.5738 -2.12843002 0 P 0 
L 1.5738 -2.12843002 1.57945 -2.12668996 0 P 0 
L 1.57945 -2.12668996 1.58498002 -2.12456998 0 P 0 
L 1.58498002 -2.12456998 1.58793996 -2.12318002 0 P 0 
L 1.58793996 -2.12318002 1.59078996 -2.12156004 0 P 0 
L 1.59078996 -2.12156004 1.59348996 -2.11971998 0 P 0 
L 1.59348996 -2.11971998 1.59525 -2.11833002 0 P 0 
L 1.59525 -2.11833002 1.5969 -2.11681998 0 P 0 
L 1.5969 -2.11681998 1.59846004 -2.11521004 0 P 0 
L 1.59846004 -2.11521004 1.59991004 -2.11348002 0 P 0 
L 1.59991004 -2.11348002 1.60175 -2.11093996 0 P 0 
L 1.60175 -2.11093996 1.60338002 -2.10826998 0 P 0 
L 1.60338002 -2.10826998 1.60481004 -2.10548002 0 P 0 
L 1.60481004 -2.10548002 1.60573002 -2.10321004 0 P 0 
L 1.60573002 -2.10321004 1.60646004 -2.10088002 0 P 0 
L 1.60646004 -2.10088002 1.60698002 -2.09848996 0 P 0 
L 1.60698002 -2.09848996 1.60756004 -2.09421998 0 P 0 
L 1.60756004 -2.09421998 1.6078 -2.08991004 0 P 0 
L 1.6078 -2.08991004 1.60768996 -2.08565 0 P 0 
L 1.60768996 -2.08565 1.60723002 -2.08141998 0 P 0 
L 1.60723002 -2.08141998 1.60691998 -2.07968002 0 P 0 
L 1.60691998 -2.07968002 1.60646998 -2.07796998 0 P 0 
L 1.60646998 -2.07796998 1.60591998 -2.0763 0 P 0 
L 1.60591998 -2.0763 1.60523002 -2.07466998 0 P 0 
L 1.60523002 -2.07466998 1.60411998 -2.07246998 0 P 0 
L 1.60411998 -2.07246998 1.60281004 -2.07038002 0 P 0 
L 1.60281004 -2.07038002 1.60131998 -2.06838996 0 P 0 
L 1.60131998 -2.06838996 1.59803996 -2.06461998 0 P 0 
L 1.59803996 -2.06461998 1.59455 -2.06101998 0 P 0 
L 1.59455 -2.06101998 1.59031998 -2.05708996 0 P 0 
L 1.59031998 -2.05708996 1.58586004 -2.05333996 0 P 0 
L 1.58586004 -2.05333996 1.57588002 -2.04598996 0 P 0 
L 1.57588002 -2.04598996 1.56685 -2.03963996 0 P 0 
L 1.56685 -2.03963996 1.56578002 -2.03878996 0 P 0 
L 1.56578002 -2.03878996 1.56476998 -2.03786004 0 P 0 
L 1.56476998 -2.03786004 1.56383002 -2.03686998 0 P 0 
L 1.56383002 -2.03686998 1.56295 -2.0358 0 P 0 
L 1.56295 -2.0358 1.56276998 -2.03555 0 P 0 
L 1.56276998 -2.03555 1.56261004 -2.03528002 0 P 0 
L 1.56261004 -2.03528002 1.56246998 -2.035 0 P 0 
L 1.56246998 -2.035 1.56236004 -2.03471998 0 P 0 
L 1.56236004 -2.03471998 1.56226998 -2.03441998 0 P 0 
L 1.56226998 -2.03441998 1.5622 -2.03411998 0 P 0 
L 1.5622 -2.03411998 1.56216004 -2.03381998 0 P 0 
L 1.56216004 -2.03381998 1.56213996 -2.03351004 0 P 0 
L 1.56213996 -2.03351004 1.56215 -2.0332 0 P 0 
L 1.56215 -2.0332 1.56218002 -2.03288996 0 P 0 
L 1.56218002 -2.03288996 1.56225 -2.03253996 0 P 0 
L 1.56225 -2.03253996 1.56233996 -2.03221004 0 P 0 
L 1.56233996 -2.03221004 1.56246004 -2.03186998 0 P 0 
L 1.56246004 -2.03186998 1.56261004 -2.03156004 0 P 0 
L 1.56261004 -2.03156004 1.56278996 -2.03125 0 P 0 
L 1.56278996 -2.03125 1.56298002 -2.03096004 0 P 0 
L 1.56298002 -2.03096004 1.56321004 -2.03068996 0 P 0 
L 1.56321004 -2.03068996 1.56345 -2.03043996 0 P 0 
L 1.56345 -2.03043996 1.56371004 -2.0302 0 P 0 
L 1.56371004 -2.0302 1.56416004 -2.02986004 0 P 0 
L 1.56416004 -2.02986004 1.56463002 -2.02955 0 P 0 
L 1.56463002 -2.02955 1.56511998 -2.02928002 0 P 0 
L 1.56511998 -2.02928002 1.56561998 -2.02903002 0 P 0 
L 1.56561998 -2.02903002 1.56611998 -2.02883996 0 P 0 
L 1.56611998 -2.02883996 1.56663996 -2.02866998 0 P 0 
L 1.56663996 -2.02866998 1.56716004 -2.02855 0 P 0 
L 1.56716004 -2.02855 1.5677 -2.02846998 0 P 0 
L 1.5677 -2.02846998 1.56926998 -2.02835 0 P 0 
L 1.56926998 -2.02835 1.57085 -2.02833996 0 P 0 
L 1.57085 -2.02833996 1.57725 -2.02866998 0 P 0 
L 1.57725 -2.02866998 1.58205 -2.02906004 0 P 0 
L 1.58205 -2.02906004 1.58746998 -2.02975 0 P 0 
L 1.58746998 -2.02975 1.59271004 -2.03056998 0 P 0 
L 1.59271004 -2.03056998 1.59681004 -2.03143002 0 P 0 
L 1.59681004 -2.03143002 1.60016004 -2.03221998 0 P 0 
L 1.60016004 -2.03221998 1.60308002 -2.03281004 0 P 0 
L 1.60308002 -2.03281004 1.60553996 -2.03323996 0 P 0 
L 1.60553996 -2.03323996 1.60568996 -2.03323996 0 P 0 
L 1.60568996 -2.03323996 1.60576998 -2.03321998 0 P 0 
L 1.60576998 -2.03321998 1.60586004 -2.03316004 0 P 0 
L 1.60586004 -2.03316004 1.6059 -2.03313996 0 P 0 
L 1.6059 -2.03313996 1.60591998 -2.03311004 0 P 0 
L 1.60591998 -2.03311004 1.60598996 -2.03303996 0 P 0 
L 1.60598996 -2.03303996 1.60605 -2.03296998 0 P 0 
L 1.60605 -2.03296998 1.6061 -2.03288996 0 P 0 
L 1.6061 -2.03288996 1.60618002 -2.03273002 0 P 0 
L 1.60618002 -2.03273002 1.60621004 -2.03263002 0 P 0 
L 1.60621004 -2.03263002 1.60623002 -2.03253996 0 P 0 
L 1.60623002 -2.03253996 1.60625 -2.03236004 0 P 0 
L 1.60625 -2.03236004 1.60623996 -2.03226004 0 P 0 
L 1.60623996 -2.03226004 1.60508002 -2.01578002 0 P 0 
L 1.60508002 -2.01578002 1.60393996 -2.00068002 0 P 0 
L 1.60393996 -2.00068002 1.60368002 -1.99833996 0 P 0 
L 1.60368002 -1.99833996 1.60326998 -1.99601004 0 P 0 
L 1.60326998 -1.99601004 1.60321004 -1.99576998 0 P 0 
L 1.60321004 -1.99576998 1.60313996 -1.99553002 0 P 0 
L 1.60313996 -1.99553002 1.60303996 -1.9953 0 P 0 
L 1.60303996 -1.9953 1.60293002 -1.99508002 0 P 0 
L 1.60293002 -1.99508002 1.60281004 -1.99486004 0 P 0 
L 1.60281004 -1.99486004 1.60261998 -1.9946 0 P 0 
L 1.60261998 -1.9946 1.60241004 -1.99435 0 P 0 
L 1.60241004 -1.99435 1.60218002 -1.99411998 0 P 0 
L 1.60218002 -1.99411998 1.60191998 -1.99391004 0 P 0 
L 1.60191998 -1.99391004 1.60161004 -1.99368996 0 P 0 
L 1.60161004 -1.99368996 1.60128996 -1.99348996 0 P 0 
L 1.60128996 -1.99348996 1.60095 -1.99331998 0 P 0 
L 1.60095 -1.99331998 1.6006 -1.99316004 0 P 0 
L 1.6006 -1.99316004 1.59966004 -1.99283002 0 P 0 
L 1.59966004 -1.99283002 1.59871004 -1.99255 0 P 0 
L 1.59871004 -1.99255 1.5933 -1.99135 0 P 0 
L 1.5933 -1.99135 1.5878 -1.9905 0 P 0 
L 1.5878 -1.9905 1.57285 -1.98915 0 P 0 
L 1.57285 -1.98915 1.55763996 -1.98861004 0 P 0 
L 1.55763996 -1.98861004 1.55171004 -1.98876004 0 P 0 
L 1.55171004 -1.98876004 1.54575 -1.98923996 0 P 0 
L 1.53011998 -2.12786998 1.5666 -2.12786998 0 P 0 
L 1.52236004 -2.12686998 1.57168002 -2.12686998 0 P 0 
L 1.51621998 -2.12586998 1.5753 -2.12586998 0 P 0 
L 1.51071004 -2.12486998 1.57856004 -2.12486998 0 P 0 
L 1.50553002 -2.12386998 1.58121004 -2.12386998 0 P 0 
L 1.50431004 -2.12286998 1.58381998 -2.12286998 0 P 0 
L 1.50423002 -2.12186998 1.58601998 -2.12186998 0 P 0 
L 1.50413996 -2.12086998 1.58796004 -2.12086998 0 P 0 
L 1.50406004 -2.11986998 1.58971004 -2.11986998 0 P 0 
L 1.50396998 -2.11886998 1.59118002 -2.11886998 0 P 0 
L 1.50388996 -2.11786998 1.5926 -2.11786998 0 P 0 
L 1.50381004 -2.11686998 1.59386004 -2.11686998 0 P 0 
L 1.50371998 -2.11586998 1.59496998 -2.11586998 0 P 0 
L 1.50363996 -2.11486998 1.59601004 -2.11486998 0 P 0 
L 1.50355 -2.11386998 1.59696998 -2.11386998 0 P 0 
L 1.50346998 -2.11286998 1.59781004 -2.11286998 0 P 0 
L 1.50338002 -2.11186998 1.5986 -2.11186998 0 P 0 
L 1.5033 -2.11086998 1.59933002 -2.11086998 0 P 0 
L 1.50321004 -2.10986998 1.60005 -2.10986998 0 P 0 
L 1.50313002 -2.10886998 1.60066998 -2.10886998 0 P 0 
L 1.50305 -2.10786998 1.60128002 -2.10786998 0 P 0 
L 1.50296004 -2.10686998 1.60185 -2.10686998 0 P 0 
L 1.50288002 -2.10586998 1.60236004 -2.10586998 0 P 0 
L 1.50278996 -2.10486998 1.60286998 -2.10486998 0 P 0 
L 1.50271004 -2.10386998 1.6033 -2.10386998 0 P 0 
L 1.50263002 -2.10286998 1.60371004 -2.10286998 0 P 0 
L 1.50255 -2.10186998 1.60405 -2.10186998 0 P 0 
L 1.50246998 -2.10086998 1.60436004 -2.10086998 0 P 0 
L 1.50238996 -2.09986998 1.60463002 -2.09986998 0 P 0 
L 1.50231004 -2.09886998 1.60485 -2.09886998 0 P 0 
L 1.50223002 -2.09786998 1.60505 -2.09786998 0 P 0 
L 1.50215 -2.09686998 1.60518002 -2.09686998 0 P 0 
L 1.50206998 -2.09586998 1.60531998 -2.09586998 0 P 0 
L 1.50198996 -2.09486998 1.60545 -2.09486998 0 P 0 
L 1.50191004 -2.09386998 1.60558002 -2.09386998 0 P 0 
L 1.50183002 -2.09286998 1.60563002 -2.09286998 0 P 0 
L 1.50175 -2.09186998 1.53725 -2.09186998 0 P 0 
L 1.54638996 -2.09186998 1.60568996 -2.09186998 0 P 0 
L 1.50166998 -2.09086998 1.5295 -2.09086998 0 P 0 
L 1.54956998 -2.09086998 1.60573996 -2.09086998 0 P 0 
L 1.50158996 -2.08986998 1.52436004 -2.08986998 0 P 0 
L 1.55125 -2.08986998 1.60578996 -2.08986998 0 P 0 
L 1.50151004 -2.08886998 1.52021004 -2.08886998 0 P 0 
L 1.55226998 -2.08886998 1.60576998 -2.08886998 0 P 0 
L 1.50143002 -2.08786998 1.51633002 -2.08786998 0 P 0 
L 1.55298002 -2.08786998 1.60573996 -2.08786998 0 P 0 
L 1.50133996 -2.08686998 1.51246004 -2.08686998 0 P 0 
L 1.55346998 -2.08686998 1.60571998 -2.08686998 0 P 0 
L 1.50126998 -2.08586998 1.50861998 -2.08586998 0 P 0 
L 1.55375 -2.08586998 1.60568996 -2.08586998 0 P 0 
L 1.50118002 -2.08486998 1.50481004 -2.08486998 0 P 0 
L 1.55383002 -2.08486998 1.60558996 -2.08486998 0 P 0 
L 1.55371998 -2.08386998 1.60548996 -2.08386998 0 P 0 
L 1.54886998 -2.12886998 1.53358996 -2.12823996 0 P 0 
L 1.53358996 -2.12823996 1.52631998 -2.12746998 0 P 0 
L 1.52631998 -2.12746998 1.51906004 -2.12636998 0 P 0 
L 1.51906004 -2.12636998 1.51363002 -2.12541004 0 P 0 
L 1.51363002 -2.12541004 1.50886998 -2.12451998 0 P 0 
L 1.50886998 -2.12451998 1.50483996 -2.12373996 0 P 0 
L 1.50483996 -2.12373996 1.50448996 -2.12365 0 P 0 
L 1.50448996 -2.12365 1.50438002 -2.12361004 0 P 0 
L 1.50438002 -2.12361004 1.5027 -2.10378002 0 P 0 
L 1.5027 -2.10378002 1.50111998 -2.08403002 0 P 0 
L 1.50111998 -2.08403002 1.50263996 -2.08433996 0 P 0 
L 1.50263996 -2.08433996 1.50581004 -2.08511004 0 P 0 
L 1.50581004 -2.08511004 1.50955 -2.08611998 0 P 0 
L 1.50955 -2.08611998 1.52306004 -2.08961004 0 P 0 
L 1.52306004 -2.08961004 1.52311004 -2.08961998 0 P 0 
L 1.52311004 -2.08961998 1.52875 -2.09076004 0 P 0 
L 1.52875 -2.09076004 1.5288 -2.09076004 0 P 0 
L 1.5288 -2.09076004 1.53443996 -2.09161004 0 P 0 
L 1.53443996 -2.09161004 1.53893996 -2.09203002 0 P 0 
L 1.53893996 -2.09203002 1.54346004 -2.09216998 0 P 0 
L 1.54346004 -2.09216998 1.54473996 -2.09211004 0 P 0 
L 1.54473996 -2.09211004 1.54603002 -2.09195 0 P 0 
L 1.54603002 -2.09195 1.54728996 -2.09166998 0 P 0 
L 1.54728996 -2.09166998 1.54853002 -2.09128996 0 P 0 
L 1.54853002 -2.09128996 1.54973002 -2.09081004 0 P 0 
L 1.54973002 -2.09081004 1.55026998 -2.09053996 0 P 0 
L 1.55026998 -2.09053996 1.55076998 -2.09023002 0 P 0 
L 1.55076998 -2.09023002 1.55118002 -2.08991998 0 P 0 
L 1.55118002 -2.08991998 1.55118002 -2.08991004 0 P 0 
L 1.55118002 -2.08991004 1.5512 -2.08991004 0 P 0 
L 1.5512 -2.08991004 1.55125 -2.08986998 0 P 0 
L 1.55125 -2.08986998 1.55131004 -2.08981998 0 P 0 
L 1.55131004 -2.08981998 1.55126998 -2.08978002 0 P 0 
L 1.55126998 -2.08978002 1.55136004 -2.08978002 0 P 0 
L 1.55136004 -2.08978002 1.5517 -2.08948996 0 P 0 
L 1.5517 -2.08948996 1.55206004 -2.08911998 0 P 0 
L 1.55206004 -2.08911998 1.55205 -2.08911004 0 P 0 
L 1.55205 -2.08911004 1.55206004 -2.08911004 0 P 0 
L 1.55206004 -2.08911004 1.55211998 -2.08906004 0 P 0 
L 1.55211998 -2.08906004 1.55248996 -2.08861004 0 P 0 
L 1.55248996 -2.08861004 1.55283996 -2.08811998 0 P 0 
L 1.55283996 -2.08811998 1.55313996 -2.08761004 0 P 0 
L 1.55313996 -2.08761004 1.5534 -2.08706998 0 P 0 
L 1.5534 -2.08706998 1.55356004 -2.08663002 0 P 0 
L 1.55356004 -2.08663002 1.55368996 -2.08618996 0 P 0 
L 1.55368996 -2.08618996 1.55376998 -2.08573996 0 P 0 
L 1.55376998 -2.08573996 1.55378002 -2.08565 0 P 0 
L 1.55378002 -2.08565 1.55381998 -2.08528002 0 P 0 
L 1.55381998 -2.08528002 1.55383002 -2.08481998 0 P 0 
L 1.55383002 -2.08481998 1.5538 -2.08436998 0 P 0 
L 1.5538 -2.08436998 1.55373002 -2.08391998 0 P 0 
L 1.55373002 -2.08391998 1.55361998 -2.08346998 0 P 0 
L 1.55361998 -2.08346998 1.55348002 -2.08303996 0 P 0 
L 1.55348002 -2.08303996 1.5533 -2.08261004 0 P 0 
L 1.5533 -2.08261004 1.55308996 -2.08221004 0 P 0 
L 1.55308996 -2.08221004 1.55283996 -2.08183002 0 P 0 
L 1.55283996 -2.08183002 1.55175 -2.0804 0 P 0 
L 1.55175 -2.0804 1.55055 -2.07908002 0 P 0 
L 1.55055 -2.07908002 1.54926004 -2.07783996 0 P 0 
L 1.54926004 -2.07783996 1.54788996 -2.07671998 0 P 0 
L 1.54788996 -2.07671998 1.53706998 -2.06898002 0 P 0 
L 1.53706998 -2.06898002 1.52085 -2.05713996 0 P 0 
L 1.52085 -2.05713996 1.51766004 -2.05445 0 P 0 
L 1.51766004 -2.05445 1.51468002 -2.05153996 0 P 0 
L 1.51468002 -2.05153996 1.51191998 -2.04841998 0 P 0 
L 1.51191998 -2.04841998 1.51048996 -2.04651998 0 P 0 
L 1.51048996 -2.04651998 1.50923002 -2.04453002 0 P 0 
L 1.50923002 -2.04453002 1.50813996 -2.04245 0 P 0 
L 1.50813996 -2.04245 1.50721998 -2.04026004 0 P 0 
L 1.50721998 -2.04026004 1.50643002 -2.03788002 0 P 0 
L 1.50643002 -2.03788002 1.50581004 -2.03545 0 P 0 
L 1.50581004 -2.03545 1.50536004 -2.03298996 0 P 0 
L 1.50536004 -2.03298996 1.50508996 -2.0305 0 P 0 
L 1.50508996 -2.0305 1.50498996 -2.02745 0 P 0 
L 1.50498996 -2.02745 1.50513996 -2.02443996 0 P 0 
L 1.50513996 -2.02443996 1.50551998 -2.02145 0 P 0 
L 1.50551998 -2.02145 1.50613996 -2.0185 0 P 0 
L 1.50613996 -2.0185 1.50698996 -2.01561004 0 P 0 
L 1.50698996 -2.01561004 1.50783002 -2.01341004 0 P 0 
L 1.50783002 -2.01341004 1.50883002 -2.0113 0 P 0 
L 1.50883002 -2.0113 1.51 -2.00928002 0 P 0 
L 1.51 -2.00928002 1.51133002 -2.00736004 0 P 0 
L 1.51133002 -2.00736004 1.5128 -2.00555 0 P 0 
L 1.5128 -2.00555 1.5144 -2.00386004 0 P 0 
L 1.5144 -2.00386004 1.51675 -2.00176998 0 P 0 
L 1.51675 -2.00176998 1.51923002 -1.9999 0 P 0 
L 1.51923002 -1.9999 1.52186004 -1.99823996 0 P 0 
L 1.52186004 -1.99823996 1.52461998 -1.99681004 0 P 0 
L 1.52461998 -1.99681004 1.52748996 -1.99561004 0 P 0 
L 1.52748996 -1.99561004 1.53353002 -1.99363996 0 P 0 
L 1.53353002 -1.99363996 1.5397 -1.99218002 0 P 0 
L 1.5397 -1.99218002 1.54598002 -1.99123002 0 P 0 
L 1.54598002 -1.99123002 1.55181004 -1.99075 0 P 0 
L 1.55181004 -1.99075 1.55763002 -1.99061998 0 P 0 
L 1.55763002 -1.99061998 1.57273002 -1.99113996 0 P 0 
L 1.57273002 -1.99113996 1.58755 -1.99248996 0 P 0 
L 1.58755 -1.99248996 1.59293002 -1.99331998 0 P 0 
L 1.59293002 -1.99331998 1.59821004 -1.99448996 0 P 0 
L 1.59821004 -1.99448996 1.59905 -1.99473002 0 P 0 
L 1.59905 -1.99473002 1.59986004 -1.99501998 0 P 0 
L 1.59986004 -1.99501998 1.60008002 -1.99511998 0 P 0 
L 1.60008002 -1.99511998 1.6003 -1.99523002 0 P 0 
L 1.6003 -1.99523002 1.60051004 -1.99536004 0 P 0 
L 1.60051004 -1.99536004 1.60071004 -1.9955 0 P 0 
L 1.60071004 -1.9955 1.60083002 -1.99561004 0 P 0 
L 1.60083002 -1.99561004 1.60093996 -1.99571004 0 P 0 
L 1.60093996 -1.99571004 1.60103996 -1.99583002 0 P 0 
L 1.60103996 -1.99583002 1.60111998 -1.99595 0 P 0 
L 1.60111998 -1.99595 1.60116998 -1.99601998 0 P 0 
L 1.60116998 -1.99601998 1.60121004 -1.99611004 0 P 0 
L 1.60121004 -1.99611004 1.60125 -1.99621004 0 P 0 
L 1.60125 -1.99621004 1.60128002 -1.9963 0 P 0 
L 1.60128002 -1.9963 1.60131004 -1.99641004 0 P 0 
L 1.60131004 -1.99641004 1.6017 -1.99861998 0 P 0 
L 1.6017 -1.99861998 1.60195 -2.00086998 0 P 0 
L 1.60195 -2.00086998 1.60308002 -2.01593002 0 P 0 
L 1.60308002 -2.01593002 1.60415 -2.03096998 0 P 0 
L 1.60415 -2.03096998 1.60345 -2.03083996 0 P 0 
L 1.60345 -2.03083996 1.60058996 -2.03026004 0 P 0 
L 1.60058996 -2.03026004 1.59723002 -2.02948002 0 P 0 
L 1.59723002 -2.02948002 1.59721998 -2.02948002 0 P 0 
L 1.59721998 -2.02948002 1.59306998 -2.0286 0 P 0 
L 1.59306998 -2.0286 1.58776004 -2.02776998 0 P 0 
L 1.58776004 -2.02776998 1.58226004 -2.02708002 0 P 0 
L 1.58226004 -2.02708002 1.57738002 -2.02666998 0 P 0 
L 1.57738002 -2.02666998 1.5709 -2.02633996 0 P 0 
L 1.5709 -2.02633996 1.56918996 -2.02635 0 P 0 
L 1.56918996 -2.02635 1.56746998 -2.02648996 0 P 0 
L 1.56746998 -2.02648996 1.56678996 -2.02658996 0 P 0 
L 1.56678996 -2.02658996 1.56611998 -2.02673996 0 P 0 
L 1.56611998 -2.02673996 1.56546004 -2.02695 0 P 0 
L 1.56546004 -2.02695 1.56481998 -2.0272 0 P 0 
L 1.56481998 -2.0272 1.56418996 -2.0275 0 P 0 
L 1.56418996 -2.0275 1.56358002 -2.02785 0 P 0 
L 1.56358002 -2.02785 1.563 -2.02823002 0 P 0 
L 1.563 -2.02823002 1.56245 -2.02865 0 P 0 
L 1.56245 -2.02865 1.56206998 -2.02898996 0 P 0 
L 1.56206998 -2.02898996 1.56171004 -2.02936004 0 P 0 
L 1.56171004 -2.02936004 1.56138002 -2.02976004 0 P 0 
L 1.56138002 -2.02976004 1.56108996 -2.03018996 0 P 0 
L 1.56108996 -2.03018996 1.56083002 -2.03063996 0 P 0 
L 1.56083002 -2.03063996 1.56061998 -2.0311 0 P 0 
L 1.56061998 -2.0311 1.56043996 -2.03158996 0 P 0 
L 1.56043996 -2.03158996 1.5603 -2.03208002 0 P 0 
L 1.5603 -2.03208002 1.5602 -2.0326 0 P 0 
L 1.5602 -2.0326 1.56015 -2.03308002 0 P 0 
L 1.56015 -2.03308002 1.56013996 -2.03353996 0 P 0 
L 1.56013996 -2.03353996 1.56016004 -2.03391004 0 P 0 
L 1.56016004 -2.03391004 1.56048002 -2.03391004 0 P 0 
L 1.56048002 -2.03391004 1.56016004 -2.03393002 0 P 0 
L 1.56016004 -2.03393002 1.56016998 -2.03401004 0 P 0 
L 1.56016998 -2.03401004 1.56023002 -2.03448002 0 P 0 
L 1.56023002 -2.03448002 1.56025 -2.03456004 0 P 0 
L 1.56025 -2.03456004 1.56033002 -2.03493002 0 P 0 
L 1.56033002 -2.03493002 1.56046998 -2.03538002 0 P 0 
L 1.56046998 -2.03538002 1.56063996 -2.03581998 0 P 0 
L 1.56063996 -2.03581998 1.56085 -2.03623996 0 P 0 
L 1.56085 -2.03623996 1.56108996 -2.03663996 0 P 0 
L 1.56108996 -2.03663996 1.56136004 -2.03701998 0 P 0 
L 1.56136004 -2.03701998 1.56233002 -2.03818996 0 P 0 
L 1.56233002 -2.03818996 1.56336998 -2.03928996 0 P 0 
L 1.56336998 -2.03928996 1.56448002 -2.04031004 0 P 0 
L 1.56448002 -2.04031004 1.56566004 -2.04123996 0 P 0 
L 1.56566004 -2.04123996 1.57471004 -2.04761998 0 P 0 
L 1.57471004 -2.04761998 1.58461998 -2.05491004 0 P 0 
L 1.58461998 -2.05491004 1.58898996 -2.05858996 0 P 0 
L 1.58898996 -2.05858996 1.59315 -2.06245 0 P 0 
L 1.59315 -2.06245 1.59656998 -2.06596998 0 P 0 
L 1.59656998 -2.06596998 1.59976004 -2.06965 0 P 0 
L 1.59976004 -2.06965 1.60116004 -2.07151004 0 P 0 
L 1.60116004 -2.07151004 1.60238002 -2.07346004 0 P 0 
L 1.60238002 -2.07346004 1.60341998 -2.0755 0 P 0 
L 1.60341998 -2.0755 1.60403996 -2.077 0 P 0 
L 1.60403996 -2.077 1.60456004 -2.07853996 0 P 0 
L 1.60456004 -2.07853996 1.60496004 -2.08011004 0 P 0 
L 1.60496004 -2.08011004 1.60525 -2.0817 0 P 0 
L 1.60525 -2.0817 1.60568996 -2.08578002 0 P 0 
L 1.60568996 -2.08578002 1.60578996 -2.08988002 0 P 0 
L 1.60578996 -2.08988002 1.60556998 -2.09403002 0 P 0 
L 1.60556998 -2.09403002 1.60501004 -2.09813996 0 P 0 
L 1.60501004 -2.09813996 1.60451998 -2.10036998 0 P 0 
L 1.60451998 -2.10036998 1.60383996 -2.10253996 0 P 0 
L 1.60383996 -2.10253996 1.60298996 -2.10465 0 P 0 
L 1.60298996 -2.10465 1.60163996 -2.1073 0 P 0 
L 1.60163996 -2.1073 1.60008002 -2.10983002 0 P 0 
L 1.60008002 -2.10983002 1.59833002 -2.11225 0 P 0 
L 1.59833002 -2.11225 1.59696998 -2.11386998 0 P 0 
L 1.59696998 -2.11386998 1.59551004 -2.11538996 0 P 0 
L 1.59551004 -2.11538996 1.59395 -2.1168 0 P 0 
L 1.59395 -2.1168 1.59231004 -2.11811004 0 P 0 
L 1.59231004 -2.11811004 1.58973002 -2.11986004 0 P 0 
L 1.58973002 -2.11986004 1.58701998 -2.1214 0 P 0 
L 1.58701998 -2.1214 1.5842 -2.12273002 0 P 0 
L 1.5842 -2.12273002 1.5788 -2.1248 0 P 0 
L 1.5788 -2.1248 1.57326998 -2.12648996 0 P 0 
L 1.57326998 -2.12648996 1.56983002 -2.12731004 0 P 0 
L 1.56983002 -2.12731004 1.56638002 -2.12791004 0 P 0 
L 1.56638002 -2.12791004 1.56288996 -2.1283 0 P 0 
L 1.56288996 -2.1283 1.54886998 -2.12886998 0 P 0 
L 1.35851998 -2.06545 1.47866004 -2.06545 0 P 0 
L 1.35936004 -2.06445 1.47871004 -2.06445 0 P 0 
L 1.36041004 -2.06345 1.47875 -2.06345 0 P 0 
L 1.36163996 -2.06245 1.4788 -2.06245 0 P 0 
L 1.36293996 -2.06145 1.47883996 -2.06145 0 P 0 
L 1.36436004 -2.06045 1.47888996 -2.06045 0 P 0 
L 1.36598002 -2.05945 1.47893996 -2.05945 0 P 0 
L 1.36776004 -2.05845 1.47898996 -2.05845 0 P 0 
L 1.36971004 -2.05745 1.47903002 -2.05745 0 P 0 
L 1.37166004 -2.05645 1.47908002 -2.05645 0 P 0 
L 1.37391004 -2.05545 1.47911998 -2.05545 0 P 0 
L 1.37616998 -2.05445 1.47916998 -2.05445 0 P 0 
L 1.37873002 -2.05345 1.47921004 -2.05345 0 P 0 
L 1.38136004 -2.05245 1.47926004 -2.05245 0 P 0 
L 1.36875 -2.03345 1.37108996 -2.03345 0 P 0 
L 1.36886004 -2.03245 1.37385 -2.03245 0 P 0 
L 1.36896998 -2.03145 1.37678002 -2.03145 0 P 0 
L 1.36908996 -2.03045 1.3797 -2.03045 0 P 0 
L 1.36921004 -2.02945 1.38261998 -2.02945 0 P 0 
L 1.36933002 -2.02845 1.38638996 -2.02845 0 P 0 
L 1.36946004 -2.02745 1.39023996 -2.02745 0 P 0 
L 1.36958002 -2.02645 1.39503002 -2.02645 0 P 0 
L 1.3697 -2.02545 1.40068002 -2.02545 0 P 0 
L 1.36981998 -2.02445 1.41053996 -2.02445 0 P 0 
L 1.36993996 -2.02345 1.47993996 -2.02345 0 P 0 
L 1.37008002 -2.02245 1.47988002 -2.02245 0 P 0 
L 1.37021004 -2.02145 1.47978002 -2.02145 0 P 0 
L 1.37033996 -2.02045 1.47968002 -2.02045 0 P 0 
L 1.37046998 -2.01945 1.47953002 -2.01945 0 P 0 
L 1.3706 -2.01845 1.47936004 -2.01845 0 P 0 
L 1.37073002 -2.01745 1.47918002 -2.01745 0 P 0 
L 1.37086004 -2.01645 1.47893002 -2.01645 0 P 0 
L 1.37098996 -2.01545 1.47868002 -2.01545 0 P 0 
L 1.37113002 -2.01445 1.4784 -2.01445 0 P 0 
L 1.37126998 -2.01345 1.47806004 -2.01345 0 P 0 
L 1.3714 -2.01245 1.47773002 -2.01245 0 P 0 
L 1.37153996 -2.01145 1.47733002 -2.01145 0 P 0 
L 1.37168002 -2.01045 1.47691004 -2.01045 0 P 0 
L 1.37181004 -2.00945 1.47641004 -2.00945 0 P 0 
L 1.37195 -2.00845 1.47588996 -2.00845 0 P 0 
L 1.37208002 -2.00745 1.47528002 -2.00745 0 P 0 
L 1.37221004 -2.00645 1.47463996 -2.00645 0 P 0 
L 1.37235 -2.00545 1.47391998 -2.00545 0 P 0 
L 1.37248996 -2.00445 1.47311004 -2.00445 0 P 0 
L 1.37261998 -2.00345 1.47225 -2.00345 0 P 0 
L 1.37276004 -2.00245 1.47126998 -2.00245 0 P 0 
L 1.3729 -2.00145 1.4702 -2.00145 0 P 0 
L 1.37303002 -2.00045 1.46903996 -2.00045 0 P 0 
L 1.37316998 -1.99945 1.46775 -1.99945 0 P 0 
L 1.3733 -1.99845 1.46625 -1.99845 0 P 0 
L 1.37343996 -1.99745 1.46455 -1.99745 0 P 0 
L 1.37356998 -1.99645 1.46253996 -1.99645 0 P 0 
L 1.37753002 -1.99545 1.46041004 -1.99545 0 P 0 
L 1.38218996 -1.99445 1.45781004 -1.99445 0 P 0 
L 1.42925 -2.08345 1.47785 -2.08345 0 P 0 
L 1.42931998 -2.08245 1.47788996 -2.08245 0 P 0 
L 1.42938002 -2.08145 1.47793002 -2.08145 0 P 0 
L 1.42945 -2.08045 1.47796998 -2.08045 0 P 0 
L 1.42951004 -2.07945 1.47801004 -2.07945 0 P 0 
L 1.42958002 -2.07845 1.47806004 -2.07845 0 P 0 
L 1.42963996 -2.07745 1.4781 -2.07745 0 P 0 
L 1.4297 -2.07645 1.47815 -2.07645 0 P 0 
L 1.42976998 -2.07545 1.4782 -2.07545 0 P 0 
L 1.42983002 -2.07445 1.47825 -2.07445 0 P 0 
L 1.4299 -2.07345 1.47828996 -2.07345 0 P 0 
L 1.42963996 -2.07245 1.47833996 -2.07245 0 P 0 
L 1.42918996 -2.07145 1.47838002 -2.07145 0 P 0 
L 1.38425 -2.05145 1.47931004 -2.05145 0 P 0 
L 1.38731998 -2.05045 1.47933996 -2.05045 0 P 0 
L 1.39088002 -2.04945 1.47938002 -2.04945 0 P 0 
L 1.3947 -2.04845 1.47941004 -2.04845 0 P 0 
L 1.39851004 -2.04745 1.47945 -2.04745 0 P 0 
L 1.40233002 -2.04645 1.47948002 -2.04645 0 P 0 
L 1.40608002 -2.04545 1.47951004 -2.04545 0 P 0 
L 1.40983002 -2.04445 1.47955 -2.04445 0 P 0 
L 1.41306998 -2.04345 1.47958996 -2.04345 0 P 0 
L 1.41591998 -2.04245 1.47961998 -2.04245 0 P 0 
L 1.41876998 -2.04145 1.47965 -2.04145 0 P 0 
L 1.42133996 -2.04045 1.47968996 -2.04045 0 P 0 
L 1.42361998 -2.03945 1.47971998 -2.03945 0 P 0 
L 1.42591004 -2.03845 1.47975 -2.03845 0 P 0 
L 1.42805 -2.03745 1.47978002 -2.03745 0 P 0 
L 1.42936004 -2.03645 1.47981004 -2.03645 0 P 0 
L 1.43003002 -2.03545 1.47983002 -2.03545 0 P 0 
L 1.43081998 -2.03445 1.47986004 -2.03445 0 P 0 
L 1.43121004 -2.03345 1.47988002 -2.03345 0 P 0 
L 1.43141998 -2.03245 1.4799 -2.03245 0 P 0 
L 1.43146998 -2.03145 1.47993002 -2.03145 0 P 0 
L 1.43136004 -2.03045 1.47996004 -2.03045 0 P 0 
L 1.43108002 -2.02945 1.47998002 -2.02945 0 P 0 
L 1.4306 -2.02845 1.48001004 -2.02845 0 P 0 
L 1.42986998 -2.02745 1.48001004 -2.02745 0 P 0 
L 1.42875 -2.02645 1.47998996 -2.02645 0 P 0 
L 1.42658996 -2.02545 1.47996998 -2.02545 0 P 0 
L 1.42203996 -2.02445 1.47996004 -2.02445 0 P 0 
L 1.38748002 -1.99345 1.45483002 -1.99345 0 P 0 
L 1.39331998 -1.99245 1.45108996 -1.99245 0 P 0 
L 1.40051004 -1.99145 1.44503002 -1.99145 0 P 0 
L 1.38096998 -2.12745 1.4051 -2.12745 0 P 0 
L 1.37671004 -2.12645 1.41113996 -2.12645 0 P 0 
L 1.3736 -2.12545 1.41238996 -2.12545 0 P 0 
L 1.37096998 -2.12445 1.41268002 -2.12445 0 P 0 
L 1.36876998 -2.12345 1.41296998 -2.12345 0 P 0 
L 1.36685 -2.12245 1.41326998 -2.12245 0 P 0 
L 1.36516004 -2.12145 1.41356004 -2.12145 0 P 0 
L 1.36366004 -2.12045 1.41385 -2.12045 0 P 0 
L 1.36225 -2.11945 1.41413996 -2.11945 0 P 0 
L 1.361 -2.11845 1.41443002 -2.11845 0 P 0 
L 1.35983002 -2.11745 1.41471998 -2.11745 0 P 0 
L 1.35876004 -2.11645 1.41501004 -2.11645 0 P 0 
L 1.42661998 -2.12445 1.47693002 -2.12445 0 P 0 
L 1.42665 -2.12345 1.47693002 -2.12345 0 P 0 
L 1.4267 -2.12245 1.47693002 -2.12245 0 P 0 
L 1.42675 -2.12145 1.47693002 -2.12145 0 P 0 
L 1.42681004 -2.12045 1.47693002 -2.12045 0 P 0 
L 1.42686998 -2.11945 1.47693002 -2.11945 0 P 0 
L 1.42691998 -2.11845 1.47693002 -2.11845 0 P 0 
L 1.42698996 -2.11745 1.47693002 -2.11745 0 P 0 
L 1.42705 -2.11645 1.47693002 -2.11645 0 P 0 
L 1.42711004 -2.11545 1.47693002 -2.11545 0 P 0 
L 1.42716998 -2.11445 1.47693002 -2.11445 0 P 0 
L 1.42723002 -2.11345 1.47693996 -2.11345 0 P 0 
L 1.4273 -2.11245 1.47695 -2.11245 0 P 0 
L 1.42736998 -2.11145 1.47696004 -2.11145 0 P 0 
L 1.42743996 -2.11045 1.47698002 -2.11045 0 P 0 
L 1.42751004 -2.10945 1.47698996 -2.10945 0 P 0 
L 1.42758002 -2.10845 1.47701004 -2.10845 0 P 0 
L 1.42765 -2.10745 1.47703002 -2.10745 0 P 0 
L 1.42771004 -2.10645 1.47703996 -2.10645 0 P 0 
L 1.42778002 -2.10545 1.47706998 -2.10545 0 P 0 
L 1.42783996 -2.10445 1.4771 -2.10445 0 P 0 
L 1.42791004 -2.10345 1.47713002 -2.10345 0 P 0 
L 1.42798002 -2.10245 1.47716004 -2.10245 0 P 0 
L 1.42805 -2.10145 1.4772 -2.10145 0 P 0 
L 1.42811004 -2.10045 1.47723002 -2.10045 0 P 0 
L 1.40953002 -2.09945 1.41973002 -2.09945 0 P 0 
L 1.42818002 -2.09945 1.47726004 -2.09945 0 P 0 
L 1.41618002 -2.09845 1.41996998 -2.09845 0 P 0 
L 1.42825 -2.09845 1.47728996 -2.09845 0 P 0 
L 1.42831998 -2.09745 1.47733002 -2.09745 0 P 0 
L 1.42838996 -2.09645 1.47736004 -2.09645 0 P 0 
L 1.42846004 -2.09545 1.47738996 -2.09545 0 P 0 
L 1.42851998 -2.09445 1.47741998 -2.09445 0 P 0 
L 1.42858996 -2.09345 1.47746004 -2.09345 0 P 0 
L 1.42866004 -2.09245 1.4775 -2.09245 0 P 0 
L 1.42873002 -2.09145 1.47753996 -2.09145 0 P 0 
L 1.42878996 -2.09045 1.47758002 -2.09045 0 P 0 
L 1.42886004 -2.08945 1.47761998 -2.08945 0 P 0 
L 1.42893002 -2.08845 1.47766004 -2.08845 0 P 0 
L 1.42898996 -2.08745 1.4777 -2.08745 0 P 0 
L 1.42906004 -2.08645 1.47773002 -2.08645 0 P 0 
L 1.42911998 -2.08545 1.47776998 -2.08545 0 P 0 
L 1.42918996 -2.08445 1.47781004 -2.08445 0 P 0 
L 1.61686004 -2.17995 1.66846004 -2.17995 0 P 0 
L 1.61591004 -2.17895 1.67158996 -2.17895 0 P 0 
L 1.61553996 -2.17795 1.67431998 -2.17795 0 P 0 
L 1.61526998 -2.17695 1.67675 -2.17695 0 P 0 
L 1.61508002 -2.17595 1.67903996 -2.17595 0 P 0 
L 1.61496998 -2.17495 1.68108002 -2.17495 0 P 0 
L 1.61491004 -2.17395 1.68295 -2.17395 0 P 0 
L 1.61485 -2.17295 1.68458996 -2.17295 0 P 0 
L 1.61478996 -2.17195 1.6861 -2.17195 0 P 0 
L 1.61473002 -2.17095 1.6875 -2.17095 0 P 0 
L 1.61466998 -2.16995 1.68876998 -2.16995 0 P 0 
L 1.61461004 -2.16895 1.68998002 -2.16895 0 P 0 
L 1.61455 -2.16795 1.69108002 -2.16795 0 P 0 
L 1.61448996 -2.16695 1.69211998 -2.16695 0 P 0 
L 1.61443002 -2.16595 1.69316004 -2.16595 0 P 0 
L 1.61436998 -2.16495 1.69411998 -2.16495 0 P 0 
L 1.61431004 -2.16395 1.69498996 -2.16395 0 P 0 
L 1.61425 -2.16295 1.69586004 -2.16295 0 P 0 
L 1.61418996 -2.16195 1.69673002 -2.16195 0 P 0 
L 1.61413002 -2.16095 1.69746998 -2.16095 0 P 0 
L 1.61406998 -2.15995 1.6982 -2.15995 0 P 0 
L 1.61401998 -2.15895 1.69893996 -2.15895 0 P 0 
L 1.61396998 -2.15795 1.69963002 -2.15795 0 P 0 
L 1.64433002 -2.18295 1.63151004 -2.18271004 0 P 0 
L 1.63151004 -2.18271004 1.62658002 -2.18226998 0 P 0 
L 1.62658002 -2.18226998 1.62168996 -2.18146998 0 P 0 
L 1.62168996 -2.18146998 1.6201 -2.1811 0 P 0 
L 1.6201 -2.1811 1.61853996 -2.18061004 0 P 0 
L 1.61853996 -2.18061004 1.61701004 -2.18001998 0 P 0 
L 1.61701004 -2.18001998 1.61686004 -2.17995 0 P 0 
L 1.61686004 -2.17995 1.61671004 -2.17986998 0 P 0 
L 1.61671004 -2.17986998 1.61656998 -2.17976998 0 P 0 
L 1.61656998 -2.17976998 1.61643996 -2.17966998 0 P 0 
L 1.61643996 -2.17966998 1.61631998 -2.17955 0 P 0 
L 1.61631998 -2.17955 1.61621004 -2.17943002 0 P 0 
L 1.61621004 -2.17943002 1.6161 -2.1793 0 P 0 
L 1.6161 -2.1793 1.61601004 -2.17915 0 P 0 
L 1.61601004 -2.17915 1.61593002 -2.179 0 P 0 
L 1.61593002 -2.179 1.61586004 -2.17885 0 P 0 
L 1.61586004 -2.17885 1.61553002 -2.17791004 0 P 0 
L 1.61553002 -2.17791004 1.61526998 -2.17696004 0 P 0 
L 1.61526998 -2.17696004 1.61508996 -2.17598996 0 P 0 
L 1.61508996 -2.17598996 1.61496998 -2.17496998 0 P 0 
L 1.61496998 -2.17496998 1.61408002 -2.16011004 0 P 0 
L 1.61408002 -2.16011004 1.61341998 -2.14758996 0 P 0 
L 1.61341998 -2.14758996 1.6202 -2.14821004 0 P 0 
L 1.6202 -2.14821004 1.62023002 -2.14821004 0 P 0 
L 1.62023002 -2.14821004 1.63216998 -2.14893996 0 P 0 
L 1.63216998 -2.14893996 1.6349 -2.14893002 0 P 0 
L 1.6349 -2.14893002 1.63761998 -2.14873002 0 P 0 
L 1.63761998 -2.14873002 1.64031998 -2.14835 0 P 0 
L 1.64031998 -2.14835 1.64198996 -2.14798996 0 P 0 
L 1.64198996 -2.14798996 1.64363002 -2.14751998 0 P 0 
L 1.64363002 -2.14751998 1.64523002 -2.14693002 0 P 0 
L 1.64523002 -2.14693002 1.64678996 -2.14623002 0 P 0 
L 1.64678996 -2.14623002 1.64888002 -2.14506998 0 P 0 
L 1.64888002 -2.14506998 1.65086998 -2.14376004 0 P 0 
L 1.65086998 -2.14376004 1.65093996 -2.14371004 0 P 0 
L 1.65093996 -2.14371004 1.65275 -2.14228996 0 P 0 
L 1.65275 -2.14228996 1.6539 -2.14123996 0 P 0 
L 1.6539 -2.14123996 1.65496004 -2.14011004 0 P 0 
L 1.65496004 -2.14011004 1.65591998 -2.13891004 0 P 0 
L 1.65591998 -2.13891004 1.65755 -2.13653996 0 P 0 
L 1.65755 -2.13653996 1.65901998 -2.13415 0 P 0 
L 1.65901998 -2.13415 1.65903002 -2.13413002 0 P 0 
L 1.65903002 -2.13413002 1.66035 -2.13171998 0 P 0 
L 1.66035 -2.13171998 1.66155 -2.12925 0 P 0 
L 1.66155 -2.12925 1.66183996 -2.12851998 0 P 0 
L 1.66183996 -2.12851998 1.66206998 -2.12776004 0 P 0 
L 1.66206998 -2.12776004 1.66223996 -2.12696998 0 P 0 
L 1.66223996 -2.12696998 1.66233996 -2.12618002 0 P 0 
L 1.66233996 -2.12618002 1.66236998 -2.12538996 0 P 0 
L 1.66236998 -2.12538996 1.66233002 -2.12436004 0 P 0 
L 1.66233002 -2.12436004 1.66221004 -2.12335 0 P 0 
L 1.66221004 -2.12335 1.662 -2.12235 0 P 0 
L 1.662 -2.12235 1.66171004 -2.12141004 0 P 0 
L 1.66171004 -2.12141004 1.64438996 -2.07113002 0 P 0 
L 1.64438996 -2.07113002 1.62871998 -2.02606004 0 P 0 
L 1.62871998 -2.02606004 1.62116004 -2.00558996 0 P 0 
L 1.62116004 -2.00558996 1.62116004 -2.00556998 0 P 0 
L 1.62116004 -2.00556998 1.61681004 -1.99443996 0 P 0 
L 1.61681004 -1.99443996 1.67163002 -1.99443996 0 P 0 
L 1.67163002 -1.99443996 1.67301004 -2.00076004 0 P 0 
L 1.67301004 -2.00076004 1.67613002 -2.01341998 0 P 0 
L 1.67613002 -2.01341998 1.68331004 -2.03931998 0 P 0 
L 1.68331004 -2.03931998 1.69153002 -2.06856998 0 P 0 
L 1.69153002 -2.06856998 1.6916 -2.06876004 0 P 0 
L 1.6916 -2.06876004 1.69168996 -2.06896998 0 P 0 
L 1.69168996 -2.06896998 1.69181004 -2.06918002 0 P 0 
L 1.69181004 -2.06918002 1.69193002 -2.06936998 0 P 0 
L 1.69193002 -2.06936998 1.69208002 -2.06956004 0 P 0 
L 1.69208002 -2.06956004 1.69223996 -2.06973002 0 P 0 
L 1.69223996 -2.06973002 1.69241998 -2.06988002 0 P 0 
L 1.69241998 -2.06988002 1.6926 -2.07001998 0 P 0 
L 1.6926 -2.07001998 1.6928 -2.07015 0 P 0 
L 1.6928 -2.07015 1.69301004 -2.07025 0 P 0 
L 1.69301004 -2.07025 1.69323002 -2.07033996 0 P 0 
L 1.69323002 -2.07033996 1.69346004 -2.07041004 0 P 0 
L 1.69346004 -2.07041004 1.69368002 -2.07045 0 P 0 
L 1.69368002 -2.07045 1.69391998 -2.07048002 0 P 0 
L 1.69391998 -2.07048002 1.69413996 -2.07048996 0 P 0 
L 1.69413996 -2.07048996 1.6944 -2.07048002 0 P 0 
L 1.6944 -2.07048002 1.69465 -2.07045 0 P 0 
L 1.69465 -2.07045 1.69488996 -2.07038996 0 P 0 
L 1.69488996 -2.07038996 1.69513996 -2.07031998 0 P 0 
L 1.69513996 -2.07031998 1.69536998 -2.07021998 0 P 0 
L 1.69536998 -2.07021998 1.69558996 -2.0701 0 P 0 
L 1.69558996 -2.0701 1.69581004 -2.06996998 0 P 0 
L 1.69581004 -2.06996998 1.69601004 -2.06981998 0 P 0 
L 1.69601004 -2.06981998 1.6962 -2.06965 0 P 0 
L 1.6962 -2.06965 1.69636998 -2.06946004 0 P 0 
L 1.69636998 -2.06946004 1.69653002 -2.06926004 0 P 0 
L 1.69653002 -2.06926004 1.69666004 -2.06905 0 P 0 
L 1.69666004 -2.06905 1.69678996 -2.06883002 0 P 0 
L 1.69678996 -2.06883002 1.69688002 -2.0686 0 P 0 
L 1.69688002 -2.0686 1.69695 -2.0684 0 P 0 
L 1.69695 -2.0684 1.70426004 -2.04365 0 P 0 
L 1.70426004 -2.04365 1.70426004 -2.04363002 0 P 0 
L 1.70426004 -2.04363002 1.71066998 -2.0213 0 P 0 
L 1.71066998 -2.0213 1.71068002 -2.02126004 0 P 0 
L 1.71068002 -2.02126004 1.71431998 -2.00693996 0 P 0 
L 1.71431998 -2.00693996 1.71706004 -1.99496998 0 P 0 
L 1.71706004 -1.99496998 1.74335 -1.9947 0 P 0 
L 1.74335 -1.9947 1.75403002 -1.99461004 0 P 0 
L 1.75403002 -1.99461004 1.76301004 -1.99465 0 P 0 
L 1.76301004 -1.99465 1.76886004 -1.99471004 0 P 0 
L 1.76886004 -1.99471004 1.76883996 -1.99476004 0 P 0 
L 1.76883996 -1.99476004 1.74021004 -2.06556004 0 P 0 
L 1.74021004 -2.06556004 1.71298002 -2.13276998 0 P 0 
L 1.71298002 -2.13276998 1.70836998 -2.14293996 0 P 0 
L 1.70836998 -2.14293996 1.70413996 -2.15076004 0 P 0 
L 1.70413996 -2.15076004 1.69941998 -2.15828996 0 P 0 
L 1.69941998 -2.15828996 1.6967 -2.16198996 0 P 0 
L 1.6967 -2.16198996 1.6937 -2.16541998 0 P 0 
L 1.6937 -2.16541998 1.69041998 -2.1686 0 P 0 
L 1.69041998 -2.1686 1.68793996 -2.17063002 0 P 0 
L 1.68793996 -2.17063002 1.68535 -2.17248002 0 P 0 
L 1.68535 -2.17248002 1.68263996 -2.17413996 0 P 0 
L 1.68263996 -2.17413996 1.67981004 -2.17561004 0 P 0 
L 1.67981004 -2.17561004 1.67525 -2.17761004 0 P 0 
L 1.67525 -2.17761004 1.6706 -2.17931998 0 P 0 
L 1.6706 -2.17931998 1.66586004 -2.18073002 0 P 0 
L 1.66586004 -2.18073002 1.66141998 -2.1817 0 P 0 
L 1.66141998 -2.1817 1.65691998 -2.18228996 0 P 0 
L 1.65691998 -2.18228996 1.64433002 -2.18295 0 P 0 
L 1.61928996 -2.00628002 1.62683996 -2.02673002 0 P 0 
L 1.62683996 -2.02673002 1.6425 -2.07178002 0 P 0 
L 1.6425 -2.07178002 1.65981004 -2.12201998 0 P 0 
L 1.65981004 -2.12201998 1.66006004 -2.12283996 0 P 0 
L 1.66006004 -2.12283996 1.66023002 -2.12368002 0 P 0 
L 1.66023002 -2.12368002 1.66033996 -2.12451998 0 P 0 
L 1.66033996 -2.12451998 1.66036998 -2.12538002 0 P 0 
L 1.66036998 -2.12538002 1.66033996 -2.12601004 0 P 0 
L 1.66033996 -2.12601004 1.66026998 -2.12663996 0 P 0 
L 1.66026998 -2.12663996 1.66013996 -2.12725 0 P 0 
L 1.66013996 -2.12725 1.65995 -2.12786004 0 P 0 
L 1.65995 -2.12786004 1.65971004 -2.12843996 0 P 0 
L 1.65971004 -2.12843996 1.65856998 -2.1308 0 P 0 
L 1.65856998 -2.1308 1.6573 -2.13313002 0 P 0 
L 1.6573 -2.13313002 1.65586998 -2.13545 0 P 0 
L 1.65586998 -2.13545 1.65431004 -2.13771998 0 P 0 
L 1.65431004 -2.13771998 1.65343996 -2.1388 0 P 0 
L 1.65343996 -2.1388 1.65248996 -2.13981998 0 P 0 
L 1.65248996 -2.13981998 1.65146004 -2.14076004 0 P 0 
L 1.65146004 -2.14076004 1.64971004 -2.14213002 0 P 0 
L 1.64971004 -2.14213002 1.64785 -2.14336004 0 P 0 
L 1.64785 -2.14336004 1.64588996 -2.14443996 0 P 0 
L 1.64588996 -2.14443996 1.64446998 -2.14508002 0 P 0 
L 1.64446998 -2.14508002 1.64301004 -2.14561998 0 P 0 
L 1.64301004 -2.14561998 1.64151004 -2.14605 0 P 0 
L 1.64151004 -2.14605 1.63996998 -2.14636998 0 P 0 
L 1.63996998 -2.14636998 1.63741004 -2.14673996 0 P 0 
L 1.63741004 -2.14673996 1.63483002 -2.14693002 0 P 0 
L 1.63483002 -2.14693002 1.63223002 -2.14693996 0 P 0 
L 1.63223002 -2.14693996 1.62036004 -2.14621998 0 P 0 
L 1.62036004 -2.14621998 1.6113 -2.14538002 0 P 0 
L 1.6113 -2.14538002 1.61208996 -2.16023002 0 P 0 
L 1.61208996 -2.16023002 1.61298002 -2.17515 0 P 0 
L 1.61298002 -2.17515 1.6131 -2.17628002 0 P 0 
L 1.6131 -2.17628002 1.61331998 -2.17741004 0 P 0 
L 1.61331998 -2.17741004 1.61361998 -2.17851004 0 P 0 
L 1.61361998 -2.17851004 1.614 -2.17958996 0 P 0 
L 1.614 -2.17958996 1.61413996 -2.17988996 0 P 0 
L 1.61413996 -2.17988996 1.61428996 -2.18018002 0 P 0 
L 1.61428996 -2.18018002 1.61446998 -2.18045 0 P 0 
L 1.61446998 -2.18045 1.61466998 -2.18071004 0 P 0 
L 1.61466998 -2.18071004 1.61488996 -2.18095 0 P 0 
L 1.61488996 -2.18095 1.61511998 -2.18116998 0 P 0 
L 1.61511998 -2.18116998 1.61538002 -2.18138002 0 P 0 
L 1.61538002 -2.18138002 1.61565 -2.18156004 0 P 0 
L 1.61565 -2.18156004 1.61593002 -2.18173002 0 P 0 
L 1.61593002 -2.18173002 1.61623002 -2.18186004 0 P 0 
L 1.61623002 -2.18186004 1.61788002 -2.1825 0 P 0 
L 1.61788002 -2.1825 1.61956998 -2.18301998 0 P 0 
L 1.61956998 -2.18301998 1.6213 -2.18343002 0 P 0 
L 1.6213 -2.18343002 1.62633002 -2.18426004 0 P 0 
L 1.62633002 -2.18426004 1.6314 -2.18471004 0 P 0 
L 1.6314 -2.18471004 1.64436004 -2.18495 0 P 0 
L 1.64436004 -2.18495 1.65711004 -2.18428002 0 P 0 
L 1.65711004 -2.18428002 1.66176998 -2.18366998 0 P 0 
L 1.66176998 -2.18366998 1.66636004 -2.18266998 0 P 0 
L 1.66636004 -2.18266998 1.67123002 -2.18121004 0 P 0 
L 1.67123002 -2.18121004 1.676 -2.17946998 0 P 0 
L 1.676 -2.17946998 1.68068002 -2.17741998 0 P 0 
L 1.68068002 -2.17741998 1.68361998 -2.17588002 0 P 0 
L 1.68361998 -2.17588002 1.68646004 -2.17415 0 P 0 
L 1.68646004 -2.17415 1.68916004 -2.17221998 0 P 0 
L 1.68916004 -2.17221998 1.69175 -2.17008996 0 P 0 
L 1.69175 -2.17008996 1.69515 -2.1668 0 P 0 
L 1.69515 -2.1668 1.69826004 -2.16323996 0 P 0 
L 1.69826004 -2.16323996 1.70108002 -2.15941998 0 P 0 
L 1.70108002 -2.15941998 1.70586004 -2.15176998 0 P 0 
L 1.70586004 -2.15176998 1.71016004 -2.14383002 0 P 0 
L 1.71016004 -2.14383002 1.71481998 -2.13356004 0 P 0 
L 1.71481998 -2.13356004 1.74206998 -2.06631004 0 P 0 
L 1.74206998 -2.06631004 1.77071004 -1.99548002 0 P 0 
L 1.77071004 -1.99548002 1.77088002 -1.99498996 0 P 0 
L 1.77088002 -1.99498996 1.77101998 -1.99448996 0 P 0 
L 1.77101998 -1.99448996 1.77111998 -1.99398996 0 P 0 
L 1.77111998 -1.99398996 1.77118002 -1.99346998 0 P 0 
L 1.77118002 -1.99346998 1.7712 -1.99295 0 P 0 
L 1.7712 -1.99295 1.7712 -1.99293002 0 P 0 
L 1.7712 -1.99293002 1.77118996 -1.99286998 0 P 0 
L 1.77118996 -1.99286998 1.77118002 -1.99286004 0 P 0 
L 1.77118002 -1.99286004 1.77118002 -1.99283996 0 P 0 
L 1.77118002 -1.99283996 1.77111004 -1.99276998 0 P 0 
L 1.77111004 -1.99276998 1.77106998 -1.99275 0 P 0 
L 1.77106998 -1.99275 1.77106004 -1.99273996 0 P 0 
L 1.77106004 -1.99273996 1.771 -1.99273002 0 P 0 
L 1.771 -1.99273002 1.77098002 -1.99273002 0 P 0 
L 1.77098002 -1.99273002 1.76301004 -1.99265 0 P 0 
L 1.76301004 -1.99265 1.75401998 -1.99261004 0 P 0 
L 1.75401998 -1.99261004 1.74333002 -1.9927 0 P 0 
L 1.74333002 -1.9927 1.71546004 -1.99298996 0 P 0 
L 1.71546004 -1.99298996 1.71236998 -2.00646998 0 P 0 
L 1.71236998 -2.00646998 1.70873996 -2.02078002 0 P 0 
L 1.70873996 -2.02078002 1.70233996 -2.04308002 0 P 0 
L 1.70233996 -2.04308002 1.69505 -2.0678 0 P 0 
L 1.69505 -2.0678 1.69501998 -2.06788002 0 P 0 
L 1.69501998 -2.06788002 1.69498996 -2.06795 0 P 0 
L 1.69498996 -2.06795 1.69495 -2.06801998 0 P 0 
L 1.69495 -2.06801998 1.69485 -2.06816004 0 P 0 
L 1.69485 -2.06816004 1.69478996 -2.06821998 0 P 0 
L 1.69478996 -2.06821998 1.69466998 -2.06831998 0 P 0 
L 1.69466998 -2.06831998 1.69453002 -2.0684 0 P 0 
L 1.69453002 -2.0684 1.69445 -2.06843002 0 P 0 
L 1.69445 -2.06843002 1.69438002 -2.06846004 0 P 0 
L 1.69438002 -2.06846004 1.69428996 -2.06846998 0 P 0 
L 1.69428996 -2.06846998 1.69421004 -2.06848996 0 P 0 
L 1.69421004 -2.06848996 1.69406998 -2.06848996 0 P 0 
L 1.69406998 -2.06848996 1.69395 -2.06846998 0 P 0 
L 1.69395 -2.06846998 1.69383002 -2.06843002 0 P 0 
L 1.69383002 -2.06843002 1.69373002 -2.06836998 0 P 0 
L 1.69373002 -2.06836998 1.69363002 -2.06828996 0 P 0 
L 1.69363002 -2.06828996 1.69358996 -2.06823996 0 P 0 
L 1.69358996 -2.06823996 1.69355 -2.0682 0 P 0 
L 1.69355 -2.0682 1.69351998 -2.06815 0 P 0 
L 1.69351998 -2.06815 1.69346004 -2.06803996 0 P 0 
L 1.69346004 -2.06803996 1.69343996 -2.06798002 0 P 0 
L 1.69343996 -2.06798002 1.68523002 -2.03878002 0 P 0 
L 1.68523002 -2.03878002 1.67806998 -2.01291998 0 P 0 
L 1.67806998 -2.01291998 1.67496004 -2.00031004 0 P 0 
L 1.67496004 -2.00031004 1.67323002 -1.99243996 0 P 0 
L 1.67323002 -1.99243996 1.61388002 -1.99243996 0 P 0 
L 1.61388002 -1.99243996 1.61928996 -2.00628002 0 P 0 
L 1.35018002 -2.08345 1.39488996 -2.08345 0 P 0 
L 1.35026004 -2.08245 1.39586004 -2.08245 0 P 0 
L 1.35041004 -2.08145 1.39708996 -2.08145 0 P 0 
L 1.35058996 -2.08045 1.39853002 -2.08045 0 P 0 
L 1.35083996 -2.07945 1.40031998 -2.07945 0 P 0 
L 1.35116998 -2.07845 1.40271004 -2.07845 0 P 0 
L 1.35158002 -2.07745 1.40561998 -2.07745 0 P 0 
L 1.35203002 -2.07645 1.4092 -2.07645 0 P 0 
L 1.35248002 -2.07545 1.41288996 -2.07545 0 P 0 
L 1.35293002 -2.07445 1.4164 -2.07445 0 P 0 
L 1.35338996 -2.07345 1.41975 -2.07345 0 P 0 
L 1.35393996 -2.07245 1.42293996 -2.07245 0 P 0 
L 1.35448996 -2.07145 1.42606998 -2.07145 0 P 0 
L 1.35505 -2.07045 1.47843002 -2.07045 0 P 0 
L 1.3557 -2.06945 1.47846998 -2.06945 0 P 0 
L 1.35635 -2.06845 1.47851998 -2.06845 0 P 0 
L 1.35701998 -2.06745 1.47856998 -2.06745 0 P 0 
L 1.35776998 -2.06645 1.47861004 -2.06645 0 P 0 
L 1.29346998 -2.00516004 1.33388996 -2.00516004 0 P 0 
L 1.29448996 -2.00416004 1.33385 -2.00416004 0 P 0 
L 1.29551004 -2.00316004 1.33381004 -2.00316004 0 P 0 
L 1.29653996 -2.00216004 1.33376004 -2.00216004 0 P 0 
L 1.29756004 -2.00116004 1.33371004 -2.00116004 0 P 0 
L 1.29861998 -2.00016004 1.33366004 -2.00016004 0 P 0 
L 1.29973002 -1.99916004 1.3336 -1.99916004 0 P 0 
L 1.30101004 -1.99816004 1.33355 -1.99816004 0 P 0 
L 1.30238996 -1.99716004 1.3335 -1.99716004 0 P 0 
L 1.30393996 -1.99616004 1.33345 -1.99616004 0 P 0 
L 1.30571004 -1.99516004 1.33338996 -1.99516004 0 P 0 
L 1.3077 -1.99416004 1.33333002 -1.99416004 0 P 0 
L 1.31001004 -1.99316004 1.33328002 -1.99316004 0 P 0 
L 1.31288002 -1.99216004 1.33321998 -1.99216004 0 P 0 
L 1.31688996 -1.99116004 1.33316004 -1.99116004 0 P 0 
L 1.39798996 -1.98971998 1.39326998 -1.99043002 0 P 0 
L 1.39326998 -1.99043002 1.38806998 -1.9913 0 P 0 
L 1.38806998 -1.9913 1.38316004 -1.9922 0 P 0 
L 1.38316004 -1.9922 1.37946004 -1.99296998 0 P 0 
L 1.37946004 -1.99296998 1.3718 -1.99466998 0 P 0 
L 1.3718 -1.99466998 1.36896004 -2.01553996 0 P 0 
L 1.36896004 -2.01553996 1.36791004 -2.02358996 0 P 0 
L 1.36791004 -2.02358996 1.36708002 -2.03043002 0 P 0 
L 1.36708002 -2.03043002 1.36638996 -2.03646004 0 P 0 
L 1.36638996 -2.03646004 1.36638002 -2.03648996 0 P 0 
L 1.36638002 -2.03648996 1.36638996 -2.03653002 0 P 0 
L 1.36638996 -2.03653002 1.36638996 -2.03656998 0 P 0 
L 1.36638996 -2.03656998 1.3664 -2.03663996 0 P 0 
L 1.3664 -2.03663996 1.36641998 -2.03666998 0 P 0 
L 1.36641998 -2.03666998 1.36643002 -2.03671004 0 P 0 
L 1.36643002 -2.03671004 1.36648996 -2.0368 0 P 0 
L 1.36648996 -2.0368 1.36656004 -2.03686004 0 P 0 
L 1.36656004 -2.03686004 1.3666 -2.03688996 0 P 0 
L 1.3666 -2.03688996 1.36663002 -2.03691004 0 P 0 
L 1.36663002 -2.03691004 1.36666004 -2.03691004 0 P 0 
L 1.36666004 -2.03691004 1.36671004 -2.03693002 0 P 0 
L 1.36671004 -2.03693002 1.36676998 -2.03693002 0 P 0 
L 1.36676998 -2.03693002 1.36685 -2.03691998 0 P 0 
L 1.36685 -2.03691998 1.36895 -2.03628002 0 P 0 
L 1.36895 -2.03628002 1.37143002 -2.03545 0 P 0 
L 1.37143002 -2.03545 1.37428996 -2.03441004 0 P 0 
L 1.37428996 -2.03441004 1.38346004 -2.03126998 0 P 0 
L 1.38346004 -2.03126998 1.39251998 -2.02891998 0 P 0 
L 1.39251998 -2.02891998 1.40156004 -2.02731998 0 P 0 
L 1.40156004 -2.02731998 1.41068002 -2.02643996 0 P 0 
L 1.41068002 -2.02643996 1.41566998 -2.02628002 0 P 0 
L 1.41566998 -2.02628002 1.42066004 -2.02633996 0 P 0 
L 1.42066004 -2.02633996 1.42221004 -2.02646998 0 P 0 
L 1.42221004 -2.02646998 1.42375 -2.02671998 0 P 0 
L 1.42375 -2.02671998 1.42525 -2.0271 0 P 0 
L 1.42525 -2.0271 1.42671998 -2.02761004 0 P 0 
L 1.42671998 -2.02761004 1.42706004 -2.02776004 0 P 0 
L 1.42706004 -2.02776004 1.42738002 -2.02793002 0 P 0 
L 1.42738002 -2.02793002 1.42768002 -2.02813996 0 P 0 
L 1.42768002 -2.02813996 1.42796998 -2.02836004 0 P 0 
L 1.42796998 -2.02836004 1.42823002 -2.02861004 0 P 0 
L 1.42823002 -2.02861004 1.42848002 -2.02888996 0 P 0 
L 1.42848002 -2.02888996 1.4287 -2.02918002 0 P 0 
L 1.4287 -2.02918002 1.42888996 -2.02948996 0 P 0 
L 1.42888996 -2.02948996 1.42906004 -2.02981004 0 P 0 
L 1.42906004 -2.02981004 1.4292 -2.03015 0 P 0 
L 1.4292 -2.03015 1.42931998 -2.0305 0 P 0 
L 1.42931998 -2.0305 1.4294 -2.03086004 0 P 0 
L 1.4294 -2.03086004 1.42945 -2.03121998 0 P 0 
L 1.42945 -2.03121998 1.42946998 -2.03158002 0 P 0 
L 1.42946998 -2.03158002 1.42946004 -2.03195 0 P 0 
L 1.42946004 -2.03195 1.42941998 -2.03231004 0 P 0 
L 1.42941998 -2.03231004 1.42935 -2.03266998 0 P 0 
L 1.42935 -2.03266998 1.42925 -2.03301998 0 P 0 
L 1.42925 -2.03301998 1.42911998 -2.03336004 0 P 0 
L 1.42911998 -2.03336004 1.42896004 -2.03368996 0 P 0 
L 1.42896004 -2.03368996 1.42875 -2.03405 0 P 0 
L 1.42875 -2.03405 1.42851004 -2.03438996 0 P 0 
L 1.42851004 -2.03438996 1.42825 -2.03471004 0 P 0 
L 1.42825 -2.03471004 1.42796004 -2.03501004 0 P 0 
L 1.42796004 -2.03501004 1.42765 -2.03528996 0 P 0 
L 1.42765 -2.03528996 1.42731998 -2.03553996 0 P 0 
L 1.42731998 -2.03553996 1.42696998 -2.03576004 0 P 0 
L 1.42696998 -2.03576004 1.4266 -2.03596004 0 P 0 
L 1.4266 -2.03596004 1.41951004 -2.03906004 0 P 0 
L 1.41951004 -2.03906004 1.4109 -2.04208996 0 P 0 
L 1.4109 -2.04208996 1.40178002 -2.04451998 0 P 0 
L 1.40178002 -2.04451998 1.3878 -2.04818996 0 P 0 
L 1.3878 -2.04818996 1.38176998 -2.05015 0 P 0 
L 1.38176998 -2.05015 1.3758 -2.05243002 0 P 0 
L 1.3758 -2.05243002 1.37086998 -2.0546 0 P 0 
L 1.37086998 -2.0546 1.36603996 -2.05708002 0 P 0 
L 1.36603996 -2.05708002 1.36356004 -2.05856004 0 P 0 
L 1.36356004 -2.05856004 1.36118996 -2.06023002 0 P 0 
L 1.36118996 -2.06023002 1.35895 -2.06206004 0 P 0 
L 1.35895 -2.06206004 1.35805 -2.06291004 0 P 0 
L 1.35805 -2.06291004 1.35721998 -2.06385 0 P 0 
L 1.35721998 -2.06385 1.35518996 -2.06655 0 P 0 
L 1.35518996 -2.06655 1.3532 -2.06961998 0 P 0 
L 1.3532 -2.06961998 1.35156004 -2.07263002 0 P 0 
L 1.35156004 -2.07263002 1.34951004 -2.07718002 0 P 0 
L 1.34951004 -2.07718002 1.34911004 -2.07825 0 P 0 
L 1.34911004 -2.07825 1.34878996 -2.07935 0 P 0 
L 1.34878996 -2.07935 1.34853002 -2.08046998 0 P 0 
L 1.34853002 -2.08046998 1.34825 -2.08238002 0 P 0 
L 1.34825 -2.08238002 1.34811998 -2.08431004 0 P 0 
L 1.34811998 -2.08431004 1.348 -2.09128996 0 P 0 
L 1.348 -2.09128996 1.3481 -2.09761004 0 P 0 
L 1.3481 -2.09761004 1.34823002 -2.09961004 0 P 0 
L 1.34823002 -2.09961004 1.34846998 -2.10161004 0 P 0 
L 1.34846998 -2.10161004 1.34876998 -2.10321998 0 P 0 
L 1.34876998 -2.10321998 1.3492 -2.10478996 0 P 0 
L 1.3492 -2.10478996 1.3498 -2.10648996 0 P 0 
L 1.3498 -2.10648996 1.3505 -2.10815 0 P 0 
L 1.3505 -2.10815 1.35178996 -2.11066004 0 P 0 
L 1.35178996 -2.11066004 1.35328002 -2.11305 0 P 0 
L 1.35328002 -2.11305 1.35496998 -2.1153 0 P 0 
L 1.35496998 -2.1153 1.35685 -2.1174 0 P 0 
L 1.35685 -2.1174 1.35891998 -2.11933996 0 P 0 
L 1.35891998 -2.11933996 1.36126998 -2.12121998 0 P 0 
L 1.36126998 -2.12121998 1.36373996 -2.12293002 0 P 0 
L 1.36373996 -2.12293002 1.36633002 -2.12446004 0 P 0 
L 1.36633002 -2.12446004 1.36901004 -2.1258 0 P 0 
L 1.36901004 -2.1258 1.3718 -2.12695 0 P 0 
L 1.3718 -2.12695 1.37578996 -2.12828002 0 P 0 
L 1.37578996 -2.12828002 1.37986998 -2.12928996 0 P 0 
L 1.37986998 -2.12928996 1.38401998 -2.12998996 0 P 0 
L 1.38401998 -2.12998996 1.3882 -2.13036004 0 P 0 
L 1.3882 -2.13036004 1.39443002 -2.13045 0 P 0 
L 1.39443002 -2.13045 1.40066004 -2.13006998 0 P 0 
L 1.40066004 -2.13006998 1.40685 -2.12923002 0 P 0 
L 1.40685 -2.12923002 1.41371004 -2.12801998 0 P 0 
L 1.41371004 -2.12801998 1.41583002 -2.12081004 0 P 0 
L 1.41583002 -2.12081004 1.41953996 -2.10798996 0 P 0 
L 1.41953996 -2.10798996 1.42135 -2.10126998 0 P 0 
L 1.42135 -2.10126998 1.42236998 -2.097 0 P 0 
L 1.42236998 -2.097 1.42238996 -2.09691004 0 P 0 
L 1.42238996 -2.09691004 1.4224 -2.09681998 0 P 0 
L 1.4224 -2.09681998 1.4224 -2.09673996 0 P 0 
L 1.4224 -2.09673996 1.42238002 -2.09656004 0 P 0 
L 1.42238002 -2.09656004 1.42235 -2.09648002 0 P 0 
L 1.42235 -2.09648002 1.42233002 -2.09638996 0 P 0 
L 1.42233002 -2.09638996 1.42225 -2.09623002 0 P 0 
L 1.42225 -2.09623002 1.4222 -2.09616004 0 P 0 
L 1.4222 -2.09616004 1.42213996 -2.09608996 0 P 0 
L 1.42213996 -2.09608996 1.42208996 -2.09601998 0 P 0 
L 1.42208996 -2.09601998 1.42203996 -2.09598996 0 P 0 
L 1.42203996 -2.09598996 1.42198996 -2.09595 0 P 0 
L 1.42198996 -2.09595 1.42188996 -2.09588996 0 P 0 
L 1.42188996 -2.09588996 1.42183002 -2.09586004 0 P 0 
L 1.42183002 -2.09586004 1.42178002 -2.09585 0 P 0 
L 1.42178002 -2.09585 1.42171998 -2.09583002 0 P 0 
L 1.42171998 -2.09583002 1.42166004 -2.09581998 0 P 0 
L 1.42166004 -2.09581998 1.42153996 -2.09581998 0 P 0 
L 1.42153996 -2.09581998 1.41978002 -2.09591004 0 P 0 
L 1.41978002 -2.09591004 1.41763996 -2.09615 0 P 0 
L 1.41763996 -2.09615 1.41521998 -2.09658002 0 P 0 
L 1.41521998 -2.09658002 1.4107 -2.09733002 0 P 0 
L 1.4107 -2.09733002 1.40613002 -2.09775 0 P 0 
L 1.40613002 -2.09775 1.40481004 -2.09778002 0 P 0 
L 1.40481004 -2.09778002 1.40348996 -2.09771998 0 P 0 
L 1.40348996 -2.09771998 1.40216998 -2.09756004 0 P 0 
L 1.40216998 -2.09756004 1.40086998 -2.0973 0 P 0 
L 1.40086998 -2.0973 1.39958996 -2.09695 0 P 0 
L 1.39958996 -2.09695 1.39895 -2.09671998 0 P 0 
L 1.39895 -2.09671998 1.39831998 -2.09643002 0 P 0 
L 1.39831998 -2.09643002 1.39773002 -2.0961 0 P 0 
L 1.39773002 -2.0961 1.39716004 -2.09571004 0 P 0 
L 1.39716004 -2.09571004 1.39663002 -2.09528002 0 P 0 
L 1.39663002 -2.09528002 1.39613996 -2.0948 0 P 0 
L 1.39613996 -2.0948 1.39568002 -2.09428002 0 P 0 
L 1.39568002 -2.09428002 1.39533996 -2.09381998 0 P 0 
L 1.39533996 -2.09381998 1.39505 -2.09333996 0 P 0 
L 1.39505 -2.09333996 1.39478996 -2.09281998 0 P 0 
L 1.39478996 -2.09281998 1.39456998 -2.09228996 0 P 0 
L 1.39456998 -2.09228996 1.3944 -2.09173996 0 P 0 
L 1.3944 -2.09173996 1.39428002 -2.09118996 0 P 0 
L 1.39428002 -2.09118996 1.39421004 -2.09061998 0 P 0 
L 1.39421004 -2.09061998 1.39418002 -2.09003996 0 P 0 
L 1.39418002 -2.09003996 1.39421004 -2.08943002 0 P 0 
L 1.39421004 -2.08943002 1.39428002 -2.08883002 0 P 0 
L 1.39428002 -2.08883002 1.39441004 -2.08823002 0 P 0 
L 1.39441004 -2.08823002 1.3946 -2.08765 0 P 0 
L 1.3946 -2.08765 1.39483002 -2.08708002 0 P 0 
L 1.39483002 -2.08708002 1.39511004 -2.08653996 0 P 0 
L 1.39511004 -2.08653996 1.39555 -2.08583996 0 P 0 
L 1.39555 -2.08583996 1.39603996 -2.08518002 0 P 0 
L 1.39603996 -2.08518002 1.39658002 -2.08456004 0 P 0 
L 1.39658002 -2.08456004 1.39716004 -2.08396998 0 P 0 
L 1.39716004 -2.08396998 1.39778002 -2.08343002 0 P 0 
L 1.39778002 -2.08343002 1.39878996 -2.08266998 0 P 0 
L 1.39878996 -2.08266998 1.39985 -2.08196998 0 P 0 
L 1.39985 -2.08196998 1.40096004 -2.08135 0 P 0 
L 1.40096004 -2.08135 1.40211998 -2.08081004 0 P 0 
L 1.40211998 -2.08081004 1.40503002 -2.07971004 0 P 0 
L 1.40503002 -2.07971004 1.40801998 -2.07881998 0 P 0 
L 1.40801998 -2.07881998 1.41128996 -2.07796004 0 P 0 
L 1.41128996 -2.07796004 1.41506004 -2.07691998 0 P 0 
L 1.41506004 -2.07691998 1.41871998 -2.07585 0 P 0 
L 1.41871998 -2.07585 1.42165 -2.07495 0 P 0 
L 1.42165 -2.07495 1.42791998 -2.07295 0 P 0 
L 1.42791998 -2.07295 1.42731998 -2.08241004 0 P 0 
L 1.42731998 -2.08241004 1.42701004 -2.08708002 0 P 0 
L 1.42701004 -2.08708002 1.42658002 -2.09353996 0 P 0 
L 1.42658002 -2.09353996 1.4261 -2.10055 0 P 0 
L 1.4261 -2.10055 1.42566998 -2.10706004 0 P 0 
L 1.42566998 -2.10706004 1.42525 -2.11306004 0 P 0 
L 1.42525 -2.11306004 1.42491998 -2.11851998 0 P 0 
L 1.42491998 -2.11851998 1.42466004 -2.1231 0 P 0 
L 1.42466004 -2.1231 1.42461004 -2.12471004 0 P 0 
L 1.42461004 -2.12471004 1.4246 -2.12716004 0 P 0 
L 1.4246 -2.12716004 1.47893002 -2.12716004 0 P 0 
L 1.47893002 -2.12716004 1.47893002 -2.11358002 0 P 0 
L 1.47893002 -2.11358002 1.47905 -2.10616998 0 P 0 
L 1.47905 -2.10616998 1.47943996 -2.09385 0 P 0 
L 1.47943996 -2.09385 1.48 -2.07968996 0 P 0 
L 1.48 -2.07968996 1.48066004 -2.0655 0 P 0 
L 1.48066004 -2.0655 1.4813 -2.05168996 0 P 0 
L 1.4813 -2.05168996 1.48175 -2.03873996 0 P 0 
L 1.48175 -2.03873996 1.48201998 -2.02785 0 P 0 
L 1.48201998 -2.02785 1.48191998 -2.02286004 0 P 0 
L 1.48191998 -2.02286004 1.48165 -2.01995 0 P 0 
L 1.48165 -2.01995 1.48115 -2.01708002 0 P 0 
L 1.48115 -2.01708002 1.48043996 -2.01425 0 P 0 
L 1.48043996 -2.01425 1.47951004 -2.01146998 0 P 0 
L 1.47951004 -2.01146998 1.47866998 -2.00946998 0 P 0 
L 1.47866998 -2.00946998 1.47768002 -2.00753996 0 P 0 
L 1.47768002 -2.00753996 1.47655 -2.00568002 0 P 0 
L 1.47655 -2.00568002 1.47528002 -2.00391998 0 P 0 
L 1.47528002 -2.00391998 1.47388002 -2.00225 0 P 0 
L 1.47388002 -2.00225 1.47228996 -2.00063002 0 P 0 
L 1.47228996 -2.00063002 1.4706 -1.99911998 0 P 0 
L 1.4706 -1.99911998 1.4688 -1.99773002 0 P 0 
L 1.4688 -1.99773002 1.46691004 -1.99648002 0 P 0 
L 1.46691004 -1.99648002 1.46491998 -1.99535 0 P 0 
L 1.46491998 -1.99535 1.46098996 -1.99351004 0 P 0 
L 1.46098996 -1.99351004 1.45693002 -1.99196998 0 P 0 
L 1.45693002 -1.99196998 1.45276004 -1.99076004 0 P 0 
L 1.45276004 -1.99076004 1.44953996 -1.99006004 0 P 0 
L 1.44953996 -1.99006004 1.44628996 -1.98956004 0 P 0 
L 1.44628996 -1.98956004 1.44298002 -1.98923996 0 P 0 
L 1.44298002 -1.98923996 1.42695 -1.98856998 0 P 0 
L 1.42695 -1.98856998 1.41038996 -1.98865 0 P 0 
L 1.41038996 -1.98865 1.4042 -1.98901004 0 P 0 
L 1.4042 -1.98901004 1.39798996 -1.98971998 0 P 0 
L 1.35778996 -2.11545 1.4153 -2.11545 0 P 0 
L 1.35688996 -2.11445 1.41558996 -2.11445 0 P 0 
L 1.35608002 -2.11345 1.41588002 -2.11345 0 P 0 
L 1.35533002 -2.11245 1.41616998 -2.11245 0 P 0 
L 1.35463996 -2.11145 1.41646004 -2.11145 0 P 0 
L 1.35401004 -2.11045 1.41675 -2.11045 0 P 0 
L 1.35341004 -2.10945 1.41703996 -2.10945 0 P 0 
L 1.3529 -2.10845 1.41733002 -2.10845 0 P 0 
L 1.35238002 -2.10745 1.41761998 -2.10745 0 P 0 
L 1.35195 -2.10645 1.41788002 -2.10645 0 P 0 
L 1.35155 -2.10545 1.41816004 -2.10545 0 P 0 
L 1.3512 -2.10445 1.41841998 -2.10445 0 P 0 
L 1.35091004 -2.10345 1.41868996 -2.10345 0 P 0 
L 1.35066004 -2.10245 1.41896004 -2.10245 0 P 0 
L 1.35046998 -2.10145 1.41923002 -2.10145 0 P 0 
L 1.35033996 -2.10045 1.41948996 -2.10045 0 P 0 
L 1.35021998 -2.09945 1.40141004 -2.09945 0 P 0 
L 1.35016004 -2.09845 1.39791004 -2.09845 0 P 0 
L 1.3501 -2.09745 1.39616004 -2.09745 0 P 0 
L 1.35008002 -2.09645 1.39496004 -2.09645 0 P 0 
L 1.35006998 -2.09545 1.39406004 -2.09545 0 P 0 
L 1.35005 -2.09445 1.39338002 -2.09445 0 P 0 
L 1.35003996 -2.09345 1.39288002 -2.09345 0 P 0 
L 1.35001998 -2.09245 1.39253002 -2.09245 0 P 0 
L 1.35001004 -2.09145 1.3923 -2.09145 0 P 0 
L 1.35001998 -2.09045 1.3922 -2.09045 0 P 0 
L 1.35003002 -2.08945 1.3922 -2.08945 0 P 0 
L 1.35005 -2.08845 1.39231998 -2.08845 0 P 0 
L 1.35006998 -2.08745 1.39256004 -2.08745 0 P 0 
L 1.35008002 -2.08645 1.39293002 -2.08645 0 P 0 
L 1.3501 -2.08545 1.39343002 -2.08545 0 P 0 
L 1.35011004 -2.08445 1.39408996 -2.08445 0 P 0 
L 1.39438002 -2.12845 1.3883 -2.12836004 0 P 0 
L 1.3883 -2.12836004 1.38426998 -2.128 0 P 0 
L 1.38426998 -2.128 1.38028002 -2.12733002 0 P 0 
L 1.38028002 -2.12733002 1.37635 -2.12636004 0 P 0 
L 1.37635 -2.12636004 1.37248996 -2.12508002 0 P 0 
L 1.37248996 -2.12508002 1.36983996 -2.12398002 0 P 0 
L 1.36983996 -2.12398002 1.36728996 -2.1227 0 P 0 
L 1.36728996 -2.1227 1.36481998 -2.12123996 0 P 0 
L 1.36481998 -2.12123996 1.36246004 -2.11961004 0 P 0 
L 1.36246004 -2.11961004 1.36023002 -2.11781998 0 P 0 
L 1.36023002 -2.11781998 1.35828996 -2.116 0 P 0 
L 1.35828996 -2.116 1.35651998 -2.11403002 0 P 0 
L 1.35651998 -2.11403002 1.35493002 -2.11191004 0 P 0 
L 1.35493002 -2.11191004 1.35353002 -2.10966998 0 P 0 
L 1.35353002 -2.10966998 1.35231004 -2.10731004 0 P 0 
L 1.35231004 -2.10731004 1.35166998 -2.10576998 0 P 0 
L 1.35166998 -2.10576998 1.35111004 -2.1042 0 P 0 
L 1.35111004 -2.1042 1.35071998 -2.10276004 0 P 0 
L 1.35071998 -2.10276004 1.35045 -2.1013 0 P 0 
L 1.35045 -2.1013 1.35021998 -2.09943002 0 P 0 
L 1.35021998 -2.09943002 1.3501 -2.09753002 0 P 0 
L 1.3501 -2.09753002 1.35001004 -2.09128002 0 P 0 
L 1.35001004 -2.09128002 1.35011998 -2.0844 0 P 0 
L 1.35011998 -2.0844 1.35023996 -2.08258996 0 P 0 
L 1.35023996 -2.08258996 1.3505 -2.08083996 0 P 0 
L 1.3505 -2.08083996 1.35071998 -2.07985 0 P 0 
L 1.35071998 -2.07985 1.35101004 -2.07888002 0 P 0 
L 1.35101004 -2.07888002 1.35136004 -2.07793002 0 P 0 
L 1.35136004 -2.07793002 1.35335 -2.07351998 0 P 0 
L 1.35335 -2.07351998 1.35491998 -2.07065 0 P 0 
L 1.35491998 -2.07065 1.35683002 -2.0677 0 P 0 
L 1.35683002 -2.0677 1.35876998 -2.06511004 0 P 0 
L 1.35876998 -2.06511004 1.35948996 -2.0643 0 P 0 
L 1.35948996 -2.0643 1.36026998 -2.06356004 0 P 0 
L 1.36026998 -2.06356004 1.3624 -2.06181998 0 P 0 
L 1.3624 -2.06181998 1.36465 -2.06023996 0 P 0 
L 1.36465 -2.06023996 1.36701004 -2.05883002 0 P 0 
L 1.36701004 -2.05883002 1.37173002 -2.05641004 0 P 0 
L 1.37173002 -2.05641004 1.37656004 -2.05426998 0 P 0 
L 1.37656004 -2.05426998 1.38243002 -2.05203996 0 P 0 
L 1.38243002 -2.05203996 1.38836004 -2.0501 0 P 0 
L 1.38836004 -2.0501 1.4023 -2.04645 0 P 0 
L 1.4023 -2.04645 1.41148996 -2.044 0 P 0 
L 1.41148996 -2.044 1.42016998 -2.04095 0 P 0 
L 1.42016998 -2.04095 1.42016998 -2.04093996 0 P 0 
L 1.42016998 -2.04093996 1.42021004 -2.04093996 0 P 0 
L 1.42021004 -2.04093996 1.42023996 -2.04093002 0 P 0 
L 1.42023996 -2.04093002 1.42746998 -2.03776004 0 P 0 
L 1.42746998 -2.03776004 1.42753002 -2.03773002 0 P 0 
L 1.42753002 -2.03773002 1.42796998 -2.03748996 0 P 0 
L 1.42796998 -2.03748996 1.42846004 -2.03718996 0 P 0 
L 1.42846004 -2.03718996 1.42891998 -2.03683996 0 P 0 
L 1.42891998 -2.03683996 1.42935 -2.03646004 0 P 0 
L 1.42935 -2.03646004 1.42975 -2.03603996 0 P 0 
L 1.42975 -2.03603996 1.43011004 -2.0356 0 P 0 
L 1.43011004 -2.0356 1.43016004 -2.03553002 0 P 0 
L 1.43016004 -2.03553002 1.4299 -2.03535 0 P 0 
L 1.4299 -2.03535 1.43028002 -2.03535 0 P 0 
L 1.43028002 -2.03535 1.43043996 -2.03513002 0 P 0 
L 1.43043996 -2.03513002 1.43048002 -2.03506004 0 P 0 
L 1.43048002 -2.03506004 1.43041998 -2.03501998 0 P 0 
L 1.43041998 -2.03501998 1.4305 -2.03501998 0 P 0 
L 1.4305 -2.03501998 1.43073002 -2.03463002 0 P 0 
L 1.43073002 -2.03463002 1.43096004 -2.03415 0 P 0 
L 1.43096004 -2.03415 1.43115 -2.03365 0 P 0 
L 1.43115 -2.03365 1.4313 -2.03313002 0 P 0 
L 1.4313 -2.03313002 1.4314 -2.03261004 0 P 0 
L 1.4314 -2.03261004 1.43146004 -2.03208002 0 P 0 
L 1.43146004 -2.03208002 1.43146998 -2.03155 0 P 0 
L 1.43146998 -2.03155 1.43143996 -2.03101004 0 P 0 
L 1.43143996 -2.03101004 1.43143002 -2.03093002 0 P 0 
L 1.43143002 -2.03093002 1.43136004 -2.03048996 0 P 0 
L 1.43136004 -2.03048996 1.43125 -2.02996998 0 P 0 
L 1.43125 -2.02996998 1.43108002 -2.02946004 0 P 0 
L 1.43108002 -2.02946004 1.43086998 -2.02896004 0 P 0 
L 1.43086998 -2.02896004 1.43063002 -2.02848996 0 P 0 
L 1.43063002 -2.02848996 1.43033996 -2.02803996 0 P 0 
L 1.43033996 -2.02803996 1.43001998 -2.02761004 0 P 0 
L 1.43001998 -2.02761004 1.42966004 -2.02721004 0 P 0 
L 1.42966004 -2.02721004 1.42928002 -2.02685 0 P 0 
L 1.42928002 -2.02685 1.42886004 -2.02651998 0 P 0 
L 1.42886004 -2.02651998 1.42841998 -2.02623002 0 P 0 
L 1.42841998 -2.02623002 1.42795 -2.02596998 0 P 0 
L 1.42795 -2.02596998 1.42746004 -2.02575 0 P 0 
L 1.42746004 -2.02575 1.42583002 -2.02518002 0 P 0 
L 1.42583002 -2.02518002 1.42416004 -2.02476004 0 P 0 
L 1.42416004 -2.02476004 1.42245 -2.02448002 0 P 0 
L 1.42245 -2.02448002 1.42075 -2.02435 0 P 0 
L 1.42075 -2.02435 1.41565 -2.02428002 0 P 0 
L 1.41565 -2.02428002 1.4156 -2.02428002 0 P 0 
L 1.4156 -2.02428002 1.41055 -2.02445 0 P 0 
L 1.41055 -2.02445 1.41048002 -2.02445 0 P 0 
L 1.41048002 -2.02445 1.40128996 -2.02533996 0 P 0 
L 1.40128996 -2.02533996 1.39208996 -2.02696998 0 P 0 
L 1.39208996 -2.02696998 1.38288002 -2.02936004 0 P 0 
L 1.38288002 -2.02936004 1.37363002 -2.03251998 0 P 0 
L 1.37363002 -2.03251998 1.37076998 -2.03356004 0 P 0 
L 1.37076998 -2.03356004 1.36865 -2.03426998 0 P 0 
L 1.36865 -2.03426998 1.36906004 -2.03066998 0 P 0 
L 1.36906004 -2.03066998 1.36988996 -2.02383996 0 P 0 
L 1.36988996 -2.02383996 1.37095 -2.01581004 0 P 0 
L 1.37095 -2.01581004 1.37358996 -1.99631998 0 P 0 
L 1.37358996 -1.99631998 1.37988002 -1.99491998 0 P 0 
L 1.37988002 -1.99491998 1.38353996 -1.99416998 0 P 0 
L 1.38353996 -1.99416998 1.38841998 -1.99326998 0 P 0 
L 1.38841998 -1.99326998 1.39358002 -1.9924 0 P 0 
L 1.39358002 -1.9924 1.39825 -1.9917 0 P 0 
L 1.39825 -1.9917 1.40436998 -1.991 0 P 0 
L 1.40436998 -1.991 1.41045 -1.99065 0 P 0 
L 1.41045 -1.99065 1.42691004 -1.99056998 0 P 0 
L 1.42691004 -1.99056998 1.44283996 -1.99123996 0 P 0 
L 1.44283996 -1.99123996 1.44603996 -1.99153996 0 P 0 
L 1.44603996 -1.99153996 1.44918002 -1.99203002 0 P 0 
L 1.44918002 -1.99203002 1.45226004 -1.9927 0 P 0 
L 1.45226004 -1.9927 1.4563 -1.99386998 0 P 0 
L 1.4563 -1.99386998 1.46021004 -1.99535 0 P 0 
L 1.46021004 -1.99535 1.464 -1.99713002 0 P 0 
L 1.464 -1.99713002 1.46586004 -1.99818996 0 P 0 
L 1.46586004 -1.99818996 1.46763996 -1.99936004 0 P 0 
L 1.46763996 -1.99936004 1.46931998 -2.00066004 0 P 0 
L 1.46931998 -2.00066004 1.47091004 -2.00206998 0 P 0 
L 1.47091004 -2.00206998 1.47238996 -2.00358996 0 P 0 
L 1.47238996 -2.00358996 1.4737 -2.00515 0 P 0 
L 1.4737 -2.00515 1.47488002 -2.00678996 0 P 0 
L 1.47488002 -2.00678996 1.47593996 -2.00851004 0 P 0 
L 1.47593996 -2.00851004 1.47686004 -2.01031004 0 P 0 
L 1.47686004 -2.01031004 1.47763996 -2.01216998 0 P 0 
L 1.47763996 -2.01216998 1.47851998 -2.01481004 0 P 0 
L 1.47851998 -2.01481004 1.47918996 -2.01748996 0 P 0 
L 1.47918996 -2.01748996 1.47966004 -2.02021998 0 P 0 
L 1.47966004 -2.02021998 1.47993002 -2.02296998 0 P 0 
L 1.47993002 -2.02296998 1.48001998 -2.02783996 0 P 0 
L 1.48001998 -2.02783996 1.47975 -2.03868996 0 P 0 
L 1.47975 -2.03868996 1.4793 -2.05161004 0 P 0 
L 1.4793 -2.05161004 1.47866004 -2.06543002 0 P 0 
L 1.47866004 -2.06543002 1.47801004 -2.07961004 0 P 0 
L 1.47801004 -2.07961004 1.47743996 -2.09378996 0 P 0 
L 1.47743996 -2.09378996 1.47705 -2.10613002 0 P 0 
L 1.47705 -2.10613002 1.47693002 -2.11356004 0 P 0 
L 1.47693002 -2.11356004 1.47693002 -2.12516004 0 P 0 
L 1.47693002 -2.12516004 1.42661004 -2.12516004 0 P 0 
L 1.42661004 -2.12516004 1.42661004 -2.12473996 0 P 0 
L 1.42661004 -2.12473996 1.42666004 -2.12318002 0 P 0 
L 1.42666004 -2.12318002 1.42691004 -2.11863996 0 P 0 
L 1.42691004 -2.11863996 1.42725 -2.1132 0 P 0 
L 1.42725 -2.1132 1.42766004 -2.1072 0 P 0 
L 1.42766004 -2.1072 1.42766004 -2.10718996 0 P 0 
L 1.42766004 -2.10718996 1.4281 -2.10068996 0 P 0 
L 1.4281 -2.10068996 1.42858002 -2.09368002 0 P 0 
L 1.42858002 -2.09368002 1.42901004 -2.08721004 0 P 0 
L 1.42901004 -2.08721004 1.42901004 -2.0872 0 P 0 
L 1.42901004 -2.0872 1.42931004 -2.08256004 0 P 0 
L 1.42931004 -2.08256004 1.42991998 -2.07308002 0 P 0 
L 1.42991998 -2.07308002 1.42916004 -2.07136998 0 P 0 
L 1.42916004 -2.07136998 1.42731998 -2.07105 0 P 0 
L 1.42731998 -2.07105 1.42105 -2.07303996 0 P 0 
L 1.42105 -2.07303996 1.41815 -2.07393002 0 P 0 
L 1.41815 -2.07393002 1.41451004 -2.075 0 P 0 
L 1.41451004 -2.075 1.41076004 -2.07603002 0 P 0 
L 1.41076004 -2.07603002 1.40748002 -2.0769 0 P 0 
L 1.40748002 -2.0769 1.40438996 -2.07781004 0 P 0 
L 1.40438996 -2.07781004 1.40431998 -2.07783996 0 P 0 
L 1.40431998 -2.07783996 1.40133996 -2.07896998 0 P 0 
L 1.40133996 -2.07896998 1.40005 -2.07956998 0 P 0 
L 1.40005 -2.07956998 1.39881998 -2.08026004 0 P 0 
L 1.39881998 -2.08026004 1.39763996 -2.08103002 0 P 0 
L 1.39763996 -2.08103002 1.39651998 -2.08188002 0 P 0 
L 1.39651998 -2.08188002 1.39578996 -2.08251004 0 P 0 
L 1.39578996 -2.08251004 1.39573996 -2.08256004 0 P 0 
L 1.39573996 -2.08256004 1.3951 -2.08318996 0 P 0 
L 1.3951 -2.08318996 1.39446998 -2.08393002 0 P 0 
L 1.39446998 -2.08393002 1.3939 -2.08471004 0 P 0 
L 1.3939 -2.08471004 1.39336998 -2.08553996 0 P 0 
L 1.39336998 -2.08553996 1.39301004 -2.08623996 0 P 0 
L 1.39301004 -2.08623996 1.39271004 -2.08696998 0 P 0 
L 1.39271004 -2.08696998 1.39248002 -2.08771998 0 P 0 
L 1.39248002 -2.08771998 1.39231004 -2.08848996 0 P 0 
L 1.39231004 -2.08848996 1.39221004 -2.08926004 0 P 0 
L 1.39221004 -2.08926004 1.39218002 -2.09003996 0 P 0 
L 1.39218002 -2.09003996 1.39221004 -2.0908 0 P 0 
L 1.39221004 -2.0908 1.39231004 -2.09153002 0 P 0 
L 1.39231004 -2.09153002 1.39246998 -2.09226004 0 P 0 
L 1.39246998 -2.09226004 1.39268996 -2.09296998 0 P 0 
L 1.39268996 -2.09296998 1.39296004 -2.09365 0 P 0 
L 1.39296004 -2.09365 1.3933 -2.09431004 0 P 0 
L 1.3933 -2.09431004 1.39368996 -2.09493996 0 P 0 
L 1.39368996 -2.09493996 1.39411998 -2.09553996 0 P 0 
L 1.39411998 -2.09553996 1.39468996 -2.09618002 0 P 0 
L 1.39468996 -2.09618002 1.3953 -2.09678002 0 P 0 
L 1.3953 -2.09678002 1.39596004 -2.09731998 0 P 0 
L 1.39596004 -2.09731998 1.39666998 -2.0978 0 P 0 
L 1.39666998 -2.0978 1.39673996 -2.09783996 0 P 0 
L 1.39673996 -2.09783996 1.39741004 -2.09821998 0 P 0 
L 1.39741004 -2.09821998 1.39748996 -2.09825 0 P 0 
L 1.39748996 -2.09825 1.39818996 -2.09856998 0 P 0 
L 1.39818996 -2.09856998 1.39898996 -2.09886004 0 P 0 
L 1.39898996 -2.09886004 1.39906998 -2.09888002 0 P 0 
L 1.39906998 -2.09888002 1.40043996 -2.09888002 0 P 0 
L 1.40043996 -2.09888002 1.40033996 -2.09923002 0 P 0 
L 1.40033996 -2.09923002 1.40041998 -2.09925 0 P 0 
L 1.40041998 -2.09925 1.40186004 -2.09953002 0 P 0 
L 1.40186004 -2.09953002 1.40331004 -2.09971004 0 P 0 
L 1.40331004 -2.09971004 1.40478002 -2.09978002 0 P 0 
L 1.40478002 -2.09978002 1.40625 -2.09975 0 P 0 
L 1.40625 -2.09975 1.41096004 -2.09931004 0 P 0 
L 1.41096004 -2.09931004 1.41556998 -2.09855 0 P 0 
L 1.41556998 -2.09855 1.41791998 -2.09813002 0 P 0 
L 1.41791998 -2.09813002 1.41995 -2.09791004 0 P 0 
L 1.41995 -2.09791004 1.4201 -2.0979 0 P 0 
L 1.4201 -2.0979 1.41941004 -2.10078002 0 P 0 
L 1.41941004 -2.10078002 1.41761004 -2.10745 0 P 0 
L 1.41761004 -2.10745 1.41391004 -2.12025 0 P 0 
L 1.41391004 -2.12025 1.41215 -2.12626998 0 P 0 
L 1.41215 -2.12626998 1.40655 -2.12725 0 P 0 
L 1.40655 -2.12725 1.40046004 -2.12808002 0 P 0 
L 1.40046004 -2.12808002 1.39438002 -2.12845 0 P 0 
L 1.15303002 -2.08283002 1.20788996 -2.08283002 0 P 0 
L 1.15398996 -2.08183002 1.20795 -2.08183002 0 P 0 
L 1.15483002 -2.08083002 1.208 -2.08083002 0 P 0 
L 1.15555 -2.07983002 1.20805 -2.07983002 0 P 0 
L 1.15621998 -2.07883002 1.2081 -2.07883002 0 P 0 
L 1.15681998 -2.07783002 1.20816004 -2.07783002 0 P 0 
L 1.15733002 -2.07683002 1.20821004 -2.07683002 0 P 0 
L 1.15778996 -2.07583002 1.20826004 -2.07583002 0 P 0 
L 1.15818002 -2.07483002 1.20831004 -2.07483002 0 P 0 
L 1.15853996 -2.07383002 1.20836998 -2.07383002 0 P 0 
L 1.15881998 -2.07283002 1.20841998 -2.07283002 0 P 0 
L 1.1591 -2.07183002 1.20846998 -2.07183002 0 P 0 
L 1.15938002 -2.07083002 1.20853002 -2.07083002 0 P 0 
L 1.1596 -2.06983002 1.20858002 -2.06983002 0 P 0 
L 1.15981004 -2.06883002 1.20863996 -2.06883002 0 P 0 
L 1.16001004 -2.06783002 1.20868996 -2.06783002 0 P 0 
L 1.1602 -2.06683002 1.20875 -2.06683002 0 P 0 
L 1.16033996 -2.06583002 1.2088 -2.06583002 0 P 0 
L 1.16048996 -2.06483002 1.20886004 -2.06483002 0 P 0 
L 1.16063996 -2.06383002 1.20891998 -2.06383002 0 P 0 
L 1.16078002 -2.06283002 1.20896998 -2.06283002 0 P 0 
L 1.16088996 -2.06183002 1.20903002 -2.06183002 0 P 0 
L 1.16098996 -2.06083002 1.20908002 -2.06083002 0 P 0 
L 1.16108996 -2.05983002 1.20913996 -2.05983002 0 P 0 
L 1.16118002 -2.05883002 1.20918996 -2.05883002 0 P 0 
L 1.16128002 -2.05783002 1.20925 -2.05783002 0 P 0 
L 1.16133996 -2.05683002 1.2093 -2.05683002 0 P 0 
L 1.1614 -2.05583002 1.20936004 -2.05583002 0 P 0 
L 1.16146004 -2.05483002 1.20941004 -2.05483002 0 P 0 
L 1.16151998 -2.05383002 1.20946998 -2.05383002 0 P 0 
L 1.16158002 -2.05283002 1.20951998 -2.05283002 0 P 0 
L 1.16163996 -2.05183002 1.20958002 -2.05183002 0 P 0 
L 1.1617 -2.05083002 1.20963996 -2.05083002 0 P 0 
L 1.16175 -2.04983002 1.2097 -2.04983002 0 P 0 
L 1.16181004 -2.04883002 1.20975 -2.04883002 0 P 0 
L 1.16186998 -2.04783002 1.20981004 -2.04783002 0 P 0 
L 1.16193002 -2.04683002 1.20986998 -2.04683002 0 P 0 
L 1.16198996 -2.04583002 1.20993002 -2.04583002 0 P 0 
L 1.16205 -2.04483002 1.20998996 -2.04483002 0 P 0 
L 1.16211004 -2.04383002 1.21005 -2.04383002 0 P 0 
L 1.16215 -2.04283002 1.2101 -2.04283002 0 P 0 
L 1.1622 -2.04183002 1.21016004 -2.04183002 0 P 0 
L 1.16225 -2.04083002 1.21021998 -2.04083002 0 P 0 
L 1.16228996 -2.03983002 1.21028002 -2.03983002 0 P 0 
L 1.16233996 -2.03883002 1.21033996 -2.03883002 0 P 0 
L 1.16238002 -2.03783002 1.2104 -2.03783002 0 P 0 
L 1.16243002 -2.03683002 1.21046004 -2.03683002 0 P 0 
L 1.16246998 -2.03583002 1.21051004 -2.03583002 0 P 0 
L 1.16251998 -2.03483002 1.21056998 -2.03483002 0 P 0 
L 1.16256998 -2.03383002 1.21063996 -2.03383002 0 P 0 
L 1.16261004 -2.03283002 1.2107 -2.03283002 0 P 0 
L 1.16266004 -2.03183002 1.21076004 -2.03183002 0 P 0 
L 1.1627 -2.03083002 1.21083002 -2.03083002 0 P 0 
L 1.16015 -1.97631004 1.17066004 -1.97631004 0 P 0 
L 1.15961998 -1.97531004 1.17026004 -1.97531004 0 P 0 
L 1.1591 -1.97431004 1.16986998 -1.97431004 0 P 0 
L 1.15856998 -1.97331004 1.16946998 -1.97331004 0 P 0 
L 1.15803996 -1.97231004 1.16903002 -1.97231004 0 P 0 
L 1.15746998 -1.97131004 1.16858996 -1.97131004 0 P 0 
L 1.1569 -1.97031004 1.16815 -1.97031004 0 P 0 
L 1.15631998 -1.96931004 1.16771004 -1.96931004 0 P 0 
L 1.15573996 -1.96831004 1.16726998 -1.96831004 0 P 0 
L 1.15516004 -1.96731004 1.16681998 -1.96731004 0 P 0 
L 1.15458996 -1.96631004 1.16638002 -1.96631004 0 P 0 
L 1.15398002 -1.96531004 1.16593996 -1.96531004 0 P 0 
L 1.1533 -1.96431004 1.16548996 -1.96431004 0 P 0 
L 1.15261998 -1.96331004 1.16503002 -1.96331004 0 P 0 
L 1.15193996 -1.96231004 1.16448002 -1.96231004 0 P 0 
L 1.15126004 -1.96131004 1.16393002 -1.96131004 0 P 0 
L 1.15058002 -1.96031004 1.16338002 -1.96031004 0 P 0 
L 1.1499 -1.95931004 1.16283002 -1.95931004 0 P 0 
L 1.1491 -1.95831004 1.16228996 -1.95831004 0 P 0 
L 1.14831004 -1.95731004 1.16173996 -1.95731004 0 P 0 
L 1.14751004 -1.95631004 1.16118996 -1.95631004 0 P 0 
L 1.14671004 -1.95531004 1.16063996 -1.95531004 0 P 0 
L 1.14591998 -1.95431004 1.16008996 -1.95431004 0 P 0 
L 1.14511998 -1.95331004 1.15943996 -1.95331004 0 P 0 
L 1.1442 -1.95231004 1.15878002 -1.95231004 0 P 0 
L 1.14326998 -1.95131004 1.15811004 -1.95131004 0 P 0 
L 1.14233996 -1.95031004 1.15745 -1.95031004 0 P 0 
L 1.14141004 -1.94931004 1.15678002 -1.94931004 0 P 0 
L 1.14048996 -1.94831004 1.15611998 -1.94831004 0 P 0 
L 1.1395 -1.94731004 1.15545 -1.94731004 0 P 0 
L 1.13843002 -1.94631004 1.15478996 -1.94631004 0 P 0 
L 1.13736004 -1.94531004 1.15411998 -1.94531004 0 P 0 
L 1.13628996 -1.94431004 1.15333002 -1.94431004 0 P 0 
L 1.13521004 -1.94331004 1.15253002 -1.94331004 0 P 0 
L 1.13413996 -1.94231004 1.15173996 -1.94231004 0 P 0 
L 1.13306998 -1.94131004 1.15093996 -1.94131004 0 P 0 
L 1.132 -1.94031004 1.15013996 -1.94031004 0 P 0 
L 1.13081004 -1.93931004 1.14935 -1.93931004 0 P 0 
L 1.12958002 -1.93831004 1.14855 -1.93831004 0 P 0 
L 1.12833996 -1.93731004 1.14775 -1.93731004 0 P 0 
L 1.1271 -1.93631004 1.14688996 -1.93631004 0 P 0 
L 1.12586004 -1.93531004 1.14593996 -1.93531004 0 P 0 
L 1.12461998 -1.93431004 1.14498996 -1.93431004 0 P 0 
L 1.12338002 -1.93331004 1.14405 -1.93331004 0 P 0 
L 1.12203002 -1.93231004 1.1431 -1.93231004 0 P 0 
L 1.1206 -1.93131004 1.14216004 -1.93131004 0 P 0 
L 1.11916004 -1.93031004 1.14121004 -1.93031004 0 P 0 
L 1.11771998 -1.92931004 1.14026998 -1.92931004 0 P 0 
L 1.11628996 -1.92831004 1.13931998 -1.92831004 0 P 0 
L 1.11483996 -1.92731004 1.13838002 -1.92731004 0 P 0 
L 1.11338996 -1.92631004 1.13743002 -1.92631004 0 P 0 
L 1.11171998 -1.92531004 1.13648996 -1.92531004 0 P 0 
L 1.11005 -1.92431004 1.13538002 -1.92431004 0 P 0 
L 1.10838002 -1.92331004 1.13426998 -1.92331004 0 P 0 
L 1.1067 -1.92231004 1.13315 -1.92231004 0 P 0 
L 1.10503002 -1.92131004 1.13203002 -1.92131004 0 P 0 
L 1.10336004 -1.92031004 1.13091998 -1.92031004 0 P 0 
L 1.1015 -1.91931004 1.1298 -1.91931004 0 P 0 
L 1.09955 -1.91831004 1.12868002 -1.91831004 0 P 0 
L 1.16275 -2.02983002 1.21088996 -2.02983002 0 P 0 
L 1.16278996 -2.02883002 1.21095 -2.02883002 0 P 0 
L 1.16283996 -2.02783002 1.21101004 -2.02783002 0 P 0 
L 1.16226998 -2.02683002 1.21108002 -2.02683002 0 P 0 
L 1.16153996 -2.02583002 1.21113996 -2.02583002 0 P 0 
L 1.15846004 -2.02483002 1.2112 -2.02483002 0 P 0 
L 1.10036004 -2.00383002 1.21255 -2.00383002 0 P 0 
L 1.10226004 -2.00283002 1.2126 -2.00283002 0 P 0 
L 1.10433996 -2.00183002 1.21266998 -2.00183002 0 P 0 
L 1.1065 -2.00083002 1.21273002 -2.00083002 0 P 0 
L 1.10886998 -1.99983002 1.21278996 -1.99983002 0 P 0 
L 1.11138002 -1.99883002 1.21285 -1.99883002 0 P 0 
L 1.11436998 -1.99783002 1.21288002 -1.99783002 0 P 0 
L 1.11748996 -1.99683002 1.21255 -1.99683002 0 P 0 
L 1.12061998 -1.99583002 1.2089 -1.99583002 0 P 0 
L 1.12433996 -1.99483002 1.2036 -1.99483002 0 P 0 
L 1.12863996 -1.99383002 1.19728002 -1.99383002 0 P 0 
L 1.13295 -1.99283002 1.19096998 -1.99283002 0 P 0 
L 1.13985 -1.99183002 1.18111998 -1.99183002 0 P 0 
L 1.14948002 -1.99083002 1.1651 -1.99083002 0 P 0 
L 1.24218002 -2.08316004 1.29143996 -2.08316004 0 P 0 
L 1.24223002 -2.08216004 1.29151004 -2.08216004 0 P 0 
L 1.24228002 -2.08116004 1.29158996 -2.08116004 0 P 0 
L 1.24233996 -2.08016004 1.29166004 -2.08016004 0 P 0 
L 1.24238996 -2.07916004 1.29173002 -2.07916004 0 P 0 
L 1.24245 -2.07816004 1.29181004 -2.07816004 0 P 0 
L 1.2425 -2.07716004 1.29188002 -2.07716004 0 P 0 
L 1.24256004 -2.07616004 1.29195 -2.07616004 0 P 0 
L 1.24261004 -2.07516004 1.29203002 -2.07516004 0 P 0 
L 1.24266998 -2.07416004 1.2921 -2.07416004 0 P 0 
L 1.24271998 -2.07316004 1.29216998 -2.07316004 0 P 0 
L 1.24278002 -2.07216004 1.29223996 -2.07216004 0 P 0 
L 1.24283002 -2.07116004 1.29231998 -2.07116004 0 P 0 
L 1.24288002 -2.07016004 1.29238996 -2.07016004 0 P 0 
L 1.24293002 -2.06916004 1.29246004 -2.06916004 0 P 0 
L 1.24296998 -2.06816004 1.29253002 -2.06816004 0 P 0 
L 1.24301998 -2.06716004 1.29261004 -2.06716004 0 P 0 
L 1.24306004 -2.06616004 1.2927 -2.06616004 0 P 0 
L 1.24311004 -2.06516004 1.29281004 -2.06516004 0 P 0 
L 1.24315 -2.06416004 1.29291998 -2.06416004 0 P 0 
L 1.2432 -2.06316004 1.29303002 -2.06316004 0 P 0 
L 1.24323996 -2.06216004 1.29315 -2.06216004 0 P 0 
L 1.24328996 -2.06116004 1.29331998 -2.06116004 0 P 0 
L 1.24333002 -2.06016004 1.2935 -2.06016004 0 P 0 
L 1.24338002 -2.05916004 1.29366998 -2.05916004 0 P 0 
L 1.24341998 -2.05816004 1.29385 -2.05816004 0 P 0 
L 1.24346998 -2.05716004 1.29408996 -2.05716004 0 P 0 
L 1.24351004 -2.05616004 1.29433996 -2.05616004 0 P 0 
L 1.24355 -2.05516004 1.29458996 -2.05516004 0 P 0 
L 1.2436 -2.05416004 1.29485 -2.05416004 0 P 0 
L 1.24363996 -2.05316004 1.29516998 -2.05316004 0 P 0 
L 1.24368996 -2.05216004 1.29551998 -2.05216004 0 P 0 
L 1.24373002 -2.05116004 1.29586004 -2.05116004 0 P 0 
L 1.24378002 -2.05016004 1.29621004 -2.05016004 0 P 0 
L 1.24383002 -2.04916004 1.29663996 -2.04916004 0 P 0 
L 1.24386998 -2.04816004 1.29708002 -2.04816004 0 P 0 
L 1.24391004 -2.04716004 1.29753002 -2.04716004 0 P 0 
L 1.24396004 -2.04616004 1.29796998 -2.04616004 0 P 0 
L 1.244 -2.04516004 1.29851004 -2.04516004 0 P 0 
L 1.24405 -2.04416004 1.2991 -2.04416004 0 P 0 
L 1.24408996 -2.04316004 1.29975 -2.04316004 0 P 0 
L 1.24413996 -2.04216004 1.3005 -2.04216004 0 P 0 
L 1.24418002 -2.04116004 1.30131998 -2.04116004 0 P 0 
L 1.24423002 -2.04016004 1.30223002 -2.04016004 0 P 0 
L 1.24426998 -2.03916004 1.30326998 -2.03916004 0 P 0 
L 1.24431998 -2.03816004 1.30446004 -2.03816004 0 P 0 
L 1.24436004 -2.03716004 1.30581998 -2.03716004 0 P 0 
L 1.24441004 -2.03616004 1.30738002 -2.03616004 0 P 0 
L 1.24445 -2.03516004 1.30923002 -2.03516004 0 P 0 
L 1.24448996 -2.03416004 1.31156004 -2.03416004 0 P 0 
L 1.24453996 -2.03316004 1.31478996 -2.03316004 0 P 0 
L 1.24458996 -2.03216004 1.32013002 -2.03216004 0 P 0 
L 1.24461998 -2.03116004 1.33481004 -2.03116004 0 P 0 
L 1.24463996 -2.03016004 1.33478002 -2.03016004 0 P 0 
L 1.24466004 -2.02916004 1.33473996 -2.02916004 0 P 0 
L 1.24468002 -2.02816004 1.33471004 -2.02816004 0 P 0 
L 1.2447 -2.02716004 1.33468002 -2.02716004 0 P 0 
L 1.24471998 -2.02616004 1.33463996 -2.02616004 0 P 0 
L 1.24473996 -2.02516004 1.3346 -2.02516004 0 P 0 
L 1.24476004 -2.02416004 1.33456998 -2.02416004 0 P 0 
L 1.24478002 -2.02316004 1.33453002 -2.02316004 0 P 0 
L 1.2448 -2.02216004 1.3345 -2.02216004 0 P 0 
L 1.24481998 -2.02116004 1.33446998 -2.02116004 0 P 0 
L 1.24483996 -2.02016004 1.33443002 -2.02016004 0 P 0 
L 1.24486004 -2.01916004 1.3344 -2.01916004 0 P 0 
L 1.24488002 -2.01816004 1.33436004 -2.01816004 0 P 0 
L 1.2449 -2.01716004 1.33433002 -2.01716004 0 P 0 
L 1.24491998 -2.01616004 1.33428996 -2.01616004 0 P 0 
L 1.24493996 -2.01516004 1.33426004 -2.01516004 0 P 0 
L 1.24496004 -2.01416004 1.33421998 -2.01416004 0 P 0 
L 1.24498002 -2.01316004 1.33418996 -2.01316004 0 P 0 
L 1.245 -2.01216004 1.33415 -2.01216004 0 P 0 
L 1.24501998 -2.01116004 1.33411998 -2.01116004 0 P 0 
L 1.24503996 -2.01016004 1.33408002 -2.01016004 0 P 0 
L 1.24506004 -2.00916004 1.33403996 -2.00916004 0 P 0 
L 1.24508002 -2.00816004 1.334 -2.00816004 0 P 0 
L 1.2451 -2.00716004 1.33396004 -2.00716004 0 P 0 
L 1.24511998 -2.00616004 1.33393002 -2.00616004 0 P 0 
L 1.24513996 -2.00516004 1.29098996 -2.00516004 0 P 0 
L 1.24513996 -2.00416004 1.29033002 -2.00416004 0 P 0 
L 1.24513996 -2.00316004 1.29005 -2.00316004 0 P 0 
L 1.24513996 -2.00216004 1.29005 -2.00216004 0 P 0 
L 1.24513996 -2.00116004 1.29005 -2.00116004 0 P 0 
L 1.24515 -2.00016004 1.29005 -2.00016004 0 P 0 
L 1.24515 -1.99916004 1.29005 -1.99916004 0 P 0 
L 1.24515 -1.99816004 1.29005 -1.99816004 0 P 0 
L 1.24515 -1.99716004 1.29005 -1.99716004 0 P 0 
L 1.24515 -1.99616004 1.29005 -1.99616004 0 P 0 
L 1.24515 -1.99516004 1.29005 -1.99516004 0 P 0 
L 1.16085 -2.02753002 1.1601 -2.04393002 0 P 0 
L 1.1601 -2.04393002 1.15928996 -2.05771998 0 P 0 
L 1.15928996 -2.05771998 1.15883996 -2.06228002 0 P 0 
L 1.15883996 -2.06228002 1.15818002 -2.06681998 0 P 0 
L 1.15818002 -2.06681998 1.15751004 -2.07006998 0 P 0 
L 1.15751004 -2.07006998 1.15661004 -2.07328996 0 P 0 
L 1.15661004 -2.07328996 1.15616004 -2.07453996 0 P 0 
L 1.15616004 -2.07453996 1.15563002 -2.07576998 0 P 0 
L 1.15563002 -2.07576998 1.15501998 -2.07696004 0 P 0 
L 1.15501998 -2.07696004 1.15433002 -2.0781 0 P 0 
L 1.15433002 -2.0781 1.1534 -2.07941998 0 P 0 
L 1.1534 -2.07941998 1.15236004 -2.08066004 0 P 0 
L 1.15236004 -2.08066004 1.15123002 -2.08181998 0 P 0 
L 1.15123002 -2.08181998 1.15001004 -2.08286998 0 P 0 
L 1.15001004 -2.08286998 1.14871004 -2.08383002 0 P 0 
L 1.14871004 -2.08383002 1.14733002 -2.08468002 0 P 0 
L 1.14733002 -2.08468002 1.14591004 -2.0854 0 P 0 
L 1.14591004 -2.0854 1.14443996 -2.086 0 P 0 
L 1.14443996 -2.086 1.14291004 -2.08648002 0 P 0 
L 1.14291004 -2.08648002 1.14136004 -2.08683002 0 P 0 
L 1.14136004 -2.08683002 1.13976998 -2.08703996 0 P 0 
L 1.13976998 -2.08703996 1.13816004 -2.08713002 0 P 0 
L 1.13816004 -2.08713002 1.13656998 -2.08708002 0 P 0 
L 1.13656998 -2.08708002 1.13498996 -2.0869 0 P 0 
L 1.13498996 -2.0869 1.13341998 -2.08658996 0 P 0 
L 1.13341998 -2.08658996 1.13188996 -2.08615 0 P 0 
L 1.13188996 -2.08615 1.1304 -2.08558996 0 P 0 
L 1.1304 -2.08558996 1.12895 -2.08488996 0 P 0 
L 1.12895 -2.08488996 1.12756998 -2.08408002 0 P 0 
L 1.12756998 -2.08408002 1.12625 -2.08315 0 P 0 
L 1.12625 -2.08315 1.12501004 -2.08211998 0 P 0 
L 1.12501004 -2.08211998 1.12386004 -2.081 0 P 0 
L 1.12386004 -2.081 1.12281004 -2.07978002 0 P 0 
L 1.12281004 -2.07978002 1.12183996 -2.07846998 0 P 0 
L 1.12183996 -2.07846998 1.1211 -2.07726004 0 P 0 
L 1.1211 -2.07726004 1.12046998 -2.07598996 0 P 0 
L 1.12046998 -2.07598996 1.11996004 -2.07466998 0 P 0 
L 1.11996004 -2.07466998 1.11955 -2.07331004 0 P 0 
L 1.11955 -2.07331004 1.11926998 -2.07191004 0 P 0 
L 1.11926998 -2.07191004 1.11868002 -2.06693996 0 P 0 
L 1.11868002 -2.06693996 1.11848002 -2.06191004 0 P 0 
L 1.11848002 -2.06191004 1.11871004 -2.05668002 0 P 0 
L 1.11871004 -2.05668002 1.11936004 -2.05148002 0 P 0 
L 1.11936004 -2.05148002 1.11978996 -2.04936998 0 P 0 
L 1.11978996 -2.04936998 1.12036998 -2.0473 0 P 0 
L 1.12036998 -2.0473 1.12108996 -2.04528002 0 P 0 
L 1.12108996 -2.04528002 1.12196004 -2.04331998 0 P 0 
L 1.12196004 -2.04331998 1.1229 -2.04153996 0 P 0 
L 1.1229 -2.04153996 1.12396998 -2.03985 0 P 0 
L 1.12396998 -2.03985 1.12516998 -2.03823002 0 P 0 
L 1.12516998 -2.03823002 1.12735 -2.03573996 0 P 0 
L 1.12735 -2.03573996 1.12973002 -2.03345 0 P 0 
L 1.12973002 -2.03345 1.13223996 -2.03141998 0 P 0 
L 1.13223996 -2.03141998 1.13491998 -2.02961004 0 P 0 
L 1.13491998 -2.02961004 1.13611004 -2.02893002 0 P 0 
L 1.13611004 -2.02893002 1.13735 -2.02833996 0 P 0 
L 1.13735 -2.02833996 1.13861998 -2.02781998 0 P 0 
L 1.13861998 -2.02781998 1.13993996 -2.0274 0 P 0 
L 1.13993996 -2.0274 1.14191004 -2.02693002 0 P 0 
L 1.14191004 -2.02693002 1.14391004 -2.02663002 0 P 0 
L 1.14391004 -2.02663002 1.14935 -2.02626004 0 P 0 
L 1.14935 -2.02626004 1.15471004 -2.0263 0 P 0 
L 1.15471004 -2.0263 1.15591004 -2.02638996 0 P 0 
L 1.15591004 -2.02638996 1.1571 -2.02656998 0 P 0 
L 1.1571 -2.02656998 1.15828002 -2.02683996 0 P 0 
L 1.15828002 -2.02683996 1.16085 -2.02753002 0 P 0 
L 1.13876998 -2.14783002 1.20233002 -2.14783002 0 P 0 
L 1.14236998 -2.14683002 1.20266004 -2.14683002 0 P 0 
L 1.14481004 -2.14583002 1.20296004 -2.14583002 0 P 0 
L 1.1467 -2.14483002 1.20325 -2.14483002 0 P 0 
L 1.14826004 -2.14383002 1.20353002 -2.14383002 0 P 0 
L 1.1496 -2.14283002 1.20373996 -2.14283002 0 P 0 
L 1.15078996 -2.14183002 1.20395 -2.14183002 0 P 0 
L 1.15186004 -2.14083002 1.20415 -2.14083002 0 P 0 
L 1.15278996 -2.13983002 1.20431998 -2.13983002 0 P 0 
L 1.15361998 -2.13883002 1.20446004 -2.13883002 0 P 0 
L 1.15436004 -2.13783002 1.20458002 -2.13783002 0 P 0 
L 1.155 -2.13683002 1.20466998 -2.13683002 0 P 0 
L 1.15556998 -2.13583002 1.20475 -2.13583002 0 P 0 
L 1.15608996 -2.13483002 1.20481998 -2.13483002 0 P 0 
L 1.15653996 -2.13383002 1.20488996 -2.13383002 0 P 0 
L 1.15691004 -2.13283002 1.20496004 -2.13283002 0 P 0 
L 1.15723996 -2.13183002 1.20503002 -2.13183002 0 P 0 
L 1.15751998 -2.13083002 1.2051 -2.13083002 0 P 0 
L 1.15773002 -2.12983002 1.20516004 -2.12983002 0 P 0 
L 1.15793002 -2.12883002 1.20523002 -2.12883002 0 P 0 
L 1.15806004 -2.12783002 1.2053 -2.12783002 0 P 0 
L 1.15816998 -2.12683002 1.20536998 -2.12683002 0 P 0 
L 1.15821004 -2.12583002 1.20543996 -2.12583002 0 P 0 
L 1.11716004 -2.12483002 1.12726004 -2.12483002 0 P 0 
L 1.15823996 -2.12483002 1.20551004 -2.12483002 0 P 0 
L 1.10911998 -2.12383002 1.1352 -2.12383002 0 P 0 
L 1.15821998 -2.12383002 1.20556998 -2.12383002 0 P 0 
L 1.10468996 -2.12283002 1.14018996 -2.12283002 0 P 0 
L 1.1582 -2.12283002 1.20563996 -2.12283002 0 P 0 
L 1.10131004 -2.12183002 1.14366998 -2.12183002 0 P 0 
L 1.15818002 -2.12183002 1.2057 -2.12183002 0 P 0 
L 1.15808996 -2.12083002 1.20576004 -2.12083002 0 P 0 
L 1.15781004 -2.11983002 1.20583002 -2.11983002 0 P 0 
L 1.15721004 -2.11883002 1.20588002 -2.11883002 0 P 0 
L 1.14146004 -2.08883002 1.20758002 -2.08883002 0 P 0 
L 1.14525 -2.08783002 1.20763002 -2.08783002 0 P 0 
L 1.14751004 -2.08683002 1.20768002 -2.08683002 0 P 0 
L 1.14928002 -2.08583002 1.20773002 -2.08583002 0 P 0 
L 1.15073002 -2.08483002 1.20778996 -2.08483002 0 P 0 
L 1.15196004 -2.08383002 1.20783996 -2.08383002 0 P 0 
L 1.13818996 -2.08913002 1.13826998 -2.08913002 0 P 0 
L 1.13826998 -2.08913002 1.13988002 -2.08903996 0 P 0 
L 1.13988002 -2.08903996 1.13996004 -2.08903996 0 P 0 
L 1.13996004 -2.08903996 1.14001004 -2.08903002 0 P 0 
L 1.14001004 -2.08903002 1.14005 -2.08901998 0 P 0 
L 1.14005 -2.08901998 1.14163002 -2.08881004 0 P 0 
L 1.14163002 -2.08881004 1.14166998 -2.0888 0 P 0 
L 1.14166998 -2.0888 1.14171004 -2.0888 0 P 0 
L 1.14171004 -2.0888 1.14178996 -2.08878002 0 P 0 
L 1.14178996 -2.08878002 1.14335 -2.08843002 0 P 0 
L 1.14335 -2.08843002 1.14351004 -2.08838996 0 P 0 
L 1.14351004 -2.08838996 1.14503002 -2.08791004 0 P 0 
L 1.14503002 -2.08791004 1.14511004 -2.08788996 0 P 0 
L 1.14511004 -2.08788996 1.14515 -2.08786998 0 P 0 
L 1.14515 -2.08786998 1.14518996 -2.08786004 0 P 0 
L 1.14518996 -2.08786004 1.14666004 -2.08725 0 P 0 
L 1.14666004 -2.08725 1.14673996 -2.08721998 0 P 0 
L 1.14673996 -2.08721998 1.14678002 -2.0872 0 P 0 
L 1.14678002 -2.0872 1.14681998 -2.08718996 0 P 0 
L 1.14681998 -2.08718996 1.14823996 -2.08646998 0 P 0 
L 1.14823996 -2.08646998 1.14826998 -2.08645 0 P 0 
L 1.14826998 -2.08645 1.14835 -2.08641004 0 P 0 
L 1.14835 -2.08641004 1.14838002 -2.08638002 0 P 0 
L 1.14838002 -2.08638002 1.14976004 -2.08553002 0 P 0 
L 1.14976004 -2.08553002 1.14978996 -2.08551004 0 P 0 
L 1.14978996 -2.08551004 1.14983002 -2.08548996 0 P 0 
L 1.14983002 -2.08548996 1.14988996 -2.08543996 0 P 0 
L 1.14988996 -2.08543996 1.1512 -2.08448996 0 P 0 
L 1.1512 -2.08448996 1.15126004 -2.08443996 0 P 0 
L 1.15126004 -2.08443996 1.15128996 -2.08441004 0 P 0 
L 1.15128996 -2.08441004 1.15131998 -2.08438996 0 P 0 
L 1.15131998 -2.08438996 1.15253996 -2.08333002 0 P 0 
L 1.15253996 -2.08333002 1.15256998 -2.0833 0 P 0 
L 1.15256998 -2.0833 1.1526 -2.08328002 0 P 0 
L 1.1526 -2.08328002 1.15263002 -2.08323996 0 P 0 
L 1.15263002 -2.08323996 1.15266004 -2.08321998 0 P 0 
L 1.15266004 -2.08321998 1.15378996 -2.08206004 0 P 0 
L 1.15378996 -2.08206004 1.15376004 -2.08203996 0 P 0 
L 1.15376004 -2.08203996 1.15381998 -2.08203996 0 P 0 
L 1.15381998 -2.08203996 1.15383996 -2.082 0 P 0 
L 1.15383996 -2.082 1.15386998 -2.08196998 0 P 0 
L 1.15386998 -2.08196998 1.1539 -2.08195 0 P 0 
L 1.1539 -2.08195 1.15493002 -2.08071004 0 P 0 
L 1.15493002 -2.08071004 1.15493002 -2.0807 0 P 0 
L 1.15493002 -2.0807 1.15496004 -2.08066998 0 P 0 
L 1.15496004 -2.08066998 1.15498002 -2.08063996 0 P 0 
L 1.15498002 -2.08063996 1.15501004 -2.08061004 0 P 0 
L 1.15501004 -2.08061004 1.15503002 -2.08058002 0 P 0 
L 1.15503002 -2.08058002 1.15596004 -2.07926004 0 P 0 
L 1.15596004 -2.07926004 1.15603996 -2.07913996 0 P 0 
L 1.15603996 -2.07913996 1.15673002 -2.07798996 0 P 0 
L 1.15673002 -2.07798996 1.15676998 -2.07793002 0 P 0 
L 1.15676998 -2.07793002 1.15678996 -2.07786998 0 P 0 
L 1.15678996 -2.07786998 1.15741004 -2.07668996 0 P 0 
L 1.15741004 -2.07668996 1.15743996 -2.07663002 0 P 0 
L 1.15743996 -2.07663002 1.15746004 -2.07656998 0 P 0 
L 1.15746004 -2.07656998 1.15746998 -2.07656998 0 P 0 
L 1.15746998 -2.07656998 1.158 -2.07533996 0 P 0 
L 1.158 -2.07533996 1.15801004 -2.07531004 0 P 0 
L 1.15801004 -2.07531004 1.15803002 -2.07528002 0 P 0 
L 1.15803002 -2.07528002 1.15805 -2.07521998 0 P 0 
L 1.15805 -2.07521998 1.15848996 -2.07396004 0 P 0 
L 1.15848996 -2.07396004 1.15841004 -2.07393002 0 P 0 
L 1.15841004 -2.07393002 1.15851004 -2.07393002 0 P 0 
L 1.15851004 -2.07393002 1.15851998 -2.0739 0 P 0 
L 1.15851998 -2.0739 1.15853002 -2.07386004 0 P 0 
L 1.15853002 -2.07386004 1.15853996 -2.07383002 0 P 0 
L 1.15853996 -2.07383002 1.15943996 -2.07061004 0 P 0 
L 1.15943996 -2.07061004 1.15945 -2.07058002 0 P 0 
L 1.15945 -2.07058002 1.15946004 -2.07053996 0 P 0 
L 1.15946004 -2.07053996 1.15946998 -2.07051004 0 P 0 
L 1.15946998 -2.07051004 1.15946998 -2.07046998 0 P 0 
L 1.15946998 -2.07046998 1.16013996 -2.06723002 0 P 0 
L 1.16013996 -2.06723002 1.16013996 -2.0672 0 P 0 
L 1.16013996 -2.0672 1.16016004 -2.06713996 0 P 0 
L 1.16016004 -2.06713996 1.16016004 -2.06711004 0 P 0 
L 1.16016004 -2.06711004 1.16081998 -2.06256004 0 P 0 
L 1.16081998 -2.06256004 1.16081998 -2.06253996 0 P 0 
L 1.16081998 -2.06253996 1.16083002 -2.0625 0 P 0 
L 1.16083002 -2.0625 1.16083002 -2.06246998 0 P 0 
L 1.16083002 -2.06246998 1.16126998 -2.05791004 0 P 0 
L 1.16126998 -2.05791004 1.16128002 -2.0579 0 P 0 
L 1.16128002 -2.0579 1.16128002 -2.05783996 0 P 0 
L 1.16128002 -2.05783996 1.1621 -2.04405 0 P 0 
L 1.1621 -2.04405 1.1621 -2.04401998 0 P 0 
L 1.1621 -2.04401998 1.16285 -2.02761998 0 P 0 
L 1.16285 -2.02761998 1.16136998 -2.0256 0 P 0 
L 1.16136998 -2.0256 1.15878996 -2.02491004 0 P 0 
L 1.15878996 -2.02491004 1.15878002 -2.0249 0 P 0 
L 1.15878002 -2.0249 1.15871998 -2.02488996 0 P 0 
L 1.15871998 -2.02488996 1.15755 -2.02461998 0 P 0 
L 1.15755 -2.02461998 1.15746998 -2.0246 0 P 0 
L 1.15746998 -2.0246 1.1574 -2.0246 0 P 0 
L 1.1574 -2.0246 1.15621004 -2.02441004 0 P 0 
L 1.15621004 -2.02441004 1.15616998 -2.02441004 0 P 0 
L 1.15616998 -2.02441004 1.1561 -2.0244 0 P 0 
L 1.1561 -2.0244 1.15606004 -2.02438996 0 P 0 
L 1.15606004 -2.02438996 1.15486004 -2.0243 0 P 0 
L 1.15486004 -2.0243 1.15471998 -2.0243 0 P 0 
L 1.15471998 -2.0243 1.14936004 -2.02426004 0 P 0 
L 1.14936004 -2.02426004 1.14928996 -2.02426004 0 P 0 
L 1.14928996 -2.02426004 1.14925 -2.02426998 0 P 0 
L 1.14925 -2.02426998 1.14921004 -2.02426998 0 P 0 
L 1.14921004 -2.02426998 1.14376998 -2.02463996 0 P 0 
L 1.14376998 -2.02463996 1.1437 -2.02463996 0 P 0 
L 1.1437 -2.02463996 1.14365 -2.02465 0 P 0 
L 1.14365 -2.02465 1.14361004 -2.02465 0 P 0 
L 1.14361004 -2.02465 1.14161998 -2.02495 0 P 0 
L 1.14161998 -2.02495 1.14161004 -2.02495 0 P 0 
L 1.14161004 -2.02495 1.14153002 -2.02496998 0 P 0 
L 1.14153002 -2.02496998 1.14148996 -2.02496998 0 P 0 
L 1.14148996 -2.02496998 1.14143996 -2.02498996 0 P 0 
L 1.14143996 -2.02498996 1.13946998 -2.02545 0 P 0 
L 1.13946998 -2.02545 1.13943996 -2.02546998 0 P 0 
L 1.13943996 -2.02546998 1.1394 -2.02546998 0 P 0 
L 1.1394 -2.02546998 1.13933002 -2.0255 0 P 0 
L 1.13933002 -2.0255 1.13801004 -2.02591998 0 P 0 
L 1.13801004 -2.02591998 1.13798002 -2.02593002 0 P 0 
L 1.13798002 -2.02593002 1.13793996 -2.02593996 0 P 0 
L 1.13793996 -2.02593996 1.13788002 -2.02596998 0 P 0 
L 1.13788002 -2.02596998 1.1366 -2.02648002 0 P 0 
L 1.1366 -2.02648002 1.13653996 -2.0265 0 P 0 
L 1.13653996 -2.0265 1.13648002 -2.02653002 0 P 0 
L 1.13648002 -2.02653002 1.13523996 -2.02713002 0 P 0 
L 1.13523996 -2.02713002 1.13518002 -2.02716004 0 P 0 
L 1.13518002 -2.02716004 1.13515 -2.02716998 0 P 0 
L 1.13515 -2.02716998 1.13511998 -2.02718996 0 P 0 
L 1.13511998 -2.02718996 1.13393002 -2.02786998 0 P 0 
L 1.13393002 -2.02786998 1.13388996 -2.02788996 0 P 0 
L 1.13388996 -2.02788996 1.1338 -2.02795 0 P 0 
L 1.1338 -2.02795 1.13111998 -2.02976004 0 P 0 
L 1.13111998 -2.02976004 1.13105 -2.02981004 0 P 0 
L 1.13105 -2.02981004 1.13101004 -2.02983996 0 P 0 
L 1.13101004 -2.02983996 1.13098002 -2.02986004 0 P 0 
L 1.13098002 -2.02986004 1.12846998 -2.03188996 0 P 0 
L 1.12846998 -2.03188996 1.12838002 -2.03198002 0 P 0 
L 1.12838002 -2.03198002 1.12833996 -2.03201004 0 P 0 
L 1.12833996 -2.03201004 1.12596004 -2.0343 0 P 0 
L 1.12596004 -2.0343 1.12593996 -2.03433002 0 P 0 
L 1.12593996 -2.03433002 1.1259 -2.03436004 0 P 0 
L 1.1259 -2.03436004 1.12588002 -2.03438996 0 P 0 
L 1.12588002 -2.03438996 1.12585 -2.03443002 0 P 0 
L 1.12585 -2.03443002 1.12366998 -2.03691004 0 P 0 
L 1.12366998 -2.03691004 1.12363996 -2.03695 0 P 0 
L 1.12363996 -2.03695 1.12361998 -2.03698002 0 P 0 
L 1.12361998 -2.03698002 1.12358996 -2.03701004 0 P 0 
L 1.12358996 -2.03701004 1.12356998 -2.03703996 0 P 0 
L 1.12356998 -2.03703996 1.12236998 -2.03865 0 P 0 
L 1.12236998 -2.03865 1.12233996 -2.03868996 0 P 0 
L 1.12233996 -2.03868996 1.12233002 -2.03871004 0 P 0 
L 1.12233002 -2.03871004 1.12228996 -2.03878002 0 P 0 
L 1.12228996 -2.03878002 1.12121004 -2.04046998 0 P 0 
L 1.12121004 -2.04046998 1.12118996 -2.0405 0 P 0 
L 1.12118996 -2.0405 1.12116998 -2.04053996 0 P 0 
L 1.12116998 -2.04053996 1.12115 -2.04056998 0 P 0 
L 1.12115 -2.04056998 1.12113996 -2.04061004 0 P 0 
L 1.12113996 -2.04061004 1.12018996 -2.04238002 0 P 0 
L 1.12018996 -2.04238002 1.12016004 -2.04245 0 P 0 
L 1.12016004 -2.04245 1.12013996 -2.04248002 0 P 0 
L 1.12013996 -2.04248002 1.12013002 -2.04251004 0 P 0 
L 1.12013002 -2.04251004 1.11926004 -2.04446998 0 P 0 
L 1.11926004 -2.04446998 1.11925 -2.0445 0 P 0 
L 1.11925 -2.0445 1.11923002 -2.04453996 0 P 0 
L 1.11923002 -2.04453996 1.11921998 -2.04458002 0 P 0 
L 1.11921998 -2.04458002 1.11921004 -2.04461004 0 P 0 
L 1.11921004 -2.04461004 1.11848002 -2.04663002 0 P 0 
L 1.11848002 -2.04663002 1.11846998 -2.04666004 0 P 0 
L 1.11846998 -2.04666004 1.11846004 -2.0467 0 P 0 
L 1.11846004 -2.0467 1.11843996 -2.04676998 0 P 0 
L 1.11843996 -2.04676998 1.11786004 -2.04883996 0 P 0 
L 1.11786004 -2.04883996 1.11785 -2.04886998 0 P 0 
L 1.11785 -2.04886998 1.11783996 -2.04891004 0 P 0 
L 1.11783996 -2.04891004 1.11783996 -2.04893996 0 P 0 
L 1.11783996 -2.04893996 1.11783002 -2.04896998 0 P 0 
L 1.11783002 -2.04896998 1.11783002 -2.04898002 0 P 0 
L 1.11783002 -2.04898002 1.1174 -2.05108002 0 P 0 
L 1.1174 -2.05108002 1.1174 -2.05111998 0 P 0 
L 1.1174 -2.05111998 1.11738996 -2.05116004 0 P 0 
L 1.11738996 -2.05116004 1.11738002 -2.05118996 0 P 0 
L 1.11738002 -2.05118996 1.11738002 -2.05123002 0 P 0 
L 1.11738002 -2.05123002 1.11673002 -2.05643002 0 P 0 
L 1.11673002 -2.05643002 1.11671998 -2.05646998 0 P 0 
L 1.11671998 -2.05646998 1.11671998 -2.05655 0 P 0 
L 1.11671998 -2.05655 1.11671004 -2.05658996 0 P 0 
L 1.11671004 -2.05658996 1.11648996 -2.06181998 0 P 0 
L 1.11648996 -2.06181998 1.11648002 -2.06186998 0 P 0 
L 1.11648002 -2.06186998 1.11648002 -2.06195 0 P 0 
L 1.11648002 -2.06195 1.11648996 -2.06198996 0 P 0 
L 1.11648996 -2.06198996 1.11668002 -2.06696998 0 P 0 
L 1.11668002 -2.06696998 1.11768002 -2.06696998 0 P 0 
L 1.11768002 -2.06696998 1.11668002 -2.06701004 0 P 0 
L 1.11668002 -2.06701004 1.11668002 -2.06713002 0 P 0 
L 1.11668002 -2.06713002 1.11668996 -2.06716998 0 P 0 
L 1.11668996 -2.06716998 1.11728002 -2.07215 0 P 0 
L 1.11728002 -2.07215 1.11728996 -2.07218996 0 P 0 
L 1.11728996 -2.07218996 1.11728996 -2.07223002 0 P 0 
L 1.11728996 -2.07223002 1.11731004 -2.07231004 0 P 0 
L 1.11731004 -2.07231004 1.11758996 -2.07371004 0 P 0 
L 1.11758996 -2.07371004 1.1176 -2.07375 0 P 0 
L 1.1176 -2.07375 1.11761004 -2.0738 0 P 0 
L 1.11761004 -2.0738 1.11761998 -2.07383996 0 P 0 
L 1.11761998 -2.07383996 1.11763996 -2.07388002 0 P 0 
L 1.11763996 -2.07388002 1.11803996 -2.07523996 0 P 0 
L 1.11803996 -2.07523996 1.11806004 -2.07531998 0 P 0 
L 1.11806004 -2.07531998 1.11808002 -2.07536004 0 P 0 
L 1.11808002 -2.07536004 1.11808996 -2.07541004 0 P 0 
L 1.11808996 -2.07541004 1.11861004 -2.07673002 0 P 0 
L 1.11861004 -2.07673002 1.11863996 -2.07681004 0 P 0 
L 1.11863996 -2.07681004 1.11866004 -2.07683996 0 P 0 
L 1.11866004 -2.07683996 1.11868002 -2.07688002 0 P 0 
L 1.11868002 -2.07688002 1.11931004 -2.07815 0 P 0 
L 1.11931004 -2.07815 1.11935 -2.07823002 0 P 0 
L 1.11935 -2.07823002 1.1194 -2.0783 0 P 0 
L 1.1194 -2.0783 1.12013996 -2.07951998 0 P 0 
L 1.12013996 -2.07951998 1.12021004 -2.07961998 0 P 0 
L 1.12021004 -2.07961998 1.12023002 -2.07965 0 P 0 
L 1.12023002 -2.07965 1.12023002 -2.07966004 0 P 0 
L 1.12023002 -2.07966004 1.1212 -2.08096998 0 P 0 
L 1.1212 -2.08096998 1.12123996 -2.08103002 0 P 0 
L 1.12123996 -2.08103002 1.12126998 -2.08106004 0 P 0 
L 1.12126998 -2.08106004 1.12128996 -2.08108996 0 P 0 
L 1.12128996 -2.08108996 1.12235 -2.08231004 0 P 0 
L 1.12235 -2.08231004 1.12238002 -2.08233996 0 P 0 
L 1.12238002 -2.08233996 1.1224 -2.08236998 0 P 0 
L 1.1224 -2.08236998 1.12246004 -2.08243002 0 P 0 
L 1.12246004 -2.08243002 1.12361004 -2.08355 0 P 0 
L 1.12361004 -2.08355 1.12366998 -2.08361004 0 P 0 
L 1.12366998 -2.08361004 1.1237 -2.08363002 0 P 0 
L 1.1237 -2.08363002 1.12373002 -2.08366004 0 P 0 
L 1.12373002 -2.08366004 1.12496998 -2.08468996 0 P 0 
L 1.12496998 -2.08468996 1.125 -2.08471004 0 P 0 
L 1.125 -2.08471004 1.12503002 -2.08473996 0 P 0 
L 1.12503002 -2.08473996 1.12506998 -2.08476004 0 P 0 
L 1.12506998 -2.08476004 1.1251 -2.08478996 0 P 0 
L 1.1251 -2.08478996 1.12641998 -2.08571004 0 P 0 
L 1.12641998 -2.08571004 1.12645 -2.08573002 0 P 0 
L 1.12645 -2.08573002 1.12648002 -2.08576004 0 P 0 
L 1.12648002 -2.08576004 1.12651004 -2.08578002 0 P 0 
L 1.12651004 -2.08578002 1.12655 -2.0858 0 P 0 
L 1.12655 -2.0858 1.12793996 -2.08661004 0 P 0 
L 1.12793996 -2.08661004 1.12801004 -2.08665 0 P 0 
L 1.12801004 -2.08665 1.12805 -2.08666998 0 P 0 
L 1.12805 -2.08666998 1.12808002 -2.08668996 0 P 0 
L 1.12808002 -2.08668996 1.12808996 -2.08668996 0 P 0 
L 1.12808996 -2.08668996 1.12953996 -2.08738996 0 P 0 
L 1.12953996 -2.08738996 1.12961998 -2.08743002 0 P 0 
L 1.12961998 -2.08743002 1.12965 -2.08743996 0 P 0 
L 1.12965 -2.08743996 1.1297 -2.08746004 0 P 0 
L 1.1297 -2.08746004 1.13118002 -2.08801998 0 P 0 
L 1.13118002 -2.08801998 1.13133996 -2.08808002 0 P 0 
L 1.13133996 -2.08808002 1.13286998 -2.08851004 0 P 0 
L 1.13286998 -2.08851004 1.13295 -2.08853996 0 P 0 
L 1.13295 -2.08853996 1.13303996 -2.08855 0 P 0 
L 1.13303996 -2.08855 1.1346 -2.08886004 0 P 0 
L 1.1346 -2.08886004 1.13471998 -2.08888996 0 P 0 
L 1.13471998 -2.08888996 1.13476004 -2.08888996 0 P 0 
L 1.13476004 -2.08888996 1.13633996 -2.08906998 0 P 0 
L 1.13633996 -2.08906998 1.13638996 -2.08908002 0 P 0 
L 1.13638996 -2.08908002 1.13651004 -2.08908002 0 P 0 
L 1.13651004 -2.08908002 1.1381 -2.08913002 0 P 0 
L 1.1381 -2.08913002 1.13818996 -2.08913002 0 P 0 
L 1.31623996 -1.98923996 1.3135 -1.98988002 0 P 0 
L 1.3135 -1.98988002 1.31078996 -1.99071004 0 P 0 
L 1.31078996 -1.99071004 1.30813002 -1.99175 0 P 0 
L 1.30813002 -1.99175 1.30553996 -1.99296998 0 P 0 
L 1.30553996 -1.99296998 1.30308996 -1.99431998 0 P 0 
L 1.30308996 -1.99431998 1.30073996 -1.99585 0 P 0 
L 1.30073996 -1.99585 1.29863996 -1.99746004 0 P 0 
L 1.29863996 -1.99746004 1.29666004 -1.99923996 0 P 0 
L 1.29666004 -1.99923996 1.29205 -2.00375 0 P 0 
L 1.29205 -2.00375 1.29205 -1.99243996 0 P 0 
L 1.29205 -1.99243996 1.24316004 -1.99243996 0 P 0 
L 1.24316004 -1.99243996 1.24313996 -2.00521004 0 P 0 
L 1.24313996 -2.00521004 1.24261004 -2.03151004 0 P 0 
L 1.24261004 -2.03151004 1.24086998 -2.07046004 0 P 0 
L 1.24086998 -2.07046004 1.23873996 -2.10921004 0 P 0 
L 1.23873996 -2.10921004 1.23811998 -2.11641998 0 P 0 
L 1.23811998 -2.11641998 1.23711998 -2.12361998 0 P 0 
L 1.23711998 -2.12361998 1.23655 -2.12716004 0 P 0 
L 1.23655 -2.12716004 1.29205 -2.12716004 0 P 0 
L 1.29205 -2.12716004 1.29206998 -2.11766004 0 P 0 
L 1.29206998 -2.11766004 1.29238996 -2.10283996 0 P 0 
L 1.29238996 -2.10283996 1.29336004 -2.08431004 0 P 0 
L 1.29336004 -2.08431004 1.29463996 -2.06673002 0 P 0 
L 1.29463996 -2.06673002 1.29511004 -2.06253002 0 P 0 
L 1.29511004 -2.06253002 1.29583996 -2.05836004 0 P 0 
L 1.29583996 -2.05836004 1.29683002 -2.05446998 0 P 0 
L 1.29683002 -2.05446998 1.29813996 -2.05068996 0 P 0 
L 1.29813996 -2.05068996 1.29978002 -2.04701998 0 P 0 
L 1.29978002 -2.04701998 1.30056998 -2.04556998 0 P 0 
L 1.30056998 -2.04556998 1.30146998 -2.04418996 0 P 0 
L 1.30146998 -2.04418996 1.30246998 -2.04288002 0 P 0 
L 1.30246998 -2.04288002 1.30356998 -2.04165 0 P 0 
L 1.30356998 -2.04165 1.30475 -2.0405 0 P 0 
L 1.30475 -2.0405 1.30603996 -2.03945 0 P 0 
L 1.30603996 -2.03945 1.30773996 -2.03826004 0 P 0 
L 1.30773996 -2.03826004 1.30953002 -2.03723002 0 P 0 
L 1.30953002 -2.03723002 1.31141004 -2.03635 0 P 0 
L 1.31141004 -2.03635 1.31335 -2.03563002 0 P 0 
L 1.31335 -2.03563002 1.31535 -2.03508002 0 P 0 
L 1.31535 -2.03508002 1.31973996 -2.03423002 0 P 0 
L 1.31973996 -2.03423002 1.32416004 -2.03366998 0 P 0 
L 1.32416004 -2.03366998 1.32863002 -2.0334 0 P 0 
L 1.32863002 -2.0334 1.33688002 -2.03318002 0 P 0 
L 1.33688002 -2.03318002 1.33613002 -2.01151004 0 P 0 
L 1.33613002 -2.01151004 1.33581004 -2.00315 0 P 0 
L 1.33581004 -2.00315 1.33543996 -1.99596004 0 P 0 
L 1.33543996 -1.99596004 1.33508002 -1.98971004 0 P 0 
L 1.33508002 -1.98971004 1.33503996 -1.98945 0 P 0 
L 1.33503996 -1.98945 1.335 -1.98931998 0 P 0 
L 1.335 -1.98931998 1.33496004 -1.9892 0 P 0 
L 1.33496004 -1.9892 1.3349 -1.98908002 0 P 0 
L 1.3349 -1.98908002 1.33483996 -1.98896998 0 P 0 
L 1.33483996 -1.98896998 1.33476998 -1.98886004 0 P 0 
L 1.33476998 -1.98886004 1.33468996 -1.98876004 0 P 0 
L 1.33468996 -1.98876004 1.3346 -1.98866998 0 P 0 
L 1.3346 -1.98866998 1.33451004 -1.98858996 0 P 0 
L 1.33451004 -1.98858996 1.3344 -1.98851998 0 P 0 
L 1.3344 -1.98851998 1.3343 -1.98845 0 P 0 
L 1.3343 -1.98845 1.33418002 -1.98838996 0 P 0 
L 1.33418002 -1.98838996 1.33406998 -1.98833996 0 P 0 
L 1.33406998 -1.98833996 1.33395 -1.9883 0 P 0 
L 1.33395 -1.9883 1.33383002 -1.98828002 0 P 0 
L 1.33383002 -1.98828002 1.3337 -1.98826004 0 P 0 
L 1.3337 -1.98826004 1.33356998 -1.98825 0 P 0 
L 1.33356998 -1.98825 1.32756998 -1.98823002 0 P 0 
L 1.32756998 -1.98823002 1.32135 -1.98853996 0 P 0 
L 1.32135 -1.98853996 1.31878996 -1.98881998 0 P 0 
L 1.31878996 -1.98881998 1.31623996 -1.98923996 0 P 0 
L 1.2389 -2.12516004 1.29006004 -2.12516004 0 P 0 
L 1.23906998 -2.12416004 1.29006004 -2.12416004 0 P 0 
L 1.23921004 -2.12316004 1.29006004 -2.12316004 0 P 0 
L 1.23933996 -2.12216004 1.29006004 -2.12216004 0 P 0 
L 1.23948996 -2.12116004 1.29006004 -2.12116004 0 P 0 
L 1.23961998 -2.12016004 1.29006998 -2.12016004 0 P 0 
L 1.23976004 -2.11916004 1.29006998 -2.11916004 0 P 0 
L 1.2399 -2.11816004 1.29006998 -2.11816004 0 P 0 
L 1.24003996 -2.11716004 1.29008002 -2.11716004 0 P 0 
L 1.24015 -2.11616004 1.2901 -2.11616004 0 P 0 
L 1.24023996 -2.11516004 1.29011998 -2.11516004 0 P 0 
L 1.24033002 -2.11416004 1.29013996 -2.11416004 0 P 0 
L 1.24041004 -2.11316004 1.29016004 -2.11316004 0 P 0 
L 1.24048996 -2.11216004 1.29018996 -2.11216004 0 P 0 
L 1.24058002 -2.11116004 1.29021004 -2.11116004 0 P 0 
L 1.24066998 -2.11016004 1.29023002 -2.11016004 0 P 0 
L 1.24075 -2.10916004 1.29025 -2.10916004 0 P 0 
L 1.2408 -2.10816004 1.29026998 -2.10816004 0 P 0 
L 1.24086004 -2.10716004 1.29028996 -2.10716004 0 P 0 
L 1.24091004 -2.10616004 1.29031998 -2.10616004 0 P 0 
L 1.24096998 -2.10516004 1.29033996 -2.10516004 0 P 0 
L 1.24101998 -2.10416004 1.29036004 -2.10416004 0 P 0 
L 1.24108002 -2.10316004 1.29038002 -2.10316004 0 P 0 
L 1.24113002 -2.10216004 1.29041998 -2.10216004 0 P 0 
L 1.24118002 -2.10116004 1.29046998 -2.10116004 0 P 0 
L 1.24123996 -2.10016004 1.29053002 -2.10016004 0 P 0 
L 1.24128996 -2.09916004 1.29058002 -2.09916004 0 P 0 
L 1.24135 -2.09816004 1.29063002 -2.09816004 0 P 0 
L 1.2414 -2.09716004 1.29068002 -2.09716004 0 P 0 
L 1.24146004 -2.09616004 1.29073996 -2.09616004 0 P 0 
L 1.24151004 -2.09516004 1.29078996 -2.09516004 0 P 0 
L 1.24156998 -2.09416004 1.29083996 -2.09416004 0 P 0 
L 1.24161998 -2.09316004 1.2909 -2.09316004 0 P 0 
L 1.24168002 -2.09216004 1.29095 -2.09216004 0 P 0 
L 1.24173002 -2.09116004 1.291 -2.09116004 0 P 0 
L 1.24178996 -2.09016004 1.29105 -2.09016004 0 P 0 
L 1.24183996 -2.08916004 1.2911 -2.08916004 0 P 0 
L 1.2419 -2.08816004 1.29116004 -2.08816004 0 P 0 
L 1.24196004 -2.08716004 1.29121004 -2.08716004 0 P 0 
L 1.24201004 -2.08616004 1.29126998 -2.08616004 0 P 0 
L 1.24206998 -2.08516004 1.29131998 -2.08516004 0 P 0 
L 1.24211998 -2.08416004 1.29136998 -2.08416004 0 P 0 
L 1.2389 -2.12516004 1.2391 -2.12393002 0 P 0 
L 1.2391 -2.12393002 1.2391 -2.1239 0 P 0 
L 1.2391 -2.1239 1.24011004 -2.11665 0 P 0 
L 1.24011004 -2.11665 1.24073002 -2.10935 0 P 0 
L 1.24073002 -2.10935 1.24073996 -2.10931998 0 P 0 
L 1.24073996 -2.10931998 1.24286004 -2.07056004 0 P 0 
L 1.24286004 -2.07056004 1.24461004 -2.03158002 0 P 0 
L 1.24461004 -2.03158002 1.24513996 -2.00523002 0 P 0 
L 1.24513996 -2.00523002 1.24515 -1.99443996 0 P 0 
L 1.24515 -1.99443996 1.29005 -1.99443996 0 P 0 
L 1.29005 -1.99443996 1.29005 -2.00375 0 P 0 
L 1.29005 -2.00375 1.29128002 -2.0056 0 P 0 
L 1.29128002 -2.0056 1.29345 -2.00518002 0 P 0 
L 1.29345 -2.00518002 1.29803002 -2.0007 0 P 0 
L 1.29803002 -2.0007 1.29991998 -1.999 0 P 0 
L 1.29991998 -1.999 1.30188996 -1.99748996 0 P 0 
L 1.30188996 -1.99748996 1.30411998 -1.99603996 0 P 0 
L 1.30411998 -1.99603996 1.30645 -1.99475 0 P 0 
L 1.30645 -1.99475 1.30891998 -1.99358996 0 P 0 
L 1.30891998 -1.99358996 1.31145 -1.9926 0 P 0 
L 1.31145 -1.9926 1.31401998 -1.99181004 0 P 0 
L 1.31401998 -1.99181004 1.31663996 -1.9912 0 P 0 
L 1.31663996 -1.9912 1.31906004 -1.9908 0 P 0 
L 1.31906004 -1.9908 1.32151004 -1.99053002 0 P 0 
L 1.32151004 -1.99053002 1.32761998 -1.99023002 0 P 0 
L 1.32761998 -1.99023002 1.3331 -1.99025 0 P 0 
L 1.3331 -1.99025 1.33345 -1.99608002 0 P 0 
L 1.33345 -1.99608002 1.33381004 -2.00323002 0 P 0 
L 1.33381004 -2.00323002 1.33413002 -2.01158996 0 P 0 
L 1.33413002 -2.01158996 1.33413002 -2.0116 0 P 0 
L 1.33413002 -2.0116 1.33481998 -2.03123002 0 P 0 
L 1.33481998 -2.03123002 1.32853996 -2.0314 0 P 0 
L 1.32853996 -2.0314 1.32398002 -2.03166998 0 P 0 
L 1.32398002 -2.03166998 1.31941998 -2.03225 0 P 0 
L 1.31941998 -2.03225 1.31488996 -2.03313002 0 P 0 
L 1.31488996 -2.03313002 1.31273996 -2.03373002 0 P 0 
L 1.31273996 -2.03373002 1.31063996 -2.0345 0 P 0 
L 1.31063996 -2.0345 1.3086 -2.03545 0 P 0 
L 1.3086 -2.03545 1.30666004 -2.03656998 0 P 0 
L 1.30666004 -2.03656998 1.30658996 -2.03661998 0 P 0 
L 1.30658996 -2.03661998 1.30483002 -2.03786004 0 P 0 
L 1.30483002 -2.03786004 1.30341998 -2.03901004 0 P 0 
L 1.30341998 -2.03901004 1.30336998 -2.03906004 0 P 0 
L 1.30336998 -2.03906004 1.30211998 -2.04026004 0 P 0 
L 1.30211998 -2.04026004 1.30093002 -2.0416 0 P 0 
L 1.30093002 -2.0416 1.29983002 -2.04303996 0 P 0 
L 1.29983002 -2.04303996 1.29978996 -2.0431 0 P 0 
L 1.29978996 -2.0431 1.29885 -2.04453996 0 P 0 
L 1.29885 -2.04453996 1.29798996 -2.04613002 0 P 0 
L 1.29798996 -2.04613002 1.29631998 -2.04986998 0 P 0 
L 1.29631998 -2.04986998 1.29628002 -2.04995 0 P 0 
L 1.29628002 -2.04995 1.29625 -2.05003002 0 P 0 
L 1.29625 -2.05003002 1.29491998 -2.0539 0 P 0 
L 1.29491998 -2.0539 1.29388996 -2.05793996 0 P 0 
L 1.29388996 -2.05793996 1.29386998 -2.05801998 0 P 0 
L 1.29386998 -2.05801998 1.29313996 -2.06221004 0 P 0 
L 1.29313996 -2.06221004 1.29313002 -2.06223996 0 P 0 
L 1.29313002 -2.06223996 1.29311998 -2.0623 0 P 0 
L 1.29311998 -2.0623 1.29265 -2.06655 0 P 0 
L 1.29265 -2.06655 1.29136998 -2.08418996 0 P 0 
L 1.29136998 -2.08418996 1.29038996 -2.10276998 0 P 0 
L 1.29038996 -2.10276998 1.29006998 -2.11763002 0 P 0 
L 1.29006998 -2.11763002 1.29006004 -2.12516004 0 P 0 
L 1.29006004 -2.12516004 1.2389 -2.12516004 0 P 0 
L 1.09846998 -2.00483002 1.21248002 -2.00483002 0 P 0 
L 1.09838002 -2.12083002 1.14708002 -2.12083002 0 P 0 
L 1.11933002 -2.18283002 1.15161998 -2.18283002 0 P 0 
L 1.11001998 -2.18183002 1.15838002 -2.18183002 0 P 0 
L 1.10246998 -2.18083002 1.16333996 -2.18083002 0 P 0 
L 1.04061004 -1.89731004 1.09978002 -1.89731004 0 P 0 
L 1.03565 -1.89631004 1.09821004 -1.89631004 0 P 0 
L 1.03068996 -1.89531004 1.09661004 -1.89531004 0 P 0 
L 1.02573002 -1.89431004 1.09475 -1.89431004 0 P 0 
L 1.019 -1.89331004 1.09288002 -1.89331004 0 P 0 
L 1.01163996 -1.89231004 1.09101998 -1.89231004 0 P 0 
L 0.99518996 -1.89131004 1.08916004 -1.89131004 0 P 0 
L 0.87011998 -1.88331004 1.07278996 -1.88331004 0 P 0 
L 0.86963996 -1.88231004 1.07053002 -1.88231004 0 P 0 
L 0.86916004 -1.88131004 1.06828002 -1.88131004 0 P 0 
L 0.86863002 -1.88031004 1.06603002 -1.88031004 0 P 0 
L 0.86806998 -1.87931004 1.06351004 -1.87931004 0 P 0 
L 0.8675 -1.87831004 1.06076998 -1.87831004 0 P 0 
L 0.86693002 -1.87731004 1.05803996 -1.87731004 0 P 0 
L 0.86631004 -1.87631004 1.05531004 -1.87631004 0 P 0 
L 0.86563996 -1.87531004 1.05256998 -1.87531004 0 P 0 
L 0.86498002 -1.87431004 1.04983996 -1.87431004 0 P 0 
L 0.86431998 -1.87331004 1.0471 -1.87331004 0 P 0 
L 0.86356004 -1.87231004 1.04376004 -1.87231004 0 P 0 
L 0.86278996 -1.87131004 1.04041998 -1.87131004 0 P 0 
L 0.86203002 -1.87031004 1.03708002 -1.87031004 0 P 0 
L 0.86118996 -1.86931004 1.03373996 -1.86931004 0 P 0 
L 0.8603 -1.86831004 1.0304 -1.86831004 0 P 0 
L 0.85941004 -1.86731004 1.02656998 -1.86731004 0 P 0 
L 0.8585 -1.86631004 1.02231998 -1.86631004 0 P 0 
L 0.85756998 -1.86531004 1.01806998 -1.86531004 0 P 0 
L 0.85663002 -1.86431004 1.01381998 -1.86431004 0 P 0 
L 0.85568996 -1.86331004 1.00931998 -1.86331004 0 P 0 
L 0.85481004 -1.86231004 1.00335 -1.86231004 0 P 0 
L 0.85916998 -1.86131004 0.99738002 -1.86131004 0 P 0 
L 0.86716998 -1.86031004 0.99141998 -1.86031004 0 P 0 
L 0.87476998 -1.89731004 0.89943002 -1.89731004 0 P 0 
L 0.87453996 -1.89631004 0.90426004 -1.89631004 0 P 0 
L 0.87431004 -1.89531004 0.9097 -1.89531004 0 P 0 
L 0.87406998 -1.89431004 0.91608002 -1.89431004 0 P 0 
L 0.87383002 -1.89331004 0.92246004 -1.89331004 0 P 0 
L 0.87355 -1.89231004 0.93086004 -1.89231004 0 P 0 
L 0.87323002 -1.89131004 0.95553002 -1.89131004 0 P 0 
L 0.87291004 -1.89031004 1.08728996 -1.89031004 0 P 0 
L 0.87258996 -1.88931004 1.08543002 -1.88931004 0 P 0 
L 0.87223002 -1.88831004 1.08356998 -1.88831004 0 P 0 
L 0.87183002 -1.88731004 1.0817 -1.88731004 0 P 0 
L 0.87143002 -1.88631004 1.07955 -1.88631004 0 P 0 
L 0.87103002 -1.88531004 1.07728996 -1.88531004 0 P 0 
L 0.8706 -1.88431004 1.07503996 -1.88431004 0 P 0 
L 0.87525 -1.85931004 0.98545 -1.85931004 0 P 0 
L 0.88421004 -1.85831004 0.97621004 -1.85831004 0 P 0 
L 0.89393002 -1.85731004 0.96606998 -1.85731004 0 P 0 
L 0.9106 -1.85631004 0.95203002 -1.85631004 0 P 0 
L 1.08716004 -1.91231004 1.12151004 -1.91231004 0 P 0 
L 1.08486004 -1.91131004 1.12018996 -1.91131004 0 P 0 
L 1.08256004 -1.91031004 1.11886004 -1.91031004 0 P 0 
L 1.08023002 -1.90931004 1.11753996 -1.90931004 0 P 0 
L 1.07738002 -1.90831004 1.11621004 -1.90831004 0 P 0 
L 1.07453002 -1.90731004 1.11488996 -1.90731004 0 P 0 
L 1.07168996 -1.90631004 1.11356998 -1.90631004 0 P 0 
L 1.06883996 -1.90531004 1.11223996 -1.90531004 0 P 0 
L 1.066 -1.90431004 1.11076998 -1.90431004 0 P 0 
L 1.06315 -1.90331004 1.1092 -1.90331004 0 P 0 
L 1.0599 -1.90231004 1.10763002 -1.90231004 0 P 0 
L 1.05611998 -1.90131004 1.10606004 -1.90131004 0 P 0 
L 1.05235 -1.90031004 1.10448996 -1.90031004 0 P 0 
L 1.04856998 -1.89931004 1.10291998 -1.89931004 0 P 0 
L 1.04478996 -1.89831004 1.10135 -1.89831004 0 P 0 
L 0.98815 -2.08316004 1.03726998 -2.08316004 0 P 0 
L 0.98818002 -2.08216004 1.03731004 -2.08216004 0 P 0 
L 0.98821998 -2.08116004 1.03735 -2.08116004 0 P 0 
L 0.98825 -2.08016004 1.03738996 -2.08016004 0 P 0 
L 0.98828002 -2.07916004 1.03743002 -2.07916004 0 P 0 
L 0.98831998 -2.07816004 1.03746998 -2.07816004 0 P 0 
L 0.98835 -2.07716004 1.03751004 -2.07716004 0 P 0 
L 0.98838002 -2.07616004 1.03755 -2.07616004 0 P 0 
L 0.98841998 -2.07516004 1.03758002 -2.07516004 0 P 0 
L 0.98845 -2.07416004 1.03761004 -2.07416004 0 P 0 
L 0.98848002 -2.07316004 1.03763996 -2.07316004 0 P 0 
L 0.98851004 -2.07216004 1.03768002 -2.07216004 0 P 0 
L 0.98855 -2.07116004 1.03771004 -2.07116004 0 P 0 
L 0.98858002 -2.07016004 1.03773996 -2.07016004 0 P 0 
L 0.98858996 -2.06916004 1.03776998 -2.06916004 0 P 0 
L 0.98858996 -2.06816004 1.0378 -2.06816004 0 P 0 
L 0.98858996 -2.06716004 1.03783002 -2.06716004 0 P 0 
L 0.98858002 -2.06616004 1.03786004 -2.06616004 0 P 0 
L 0.98856998 -2.06516004 1.0379 -2.06516004 0 P 0 
L 0.98856998 -2.06416004 1.03793002 -2.06416004 0 P 0 
L 0.98856998 -2.06316004 1.03796004 -2.06316004 0 P 0 
L 0.98856004 -2.06216004 1.03798996 -2.06216004 0 P 0 
L 0.98855 -2.06116004 1.03801998 -2.06116004 0 P 0 
L 0.98855 -2.06016004 1.03805 -2.06016004 0 P 0 
L 0.98853996 -2.05916004 1.03808002 -2.05916004 0 P 0 
L 0.98853996 -2.05816004 1.0381 -2.05816004 0 P 0 
L 0.98853002 -2.05716004 1.03811998 -2.05716004 0 P 0 
L 0.98848002 -2.05616004 1.03815 -2.05616004 0 P 0 
L 0.98841004 -2.05516004 1.03818002 -2.05516004 0 P 0 
L 0.98835 -2.05416004 1.0382 -2.05416004 0 P 0 
L 0.98828002 -2.05316004 1.03821998 -2.05316004 0 P 0 
L 0.98821004 -2.05216004 1.03825 -2.05216004 0 P 0 
L 0.98815 -2.05116004 1.03826998 -2.05116004 0 P 0 
L 0.98808996 -2.05016004 1.03828996 -2.05016004 0 P 0 
L 0.98801998 -2.04916004 1.03831998 -2.04916004 0 P 0 
L 0.98796004 -2.04816004 1.03833996 -2.04816004 0 P 0 
L 0.98788996 -2.04716004 1.03836004 -2.04716004 0 P 0 
L 0.98783002 -2.04616004 1.03838996 -2.04616004 0 P 0 
L 0.98768996 -2.04516004 1.0384 -2.04516004 0 P 0 
L 0.98756004 -2.04416004 1.03841004 -2.04416004 0 P 0 
L 0.98738002 -2.04316004 1.03841998 -2.04316004 0 P 0 
L 0.98716004 -2.04216004 1.03843002 -2.04216004 0 P 0 
L 0.98691998 -2.04116004 1.03843996 -2.04116004 0 P 0 
L 0.98661998 -2.04016004 1.03845 -2.04016004 0 P 0 
L 0.98631998 -2.03916004 1.03846004 -2.03916004 0 P 0 
L 0.98593996 -2.03816004 1.03846998 -2.03816004 0 P 0 
L 0.98546998 -2.03716004 1.03848002 -2.03716004 0 P 0 
L 0.98491004 -2.03616004 1.03846998 -2.03616004 0 P 0 
L 0.98425 -2.03516004 1.03846004 -2.03516004 0 P 0 
L 0.98346004 -2.03416004 1.03846004 -2.03416004 0 P 0 
L 0.98251998 -2.03316004 1.03843996 -2.03316004 0 P 0 
L 0.98138002 -2.03216004 1.03843002 -2.03216004 0 P 0 
L 0.97998996 -2.03116004 1.03841998 -2.03116004 0 P 0 
L 0.97813996 -2.03016004 1.03841004 -2.03016004 0 P 0 
L 0.97491004 -2.02916004 1.0384 -2.02916004 0 P 0 
L 0.94763996 -2.00716004 1.03293996 -2.00716004 0 P 0 
L 0.94978996 -2.00616004 1.03231998 -2.00616004 0 P 0 
L 0.95081004 -2.00516004 1.0317 -2.00516004 0 P 0 
L 0.95183002 -2.00416004 1.03098002 -2.00416004 0 P 0 
L 0.95285 -2.00316004 1.03023002 -2.00316004 0 P 0 
L 0.95388996 -2.00216004 1.02936004 -2.00216004 0 P 0 
L 0.95498002 -2.00116004 1.02841998 -2.00116004 0 P 0 
L 0.95621998 -2.00016004 1.02738996 -2.00016004 0 P 0 
L 0.95761998 -1.99916004 1.0262 -1.99916004 0 P 0 
L 0.9592 -1.99816004 1.02486004 -1.99816004 0 P 0 
L 0.96083996 -1.99716004 1.02335 -1.99716004 0 P 0 
L 0.9627 -1.99616004 1.02161004 -1.99616004 0 P 0 
L 0.96468996 -1.99516004 1.01951998 -1.99516004 0 P 0 
L 0.96685 -1.99416004 1.01683002 -1.99416004 0 P 0 
L 0.96936998 -1.99316004 1.01378002 -1.99316004 0 P 0 
L 0.97236998 -1.99216004 1.00981004 -1.99216004 0 P 0 
L 0.97676004 -1.99116004 1.00456998 -1.99116004 0 P 0 
L 1.06713996 -2.08283002 1.12288002 -2.08283002 0 P 0 
L 1.06698996 -2.08183002 1.12193996 -2.08183002 0 P 0 
L 1.06686004 -2.08083002 1.12108996 -2.08083002 0 P 0 
L 1.06673996 -2.07983002 1.12036004 -2.07983002 0 P 0 
L 1.06661998 -2.07883002 1.11971998 -2.07883002 0 P 0 
L 1.06653002 -2.07783002 1.11916004 -2.07783002 0 P 0 
L 1.06648002 -2.07683002 1.11866004 -2.07683002 0 P 0 
L 1.06641998 -2.07583002 1.11826004 -2.07583002 0 P 0 
L 1.06636998 -2.07483002 1.11791998 -2.07483002 0 P 0 
L 1.06631998 -2.07383002 1.11761998 -2.07383002 0 P 0 
L 1.06626004 -2.07283002 1.11741998 -2.07283002 0 P 0 
L 1.06621004 -2.07183002 1.11723996 -2.07183002 0 P 0 
L 1.06616004 -2.07083002 1.11711998 -2.07083002 0 P 0 
L 1.06616004 -2.06983002 1.11701004 -2.06983002 0 P 0 
L 1.06616004 -2.06883002 1.11688996 -2.06883002 0 P 0 
L 1.06616998 -2.06783002 1.11676998 -2.06783002 0 P 0 
L 1.06618002 -2.06683002 1.11666998 -2.06683002 0 P 0 
L 1.06618996 -2.06583002 1.11663002 -2.06583002 0 P 0 
L 1.0662 -2.06483002 1.11658996 -2.06483002 0 P 0 
L 1.06621004 -2.06383002 1.11656004 -2.06383002 0 P 0 
L 1.06623002 -2.06283002 1.11651998 -2.06283002 0 P 0 
L 1.06631004 -2.06183002 1.11648996 -2.06183002 0 P 0 
L 1.06638002 -2.06083002 1.11653002 -2.06083002 0 P 0 
L 1.06645 -2.05983002 1.11656998 -2.05983002 0 P 0 
L 1.06651998 -2.05883002 1.11661998 -2.05883002 0 P 0 
L 1.06658996 -2.05783002 1.11666004 -2.05783002 0 P 0 
L 1.06666998 -2.05683002 1.11671004 -2.05683002 0 P 0 
L 1.06673996 -2.05583002 1.11681004 -2.05583002 0 P 0 
L 1.06686004 -2.05483002 1.11693002 -2.05483002 0 P 0 
L 1.067 -2.05383002 1.11705 -2.05383002 0 P 0 
L 1.06713996 -2.05283002 1.11718002 -2.05283002 0 P 0 
L 1.06728002 -2.05183002 1.11731004 -2.05183002 0 P 0 
L 1.06741998 -2.05083002 1.11746004 -2.05083002 0 P 0 
L 1.06756004 -2.04983002 1.11766004 -2.04983002 0 P 0 
L 1.0677 -2.04883002 1.11786004 -2.04883002 0 P 0 
L 1.06786004 -2.04783002 1.11813996 -2.04783002 0 P 0 
L 1.06806998 -2.04683002 1.11841998 -2.04683002 0 P 0 
L 1.06828002 -2.04583002 1.11876998 -2.04583002 0 P 0 
L 1.06848996 -2.04483002 1.11913002 -2.04483002 0 P 0 
L 1.06871004 -2.04383002 1.11955 -2.04383002 0 P 0 
L 1.06898996 -2.04283002 1.11998996 -2.04283002 0 P 0 
L 1.06928002 -2.04183002 1.12048002 -2.04183002 0 P 0 
L 1.06956004 -2.04083002 1.12101004 -2.04083002 0 P 0 
L 1.06985 -2.03983002 1.12161998 -2.03983002 0 P 0 
L 1.07021004 -2.03883002 1.12225 -2.03883002 0 P 0 
L 1.07056998 -2.03783002 1.12298002 -2.03783002 0 P 0 
L 1.07093002 -2.03683002 1.12373996 -2.03683002 0 P 0 
L 1.07128996 -2.03583002 1.12461998 -2.03583002 0 P 0 
L 1.07173002 -2.03483002 1.12548996 -2.03483002 0 P 0 
L 1.07216998 -2.03383002 1.12646004 -2.03383002 0 P 0 
L 1.07261998 -2.03283002 1.12748996 -2.03283002 0 P 0 
L 1.07308002 -2.03183002 1.12855 -2.03183002 0 P 0 
L 1.07361998 -2.03083002 1.12978996 -2.03083002 0 P 0 
L 1.09761004 -1.91731004 1.12756998 -1.91731004 0 P 0 
L 1.09566004 -1.91631004 1.12645 -1.91631004 0 P 0 
L 1.09371004 -1.91531004 1.12533002 -1.91531004 0 P 0 
L 1.09176004 -1.91431004 1.12416004 -1.91431004 0 P 0 
L 1.08946004 -1.91331004 1.12283996 -1.91331004 0 P 0 
L 1.07415 -2.02983002 1.13101998 -2.02983002 0 P 0 
L 1.07468996 -2.02883002 1.13248996 -2.02883002 0 P 0 
L 1.07528996 -2.02783002 1.134 -2.02783002 0 P 0 
L 1.07591998 -2.02683002 1.13586004 -2.02683002 0 P 0 
L 1.07656004 -2.02583002 1.13828996 -2.02583002 0 P 0 
L 1.07721004 -2.02483002 1.14243002 -2.02483002 0 P 0 
L 1.07795 -2.02383002 1.21126998 -2.02383002 0 P 0 
L 1.07868002 -2.02283002 1.21133002 -2.02283002 0 P 0 
L 1.07941998 -2.02183002 1.2114 -2.02183002 0 P 0 
L 1.08021004 -2.02083002 1.21146004 -2.02083002 0 P 0 
L 1.08103996 -2.01983002 1.21153002 -2.01983002 0 P 0 
L 1.08186998 -2.01883002 1.2116 -2.01883002 0 P 0 
L 1.08273002 -2.01783002 1.21166004 -2.01783002 0 P 0 
L 1.08366998 -2.01683002 1.21173002 -2.01683002 0 P 0 
L 1.0846 -2.01583002 1.2118 -2.01583002 0 P 0 
L 1.08555 -2.01483002 1.21186004 -2.01483002 0 P 0 
L 1.08661004 -2.01383002 1.21193002 -2.01383002 0 P 0 
L 1.08766998 -2.01283002 1.21198996 -2.01283002 0 P 0 
L 1.08873002 -2.01183002 1.21205 -2.01183002 0 P 0 
L 1.0898 -2.01083002 1.21211998 -2.01083002 0 P 0 
L 1.09098996 -2.00983002 1.21218002 -2.00983002 0 P 0 
L 1.09225 -2.00883002 1.21223996 -2.00883002 0 P 0 
L 1.09358996 -2.00783002 1.2123 -2.00783002 0 P 0 
L 1.09506998 -2.00683002 1.21236004 -2.00683002 0 P 0 
L 1.09668996 -2.00583002 1.21241998 -2.00583002 0 P 0 
L 0.98546998 -2.12516004 1.03548996 -2.12516004 0 P 0 
L 0.98558996 -2.12416004 1.03553996 -2.12416004 0 P 0 
L 0.9857 -2.12316004 1.03558002 -2.12316004 0 P 0 
L 0.98581004 -2.12216004 1.03561998 -2.12216004 0 P 0 
L 0.98591004 -2.12116004 1.03566998 -2.12116004 0 P 0 
L 0.98598996 -2.12016004 1.03571004 -2.12016004 0 P 0 
L 0.98608002 -2.11916004 1.03575 -2.11916004 0 P 0 
L 0.98616998 -2.11816004 1.0358 -2.11816004 0 P 0 
L 0.98625 -2.11716004 1.03583996 -2.11716004 0 P 0 
L 0.98633996 -2.11616004 1.03588002 -2.11616004 0 P 0 
L 0.98641998 -2.11516004 1.03593002 -2.11516004 0 P 0 
L 0.98651004 -2.11416004 1.03596998 -2.11416004 0 P 0 
L 0.9866 -2.11316004 1.03601004 -2.11316004 0 P 0 
L 0.98668002 -2.11216004 1.03605 -2.11216004 0 P 0 
L 0.98676998 -2.11116004 1.0361 -2.11116004 0 P 0 
L 0.98685 -2.11016004 1.03613996 -2.11016004 0 P 0 
L 0.98693996 -2.10916004 1.03618002 -2.10916004 0 P 0 
L 0.987 -2.10816004 1.03623002 -2.10816004 0 P 0 
L 0.98705 -2.10716004 1.03626998 -2.10716004 0 P 0 
L 0.9871 -2.10616004 1.03631004 -2.10616004 0 P 0 
L 0.98716004 -2.10516004 1.03636004 -2.10516004 0 P 0 
L 0.9872 -2.10416004 1.0364 -2.10416004 0 P 0 
L 0.98725 -2.10316004 1.03643996 -2.10316004 0 P 0 
L 0.98731004 -2.10216004 1.03648002 -2.10216004 0 P 0 
L 0.98735 -2.10116004 1.03653002 -2.10116004 0 P 0 
L 0.9874 -2.10016004 1.03656998 -2.10016004 0 P 0 
L 0.98746004 -2.09916004 1.03661004 -2.09916004 0 P 0 
L 0.98751004 -2.09816004 1.03666004 -2.09816004 0 P 0 
L 0.98755 -2.09716004 1.0367 -2.09716004 0 P 0 
L 0.9876 -2.09616004 1.03673996 -2.09616004 0 P 0 
L 0.98766004 -2.09516004 1.03678996 -2.09516004 0 P 0 
L 0.9877 -2.09416004 1.03683002 -2.09416004 0 P 0 
L 0.98775 -2.09316004 1.03686998 -2.09316004 0 P 0 
L 0.98781004 -2.09216004 1.03691998 -2.09216004 0 P 0 
L 0.98785 -2.09116004 1.03696004 -2.09116004 0 P 0 
L 0.9879 -2.09016004 1.037 -2.09016004 0 P 0 
L 0.98796004 -2.08916004 1.03703996 -2.08916004 0 P 0 
L 0.98798996 -2.08816004 1.03706998 -2.08816004 0 P 0 
L 0.98801998 -2.08716004 1.03711004 -2.08716004 0 P 0 
L 0.98805 -2.08616004 1.03715 -2.08616004 0 P 0 
L 0.98808996 -2.08516004 1.03718996 -2.08516004 0 P 0 
L 0.98811998 -2.08416004 1.03723002 -2.08416004 0 P 0 
L 1.08216998 -2.15683002 1.19803996 -2.15683002 0 P 0 
L 1.0821 -2.15583002 1.19861004 -2.15583002 0 P 0 
L 1.08201998 -2.15483002 1.19918002 -2.15483002 0 P 0 
L 1.08195 -2.15383002 1.1997 -2.15383002 0 P 0 
L 1.08188996 -2.15283002 1.20018002 -2.15283002 0 P 0 
L 1.08183002 -2.15183002 1.20066004 -2.15183002 0 P 0 
L 1.08176998 -2.15083002 1.20113996 -2.15083002 0 P 0 
L 1.08171998 -2.14983002 1.20153996 -2.14983002 0 P 0 
L 1.08166004 -2.14883002 1.20193002 -2.14883002 0 P 0 
L 1.0816 -2.14783002 1.11538996 -2.14783002 0 P 0 
L 1.08155 -2.14683002 1.10903002 -2.14683002 0 P 0 
L 1.0815 -2.14583002 1.10415 -2.14583002 0 P 0 
L 1.08146004 -2.14483002 1.09953002 -2.14483002 0 P 0 
L 1.08141004 -2.14383002 1.09563996 -2.14383002 0 P 0 
L 1.08136004 -2.14283002 1.09183996 -2.14283002 0 P 0 
L 1.08131004 -2.14183002 1.08821004 -2.14183002 0 P 0 
L 1.08133002 -2.14083002 1.08471998 -2.14083002 0 P 0 
L 1.09586998 -2.11983002 1.14965 -2.11983002 0 P 0 
L 1.09361998 -2.11883002 1.15221998 -2.11883002 0 P 0 
L 1.09158996 -2.11783002 1.20595 -2.11783002 0 P 0 
L 1.08988002 -2.11683002 1.20601004 -2.11683002 0 P 0 
L 1.08823996 -2.11583002 1.20606998 -2.11583002 0 P 0 
L 1.08678996 -2.11483002 1.20613002 -2.11483002 0 P 0 
L 1.08541004 -2.11383002 1.20618996 -2.11383002 0 P 0 
L 1.08416998 -2.11283002 1.20625 -2.11283002 0 P 0 
L 1.08295 -2.11183002 1.20631004 -2.11183002 0 P 0 
L 1.08188002 -2.11083002 1.20638002 -2.11083002 0 P 0 
L 1.08081998 -2.10983002 1.20643996 -2.10983002 0 P 0 
L 1.07986004 -2.10883002 1.2065 -2.10883002 0 P 0 
L 1.07895 -2.10783002 1.20656004 -2.10783002 0 P 0 
L 1.07803002 -2.10683002 1.20661998 -2.10683002 0 P 0 
L 1.07723996 -2.10583002 1.20666998 -2.10583002 0 P 0 
L 1.07646004 -2.10483002 1.20671998 -2.10483002 0 P 0 
L 1.07568002 -2.10383002 1.20678002 -2.10383002 0 P 0 
L 1.075 -2.10283002 1.20683002 -2.10283002 0 P 0 
L 1.07433002 -2.10183002 1.20688002 -2.10183002 0 P 0 
L 1.07366998 -2.10083002 1.20693996 -2.10083002 0 P 0 
L 1.07308996 -2.09983002 1.20698996 -2.09983002 0 P 0 
L 1.07253002 -2.09883002 1.20705 -2.09883002 0 P 0 
L 1.07198002 -2.09783002 1.2071 -2.09783002 0 P 0 
L 1.07146998 -2.09683002 1.20715 -2.09683002 0 P 0 
L 1.07101998 -2.09583002 1.2072 -2.09583002 0 P 0 
L 1.07056998 -2.09483002 1.20726004 -2.09483002 0 P 0 
L 1.07013002 -2.09383002 1.20731004 -2.09383002 0 P 0 
L 1.06976998 -2.09283002 1.20736004 -2.09283002 0 P 0 
L 1.06941998 -2.09183002 1.20741998 -2.09183002 0 P 0 
L 1.06906004 -2.09083002 1.20746998 -2.09083002 0 P 0 
L 1.06876004 -2.08983002 1.20753002 -2.08983002 0 P 0 
L 1.06848996 -2.08883002 1.13443002 -2.08883002 0 P 0 
L 1.06821998 -2.08783002 1.13068002 -2.08783002 0 P 0 
L 1.06795 -2.08683002 1.12836998 -2.08683002 0 P 0 
L 1.06771998 -2.08583002 1.1266 -2.08583002 0 P 0 
L 1.06753002 -2.08483002 1.12516004 -2.08483002 0 P 0 
L 1.06733002 -2.08383002 1.12393996 -2.08383002 0 P 0 
L 0.90273996 -1.85456998 0.89068996 -1.85558002 0 P 0 
L 0.89068996 -1.85558002 0.87421004 -1.85741998 0 P 0 
L 0.87421004 -1.85741998 0.85783002 -1.85946998 0 P 0 
L 0.85783002 -1.85946998 0.85526998 -1.8599 0 P 0 
L 0.85526998 -1.8599 0.85276004 -1.86055 0 P 0 
L 0.85276004 -1.86055 0.85255 -1.86063996 0 P 0 
L 0.85255 -1.86063996 0.85248996 -1.86068996 0 P 0 
L 0.85248996 -1.86068996 0.85243002 -1.86073002 0 P 0 
L 0.85243002 -1.86073002 0.85238002 -1.86078002 0 P 0 
L 0.85238002 -1.86078002 0.85233002 -1.86083996 0 P 0 
L 0.85233002 -1.86083996 0.85225 -1.86096004 0 P 0 
L 0.85225 -1.86096004 0.85218002 -1.8611 0 P 0 
L 0.85218002 -1.8611 0.85216004 -1.86116998 0 P 0 
L 0.85216004 -1.86116998 0.85215 -1.86123996 0 P 0 
L 0.85215 -1.86123996 0.85213996 -1.86136998 0 P 0 
L 0.85213996 -1.86136998 0.85213002 -1.86148996 0 P 0 
L 0.85213002 -1.86148996 0.85213996 -1.86161998 0 P 0 
L 0.85213996 -1.86161998 0.85215 -1.86173996 0 P 0 
L 0.85215 -1.86173996 0.85218002 -1.86186998 0 P 0 
L 0.85218002 -1.86186998 0.85221004 -1.86198996 0 P 0 
L 0.85221004 -1.86198996 0.85225 -1.8621 0 P 0 
L 0.85225 -1.8621 0.85231004 -1.86221998 0 P 0 
L 0.85231004 -1.86221998 0.85236998 -1.86233002 0 P 0 
L 0.85236998 -1.86233002 0.85281998 -1.863 0 P 0 
L 0.85281998 -1.863 0.8533 -1.86363996 0 P 0 
L 0.8533 -1.86363996 0.85383002 -1.86425 0 P 0 
L 0.85383002 -1.86425 0.85736004 -1.86801998 0 P 0 
L 0.85736004 -1.86801998 0.86013002 -1.87113002 0 P 0 
L 0.86013002 -1.87113002 0.86266004 -1.87443002 0 P 0 
L 0.86266004 -1.87443002 0.86501004 -1.87798996 0 P 0 
L 0.86501004 -1.87798996 0.86711998 -1.88171004 0 P 0 
L 0.86711998 -1.88171004 0.86896998 -1.88553996 0 P 0 
L 0.86896998 -1.88553996 0.87055 -1.8895 0 P 0 
L 0.87055 -1.8895 0.8718 -1.89343002 0 P 0 
L 0.8718 -1.89343002 0.87276004 -1.89745 0 P 0 
L 0.87276004 -1.89745 0.87371004 -1.90195 0 P 0 
L 0.87371004 -1.90195 0.87383002 -1.90236004 0 P 0 
L 0.87383002 -1.90236004 0.87396998 -1.90276004 0 P 0 
L 0.87396998 -1.90276004 0.87416004 -1.90313996 0 P 0 
L 0.87416004 -1.90313996 0.87436998 -1.90351004 0 P 0 
L 0.87436998 -1.90351004 0.87443002 -1.9036 0 P 0 
L 0.87443002 -1.9036 0.87456998 -1.90376004 0 P 0 
L 0.87456998 -1.90376004 0.87465 -1.90381998 0 P 0 
L 0.87465 -1.90381998 0.87473002 -1.90388996 0 P 0 
L 0.87473002 -1.90388996 0.87481998 -1.90393996 0 P 0 
L 0.87481998 -1.90393996 0.87491998 -1.90398996 0 P 0 
L 0.87491998 -1.90398996 0.87501004 -1.90403002 0 P 0 
L 0.87501004 -1.90403002 0.87521004 -1.90408996 0 P 0 
L 0.87521004 -1.90408996 0.87531998 -1.9041 0 P 0 
L 0.87531998 -1.9041 0.87573002 -1.90413002 0 P 0 
L 0.87573002 -1.90413002 0.87613996 -1.90411998 0 P 0 
L 0.87613996 -1.90411998 0.87653996 -1.90408002 0 P 0 
L 0.87653996 -1.90408002 0.87695 -1.90401004 0 P 0 
L 0.87695 -1.90401004 0.90756004 -1.89766998 0 P 0 
L 0.90756004 -1.89766998 0.92603996 -1.89478002 0 P 0 
L 0.92603996 -1.89478002 0.93486004 -1.89393996 0 P 0 
L 0.93486004 -1.89393996 0.94371004 -1.8935 0 P 0 
L 0.94371004 -1.8935 0.97045 -1.89308002 0 P 0 
L 0.97045 -1.89308002 0.99468996 -1.89328996 0 P 0 
L 0.99468996 -1.89328996 1.01021004 -1.89413996 0 P 0 
L 1.01021004 -1.89413996 1.0241 -1.89601998 0 P 0 
L 1.0241 -1.89601998 1.04188002 -1.89961004 0 P 0 
L 1.04188002 -1.89961004 1.06095 -1.90466004 0 P 0 
L 1.06095 -1.90466004 1.07963996 -1.91123002 0 P 0 
L 1.07963996 -1.91123002 1.09093996 -1.91613002 0 P 0 
L 1.09093996 -1.91613002 1.10186998 -1.92175 0 P 0 
L 1.10186998 -1.92175 1.11243996 -1.92806998 0 P 0 
L 1.11243996 -1.92806998 1.12163002 -1.93446998 0 P 0 
L 1.12163002 -1.93446998 1.13033002 -1.94148996 0 P 0 
L 1.13033002 -1.94148996 1.1385 -1.94911004 0 P 0 
L 1.1385 -1.94911004 1.14358996 -1.9546 0 P 0 
L 1.14358996 -1.9546 1.14825 -1.96045 0 P 0 
L 1.14825 -1.96045 1.15246998 -1.96663002 0 P 0 
L 1.15246998 -1.96663002 1.15623002 -1.97316004 0 P 0 
L 1.15623002 -1.97316004 1.15895 -1.97831004 0 P 0 
L 1.15895 -1.97831004 1.17358996 -1.97831004 0 P 0 
L 1.17358996 -1.97831004 1.17135 -1.9726 0 P 0 
L 1.17135 -1.9726 1.16696004 -1.96266998 0 P 0 
L 1.16696004 -1.96266998 1.16171998 -1.95313002 0 P 0 
L 1.16171998 -1.95313002 1.1557 -1.94406998 0 P 0 
L 1.1557 -1.94406998 1.14885 -1.93548002 0 P 0 
L 1.14885 -1.93548002 1.13778996 -1.92378002 0 P 0 
L 1.13778996 -1.92378002 1.12576998 -1.91301998 0 P 0 
L 1.12576998 -1.91301998 1.11283996 -1.90326004 0 P 0 
L 1.11283996 -1.90326004 1.09783002 -1.89368996 0 P 0 
L 1.09783002 -1.89368996 1.08213002 -1.88526998 0 P 0 
L 1.08213002 -1.88526998 1.06576998 -1.87801004 0 P 0 
L 1.06576998 -1.87801004 1.04776004 -1.87141998 0 P 0 
L 1.04776004 -1.87141998 1.02938002 -1.86591998 0 P 0 
L 1.02938002 -1.86591998 1.01058002 -1.8615 0 P 0 
L 1.01058002 -1.8615 0.98441998 -1.85711004 0 P 0 
L 0.98441998 -1.85711004 0.95781004 -1.85448996 0 P 0 
L 0.95781004 -1.85448996 0.93061004 -1.85366004 0 P 0 
L 0.93061004 -1.85366004 0.90273996 -1.85456998 0 P 0 
L 1.16015 -1.97631004 1.15798002 -1.97218996 0 P 0 
L 1.15798002 -1.97218996 1.15796004 -1.97216004 0 P 0 
L 1.15796004 -1.97216004 1.15416004 -1.96556998 0 P 0 
L 1.15416004 -1.96556998 1.15411998 -1.96551004 0 P 0 
L 1.15411998 -1.96551004 1.14986004 -1.95926004 0 P 0 
L 1.14986004 -1.95926004 1.14981998 -1.95921004 0 P 0 
L 1.14981998 -1.95921004 1.14511004 -1.9533 0 P 0 
L 1.14511004 -1.9533 1.13991998 -1.9477 0 P 0 
L 1.13991998 -1.9477 1.13986004 -1.94765 0 P 0 
L 1.13986004 -1.94765 1.13163996 -1.93998002 0 P 0 
L 1.13163996 -1.93998002 1.12283002 -1.93286004 0 P 0 
L 1.12283002 -1.93286004 1.11351998 -1.92638996 0 P 0 
L 1.11351998 -1.92638996 1.10283996 -1.92 0 P 0 
L 1.10283996 -1.92 1.0918 -1.91433002 0 P 0 
L 1.0918 -1.91433002 1.08036998 -1.90936004 0 P 0 
L 1.08036998 -1.90936004 1.06153002 -1.90273996 0 P 0 
L 1.06153002 -1.90273996 1.06146004 -1.90273002 0 P 0 
L 1.06146004 -1.90273002 1.04233002 -1.89766004 0 P 0 
L 1.04233002 -1.89766004 1.02443002 -1.89405 0 P 0 
L 1.02443002 -1.89405 1.0104 -1.89213996 0 P 0 
L 1.0104 -1.89213996 0.99475 -1.89128996 0 P 0 
L 0.99475 -1.89128996 0.97045 -1.89108002 0 P 0 
L 0.97045 -1.89108002 0.94365 -1.8915 0 P 0 
L 0.94365 -1.8915 0.94361998 -1.8915 0 P 0 
L 0.94361998 -1.8915 0.93471998 -1.89195 0 P 0 
L 0.93471998 -1.89195 0.92578996 -1.89278996 0 P 0 
L 0.92578996 -1.89278996 0.9072 -1.89571004 0 P 0 
L 0.9072 -1.89571004 0.87656998 -1.90203996 0 P 0 
L 0.87656998 -1.90203996 0.87626998 -1.9021 0 P 0 
L 0.87626998 -1.9021 0.87601998 -1.90211998 0 P 0 
L 0.87601998 -1.90211998 0.87588996 -1.90213002 0 P 0 
L 0.87588996 -1.90213002 0.87583002 -1.90198996 0 P 0 
L 0.87583002 -1.90198996 0.87573002 -1.90175 0 P 0 
L 0.87573002 -1.90175 0.87566004 -1.90146998 0 P 0 
L 0.87566004 -1.90146998 0.87471004 -1.89701004 0 P 0 
L 0.87471004 -1.89701004 0.8747 -1.89698996 0 P 0 
L 0.8747 -1.89698996 0.87373002 -1.89288996 0 P 0 
L 0.87373002 -1.89288996 0.87243002 -1.88881998 0 P 0 
L 0.87243002 -1.88881998 0.8724 -1.88876004 0 P 0 
L 0.8724 -1.88876004 0.8708 -1.88473996 0 P 0 
L 0.8708 -1.88473996 0.8689 -1.88078002 0 P 0 
L 0.8689 -1.88078002 0.86671998 -1.87693996 0 P 0 
L 0.86671998 -1.87693996 0.86428996 -1.87326004 0 P 0 
L 0.86428996 -1.87326004 0.86166998 -1.86985 0 P 0 
L 0.86166998 -1.86985 0.85883996 -1.86668002 0 P 0 
L 0.85883996 -1.86668002 0.85883002 -1.86666004 0 P 0 
L 0.85883002 -1.86666004 0.85531998 -1.86291004 0 P 0 
L 0.85531998 -1.86291004 0.85486004 -1.86238002 0 P 0 
L 0.85486004 -1.86238002 0.85466004 -1.86211998 0 P 0 
L 0.85466004 -1.86211998 0.8557 -1.86186004 0 P 0 
L 0.8557 -1.86186004 0.85811998 -1.86145 0 P 0 
L 0.85811998 -1.86145 0.87443996 -1.85941004 0 P 0 
L 0.87443996 -1.85941004 0.89088996 -1.85756998 0 P 0 
L 0.89088996 -1.85756998 0.90286004 -1.85656998 0 P 0 
L 0.90286004 -1.85656998 0.93061004 -1.85566004 0 P 0 
L 0.93061004 -1.85566004 0.95768002 -1.85648996 0 P 0 
L 0.95768002 -1.85648996 0.98416004 -1.8591 0 P 0 
L 0.98416004 -1.8591 1.01018996 -1.86346004 0 P 0 
L 1.01018996 -1.86346004 1.02886004 -1.86785 0 P 0 
L 1.02886004 -1.86785 1.04711998 -1.87331998 0 P 0 
L 1.04711998 -1.87331998 1.06501004 -1.87986004 0 P 0 
L 1.06501004 -1.87986004 1.08125 -1.88706998 0 P 0 
L 1.08125 -1.88706998 1.09681004 -1.89541998 0 P 0 
L 1.09681004 -1.89541998 1.1117 -1.9049 0 P 0 
L 1.1117 -1.9049 1.1245 -1.91456998 0 P 0 
L 1.1245 -1.91456998 1.13638996 -1.92521004 0 P 0 
L 1.13638996 -1.92521004 1.14733996 -1.93678996 0 P 0 
L 1.14733996 -1.93678996 1.15408002 -1.94525 0 P 0 
L 1.15408002 -1.94525 1.16001004 -1.95416998 0 P 0 
L 1.16001004 -1.95416998 1.16516004 -1.96355 0 P 0 
L 1.16516004 -1.96355 1.1695 -1.97336998 0 P 0 
L 1.1695 -1.97336998 1.17066004 -1.97631004 0 P 0 
L 1.17066004 -1.97631004 1.16015 -1.97631004 0 P 0 
L 0.87563002 -1.90131004 0.8801 -1.90131004 0 P 0 
L 0.87541004 -1.90031004 0.88493996 -1.90031004 0 P 0 
L 0.8752 -1.89931004 0.88976998 -1.89931004 0 P 0 
L 0.87498996 -1.89831004 0.8946 -1.89831004 0 P 0 
L 0.89423002 -2.08316004 0.94355 -2.08316004 0 P 0 
L 0.89428996 -2.08216004 0.9436 -2.08216004 0 P 0 
L 0.89435 -2.08116004 0.94365 -2.08116004 0 P 0 
L 0.89441004 -2.08016004 0.9437 -2.08016004 0 P 0 
L 0.89446004 -2.07916004 0.94375 -2.07916004 0 P 0 
L 0.89451998 -2.07816004 0.94378996 -2.07816004 0 P 0 
L 0.89458002 -2.07716004 0.94383996 -2.07716004 0 P 0 
L 0.89463996 -2.07616004 0.94388996 -2.07616004 0 P 0 
L 0.8947 -2.07516004 0.94393996 -2.07516004 0 P 0 
L 0.89475 -2.07416004 0.94398002 -2.07416004 0 P 0 
L 0.89481004 -2.07316004 0.94403002 -2.07316004 0 P 0 
L 0.89486998 -2.07216004 0.94408002 -2.07216004 0 P 0 
L 0.89493002 -2.07116004 0.94415 -2.07116004 0 P 0 
L 0.89498996 -2.07016004 0.94426004 -2.07016004 0 P 0 
L 0.89505 -2.06916004 0.94436998 -2.06916004 0 P 0 
L 0.8951 -2.06816004 0.94448002 -2.06816004 0 P 0 
L 0.89516004 -2.06716004 0.94458996 -2.06716004 0 P 0 
L 0.89521998 -2.06616004 0.9447 -2.06616004 0 P 0 
L 0.89526998 -2.06516004 0.94481004 -2.06516004 0 P 0 
L 0.89531004 -2.06416004 0.94491998 -2.06416004 0 P 0 
L 0.89535 -2.06316004 0.94503002 -2.06316004 0 P 0 
L 0.8954 -2.06216004 0.94513996 -2.06216004 0 P 0 
L 0.89543996 -2.06116004 0.94531998 -2.06116004 0 P 0 
L 0.89548996 -2.06016004 0.94551004 -2.06016004 0 P 0 
L 0.89553002 -2.05916004 0.9457 -2.05916004 0 P 0 
L 0.89558002 -2.05816004 0.94588996 -2.05816004 0 P 0 
L 0.89561998 -2.05716004 0.94608002 -2.05716004 0 P 0 
L 0.89566998 -2.05616004 0.94626998 -2.05616004 0 P 0 
L 0.89571004 -2.05516004 0.94646998 -2.05516004 0 P 0 
L 0.89575 -2.05416004 0.94666004 -2.05416004 0 P 0 
L 0.8958 -2.05316004 0.94685 -2.05316004 0 P 0 
L 0.89583996 -2.05216004 0.94708002 -2.05216004 0 P 0 
L 0.89588996 -2.05116004 0.94735 -2.05116004 0 P 0 
L 0.89593996 -2.05016004 0.94761998 -2.05016004 0 P 0 
L 0.89598002 -2.04916004 0.9479 -2.04916004 0 P 0 
L 0.89601998 -2.04816004 0.94825 -2.04816004 0 P 0 
L 0.89606998 -2.04716004 0.94858996 -2.04716004 0 P 0 
L 0.89611004 -2.04616004 0.94893002 -2.04616004 0 P 0 
L 0.89616004 -2.04516004 0.94935 -2.04516004 0 P 0 
L 0.8962 -2.04416004 0.94976998 -2.04416004 0 P 0 
L 0.89625 -2.04316004 0.9502 -2.04316004 0 P 0 
L 0.89628002 -2.04216004 0.95068996 -2.04216004 0 P 0 
L 0.89631004 -2.04116004 0.95118996 -2.04116004 0 P 0 
L 0.89633996 -2.04016004 0.95168996 -2.04016004 0 P 0 
L 0.89638002 -2.03916004 0.95228002 -2.03916004 0 P 0 
L 0.89641004 -2.03816004 0.95291004 -2.03816004 0 P 0 
L 0.89643996 -2.03716004 0.95363002 -2.03716004 0 P 0 
L 0.89646998 -2.03616004 0.95445 -2.03616004 0 P 0 
L 0.89651004 -2.03516004 0.95535 -2.03516004 0 P 0 
L 0.89653996 -2.03416004 0.95636998 -2.03416004 0 P 0 
L 0.89656998 -2.03316004 0.95756998 -2.03316004 0 P 0 
L 0.8966 -2.03216004 0.95893996 -2.03216004 0 P 0 
L 0.89663996 -2.03116004 0.96055 -2.03116004 0 P 0 
L 0.89666998 -2.03016004 0.96278002 -2.03016004 0 P 0 
L 0.8967 -2.02916004 0.96676004 -2.02916004 0 P 0 
L 0.89673996 -2.02816004 1.03838996 -2.02816004 0 P 0 
L 0.89676998 -2.02716004 1.03838002 -2.02716004 0 P 0 
L 0.8968 -2.02616004 1.03833996 -2.02616004 0 P 0 
L 0.89683996 -2.02516004 1.03828996 -2.02516004 0 P 0 
L 0.89686998 -2.02416004 1.03823002 -2.02416004 0 P 0 
L 0.8969 -2.02316004 1.03816004 -2.02316004 0 P 0 
L 0.89693996 -2.02216004 1.0381 -2.02216004 0 P 0 
L 0.89696998 -2.02116004 1.03803996 -2.02116004 0 P 0 
L 0.897 -2.02016004 1.0379 -2.02016004 0 P 0 
L 0.89703002 -2.01916004 1.03773996 -2.01916004 0 P 0 
L 0.89706004 -2.01816004 1.03751998 -2.01816004 0 P 0 
L 0.89708996 -2.01716004 1.03728002 -2.01716004 0 P 0 
L 0.89711998 -2.01616004 1.03698996 -2.01616004 0 P 0 
L 0.89713996 -2.01516004 1.03668002 -2.01516004 0 P 0 
L 0.89716998 -2.01416004 1.03631004 -2.01416004 0 P 0 
L 0.8972 -2.01316004 1.03591998 -2.01316004 0 P 0 
L 0.89721998 -2.01216004 1.03548996 -2.01216004 0 P 0 
L 0.89725 -2.01116004 1.03505 -2.01116004 0 P 0 
L 0.89726998 -2.01016004 1.03458002 -2.01016004 0 P 0 
L 0.8973 -2.00916004 1.03405 -2.00916004 0 P 0 
L 0.89733002 -2.00816004 1.03351998 -2.00816004 0 P 0 
L 0.89736004 -2.00716004 0.94676004 -2.00716004 0 P 0 
L 0.89738002 -2.00616004 0.9461 -2.00616004 0 P 0 
L 0.89741004 -2.00516004 0.94563996 -2.00516004 0 P 0 
L 0.89743996 -2.00416004 0.94563996 -2.00416004 0 P 0 
L 0.89746004 -2.00316004 0.94563996 -2.00316004 0 P 0 
L 0.89748996 -2.00216004 0.94563996 -2.00216004 0 P 0 
L 0.89751004 -2.00116004 0.94563996 -2.00116004 0 P 0 
L 0.89753996 -2.00016004 0.94563996 -2.00016004 0 P 0 
L 0.89756998 -1.99916004 0.94563996 -1.99916004 0 P 0 
L 0.8976 -1.99816004 0.94563996 -1.99816004 0 P 0 
L 0.89761998 -1.99716004 0.94563996 -1.99716004 0 P 0 
L 0.89765 -1.99616004 0.94563996 -1.99616004 0 P 0 
L 0.89768002 -1.99516004 0.94563996 -1.99516004 0 P 0 
L 0.97546998 -1.98933996 0.97236998 -1.99006004 0 P 0 
L 0.97236998 -1.99006004 0.96931998 -1.99103002 0 P 0 
L 0.96931998 -1.99103002 0.96603002 -1.99233002 0 P 0 
L 0.96603002 -1.99233002 0.96281004 -1.99383002 0 P 0 
L 0.96281004 -1.99383002 0.95976004 -1.99546998 0 P 0 
L 0.95976004 -1.99546998 0.95681004 -1.99728996 0 P 0 
L 0.95681004 -1.99728996 0.95521004 -1.99841004 0 P 0 
L 0.95521004 -1.99841004 0.95368996 -1.99963002 0 P 0 
L 0.95368996 -1.99963002 0.95223996 -2.00095 0 P 0 
L 0.95223996 -2.00095 0.94763996 -2.00546998 0 P 0 
L 0.94763996 -2.00546998 0.94763996 -1.99243996 0 P 0 
L 0.94763996 -1.99243996 0.89575 -1.99243996 0 P 0 
L 0.89575 -1.99243996 0.89505 -2.01878002 0 P 0 
L 0.89505 -2.01878002 0.89423996 -2.04316004 0 P 0 
L 0.89423996 -2.04316004 0.89321998 -2.0661 0 P 0 
L 0.89321998 -2.0661 0.89198996 -2.08728996 0 P 0 
L 0.89198996 -2.08728996 0.89055 -2.1063 0 P 0 
L 0.89055 -2.1063 0.88993996 -2.11358002 0 P 0 
L 0.88993996 -2.11358002 0.88943002 -2.11988002 0 P 0 
L 0.88943002 -2.11988002 0.88898996 -2.12533996 0 P 0 
L 0.88898996 -2.12533996 0.88896004 -2.12613002 0 P 0 
L 0.88896004 -2.12613002 0.88896998 -2.12621004 0 P 0 
L 0.88896998 -2.12621004 0.88898002 -2.12625 0 P 0 
L 0.88898002 -2.12625 0.88898996 -2.12628002 0 P 0 
L 0.88898996 -2.12628002 0.88901998 -2.12636004 0 P 0 
L 0.88901998 -2.12636004 0.88903996 -2.12638996 0 P 0 
L 0.88903996 -2.12638996 0.88906998 -2.12641998 0 P 0 
L 0.88906998 -2.12641998 0.88908996 -2.12645 0 P 0 
L 0.88908996 -2.12645 0.88911998 -2.12646998 0 P 0 
L 0.88911998 -2.12646998 0.88915 -2.1265 0 P 0 
L 0.88915 -2.1265 0.88921004 -2.12653996 0 P 0 
L 0.88921004 -2.12653996 0.88925 -2.12655 0 P 0 
L 0.88925 -2.12655 0.88928002 -2.12656004 0 P 0 
L 0.88928002 -2.12656004 0.88931998 -2.12658002 0 P 0 
L 0.88931998 -2.12658002 0.8894 -2.12658002 0 P 0 
L 0.8894 -2.12658002 0.89648002 -2.12686998 0 P 0 
L 0.89648002 -2.12686998 0.90518996 -2.1271 0 P 0 
L 0.90518996 -2.1271 0.9165 -2.12716004 0 P 0 
L 0.9165 -2.12716004 0.94403996 -2.12716004 0 P 0 
L 0.94403996 -2.12716004 0.94468996 -2.10135 0 P 0 
L 0.94468996 -2.10135 0.9461 -2.07171998 0 P 0 
L 0.9461 -2.07171998 0.94713002 -2.06233002 0 P 0 
L 0.94713002 -2.06233002 0.9489 -2.05308002 0 P 0 
L 0.9489 -2.05308002 0.94975 -2.04995 0 P 0 
L 0.94975 -2.04995 0.9508 -2.04688996 0 P 0 
L 0.9508 -2.04688996 0.95205 -2.0439 0 P 0 
L 0.95205 -2.0439 0.95351004 -2.041 0 P 0 
L 0.95351004 -2.041 0.9544 -2.03951004 0 P 0 
L 0.9544 -2.03951004 0.95541998 -2.03811004 0 P 0 
L 0.95541998 -2.03811004 0.95655 -2.03678996 0 P 0 
L 0.95655 -2.03678996 0.95778996 -2.03556998 0 P 0 
L 0.95778996 -2.03556998 0.95911998 -2.03446998 0 P 0 
L 0.95911998 -2.03446998 0.96056998 -2.03346998 0 P 0 
L 0.96056998 -2.03346998 0.96151004 -2.03291004 0 P 0 
L 0.96151004 -2.03291004 0.96248996 -2.03243002 0 P 0 
L 0.96248996 -2.03243002 0.96351004 -2.03201998 0 P 0 
L 0.96351004 -2.03201998 0.96455 -2.03168996 0 P 0 
L 0.96455 -2.03168996 0.96613002 -2.0313 0 P 0 
L 0.96613002 -2.0313 0.96773002 -2.03101998 0 P 0 
L 0.96773002 -2.03101998 0.96935 -2.03086004 0 P 0 
L 0.96935 -2.03086004 0.97095 -2.03081004 0 P 0 
L 0.97095 -2.03081004 0.97255 -2.03086998 0 P 0 
L 0.97255 -2.03086998 0.97413002 -2.03105 0 P 0 
L 0.97413002 -2.03105 0.97513002 -2.03123996 0 P 0 
L 0.97513002 -2.03123996 0.9761 -2.03151004 0 P 0 
L 0.9761 -2.03151004 0.97706004 -2.03186004 0 P 0 
L 0.97706004 -2.03186004 0.97796998 -2.0323 0 P 0 
L 0.97796998 -2.0323 0.97885 -2.0328 0 P 0 
L 0.97885 -2.0328 0.97968002 -2.03336998 0 P 0 
L 0.97968002 -2.03336998 0.98046998 -2.03398996 0 P 0 
L 0.98046998 -2.03398996 0.98121998 -2.03468002 0 P 0 
L 0.98121998 -2.03468002 0.98191004 -2.03541998 0 P 0 
L 0.98191004 -2.03541998 0.98253996 -2.0362 0 P 0 
L 0.98253996 -2.0362 0.9831 -2.03703002 0 P 0 
L 0.9831 -2.03703002 0.9836 -2.03788996 0 P 0 
L 0.9836 -2.03788996 0.98403996 -2.0388 0 P 0 
L 0.98403996 -2.0388 0.9844 -2.03973996 0 P 0 
L 0.9844 -2.03973996 0.98505 -2.04188996 0 P 0 
L 0.98505 -2.04188996 0.98553002 -2.04408002 0 P 0 
L 0.98553002 -2.04408002 0.98583002 -2.0463 0 P 0 
L 0.98583002 -2.0463 0.98653002 -2.05705 0 P 0 
L 0.98653002 -2.05705 0.9866 -2.06961004 0 P 0 
L 0.9866 -2.06961004 0.98596004 -2.08908002 0 P 0 
L 0.98596004 -2.08908002 0.98498002 -2.10858002 0 P 0 
L 0.98498002 -2.10858002 0.98388002 -2.12146998 0 P 0 
L 0.98388002 -2.12146998 0.98323002 -2.12716004 0 P 0 
L 0.98323002 -2.12716004 1.03741004 -2.12716004 0 P 0 
L 1.03741004 -2.12716004 1.03896004 -2.09103002 0 P 0 
L 1.03896004 -2.09103002 1.03956004 -2.0759 0 P 0 
L 1.03956004 -2.0759 1.04005 -2.06025 0 P 0 
L 1.04005 -2.06025 1.04038996 -2.04626004 0 P 0 
L 1.04038996 -2.04626004 1.04048002 -2.03698996 0 P 0 
L 1.04048002 -2.03698996 1.04036998 -2.02651998 0 P 0 
L 1.04036998 -2.02651998 1.04003996 -2.02096998 0 P 0 
L 1.04003996 -2.02096998 1.03975 -2.01895 0 P 0 
L 1.03975 -2.01895 1.0393 -2.01693996 0 P 0 
L 1.0393 -2.01693996 1.03868996 -2.01483996 0 P 0 
L 1.03868996 -2.01483996 1.03793996 -2.01278002 0 P 0 
L 1.03793996 -2.01278002 1.03658996 -2.00968002 0 P 0 
L 1.03658996 -2.00968002 1.03501004 -2.00668996 0 P 0 
L 1.03501004 -2.00668996 1.0332 -2.0038 0 P 0 
L 1.0332 -2.0038 1.03186998 -2.002 0 P 0 
L 1.03186998 -2.002 1.0304 -2.0003 0 P 0 
L 1.0304 -2.0003 1.0288 -1.99873002 0 P 0 
L 1.0288 -1.99873002 1.02708002 -1.99728996 0 P 0 
L 1.02708002 -1.99728996 1.02518002 -1.99593002 0 P 0 
L 1.02518002 -1.99593002 1.02318002 -1.99471998 0 P 0 
L 1.02318002 -1.99471998 1.0211 -1.99365 0 P 0 
L 1.0211 -1.99365 1.01893002 -1.99273996 0 P 0 
L 1.01893002 -1.99273996 1.01358996 -1.99098996 0 P 0 
L 1.01358996 -1.99098996 1.0081 -1.98971004 0 P 0 
L 1.0081 -1.98971004 1.00428996 -1.98908996 0 P 0 
L 1.00428996 -1.98908996 1.00043996 -1.98868002 0 P 0 
L 1.00043996 -1.98868002 0.99138002 -1.98826004 0 P 0 
L 0.99138002 -1.98826004 0.98251998 -1.98846998 0 P 0 
L 0.98251998 -1.98846998 0.97898996 -1.98878996 0 P 0 
L 0.97898996 -1.98878996 0.97546998 -1.98933996 0 P 0 
L 0.91651004 -2.12516004 0.94208996 -2.12516004 0 P 0 
L 0.8911 -2.12416004 0.94211004 -2.12416004 0 P 0 
L 0.89118002 -2.12316004 0.94213996 -2.12316004 0 P 0 
L 0.89125 -2.12216004 0.94216004 -2.12216004 0 P 0 
L 0.89133002 -2.12116004 0.94218996 -2.12116004 0 P 0 
L 0.89141004 -2.12016004 0.94221004 -2.12016004 0 P 0 
L 0.89148996 -2.11916004 0.94223996 -2.11916004 0 P 0 
L 0.89156998 -2.11816004 0.94226998 -2.11816004 0 P 0 
L 0.89166004 -2.11716004 0.94228996 -2.11716004 0 P 0 
L 0.89173996 -2.11616004 0.94231004 -2.11616004 0 P 0 
L 0.89181998 -2.11516004 0.94233996 -2.11516004 0 P 0 
L 0.8919 -2.11416004 0.94236004 -2.11416004 0 P 0 
L 0.89198002 -2.11316004 0.94238996 -2.11316004 0 P 0 
L 0.89206998 -2.11216004 0.94241998 -2.11216004 0 P 0 
L 0.89215 -2.11116004 0.94243996 -2.11116004 0 P 0 
L 0.89223002 -2.11016004 0.94246998 -2.11016004 0 P 0 
L 0.89231998 -2.10916004 0.94248996 -2.10916004 0 P 0 
L 0.8924 -2.10816004 0.94251998 -2.10816004 0 P 0 
L 0.89248002 -2.10716004 0.94255 -2.10716004 0 P 0 
L 0.89256998 -2.10616004 0.94256998 -2.10616004 0 P 0 
L 0.89263996 -2.10516004 0.94258996 -2.10516004 0 P 0 
L 0.89271004 -2.10416004 0.94261998 -2.10416004 0 P 0 
L 0.89278996 -2.10316004 0.94263996 -2.10316004 0 P 0 
L 0.89286998 -2.10216004 0.94266998 -2.10216004 0 P 0 
L 0.89293996 -2.10116004 0.9427 -2.10116004 0 P 0 
L 0.89301998 -2.10016004 0.94275 -2.10016004 0 P 0 
L 0.89308996 -2.09916004 0.94278996 -2.09916004 0 P 0 
L 0.89316998 -2.09816004 0.94283996 -2.09816004 0 P 0 
L 0.89325 -2.09716004 0.94288996 -2.09716004 0 P 0 
L 0.89331998 -2.09616004 0.94293996 -2.09616004 0 P 0 
L 0.8934 -2.09516004 0.94298002 -2.09516004 0 P 0 
L 0.89346998 -2.09416004 0.94303002 -2.09416004 0 P 0 
L 0.89355 -2.09316004 0.94308002 -2.09316004 0 P 0 
L 0.89361998 -2.09216004 0.94313002 -2.09216004 0 P 0 
L 0.8937 -2.09116004 0.94318002 -2.09116004 0 P 0 
L 0.89378002 -2.09016004 0.94321998 -2.09016004 0 P 0 
L 0.89385 -2.08916004 0.94326998 -2.08916004 0 P 0 
L 0.89393002 -2.08816004 0.94331998 -2.08816004 0 P 0 
L 0.894 -2.08716004 0.94336004 -2.08716004 0 P 0 
L 0.89406004 -2.08616004 0.94341004 -2.08616004 0 P 0 
L 0.89411998 -2.08516004 0.94346004 -2.08516004 0 P 0 
L 0.89418002 -2.08416004 0.94351004 -2.08416004 0 P 0 
L 0.91651004 -2.12516004 0.90521998 -2.1251 0 P 0 
L 0.90521998 -2.1251 0.89655 -2.12486998 0 P 0 
L 0.89655 -2.12486998 0.89106004 -2.12465 0 P 0 
L 0.89106004 -2.12465 0.89141998 -2.12003996 0 P 0 
L 0.89141998 -2.12003996 0.89193996 -2.11373996 0 P 0 
L 0.89193996 -2.11373996 0.89253996 -2.10645 0 P 0 
L 0.89253996 -2.10645 0.89398002 -2.08741998 0 P 0 
L 0.89398002 -2.08741998 0.89521998 -2.06621998 0 P 0 
L 0.89521998 -2.06621998 0.89521998 -2.06618996 0 P 0 
L 0.89521998 -2.06618996 0.89623996 -2.04323002 0 P 0 
L 0.89623996 -2.04323002 0.89703996 -2.01883002 0 P 0 
L 0.89703996 -2.01883002 0.8977 -1.99443996 0 P 0 
L 0.8977 -1.99443996 0.94563996 -1.99443996 0 P 0 
L 0.94563996 -1.99443996 0.94563996 -2.00546998 0 P 0 
L 0.94563996 -2.00546998 0.94686004 -2.00731004 0 P 0 
L 0.94686004 -2.00731004 0.94903002 -2.00688996 0 P 0 
L 0.94903002 -2.00688996 0.95361998 -2.00241004 0 P 0 
L 0.95361998 -2.00241004 0.95498996 -2.00115 0 P 0 
L 0.95498996 -2.00115 0.95641998 -2.00001004 0 P 0 
L 0.95641998 -2.00001004 0.9579 -1.99896004 0 P 0 
L 0.9579 -1.99896004 0.96076004 -1.9972 0 P 0 
L 0.96076004 -1.9972 0.9637 -1.99561998 0 P 0 
L 0.9637 -1.99561998 0.96683002 -1.99416998 0 P 0 
L 0.96683002 -1.99416998 0.96998996 -1.99291998 0 P 0 
L 0.96998996 -1.99291998 0.9729 -1.99198996 0 P 0 
L 0.9729 -1.99198996 0.97586004 -1.9913 0 P 0 
L 0.97586004 -1.9913 0.97923002 -1.99076998 0 P 0 
L 0.97923002 -1.99076998 0.98263002 -1.99046998 0 P 0 
L 0.98263002 -1.99046998 0.99136004 -1.99026004 0 P 0 
L 0.99136004 -1.99026004 1.00028996 -1.99066998 0 P 0 
L 1.00028996 -1.99066998 1.00403002 -1.99108002 0 P 0 
L 1.00403002 -1.99108002 1.00771004 -1.99166998 0 P 0 
L 1.00771004 -1.99166998 1.01305 -1.99291998 0 P 0 
L 1.01305 -1.99291998 1.01823002 -1.99461998 0 P 0 
L 1.01823002 -1.99461998 1.02026004 -1.99546998 0 P 0 
L 1.02026004 -1.99546998 1.02221004 -1.99646998 0 P 0 
L 1.02221004 -1.99646998 1.02408002 -1.9976 0 P 0 
L 1.02408002 -1.9976 1.02585 -1.99886998 0 P 0 
L 1.02585 -1.99886998 1.02746004 -2.00021004 0 P 0 
L 1.02746004 -2.00021004 1.02893996 -2.00166998 0 P 0 
L 1.02893996 -2.00166998 1.03031004 -2.00325 0 P 0 
L 1.03031004 -2.00325 1.03155 -2.00493002 0 P 0 
L 1.03155 -2.00493002 1.03326998 -2.00768002 0 P 0 
L 1.03326998 -2.00768002 1.03478002 -2.01055 0 P 0 
L 1.03478002 -2.01055 1.03608002 -2.01351998 0 P 0 
L 1.03608002 -2.01351998 1.03678996 -2.01546998 0 P 0 
L 1.03678996 -2.01546998 1.03736004 -2.01743002 0 P 0 
L 1.03736004 -2.01743002 1.03778002 -2.0193 0 P 0 
L 1.03778002 -2.0193 1.03805 -2.02116998 0 P 0 
L 1.03805 -2.02116998 1.03836998 -2.02658996 0 P 0 
L 1.03836998 -2.02658996 1.03848002 -2.03698996 0 P 0 
L 1.03848002 -2.03698996 1.03838996 -2.04623002 0 P 0 
L 1.03838996 -2.04623002 1.03805 -2.06018996 0 P 0 
L 1.03805 -2.06018996 1.03756004 -2.07583002 0 P 0 
L 1.03756004 -2.07583002 1.03696998 -2.09095 0 P 0 
L 1.03696998 -2.09095 1.03548996 -2.12516004 0 P 0 
L 1.03548996 -2.12516004 0.98546998 -2.12516004 0 P 0 
L 0.98546998 -2.12516004 0.98586998 -2.12166004 0 P 0 
L 0.98586998 -2.12166004 0.98696998 -2.10871998 0 P 0 
L 0.98696998 -2.10871998 0.98796004 -2.08916004 0 P 0 
L 0.98796004 -2.08916004 0.9886 -2.06963002 0 P 0 
L 0.9886 -2.06963002 0.98853002 -2.05698002 0 P 0 
L 0.98853002 -2.05698002 0.98781998 -2.0461 0 P 0 
L 0.98781998 -2.0461 0.9875 -2.04373002 0 P 0 
L 0.9875 -2.04373002 0.98748002 -2.04365 0 P 0 
L 0.98748002 -2.04365 0.98698996 -2.04138996 0 P 0 
L 0.98698996 -2.04138996 0.9863 -2.03908002 0 P 0 
L 0.9863 -2.03908002 0.98588002 -2.038 0 P 0 
L 0.98588002 -2.038 0.98538002 -2.03696004 0 P 0 
L 0.98538002 -2.03696004 0.9848 -2.03596004 0 P 0 
L 0.9848 -2.03596004 0.98413996 -2.03501004 0 P 0 
L 0.98413996 -2.03501004 0.98341998 -2.03411004 0 P 0 
L 0.98341998 -2.03411004 0.98336998 -2.03405 0 P 0 
L 0.98336998 -2.03405 0.98263002 -2.03326004 0 P 0 
L 0.98263002 -2.03326004 0.98176998 -2.03246998 0 P 0 
L 0.98176998 -2.03246998 0.98086998 -2.03175 0 P 0 
L 0.98086998 -2.03175 0.97991004 -2.0311 0 P 0 
L 0.97991004 -2.0311 0.9789 -2.03051998 0 P 0 
L 0.9789 -2.03051998 0.97783002 -2.03001998 0 P 0 
L 0.97783002 -2.03001998 0.97673002 -2.02961004 0 P 0 
L 0.97673002 -2.02961004 0.97663996 -2.02958002 0 P 0 
L 0.97663996 -2.02958002 0.97558996 -2.02928996 0 P 0 
L 0.97558996 -2.02928996 0.97443002 -2.02906998 0 P 0 
L 0.97443002 -2.02906998 0.9727 -2.02888002 0 P 0 
L 0.9727 -2.02888002 0.97261998 -2.02886998 0 P 0 
L 0.97261998 -2.02886998 0.97096004 -2.02881004 0 P 0 
L 0.97096004 -2.02881004 0.96921004 -2.02886004 0 P 0 
L 0.96921004 -2.02886004 0.96745 -2.02903996 0 P 0 
L 0.96745 -2.02903996 0.96571004 -2.02933996 0 P 0 
L 0.96571004 -2.02933996 0.964 -2.02976004 0 P 0 
L 0.964 -2.02976004 0.96283002 -2.03013996 0 P 0 
L 0.96283002 -2.03013996 0.96168002 -2.0306 0 P 0 
L 0.96168002 -2.0306 0.96056998 -2.03115 0 P 0 
L 0.96056998 -2.03115 0.95948996 -2.03178002 0 P 0 
L 0.95948996 -2.03178002 0.95791004 -2.03286998 0 P 0 
L 0.95791004 -2.03286998 0.95645 -2.03408996 0 P 0 
L 0.95645 -2.03408996 0.95508996 -2.03541998 0 P 0 
L 0.95508996 -2.03541998 0.95383996 -2.03686998 0 P 0 
L 0.95383996 -2.03686998 0.9538 -2.03693002 0 P 0 
L 0.9538 -2.03693002 0.95273002 -2.03841004 0 P 0 
L 0.95273002 -2.03841004 0.95175 -2.04003996 0 P 0 
L 0.95175 -2.04003996 0.95023002 -2.04306004 0 P 0 
L 0.95023002 -2.04306004 0.94896004 -2.04611004 0 P 0 
L 0.94896004 -2.04611004 0.94893002 -2.04616998 0 P 0 
L 0.94893002 -2.04616998 0.94783002 -2.04936004 0 P 0 
L 0.94783002 -2.04936004 0.94695 -2.05263002 0 P 0 
L 0.94695 -2.05263002 0.94515 -2.06203002 0 P 0 
L 0.94515 -2.06203002 0.9441 -2.07156004 0 P 0 
L 0.9441 -2.07156004 0.9427 -2.10128002 0 P 0 
L 0.9427 -2.10128002 0.94208996 -2.12516004 0 P 0 
L 0.94208996 -2.12516004 0.91651004 -2.12516004 0 P 0 
L 0.93143002 -2.21261998 1.00578996 -2.21261998 0 P 0 
L 0.94051004 -2.21161998 1.00803002 -2.21161998 0 P 0 
L 0.94941998 -2.21061998 1.01026004 -2.21061998 0 P 0 
L 0.9555 -2.20961998 1.0125 -2.20961998 0 P 0 
L 0.96158002 -2.20861998 1.01473996 -2.20861998 0 P 0 
L 0.96766004 -2.20761998 1.01696998 -2.20761998 0 P 0 
L 0.97373002 -2.20661998 1.01921004 -2.20661998 0 P 0 
L 0.97981004 -2.20561998 1.02145 -2.20561998 0 P 0 
L 0.98498996 -2.20461998 1.02368996 -2.20461998 0 P 0 
L 0.98973996 -2.20361998 1.02591998 -2.20361998 0 P 0 
L 0.99448996 -2.20261998 1.02816004 -2.20261998 0 P 0 
L 0.99923996 -2.20161998 1.0304 -2.20161998 0 P 0 
L 1.00398996 -2.20061998 1.03243996 -2.20061998 0 P 0 
L 1.00875 -2.19961998 1.0344 -2.19961998 0 P 0 
L 1.01348996 -2.19861998 1.03636998 -2.19861998 0 P 0 
L 1.0178 -2.19761998 1.03833996 -2.19761998 0 P 0 
L 1.02168996 -2.19661998 1.04031004 -2.19661998 0 P 0 
L 1.02558002 -2.19561998 1.04228002 -2.19561998 0 P 0 
L 1.02946998 -2.19461998 1.04415 -2.19461998 0 P 0 
L 1.03336004 -2.19361998 1.04596998 -2.19361998 0 P 0 
L 1.03725 -2.19261998 1.04778996 -2.19261998 0 P 0 
L 1.04113996 -2.19161998 1.0496 -2.19161998 0 P 0 
L 1.14356998 -1.98926998 1.13261004 -1.99086004 0 P 0 
L 1.13261004 -1.99086004 1.12165 -1.9934 0 P 0 
L 1.12165 -1.9934 1.11125 -1.99673002 0 P 0 
L 1.11125 -1.99673002 1.10658002 -1.99858996 0 P 0 
L 1.10658002 -1.99858996 1.10198996 -2.00071004 0 P 0 
L 1.10198996 -2.00071004 1.09653002 -2.00358996 0 P 0 
L 1.09653002 -2.00358996 1.09436998 -2.00488996 0 P 0 
L 1.09436998 -2.00488996 1.09226004 -2.00631004 0 P 0 
L 1.09226004 -2.00631004 1.09028002 -2.00781004 0 P 0 
L 1.09028002 -2.00781004 1.08836998 -2.00941998 0 P 0 
L 1.08836998 -2.00941998 1.08405 -2.0135 0 P 0 
L 1.08405 -2.0135 1.08096998 -2.01678996 0 P 0 
L 1.08096998 -2.01678996 1.07808002 -2.02026998 0 P 0 
L 1.07808002 -2.02026998 1.0754 -2.02393002 0 P 0 
L 1.0754 -2.02393002 1.07313996 -2.02748002 0 P 0 
L 1.07313996 -2.02748002 1.07116004 -2.03118996 0 P 0 
L 1.07116004 -2.03118996 1.06943996 -2.03505 0 P 0 
L 1.06943996 -2.03505 1.06795 -2.03918996 0 P 0 
L 1.06795 -2.03918996 1.06673996 -2.04343996 0 P 0 
L 1.06673996 -2.04343996 1.06583002 -2.04778002 0 P 0 
L 1.06583002 -2.04778002 1.06476998 -2.05538996 0 P 0 
L 1.06476998 -2.05538996 1.06421004 -2.06306004 0 P 0 
L 1.06421004 -2.06306004 1.06415 -2.07076004 0 P 0 
L 1.06415 -2.07076004 1.06456998 -2.0785 0 P 0 
L 1.06456998 -2.0785 1.06508996 -2.08276004 0 P 0 
L 1.06508996 -2.08276004 1.06591004 -2.08696004 0 P 0 
L 1.06591004 -2.08696004 1.06703002 -2.09108002 0 P 0 
L 1.06703002 -2.09108002 1.06833002 -2.09473002 0 P 0 
L 1.06833002 -2.09473002 1.06991998 -2.09823996 0 P 0 
L 1.06991998 -2.09823996 1.0718 -2.10161998 0 P 0 
L 1.0718 -2.10161998 1.07398002 -2.10491998 0 P 0 
L 1.07398002 -2.10491998 1.07641998 -2.10803002 0 P 0 
L 1.07641998 -2.10803002 1.07908996 -2.11095 0 P 0 
L 1.07908996 -2.11095 1.08175 -2.11345 0 P 0 
L 1.08175 -2.11345 1.08458996 -2.11573996 0 P 0 
L 1.08458996 -2.11573996 1.08758996 -2.1178 0 P 0 
L 1.08758996 -2.1178 1.09073002 -2.11963996 0 P 0 
L 1.09073002 -2.11963996 1.094 -2.12123996 0 P 0 
L 1.094 -2.12123996 1.0986 -2.12306998 0 P 0 
L 1.0986 -2.12306998 1.10331004 -2.12456004 0 P 0 
L 1.10331004 -2.12456004 1.10811004 -2.12568996 0 P 0 
L 1.10811004 -2.12568996 1.11298002 -2.12646998 0 P 0 
L 1.11298002 -2.12646998 1.1182 -2.12693002 0 P 0 
L 1.1182 -2.12693002 1.12343996 -2.12703002 0 P 0 
L 1.12343996 -2.12703002 1.12866998 -2.12676004 0 P 0 
L 1.12866998 -2.12676004 1.13388002 -2.12613002 0 P 0 
L 1.13388002 -2.12613002 1.14086004 -2.12473996 0 P 0 
L 1.14086004 -2.12473996 1.1477 -2.12273996 0 P 0 
L 1.1477 -2.12273996 1.15433996 -2.12015 0 P 0 
L 1.15433996 -2.12015 1.1545 -2.12008996 0 P 0 
L 1.1545 -2.12008996 1.15466004 -2.12003996 0 P 0 
L 1.15466004 -2.12003996 1.15483002 -2.12001004 0 P 0 
L 1.15483002 -2.12001004 1.15498996 -2.11998996 0 P 0 
L 1.15498996 -2.11998996 1.15533002 -2.11998996 0 P 0 
L 1.15533002 -2.11998996 1.15538996 -2.12 0 P 0 
L 1.15538996 -2.12 1.15545 -2.12001998 0 P 0 
L 1.15545 -2.12001998 1.15551004 -2.12003002 0 P 0 
L 1.15551004 -2.12003002 1.15556004 -2.12006004 0 P 0 
L 1.15556004 -2.12006004 1.15561004 -2.12008002 0 P 0 
L 1.15561004 -2.12008002 1.15566004 -2.12011004 0 P 0 
L 1.15566004 -2.12011004 1.15571004 -2.12015 0 P 0 
L 1.15571004 -2.12015 1.15575 -2.12018996 0 P 0 
L 1.15575 -2.12018996 1.15578996 -2.12023996 0 P 0 
L 1.15578996 -2.12023996 1.15583002 -2.12028002 0 P 0 
L 1.15583002 -2.12028002 1.15586004 -2.12033996 0 P 0 
L 1.15586004 -2.12033996 1.15588002 -2.12038996 0 P 0 
L 1.15588002 -2.12038996 1.15591004 -2.12043996 0 P 0 
L 1.15591004 -2.12043996 1.15601998 -2.12076004 0 P 0 
L 1.15601998 -2.12076004 1.1561 -2.12108002 0 P 0 
L 1.1561 -2.12108002 1.15616004 -2.12141998 0 P 0 
L 1.15616004 -2.12141998 1.15618002 -2.12175 0 P 0 
L 1.15618002 -2.12175 1.15623996 -2.12505 0 P 0 
L 1.15623996 -2.12505 1.15616004 -2.12688002 0 P 0 
L 1.15616004 -2.12688002 1.15593002 -2.12871004 0 P 0 
L 1.15593002 -2.12871004 1.15553996 -2.13051998 0 P 0 
L 1.15553996 -2.13051998 1.15516004 -2.1318 0 P 0 
L 1.15516004 -2.1318 1.1547 -2.13305 0 P 0 
L 1.1547 -2.13305 1.15415 -2.13426004 0 P 0 
L 1.15415 -2.13426004 1.15351004 -2.13545 0 P 0 
L 1.15351004 -2.13545 1.15278996 -2.1366 0 P 0 
L 1.15278996 -2.1366 1.15198002 -2.13768996 0 P 0 
L 1.15198002 -2.13768996 1.15111004 -2.13873002 0 P 0 
L 1.15111004 -2.13873002 1.15016004 -2.13971004 0 P 0 
L 1.15016004 -2.13971004 1.14876004 -2.14096004 0 P 0 
L 1.14876004 -2.14096004 1.14726004 -2.1421 0 P 0 
L 1.14726004 -2.1421 1.14566998 -2.14311004 0 P 0 
L 1.14566998 -2.14311004 1.144 -2.144 0 P 0 
L 1.144 -2.144 1.14226004 -2.14476004 0 P 0 
L 1.14226004 -2.14476004 1.14046004 -2.14536998 0 P 0 
L 1.14046004 -2.14536998 1.13863002 -2.14583002 0 P 0 
L 1.13863002 -2.14583002 1.13676004 -2.14613996 0 P 0 
L 1.13676004 -2.14613996 1.13041998 -2.14663996 0 P 0 
L 1.13041998 -2.14663996 1.12403996 -2.1466 0 P 0 
L 1.12403996 -2.1466 1.11621998 -2.14593996 0 P 0 
L 1.11621998 -2.14593996 1.10843996 -2.14471004 0 P 0 
L 1.10843996 -2.14471004 1.09946998 -2.14276998 0 P 0 
L 1.09946998 -2.14276998 1.0905 -2.14041004 0 P 0 
L 1.0905 -2.14041004 1.07963996 -2.13728996 0 P 0 
L 1.07963996 -2.13728996 1.07936004 -2.1401 0 P 0 
L 1.07936004 -2.1401 1.07931004 -2.14103996 0 P 0 
L 1.07931004 -2.14103996 1.07931998 -2.14198002 0 P 0 
L 1.07931998 -2.14198002 1.07956998 -2.14735 0 P 0 
L 1.07956998 -2.14735 1.07993996 -2.15375 0 P 0 
L 1.07993996 -2.15375 1.08045 -2.16081998 0 P 0 
L 1.08045 -2.16081998 1.08181004 -2.17873002 0 P 0 
L 1.08181004 -2.17873002 1.08996004 -2.18061004 0 P 0 
L 1.08996004 -2.18061004 1.09951004 -2.18246004 0 P 0 
L 1.09951004 -2.18246004 1.11243996 -2.18416998 0 P 0 
L 1.11243996 -2.18416998 1.1254 -2.18543002 0 P 0 
L 1.1254 -2.18543002 1.13508002 -2.18583002 0 P 0 
L 1.13508002 -2.18583002 1.14765 -2.18528996 0 P 0 
L 1.14765 -2.18528996 1.15368002 -2.18461004 0 P 0 
L 1.15368002 -2.18461004 1.15971004 -2.18363996 0 P 0 
L 1.15971004 -2.18363996 1.16521004 -2.18248002 0 P 0 
L 1.16521004 -2.18248002 1.17063996 -2.18103002 0 P 0 
L 1.17063996 -2.18103002 1.17528996 -2.17946998 0 P 0 
L 1.17528996 -2.17946998 1.17978002 -2.17753996 0 P 0 
L 1.17978002 -2.17753996 1.18216998 -2.1763 0 P 0 
L 1.18216998 -2.1763 1.18446004 -2.17488996 0 P 0 
L 1.18446004 -2.17488996 1.18663996 -2.17331004 0 P 0 
L 1.18663996 -2.17331004 1.18871004 -2.17156004 0 P 0 
L 1.18871004 -2.17156004 1.19161004 -2.16871998 0 P 0 
L 1.19161004 -2.16871998 1.19431004 -2.16568996 0 P 0 
L 1.19431004 -2.16568996 1.19678996 -2.16246998 0 P 0 
L 1.19678996 -2.16246998 1.19908996 -2.15901998 0 P 0 
L 1.19908996 -2.15901998 1.20113996 -2.15543996 0 P 0 
L 1.20113996 -2.15543996 1.20295 -2.15171004 0 P 0 
L 1.20295 -2.15171004 1.20435 -2.14815 0 P 0 
L 1.20435 -2.14815 1.20543996 -2.14448996 0 P 0 
L 1.20543996 -2.14448996 1.20621004 -2.14073996 0 P 0 
L 1.20621004 -2.14073996 1.20651998 -2.13855 0 P 0 
L 1.20651998 -2.13855 1.20671998 -2.13633996 0 P 0 
L 1.20671998 -2.13633996 1.20761998 -2.12321004 0 P 0 
L 1.20761998 -2.12321004 1.20858002 -2.10753996 0 P 0 
L 1.20858002 -2.10753996 1.20951004 -2.09021998 0 P 0 
L 1.20951004 -2.09021998 1.21048002 -2.07166004 0 P 0 
L 1.21048002 -2.07166004 1.21156004 -2.05228002 0 P 0 
L 1.21156004 -2.05228002 1.21258002 -2.03478996 0 P 0 
L 1.21258002 -2.03478996 1.21333002 -2.02286004 0 P 0 
L 1.21333002 -2.02286004 1.21393996 -2.01373996 0 P 0 
L 1.21393996 -2.01373996 1.21443996 -2.00568996 0 P 0 
L 1.21443996 -2.00568996 1.21485 -1.99883996 0 P 0 
L 1.21485 -1.99883996 1.2149 -1.99721004 0 P 0 
L 1.2149 -1.99721004 1.21488996 -1.99703996 0 P 0 
L 1.21488996 -1.99703996 1.21486998 -1.99686004 0 P 0 
L 1.21486998 -1.99686004 1.21483996 -1.99668996 0 P 0 
L 1.21483996 -1.99668996 1.21478996 -1.99653002 0 P 0 
L 1.21478996 -1.99653002 1.21473002 -1.99636998 0 P 0 
L 1.21473002 -1.99636998 1.21466004 -1.99621004 0 P 0 
L 1.21466004 -1.99621004 1.21458002 -1.99606004 0 P 0 
L 1.21458002 -1.99606004 1.21448002 -1.99591004 0 P 0 
L 1.21448002 -1.99591004 1.21433002 -1.99571998 0 P 0 
L 1.21433002 -1.99571998 1.21416998 -1.99553996 0 P 0 
L 1.21416998 -1.99553996 1.21398996 -1.99538002 0 P 0 
L 1.21398996 -1.99538002 1.21378996 -1.99523996 0 P 0 
L 1.21378996 -1.99523996 1.21358002 -1.99511004 0 P 0 
L 1.21358002 -1.99511004 1.21336004 -1.995 0 P 0 
L 1.21336004 -1.995 1.21261004 -1.99468996 0 P 0 
L 1.21261004 -1.99468996 1.21183996 -1.99443996 0 P 0 
L 1.21183996 -1.99443996 1.21105 -1.99423002 0 P 0 
L 1.21105 -1.99423002 1.20593996 -1.99318002 0 P 0 
L 1.20593996 -1.99318002 1.18996998 -1.99065 0 P 0 
L 1.18996998 -1.99065 1.17318996 -1.98908002 0 P 0 
L 1.17318996 -1.98908002 1.15718996 -1.98858002 0 P 0 
L 1.15718996 -1.98858002 1.1504 -1.98876004 0 P 0 
L 1.1504 -1.98876004 1.14356998 -1.98926998 0 P 0 
L 1.04503996 -2.19061998 1.05141998 -2.19061998 0 P 0 
L 1.04893002 -2.18961998 1.05323002 -2.18961998 0 P 0 
L 1.05263002 -2.18861998 1.05503996 -2.18861998 0 P 0 
L 1.05628996 -2.18761998 1.05676004 -2.18761998 0 P 0 
L 1.09645 -2.17983002 1.16738002 -2.17983002 0 P 0 
L 1.09126004 -2.17883002 1.17091004 -2.17883002 0 P 0 
L 1.0868 -2.17783002 1.17386998 -2.17783002 0 P 0 
L 1.08368002 -2.17683002 1.17636004 -2.17683002 0 P 0 
L 1.0836 -2.17583002 1.1787 -2.17583002 0 P 0 
L 1.08351998 -2.17483002 1.18066998 -2.17483002 0 P 0 
L 1.08345 -2.17383002 1.18236998 -2.17383002 0 P 0 
L 1.08336998 -2.17283002 1.1839 -2.17283002 0 P 0 
L 1.08328996 -2.17183002 1.18526998 -2.17183002 0 P 0 
L 1.08321998 -2.17083002 1.18646998 -2.17083002 0 P 0 
L 1.08313996 -2.16983002 1.18761998 -2.16983002 0 P 0 
L 1.08306998 -2.16883002 1.18863996 -2.16883002 0 P 0 
L 1.08298996 -2.16783002 1.18966004 -2.16783002 0 P 0 
L 1.08291998 -2.16683002 1.19061004 -2.16683002 0 P 0 
L 1.08283996 -2.16583002 1.1915 -2.16583002 0 P 0 
L 1.08276004 -2.16483002 1.19238996 -2.16483002 0 P 0 
L 1.08268996 -2.16383002 1.19321004 -2.16383002 0 P 0 
L 1.08261004 -2.16283002 1.19398002 -2.16283002 0 P 0 
L 1.08253002 -2.16183002 1.19476004 -2.16183002 0 P 0 
L 1.08246004 -2.16083002 1.19548002 -2.16083002 0 P 0 
L 1.08238002 -2.15983002 1.19613996 -2.15983002 0 P 0 
L 1.08231004 -2.15883002 1.19681004 -2.15883002 0 P 0 
L 1.08223996 -2.15783002 1.19746004 -2.15783002 0 P 0 
L 1.13506998 -2.18383002 1.12553002 -2.18343996 0 P 0 
L 1.12553002 -2.18343996 1.11266004 -2.18218002 0 P 0 
L 1.11266004 -2.18218002 1.09983002 -2.18048002 0 P 0 
L 1.09983002 -2.18048002 1.09036998 -2.17866004 0 P 0 
L 1.09036998 -2.17866004 1.0837 -2.17711004 0 P 0 
L 1.0837 -2.17711004 1.08245 -2.16066998 0 P 0 
L 1.08245 -2.16066998 1.08193996 -2.15361998 0 P 0 
L 1.08193996 -2.15361998 1.08156998 -2.14726004 0 P 0 
L 1.08156998 -2.14726004 1.08131998 -2.14191004 0 P 0 
L 1.08131998 -2.14191004 1.08131004 -2.14108996 0 P 0 
L 1.08131004 -2.14108996 1.08136004 -2.14026004 0 P 0 
L 1.08136004 -2.14026004 1.0814 -2.13986998 0 P 0 
L 1.0814 -2.13986998 1.08996004 -2.14233002 0 P 0 
L 1.08996004 -2.14233002 1.08996998 -2.14233996 0 P 0 
L 1.08996998 -2.14233996 1.08998996 -2.14233996 0 P 0 
L 1.08998996 -2.14233996 1.099 -2.14471998 0 P 0 
L 1.099 -2.14471998 1.10806998 -2.14668002 0 P 0 
L 1.10806998 -2.14668002 1.11598002 -2.14791998 0 P 0 
L 1.11598002 -2.14791998 1.12395 -2.1486 0 P 0 
L 1.12395 -2.1486 1.13048996 -2.14863996 0 P 0 
L 1.13048996 -2.14863996 1.137 -2.14811998 0 P 0 
L 1.137 -2.14811998 1.13903002 -2.14778996 0 P 0 
L 1.13903002 -2.14778996 1.14103002 -2.14728996 0 P 0 
L 1.14103002 -2.14728996 1.14298002 -2.14661998 0 P 0 
L 1.14298002 -2.14661998 1.14486998 -2.14581004 0 P 0 
L 1.14486998 -2.14581004 1.14668002 -2.14483996 0 P 0 
L 1.14668002 -2.14483996 1.1484 -2.14373996 0 P 0 
L 1.1484 -2.14373996 1.15003002 -2.1425 0 P 0 
L 1.15003002 -2.1425 1.15155 -2.14115 0 P 0 
L 1.15155 -2.14115 1.1526 -2.14006998 0 P 0 
L 1.1526 -2.14006998 1.15263996 -2.14001998 0 P 0 
L 1.15263996 -2.14001998 1.15356004 -2.13893002 0 P 0 
L 1.15356004 -2.13893002 1.15443996 -2.13771998 0 P 0 
L 1.15443996 -2.13771998 1.15523002 -2.13646004 0 P 0 
L 1.15523002 -2.13646004 1.15593996 -2.13515 0 P 0 
L 1.15593996 -2.13515 1.15655 -2.13381004 0 P 0 
L 1.15655 -2.13381004 1.15706004 -2.13243002 0 P 0 
L 1.15706004 -2.13243002 1.15748002 -2.13101004 0 P 0 
L 1.15748002 -2.13101004 1.1579 -2.12905 0 P 0 
L 1.1579 -2.12905 1.15816004 -2.12706004 0 P 0 
L 1.15816004 -2.12706004 1.15825 -2.12506998 0 P 0 
L 1.15825 -2.12506998 1.15818002 -2.12165 0 P 0 
L 1.15818002 -2.12165 1.15813996 -2.12118002 0 P 0 
L 1.15813996 -2.12118002 1.15813002 -2.1211 0 P 0 
L 1.15813002 -2.1211 1.15806004 -2.12068002 0 P 0 
L 1.15806004 -2.12068002 1.15793996 -2.12018996 0 P 0 
L 1.15793996 -2.12018996 1.15778002 -2.11973002 0 P 0 
L 1.15778002 -2.11973002 1.1577 -2.11953002 0 P 0 
L 1.1577 -2.11953002 1.15758996 -2.11933002 0 P 0 
L 1.15758996 -2.11933002 1.15746998 -2.11913996 0 P 0 
L 1.15746998 -2.11913996 1.15733002 -2.11895 0 P 0 
L 1.15733002 -2.11895 1.15716998 -2.11878002 0 P 0 
L 1.15716998 -2.11878002 1.157 -2.11863002 0 P 0 
L 1.157 -2.11863002 1.15681998 -2.11848996 0 P 0 
L 1.15681998 -2.11848996 1.15663002 -2.11836004 0 P 0 
L 1.15663002 -2.11836004 1.15641998 -2.11825 0 P 0 
L 1.15641998 -2.11825 1.15621004 -2.11816004 0 P 0 
L 1.15621004 -2.11816004 1.15598996 -2.11808996 0 P 0 
L 1.15598996 -2.11808996 1.15576998 -2.11803996 0 P 0 
L 1.15576998 -2.11803996 1.15553002 -2.118 0 P 0 
L 1.15553002 -2.118 1.15518002 -2.11798002 0 P 0 
L 1.15518002 -2.11798002 1.15483996 -2.11798996 0 P 0 
L 1.15483996 -2.11798996 1.15451004 -2.11803002 0 P 0 
L 1.15451004 -2.11803002 1.15418002 -2.1181 0 P 0 
L 1.15418002 -2.1181 1.15386004 -2.1182 0 P 0 
L 1.15386004 -2.1182 1.15361004 -2.11828996 0 P 0 
L 1.15361004 -2.11828996 1.14705 -2.12083996 0 P 0 
L 1.14705 -2.12083996 1.14038996 -2.12278996 0 P 0 
L 1.14038996 -2.12278996 1.13356004 -2.12416004 0 P 0 
L 1.13356004 -2.12416004 1.1285 -2.12476998 0 P 0 
L 1.1285 -2.12476998 1.12341004 -2.12501998 0 P 0 
L 1.12341004 -2.12501998 1.11831004 -2.12493002 0 P 0 
L 1.11831004 -2.12493002 1.11323002 -2.12448996 0 P 0 
L 1.11323002 -2.12448996 1.10848996 -2.12373002 0 P 0 
L 1.10848996 -2.12373002 1.10383996 -2.12263002 0 P 0 
L 1.10383996 -2.12263002 1.09926998 -2.12118996 0 P 0 
L 1.09926998 -2.12118996 1.09481004 -2.11941004 0 P 0 
L 1.09481004 -2.11941004 1.09168002 -2.11788002 0 P 0 
L 1.09168002 -2.11788002 1.08866004 -2.11611998 0 P 0 
L 1.08866004 -2.11611998 1.08578002 -2.11413002 0 P 0 
L 1.08578002 -2.11413002 1.08306998 -2.11193996 0 P 0 
L 1.08306998 -2.11193996 1.08051998 -2.10955 0 P 0 
L 1.08051998 -2.10955 1.07793996 -2.10673002 0 P 0 
L 1.07793996 -2.10673002 1.07561004 -2.10373996 0 P 0 
L 1.07561004 -2.10373996 1.07351004 -2.10058002 0 P 0 
L 1.07351004 -2.10058002 1.07171004 -2.09733996 0 P 0 
L 1.07171004 -2.09733996 1.07018002 -2.09396998 0 P 0 
L 1.07018002 -2.09396998 1.06893996 -2.09048002 0 P 0 
L 1.06893996 -2.09048002 1.06786004 -2.0865 0 P 0 
L 1.06786004 -2.0865 1.06706004 -2.08243996 0 P 0 
L 1.06706004 -2.08243996 1.06656004 -2.07833002 0 P 0 
L 1.06656004 -2.07833002 1.06615 -2.07071004 0 P 0 
L 1.06615 -2.07071004 1.06621004 -2.06313996 0 P 0 
L 1.06621004 -2.06313996 1.06675 -2.0556 0 P 0 
L 1.06675 -2.0556 1.0678 -2.04813002 0 P 0 
L 1.0678 -2.04813002 1.06868996 -2.04391998 0 P 0 
L 1.06868996 -2.04391998 1.06985 -2.03981004 0 P 0 
L 1.06985 -2.03981004 1.0713 -2.03578996 0 P 0 
L 1.0713 -2.03578996 1.07296004 -2.03206998 0 P 0 
L 1.07296004 -2.03206998 1.07486998 -2.02848996 0 P 0 
L 1.07486998 -2.02848996 1.07705 -2.02506004 0 P 0 
L 1.07705 -2.02506004 1.07966004 -2.0215 0 P 0 
L 1.07966004 -2.0215 1.08246998 -2.01811004 0 P 0 
L 1.08246998 -2.01811004 1.08546998 -2.01491004 0 P 0 
L 1.08546998 -2.01491004 1.0897 -2.01091004 0 P 0 
L 1.0897 -2.01091004 1.09153002 -2.00936998 0 P 0 
L 1.09153002 -2.00936998 1.09341998 -2.00793996 0 P 0 
L 1.09341998 -2.00793996 1.09545 -2.00658002 0 P 0 
L 1.09545 -2.00658002 1.09751004 -2.00533996 0 P 0 
L 1.09751004 -2.00533996 1.10288002 -2.0025 0 P 0 
L 1.10288002 -2.0025 1.10736998 -2.00043002 0 P 0 
L 1.10736998 -2.00043002 1.11193002 -1.99861004 0 P 0 
L 1.11193002 -1.99861004 1.12218002 -1.99533002 0 P 0 
L 1.12218002 -1.99533002 1.13298002 -1.99281998 0 P 0 
L 1.13298002 -1.99281998 1.14378996 -1.99126004 0 P 0 
L 1.14378996 -1.99126004 1.1505 -1.99075 0 P 0 
L 1.1505 -1.99075 1.15718002 -1.99058996 0 P 0 
L 1.15718002 -1.99058996 1.17306998 -1.99108002 0 P 0 
L 1.17306998 -1.99108002 1.18971998 -1.99263002 0 P 0 
L 1.18971998 -1.99263002 1.20558002 -1.99515 0 P 0 
L 1.20558002 -1.99515 1.21058996 -1.99618002 0 P 0 
L 1.21058996 -1.99618002 1.21126998 -1.99636004 0 P 0 
L 1.21126998 -1.99636004 1.21191998 -1.99656998 0 P 0 
L 1.21191998 -1.99656998 1.21253002 -1.99681998 0 P 0 
L 1.21253002 -1.99681998 1.21261004 -1.99686004 0 P 0 
L 1.21261004 -1.99686004 1.21266004 -1.99688996 0 P 0 
L 1.21266004 -1.99688996 1.21271998 -1.99693002 0 P 0 
L 1.21271998 -1.99693002 1.21281998 -1.99703002 0 P 0 
L 1.21281998 -1.99703002 1.21286004 -1.99708996 0 P 0 
L 1.21286004 -1.99708996 1.21288002 -1.99711004 0 P 0 
L 1.21288002 -1.99711004 1.21288002 -1.99711998 0 P 0 
L 1.21288002 -1.99711998 1.21288996 -1.99715 0 P 0 
L 1.21288996 -1.99715 1.2129 -1.99716998 0 P 0 
L 1.2129 -1.99716998 1.2129 -1.99721998 0 P 0 
L 1.2129 -1.99721998 1.21285 -1.99875 0 P 0 
L 1.21285 -1.99875 1.21243996 -2.00556998 0 P 0 
L 1.21243996 -2.00556998 1.21193996 -2.01361004 0 P 0 
L 1.21193996 -2.01361004 1.21133996 -2.02273002 0 P 0 
L 1.21133996 -2.02273002 1.21133996 -2.02273996 0 P 0 
L 1.21133996 -2.02273996 1.21058996 -2.03468002 0 P 0 
L 1.21058996 -2.03468002 1.20956004 -2.05216998 0 P 0 
L 1.20956004 -2.05216998 1.20848996 -2.07156004 0 P 0 
L 1.20848996 -2.07156004 1.20848996 -2.07156998 0 P 0 
L 1.20848996 -2.07156998 1.20751004 -2.09011004 0 P 0 
L 1.20751004 -2.09011004 1.20658996 -2.10743996 0 P 0 
L 1.20658996 -2.10743996 1.20561998 -2.12308996 0 P 0 
L 1.20561998 -2.12308996 1.20473002 -2.13618996 0 P 0 
L 1.20473002 -2.13618996 1.20453002 -2.13831998 0 P 0 
L 1.20453002 -2.13831998 1.20423996 -2.14041004 0 P 0 
L 1.20423996 -2.14041004 1.2035 -2.144 0 P 0 
L 1.2035 -2.144 1.20246004 -2.1475 0 P 0 
L 1.20246004 -2.1475 1.20111998 -2.1509 0 P 0 
L 1.20111998 -2.1509 1.19936998 -2.1545 0 P 0 
L 1.19936998 -2.1545 1.19738002 -2.15796998 0 P 0 
L 1.19738002 -2.15796998 1.19516004 -2.1613 0 P 0 
L 1.19516004 -2.1613 1.19276998 -2.16441004 0 P 0 
L 1.19276998 -2.16441004 1.19016004 -2.16733996 0 P 0 
L 1.19016004 -2.16733996 1.18736004 -2.17008002 0 P 0 
L 1.18736004 -2.17008002 1.1854 -2.17173996 0 P 0 
L 1.1854 -2.17173996 1.18335 -2.17323002 0 P 0 
L 1.18335 -2.17323002 1.18118002 -2.17456004 0 P 0 
L 1.18118002 -2.17456004 1.17893002 -2.17573002 0 P 0 
L 1.17893002 -2.17573002 1.17456998 -2.1776 0 P 0 
L 1.17456998 -2.1776 1.17006998 -2.17911998 0 P 0 
L 1.17006998 -2.17911998 1.16473996 -2.18053002 0 P 0 
L 1.16473996 -2.18053002 1.15935 -2.18166998 0 P 0 
L 1.15935 -2.18166998 1.15341998 -2.18263002 0 P 0 
L 1.15341998 -2.18263002 1.1475 -2.18328996 0 P 0 
L 1.1475 -2.18328996 1.13506998 -2.18383002 0 P 0 
L 0.90491998 -2.21461998 1.00131004 -2.21461998 0 P 0 
L 0.92235 -2.21361998 1.00355 -2.21361998 0 P 0 
L 0.76925 -1.8965 0.85586998 -1.8965 0 P 0 
L 0.76958996 -1.8955 0.85556004 -1.8955 0 P 0 
L 0.76995 -1.8945 0.85521004 -1.8945 0 P 0 
L 0.77031004 -1.8935 0.85486004 -1.8935 0 P 0 
L 0.77071004 -1.8925 0.85443996 -1.8925 0 P 0 
L 0.77115 -1.8915 0.85401004 -1.8915 0 P 0 
L 0.7716 -1.8905 0.85355 -1.8905 0 P 0 
L 0.77206004 -1.8895 0.85303002 -1.8895 0 P 0 
L 0.7726 -1.8885 0.85251004 -1.8885 0 P 0 
L 0.77313996 -1.8875 0.85198996 -1.8875 0 P 0 
L 0.77368996 -1.8865 0.85138002 -1.8865 0 P 0 
L 0.77433002 -1.8855 0.85073996 -1.8855 0 P 0 
L 0.77496004 -1.8845 0.85011004 -1.8845 0 P 0 
L 0.77561998 -1.8835 0.84943002 -1.8835 0 P 0 
L 0.77636004 -1.8825 0.84866998 -1.8825 0 P 0 
L 0.77711004 -1.8815 0.84791004 -1.8815 0 P 0 
L 0.7779 -1.8805 0.84713002 -1.8805 0 P 0 
L 0.77876998 -1.8795 0.84623002 -1.8795 0 P 0 
L 0.77963996 -1.8785 0.84533002 -1.8785 0 P 0 
L 0.7806 -1.8775 0.8444 -1.8775 0 P 0 
L 0.78161004 -1.8765 0.84335 -1.8765 0 P 0 
L 0.78265 -1.8755 0.84228996 -1.8755 0 P 0 
L 0.78381998 -1.8745 0.84108996 -1.8745 0 P 0 
L 0.78498996 -1.8735 0.83986998 -1.8735 0 P 0 
L 0.78635 -1.8725 0.83848002 -1.8725 0 P 0 
L 0.78773002 -1.8715 0.83706004 -1.8715 0 P 0 
L 0.78933002 -1.8705 0.83541998 -1.8705 0 P 0 
L 0.791 -1.8695 0.83366004 -1.8695 0 P 0 
L 0.793 -1.8685 0.83171998 -1.8685 0 P 0 
L 0.79525 -1.8675 0.82941998 -1.8675 0 P 0 
L 0.79791998 -1.8665 0.82671004 -1.8665 0 P 0 
L 0.80143996 -1.8655 0.82328996 -1.8655 0 P 0 
L 0.80705 -1.8645 0.81776004 -1.8645 0 P 0 
L 0.74543002 -1.89661998 0.75033002 -1.89661998 0 P 0 
L 0.74751004 -1.89561998 0.75058996 -1.89561998 0 P 0 
L 0.74958996 -1.89461998 0.75086004 -1.89461998 0 P 0 
L 0.76733996 -1.9125 0.85751998 -1.9125 0 P 0 
L 0.76728996 -1.9115 0.85756004 -1.9115 0 P 0 
L 0.76723996 -1.9105 0.85758996 -1.9105 0 P 0 
L 0.76721998 -1.9095 0.85763002 -1.9095 0 P 0 
L 0.76725 -1.9085 0.85761004 -1.9085 0 P 0 
L 0.76728002 -1.9075 0.85756998 -1.9075 0 P 0 
L 0.76731004 -1.9065 0.85753002 -1.9065 0 P 0 
L 0.76741998 -1.9055 0.85748996 -1.9055 0 P 0 
L 0.76753996 -1.9045 0.85738002 -1.9045 0 P 0 
L 0.76766004 -1.9035 0.85726004 -1.9035 0 P 0 
L 0.76781998 -1.9025 0.85713996 -1.9025 0 P 0 
L 0.76801998 -1.9015 0.85701004 -1.9015 0 P 0 
L 0.76821004 -1.9005 0.85683002 -1.9005 0 P 0 
L 0.76841998 -1.8995 0.85661998 -1.8995 0 P 0 
L 0.7687 -1.8985 0.85641004 -1.8985 0 P 0 
L 0.76896998 -1.8975 0.85613996 -1.8975 0 P 0 
L 0.76751004 -2.08325 0.8416 -2.08325 0 P 0 
L 0.76761998 -2.08225 0.84161998 -2.08225 0 P 0 
L 0.76773996 -2.08125 0.84166998 -2.08125 0 P 0 
L 0.76786004 -2.08025 0.84171998 -2.08025 0 P 0 
L 0.76796998 -2.07925 0.84176998 -2.07925 0 P 0 
L 0.76808002 -2.07825 0.84181004 -2.07825 0 P 0 
L 0.76818002 -2.07725 0.84186004 -2.07725 0 P 0 
L 0.76828996 -2.07625 0.8419 -2.07625 0 P 0 
L 0.76838996 -2.07525 0.84195 -2.07525 0 P 0 
L 0.76848996 -2.07425 0.842 -2.07425 0 P 0 
L 0.7686 -2.07325 0.84205 -2.07325 0 P 0 
L 0.7687 -2.07225 0.84208996 -2.07225 0 P 0 
L 0.7688 -2.07125 0.84213996 -2.07125 0 P 0 
L 0.7689 -2.07025 0.84218002 -2.07025 0 P 0 
L 0.76901004 -2.06925 0.84223002 -2.06925 0 P 0 
L 0.76911004 -2.06825 0.84228002 -2.06825 0 P 0 
L 0.76921004 -2.06725 0.84233002 -2.06725 0 P 0 
L 0.76931998 -2.06625 0.84236998 -2.06625 0 P 0 
L 0.76941998 -2.06525 0.84241998 -2.06525 0 P 0 
L 0.76948996 -2.06425 0.84246004 -2.06425 0 P 0 
L 0.76956004 -2.06325 0.84251004 -2.06325 0 P 0 
L 0.76963002 -2.06225 0.84256004 -2.06225 0 P 0 
L 0.7697 -2.06125 0.8426 -2.06125 0 P 0 
L 0.76976998 -2.06025 0.84265 -2.06025 0 P 0 
L 0.76983996 -2.05925 0.8427 -2.05925 0 P 0 
L 0.76991004 -2.05825 0.84273996 -2.05825 0 P 0 
L 0.76996998 -2.05725 0.84278996 -2.05725 0 P 0 
L 0.77001004 -2.05625 0.84283996 -2.05625 0 P 0 
L 0.77003996 -2.05525 0.84288002 -2.05525 0 P 0 
L 0.77008002 -2.05425 0.84295 -2.05425 0 P 0 
L 0.77011998 -2.05325 0.84303996 -2.05325 0 P 0 
L 0.77016004 -2.05225 0.84311998 -2.05225 0 P 0 
L 0.77018996 -2.05125 0.84321004 -2.05125 0 P 0 
L 0.77023002 -2.05025 0.8433 -2.05025 0 P 0 
L 0.77026998 -2.04925 0.84338002 -2.04925 0 P 0 
L 0.77031004 -2.04825 0.84346998 -2.04825 0 P 0 
L 0.77033996 -2.04725 0.84356004 -2.04725 0 P 0 
L 0.77038002 -2.04625 0.84363996 -2.04625 0 P 0 
L 0.77041004 -2.04525 0.84373002 -2.04525 0 P 0 
L 0.77043996 -2.04425 0.84381004 -2.04425 0 P 0 
L 0.77046004 -2.04325 0.8439 -2.04325 0 P 0 
L 0.77048002 -2.04225 0.84398996 -2.04225 0 P 0 
L 0.77051004 -2.04125 0.84406998 -2.04125 0 P 0 
L 0.77053002 -2.04025 0.84416004 -2.04025 0 P 0 
L 0.77055 -2.03925 0.84425 -2.03925 0 P 0 
L 0.77058002 -2.03825 0.84433002 -2.03825 0 P 0 
L 0.7706 -2.03725 0.84441998 -2.03725 0 P 0 
L 0.77061998 -2.03625 0.84451004 -2.03625 0 P 0 
L 0.77065 -2.03525 0.84458996 -2.03525 0 P 0 
L 0.77066998 -2.03425 0.84468002 -2.03425 0 P 0 
L 0.7707 -2.03325 0.84476998 -2.03325 0 P 0 
L 0.77071998 -2.03225 0.84485 -2.03225 0 P 0 
L 0.77073002 -2.03125 0.84493996 -2.03125 0 P 0 
L 0.77073996 -2.03025 0.84503002 -2.03025 0 P 0 
L 0.79986004 -1.8638 0.79643996 -1.86486998 0 P 0 
L 0.79643996 -1.86486998 0.79311998 -1.86621004 0 P 0 
L 0.79311998 -1.86621004 0.78991004 -1.86781004 0 P 0 
L 0.78991004 -1.86781004 0.78683996 -1.86966998 0 P 0 
L 0.78683996 -1.86966998 0.78391998 -1.87178002 0 P 0 
L 0.78391998 -1.87178002 0.78111998 -1.87416998 0 P 0 
L 0.78111998 -1.87416998 0.7785 -1.87676004 0 P 0 
L 0.7785 -1.87676004 0.77608002 -1.87953996 0 P 0 
L 0.77608002 -1.87953996 0.77386998 -1.8825 0 P 0 
L 0.77386998 -1.8825 0.77188002 -1.88561998 0 P 0 
L 0.77188002 -1.88561998 0.77013996 -1.88886004 0 P 0 
L 0.77013996 -1.88886004 0.76863996 -1.89221004 0 P 0 
L 0.76863996 -1.89221004 0.7674 -1.89566998 0 P 0 
L 0.7674 -1.89566998 0.76643002 -1.89921004 0 P 0 
L 0.76643002 -1.89921004 0.76571004 -1.90283996 0 P 0 
L 0.76571004 -1.90283996 0.76531004 -1.90636004 0 P 0 
L 0.76531004 -1.90636004 0.7652 -1.90991004 0 P 0 
L 0.7652 -1.90991004 0.76538996 -1.91345 0 P 0 
L 0.76538996 -1.91345 0.76586998 -1.91696998 0 P 0 
L 0.76586998 -1.91696998 0.76663996 -1.92046004 0 P 0 
L 0.76663996 -1.92046004 0.76803002 -1.92493996 0 P 0 
L 0.76803002 -1.92493996 0.76978002 -1.9293 0 P 0 
L 0.76978002 -1.9293 0.77106998 -1.93193996 0 P 0 
L 0.77106998 -1.93193996 0.77253002 -1.93448002 0 P 0 
L 0.77253002 -1.93448002 0.77416004 -1.93693996 0 P 0 
L 0.77416004 -1.93693996 0.77593002 -1.93923002 0 P 0 
L 0.77593002 -1.93923002 0.77783996 -1.94141004 0 P 0 
L 0.77783996 -1.94141004 0.77988996 -1.94345 0 P 0 
L 0.77988996 -1.94345 0.78216004 -1.94545 0 P 0 
L 0.78216004 -1.94545 0.78453996 -1.9473 0 P 0 
L 0.78453996 -1.9473 0.78703002 -1.94901998 0 P 0 
L 0.78703002 -1.94901998 0.79016998 -1.95088002 0 P 0 
L 0.79016998 -1.95088002 0.79343996 -1.95248996 0 P 0 
L 0.79343996 -1.95248996 0.79683002 -1.95383996 0 P 0 
L 0.79683002 -1.95383996 0.80031998 -1.95491998 0 P 0 
L 0.80031998 -1.95491998 0.80391004 -1.95573996 0 P 0 
L 0.80391004 -1.95573996 0.80751998 -1.95626004 0 P 0 
L 0.80751998 -1.95626004 0.81116004 -1.9565 0 P 0 
L 0.81116004 -1.9565 0.81481004 -1.95646004 0 P 0 
L 0.81481004 -1.95646004 0.81843996 -1.95613002 0 P 0 
L 0.81843996 -1.95613002 0.82205 -1.95551004 0 P 0 
L 0.82205 -1.95551004 0.82561998 -1.95461004 0 P 0 
L 0.82561998 -1.95461004 0.82911004 -1.95345 0 P 0 
L 0.82911004 -1.95345 0.83248996 -1.95201004 0 P 0 
L 0.83248996 -1.95201004 0.83576004 -1.95031998 0 P 0 
L 0.83576004 -1.95031998 0.83891998 -1.94836004 0 P 0 
L 0.83891998 -1.94836004 0.84191998 -1.94616998 0 P 0 
L 0.84191998 -1.94616998 0.84475 -1.94375 0 P 0 
L 0.84475 -1.94375 0.84738996 -1.94113996 0 P 0 
L 0.84738996 -1.94113996 0.84983002 -1.93833996 0 P 0 
L 0.84983002 -1.93833996 0.85206998 -1.93533996 0 P 0 
L 0.85206998 -1.93533996 0.8536 -1.93291998 0 P 0 
L 0.8536 -1.93291998 0.85496004 -1.93041004 0 P 0 
L 0.85496004 -1.93041004 0.85613996 -1.9278 0 P 0 
L 0.85613996 -1.9278 0.85711998 -1.92511004 0 P 0 
L 0.85711998 -1.92511004 0.85823002 -1.92123002 0 P 0 
L 0.85823002 -1.92123002 0.85901998 -1.91726998 0 P 0 
L 0.85901998 -1.91726998 0.85948996 -1.91323996 0 P 0 
L 0.85948996 -1.91323996 0.85963996 -1.90918002 0 P 0 
L 0.85963996 -1.90918002 0.85946998 -1.90513002 0 P 0 
L 0.85946998 -1.90513002 0.85898002 -1.9011 0 P 0 
L 0.85898002 -1.9011 0.85841998 -1.89826004 0 P 0 
L 0.85841998 -1.89826004 0.85766004 -1.89546004 0 P 0 
L 0.85766004 -1.89546004 0.85671004 -1.89273002 0 P 0 
L 0.85671004 -1.89273002 0.85556998 -1.89006004 0 P 0 
L 0.85556998 -1.89006004 0.85361998 -1.88631004 0 P 0 
L 0.85361998 -1.88631004 0.85136004 -1.88273996 0 P 0 
L 0.85136004 -1.88273996 0.84881004 -1.87938002 0 P 0 
L 0.84881004 -1.87938002 0.84596998 -1.87623002 0 P 0 
L 0.84596998 -1.87623002 0.84355 -1.87393996 0 P 0 
L 0.84355 -1.87393996 0.84096998 -1.87181998 0 P 0 
L 0.84096998 -1.87181998 0.83826004 -1.86988996 0 P 0 
L 0.83826004 -1.86988996 0.83541004 -1.86815 0 P 0 
L 0.83541004 -1.86815 0.83243996 -1.86661004 0 P 0 
L 0.83243996 -1.86661004 0.82938996 -1.86531004 0 P 0 
L 0.82938996 -1.86531004 0.82625 -1.86423002 0 P 0 
L 0.82625 -1.86423002 0.82303996 -1.86336004 0 P 0 
L 0.82303996 -1.86336004 0.81978002 -1.86273002 0 P 0 
L 0.81978002 -1.86273002 0.81646998 -1.86233002 0 P 0 
L 0.81646998 -1.86233002 0.81228996 -1.86215 0 P 0 
L 0.81228996 -1.86215 0.80811004 -1.86233996 0 P 0 
L 0.80811004 -1.86233996 0.80396004 -1.86288996 0 P 0 
L 0.80396004 -1.86288996 0.79986004 -1.8638 0 P 0 
L 0.80308996 -1.9535 0.82186004 -1.9535 0 P 0 
L 0.79926004 -1.9525 0.82563996 -1.9525 0 P 0 
L 0.79636004 -1.9515 0.82856998 -1.9515 0 P 0 
L 0.79393002 -1.9505 0.83093996 -1.9505 0 P 0 
L 0.7919 -1.9495 0.83298996 -1.9495 0 P 0 
L 0.79008002 -1.9485 0.8349 -1.9485 0 P 0 
L 0.78838996 -1.9475 0.83651004 -1.9475 0 P 0 
L 0.7869 -1.9465 0.83806998 -1.9465 0 P 0 
L 0.78548002 -1.9455 0.83943996 -1.9455 0 P 0 
L 0.7842 -1.9445 0.84078996 -1.9445 0 P 0 
L 0.78298002 -1.9435 0.84196998 -1.9435 0 P 0 
L 0.78183996 -1.9425 0.84313996 -1.9425 0 P 0 
L 0.78076998 -1.9415 0.84418996 -1.9415 0 P 0 
L 0.77976004 -1.9405 0.8452 -1.9405 0 P 0 
L 0.77883002 -1.9395 0.84616998 -1.9395 0 P 0 
L 0.77793996 -1.9385 0.84703996 -1.9385 0 P 0 
L 0.77711998 -1.9375 0.84791004 -1.9375 0 P 0 
L 0.77635 -1.9365 0.84871004 -1.9365 0 P 0 
L 0.77561004 -1.9355 0.84945 -1.9355 0 P 0 
L 0.77493996 -1.9345 0.8502 -1.9345 0 P 0 
L 0.77428002 -1.9335 0.85086998 -1.9335 0 P 0 
L 0.7737 -1.9325 0.8515 -1.9325 0 P 0 
L 0.77311998 -1.9315 0.8521 -1.9315 0 P 0 
L 0.77258996 -1.9305 0.85263996 -1.9305 0 P 0 
L 0.7721 -1.9295 0.85318002 -1.9295 0 P 0 
L 0.77161004 -1.9285 0.85363002 -1.9285 0 P 0 
L 0.77121004 -1.9275 0.85408002 -1.9275 0 P 0 
L 0.77081004 -1.9265 0.85448002 -1.9265 0 P 0 
L 0.77041004 -1.9255 0.85485 -1.9255 0 P 0 
L 0.77001004 -1.9245 0.85521998 -1.9245 0 P 0 
L 0.76968002 -1.9235 0.8555 -1.9235 0 P 0 
L 0.76936998 -1.9225 0.85578996 -1.9225 0 P 0 
L 0.76906004 -1.9215 0.85606998 -1.9215 0 P 0 
L 0.76875 -1.9205 0.85633002 -1.9205 0 P 0 
L 0.76848002 -1.9195 0.85653002 -1.9195 0 P 0 
L 0.76826004 -1.9185 0.85673002 -1.9185 0 P 0 
L 0.76803002 -1.9175 0.85693002 -1.9175 0 P 0 
L 0.76783002 -1.9165 0.85708996 -1.9165 0 P 0 
L 0.76768996 -1.9155 0.85721004 -1.9155 0 P 0 
L 0.76755 -1.9145 0.85733002 -1.9145 0 P 0 
L 0.76741998 -1.9135 0.85745 -1.9135 0 P 0 
L 0.81121004 -1.9545 0.80773002 -1.95426998 0 P 0 
L 0.80773002 -1.95426998 0.80426998 -1.95376998 0 P 0 
L 0.80426998 -1.95376998 0.80083996 -1.95298996 0 P 0 
L 0.80083996 -1.95298996 0.7975 -1.95195 0 P 0 
L 0.7975 -1.95195 0.79426004 -1.95066004 0 P 0 
L 0.79426004 -1.95066004 0.79111998 -1.94911998 0 P 0 
L 0.79111998 -1.94911998 0.78811004 -1.94733002 0 P 0 
L 0.78811004 -1.94733002 0.78573002 -1.94568996 0 P 0 
L 0.78573002 -1.94568996 0.78343996 -1.9439 0 P 0 
L 0.78343996 -1.9439 0.78126004 -1.94198996 0 P 0 
L 0.78126004 -1.94198996 0.7793 -1.94003996 0 P 0 
L 0.7793 -1.94003996 0.77746998 -1.93796004 0 P 0 
L 0.77746998 -1.93796004 0.77578996 -1.93576998 0 P 0 
L 0.77578996 -1.93576998 0.77423002 -1.93343002 0 P 0 
L 0.77423002 -1.93343002 0.77283996 -1.931 0 P 0 
L 0.77283996 -1.931 0.77161004 -1.92848996 0 P 0 
L 0.77161004 -1.92848996 0.76991998 -1.92426998 0 P 0 
L 0.76991998 -1.92426998 0.76858002 -1.91993996 0 P 0 
L 0.76858002 -1.91993996 0.76783996 -1.91661998 0 P 0 
L 0.76783996 -1.91661998 0.76738002 -1.91326998 0 P 0 
L 0.76738002 -1.91326998 0.76721004 -1.90988996 0 P 0 
L 0.76721004 -1.90988996 0.76731004 -1.90651004 0 P 0 
L 0.76731004 -1.90651004 0.7677 -1.90315 0 P 0 
L 0.7677 -1.90315 0.76838002 -1.89966998 0 P 0 
L 0.76838002 -1.89966998 0.76931004 -1.89626998 0 P 0 
L 0.76931004 -1.89626998 0.7705 -1.89296004 0 P 0 
L 0.7705 -1.89296004 0.77193996 -1.88973996 0 P 0 
L 0.77193996 -1.88973996 0.7736 -1.88663996 0 P 0 
L 0.7736 -1.88663996 0.77551004 -1.88363996 0 P 0 
L 0.77551004 -1.88363996 0.77763002 -1.8808 0 P 0 
L 0.77763002 -1.8808 0.77996004 -1.87813002 0 P 0 
L 0.77996004 -1.87813002 0.78246998 -1.87565 0 P 0 
L 0.78246998 -1.87565 0.78516004 -1.87336004 0 P 0 
L 0.78516004 -1.87336004 0.78795 -1.87133996 0 P 0 
L 0.78795 -1.87133996 0.79088002 -1.86956004 0 P 0 
L 0.79088002 -1.86956004 0.79393996 -1.86803002 0 P 0 
L 0.79393996 -1.86803002 0.79711004 -1.86675 0 P 0 
L 0.79711004 -1.86675 0.80038002 -1.86573002 0 P 0 
L 0.80038002 -1.86573002 0.80431004 -1.86486004 0 P 0 
L 0.80431004 -1.86486004 0.80828996 -1.86433996 0 P 0 
L 0.80828996 -1.86433996 0.8123 -1.86416004 0 P 0 
L 0.8123 -1.86416004 0.81631004 -1.86431998 0 P 0 
L 0.81631004 -1.86431998 0.81946998 -1.86471004 0 P 0 
L 0.81946998 -1.86471004 0.82258996 -1.86531004 0 P 0 
L 0.82258996 -1.86531004 0.82566004 -1.86613996 0 P 0 
L 0.82566004 -1.86613996 0.82866998 -1.86718002 0 P 0 
L 0.82866998 -1.86718002 0.83158996 -1.86843002 0 P 0 
L 0.83158996 -1.86843002 0.83443002 -1.86988996 0 P 0 
L 0.83443002 -1.86988996 0.83716004 -1.87156004 0 P 0 
L 0.83716004 -1.87156004 0.83976004 -1.87341004 0 P 0 
L 0.83976004 -1.87341004 0.84223002 -1.87543996 0 P 0 
L 0.84223002 -1.87543996 0.84453996 -1.87763002 0 P 0 
L 0.84453996 -1.87763002 0.84726998 -1.88065 0 P 0 
L 0.84726998 -1.88065 0.84971998 -1.88388002 0 P 0 
L 0.84971998 -1.88388002 0.85188996 -1.88731004 0 P 0 
L 0.85188996 -1.88731004 0.85376004 -1.89091004 0 P 0 
L 0.85376004 -1.89091004 0.85483996 -1.89345 0 P 0 
L 0.85483996 -1.89345 0.85575 -1.89605 0 P 0 
L 0.85575 -1.89605 0.85646998 -1.89871004 0 P 0 
L 0.85646998 -1.89871004 0.857 -1.90141004 0 P 0 
L 0.857 -1.90141004 0.85748002 -1.9053 0 P 0 
L 0.85748002 -1.9053 0.85763996 -1.90918996 0 P 0 
L 0.85763996 -1.90918996 0.8575 -1.91308002 0 P 0 
L 0.8575 -1.91308002 0.85703996 -1.91696004 0 P 0 
L 0.85703996 -1.91696004 0.85628002 -1.92076004 0 P 0 
L 0.85628002 -1.92076004 0.85521998 -1.92448996 0 P 0 
L 0.85521998 -1.92448996 0.85428002 -1.92705 0 P 0 
L 0.85428002 -1.92705 0.85316998 -1.92951998 0 P 0 
L 0.85316998 -1.92951998 0.85188002 -1.93191004 0 P 0 
L 0.85188002 -1.93191004 0.85041998 -1.9342 0 P 0 
L 0.85041998 -1.9342 0.84826998 -1.93708002 0 P 0 
L 0.84826998 -1.93708002 0.84593002 -1.93976998 0 P 0 
L 0.84593002 -1.93976998 0.8434 -1.94228002 0 P 0 
L 0.8434 -1.94228002 0.84068002 -1.9446 0 P 0 
L 0.84068002 -1.9446 0.8378 -1.9467 0 P 0 
L 0.8378 -1.9467 0.83476998 -1.94858002 0 P 0 
L 0.83476998 -1.94858002 0.83163996 -1.9502 0 P 0 
L 0.83163996 -1.9502 0.8284 -1.95158002 0 P 0 
L 0.8284 -1.95158002 0.82506004 -1.95268996 0 P 0 
L 0.82506004 -1.95268996 0.82163996 -1.95356004 0 P 0 
L 0.82163996 -1.95356004 0.81818002 -1.95413996 0 P 0 
L 0.81818002 -1.95413996 0.8147 -1.95446004 0 P 0 
L 0.8147 -1.95446004 0.81121004 -1.9545 0 P 0 
L 0.77075 -2.02925 0.84511004 -2.02925 0 P 0 
L 0.77076004 -2.02825 0.8452 -2.02825 0 P 0 
L 0.77076998 -2.02725 0.84528996 -2.02725 0 P 0 
L 0.77078002 -2.02625 0.84536998 -2.02625 0 P 0 
L 0.77078996 -2.02525 0.84548996 -2.02525 0 P 0 
L 0.7708 -2.02425 0.84561998 -2.02425 0 P 0 
L 0.77081004 -2.02325 0.84575 -2.02325 0 P 0 
L 0.77081998 -2.02225 0.84588002 -2.02225 0 P 0 
L 0.77083002 -2.02125 0.84601004 -2.02125 0 P 0 
L 0.77083996 -2.02025 0.84613996 -2.02025 0 P 0 
L 0.77085 -2.01925 0.84626004 -2.01925 0 P 0 
L 0.77085 -2.01825 0.84638996 -2.01825 0 P 0 
L 0.77085 -2.01725 0.84651998 -2.01725 0 P 0 
L 0.77086004 -2.01625 0.84663996 -2.01625 0 P 0 
L 0.77086004 -2.01525 0.84676998 -2.01525 0 P 0 
L 0.77086004 -2.01425 0.8469 -2.01425 0 P 0 
L 0.77086004 -2.01325 0.84703002 -2.01325 0 P 0 
L 0.77086004 -2.01225 0.84716004 -2.01225 0 P 0 
L 0.77086004 -2.01125 0.84728996 -2.01125 0 P 0 
L 0.77086004 -2.01025 0.84741004 -2.01025 0 P 0 
L 0.77086998 -2.00925 0.84753996 -2.00925 0 P 0 
L 0.77086998 -2.00825 0.84766998 -2.00825 0 P 0 
L 0.77086998 -2.00725 0.84778996 -2.00725 0 P 0 
L 0.77086998 -2.00625 0.84791998 -2.00625 0 P 0 
L 0.77086998 -2.00525 0.84805 -2.00525 0 P 0 
L 0.77086998 -2.00425 0.84818002 -2.00425 0 P 0 
L 0.77088002 -2.00325 0.84831004 -2.00325 0 P 0 
L 0.77088002 -2.00225 0.84843996 -2.00225 0 P 0 
L 0.77088002 -2.00125 0.84856004 -2.00125 0 P 0 
L 0.77088002 -2.00025 0.84868996 -2.00025 0 P 0 
L 0.77088002 -1.99925 0.84881998 -1.99925 0 P 0 
L 0.77088002 -1.99825 0.84896004 -1.99825 0 P 0 
L 0.77088002 -1.99725 0.84911004 -1.99725 0 P 0 
L 0.77088996 -1.99625 0.84926998 -1.99625 0 P 0 
L 0.77088996 -1.99525 0.84941998 -1.99525 0 P 0 
L 0.77088996 -1.99425 0.84956998 -1.99425 0 P 0 
L 0.77088996 -1.99325 0.84971998 -1.99325 0 P 0 
L 0.77088996 -1.99225 0.84986998 -1.99225 0 P 0 
L 0.77088996 -1.99125 0.85003002 -1.99125 0 P 0 
L 0.7709 -1.99025 0.85018002 -1.99025 0 P 0 
L 0.7709 -1.98925 0.85033002 -1.98925 0 P 0 
L 0.76885 -2.01878002 0.76871998 -2.03201998 0 P 0 
L 0.76871998 -2.03201998 0.7684 -2.04553996 0 P 0 
L 0.7684 -2.04553996 0.76796004 -2.05751004 0 P 0 
L 0.76796004 -2.05751004 0.76741004 -2.06523002 0 P 0 
L 0.76741004 -2.06523002 0.76596004 -2.07933996 0 P 0 
L 0.76596004 -2.07933996 0.7636 -2.09918002 0 P 0 
L 0.7636 -2.09918002 0.76116004 -2.119 0 P 0 
L 0.76116004 -2.119 0.76011998 -2.12526004 0 P 0 
L 0.76011998 -2.12526004 0.75948996 -2.12825 0 P 0 
L 0.75948996 -2.12825 0.84418002 -2.12825 0 P 0 
L 0.84418002 -2.12825 0.84361998 -2.10788002 0 P 0 
L 0.84361998 -2.10788002 0.8436 -2.08276004 0 P 0 
L 0.8436 -2.08276004 0.8449 -2.05491998 0 P 0 
L 0.8449 -2.05491998 0.84736004 -2.02641004 0 P 0 
L 0.84736004 -2.02641004 0.85083996 -1.99923002 0 P 0 
L 0.85083996 -1.99923002 0.85268996 -1.987 0 P 0 
L 0.85268996 -1.987 0.7689 -1.987 0 P 0 
L 0.7689 -1.987 0.76885 -2.01878002 0 P 0 
L 0.76195 -2.12625 0.84211998 -2.12625 0 P 0 
L 0.76213996 -2.12525 0.8421 -2.12525 0 P 0 
L 0.76231004 -2.12425 0.84206998 -2.12425 0 P 0 
L 0.76248002 -2.12325 0.84203996 -2.12325 0 P 0 
L 0.76263996 -2.12225 0.84201004 -2.12225 0 P 0 
L 0.76281004 -2.12125 0.84198996 -2.12125 0 P 0 
L 0.76296998 -2.12025 0.84196004 -2.12025 0 P 0 
L 0.76313996 -2.11925 0.84193002 -2.11925 0 P 0 
L 0.76326998 -2.11825 0.8419 -2.11825 0 P 0 
L 0.76338996 -2.11725 0.84188002 -2.11725 0 P 0 
L 0.76351004 -2.11625 0.84185 -2.11625 0 P 0 
L 0.76363996 -2.11525 0.84181998 -2.11525 0 P 0 
L 0.76376004 -2.11425 0.84178996 -2.11425 0 P 0 
L 0.76388002 -2.11325 0.84176998 -2.11325 0 P 0 
L 0.76401004 -2.11225 0.84173996 -2.11225 0 P 0 
L 0.76413002 -2.11125 0.84171004 -2.11125 0 P 0 
L 0.76425 -2.11025 0.84168002 -2.11025 0 P 0 
L 0.76438002 -2.10925 0.84166004 -2.10925 0 P 0 
L 0.7645 -2.10825 0.84163002 -2.10825 0 P 0 
L 0.76461998 -2.10725 0.84161998 -2.10725 0 P 0 
L 0.76475 -2.10625 0.84161998 -2.10625 0 P 0 
L 0.76486998 -2.10525 0.84161998 -2.10525 0 P 0 
L 0.76498996 -2.10425 0.84161998 -2.10425 0 P 0 
L 0.76511998 -2.10325 0.84161998 -2.10325 0 P 0 
L 0.76523996 -2.10225 0.84161998 -2.10225 0 P 0 
L 0.76536004 -2.10125 0.84161998 -2.10125 0 P 0 
L 0.76548996 -2.10025 0.84161998 -2.10025 0 P 0 
L 0.76561004 -2.09925 0.84161998 -2.09925 0 P 0 
L 0.76573002 -2.09825 0.84161004 -2.09825 0 P 0 
L 0.76583996 -2.09725 0.84161004 -2.09725 0 P 0 
L 0.76596998 -2.09625 0.84161004 -2.09625 0 P 0 
L 0.76608996 -2.09525 0.84161004 -2.09525 0 P 0 
L 0.7662 -2.09425 0.84161004 -2.09425 0 P 0 
L 0.76631998 -2.09325 0.84161004 -2.09325 0 P 0 
L 0.76643996 -2.09225 0.84161004 -2.09225 0 P 0 
L 0.76656004 -2.09125 0.84161004 -2.09125 0 P 0 
L 0.76668002 -2.09025 0.84161004 -2.09025 0 P 0 
L 0.76678996 -2.08925 0.84161004 -2.08925 0 P 0 
L 0.76691998 -2.08825 0.84161004 -2.08825 0 P 0 
L 0.76703002 -2.08725 0.84161004 -2.08725 0 P 0 
L 0.76715 -2.08625 0.8416 -2.08625 0 P 0 
L 0.76726998 -2.08525 0.8416 -2.08525 0 P 0 
L 0.76738996 -2.08425 0.8416 -2.08425 0 P 0 
L 0.76195 -2.12625 0.76208002 -2.12561998 0 P 0 
L 0.76208002 -2.12561998 0.76313996 -2.11928996 0 P 0 
L 0.76313996 -2.11928996 0.76558996 -2.09941998 0 P 0 
L 0.76558996 -2.09941998 0.76558996 -2.09941004 0 P 0 
L 0.76558996 -2.09941004 0.76793996 -2.07956004 0 P 0 
L 0.76793996 -2.07956004 0.7694 -2.0654 0 P 0 
L 0.7694 -2.0654 0.76941004 -2.06536004 0 P 0 
L 0.76941004 -2.06536004 0.76996004 -2.05761998 0 P 0 
L 0.76996004 -2.05761998 0.76996004 -2.05758996 0 P 0 
L 0.76996004 -2.05758996 0.7704 -2.0456 0 P 0 
L 0.7704 -2.0456 0.77071998 -2.03206004 0 P 0 
L 0.77071998 -2.03206004 0.77085 -2.01878002 0 P 0 
L 0.77085 -2.01878002 0.7709 -1.989 0 P 0 
L 0.7709 -1.989 0.85036004 -1.989 0 P 0 
L 0.85036004 -1.989 0.84886004 -1.99895 0 P 0 
L 0.84886004 -1.99895 0.84538002 -2.02618996 0 P 0 
L 0.84538002 -2.02618996 0.8429 -2.05478996 0 P 0 
L 0.8429 -2.05478996 0.8416 -2.08271004 0 P 0 
L 0.8416 -2.08271004 0.84161998 -2.10791004 0 P 0 
L 0.84161998 -2.10791004 0.84211998 -2.12625 0 P 0 
L 0.84211998 -2.12625 0.76195 -2.12625 0 P 0 
L 0.71628996 -1.91261998 0.74938002 -1.91261998 0 P 0 
L 0.71783002 -1.91161998 0.74933002 -1.91161998 0 P 0 
L 0.71953002 -1.91061998 0.74931004 -1.91061998 0 P 0 
L 0.72133002 -1.90961998 0.74928996 -1.90961998 0 P 0 
L 0.72313996 -1.90861998 0.74926998 -1.90861998 0 P 0 
L 0.72493996 -1.90761998 0.74928996 -1.90761998 0 P 0 
L 0.72673996 -1.90661998 0.74931998 -1.90661998 0 P 0 
L 0.72855 -1.90561998 0.74935 -1.90561998 0 P 0 
L 0.73035 -1.90461998 0.74938996 -1.90461998 0 P 0 
L 0.73215 -1.90361998 0.74946998 -1.90361998 0 P 0 
L 0.73396004 -1.90261998 0.74953996 -1.90261998 0 P 0 
L 0.73576004 -1.90161998 0.74961998 -1.90161998 0 P 0 
L 0.73756998 -1.90061998 0.74973996 -1.90061998 0 P 0 
L 0.73943002 -1.89961998 0.74986004 -1.89961998 0 P 0 
L 0.74141998 -1.89861998 0.74998996 -1.89861998 0 P 0 
L 0.74341004 -1.89761998 0.75015 -1.89761998 0 P 0 
L 0.59843002 -2.08361998 0.6754 -2.08361998 0 P 0 
L 0.59846004 -2.08261998 0.67538996 -2.08261998 0 P 0 
L 0.59848002 -2.08161998 0.67538002 -2.08161998 0 P 0 
L 0.59851004 -2.08061998 0.67538002 -2.08061998 0 P 0 
L 0.59853002 -2.07961998 0.67546004 -2.07961998 0 P 0 
L 0.59856004 -2.07861998 0.67553996 -2.07861998 0 P 0 
L 0.59861998 -2.07761998 0.67561004 -2.07761998 0 P 0 
L 0.5987 -2.07661998 0.67568996 -2.07661998 0 P 0 
L 0.59878002 -2.07561998 0.67576004 -2.07561998 0 P 0 
L 0.59885 -2.07461998 0.67583996 -2.07461998 0 P 0 
L 0.59893002 -2.07361998 0.67591998 -2.07361998 0 P 0 
L 0.59901004 -2.07261998 0.67598996 -2.07261998 0 P 0 
L 0.59908002 -2.07161998 0.67606998 -2.07161998 0 P 0 
L 0.59916004 -2.07061998 0.67613996 -2.07061998 0 P 0 
L 0.59923002 -2.06961998 0.67621004 -2.06961998 0 P 0 
L 0.59936004 -2.06861998 0.6763 -2.06861998 0 P 0 
L 0.59948996 -2.06761998 0.67645 -2.06761998 0 P 0 
L 0.59963002 -2.06661998 0.6766 -2.06661998 0 P 0 
L 0.59976998 -2.06561998 0.67676004 -2.06561998 0 P 0 
L 0.5999 -2.06461998 0.67691998 -2.06461998 0 P 0 
L 0.60003002 -2.06361998 0.67706998 -2.06361998 0 P 0 
L 0.60016998 -2.06261998 0.6773 -2.06261998 0 P 0 
L 0.60031004 -2.06161998 0.67753002 -2.06161998 0 P 0 
L 0.60051004 -2.06061998 0.67776004 -2.06061998 0 P 0 
L 0.60071004 -2.05961998 0.67798996 -2.05961998 0 P 0 
L 0.60091998 -2.05861998 0.67823002 -2.05861998 0 P 0 
L 0.60111998 -2.05761998 0.67853002 -2.05761998 0 P 0 
L 0.60133002 -2.05661998 0.67883996 -2.05661998 0 P 0 
L 0.60153996 -2.05561998 0.67913996 -2.05561998 0 P 0 
L 0.60173996 -2.05461998 0.67945 -2.05461998 0 P 0 
L 0.60195 -2.05361998 0.67975 -2.05361998 0 P 0 
L 0.60223002 -2.05261998 0.68006004 -2.05261998 0 P 0 
L 0.60251004 -2.05161998 0.68036004 -2.05161998 0 P 0 
L 0.60278996 -2.05061998 0.68066998 -2.05061998 0 P 0 
L 0.60306004 -2.04961998 0.68096998 -2.04961998 0 P 0 
L 0.60333996 -2.04861998 0.68135 -2.04861998 0 P 0 
L 0.60361998 -2.04761998 0.68173002 -2.04761998 0 P 0 
L 0.6039 -2.04661998 0.68211004 -2.04661998 0 P 0 
L 0.60418002 -2.04561998 0.68248996 -2.04561998 0 P 0 
L 0.60453002 -2.04461998 0.68288002 -2.04461998 0 P 0 
L 0.60488002 -2.04361998 0.68326004 -2.04361998 0 P 0 
L 0.60523002 -2.04261998 0.68363996 -2.04261998 0 P 0 
L 0.60556998 -2.04161998 0.68401998 -2.04161998 0 P 0 
L 0.60591998 -2.04061998 0.6844 -2.04061998 0 P 0 
L 0.60626998 -2.03961998 0.68486004 -2.03961998 0 P 0 
L 0.60661998 -2.03861998 0.68531998 -2.03861998 0 P 0 
L 0.60698996 -2.03761998 0.68578002 -2.03761998 0 P 0 
L 0.60743002 -2.03661998 0.68623996 -2.03661998 0 P 0 
L 0.60786004 -2.03561998 0.6867 -2.03561998 0 P 0 
L 0.60828996 -2.03461998 0.68716004 -2.03461998 0 P 0 
L 0.60873002 -2.03361998 0.68761998 -2.03361998 0 P 0 
L 0.60916004 -2.03261998 0.68808996 -2.03261998 0 P 0 
L 0.60958996 -2.03161998 0.68856998 -2.03161998 0 P 0 
L 0.61003002 -2.03061998 0.68911004 -2.03061998 0 P 0 
L 0.61046004 -2.02961998 0.68965 -2.02961998 0 P 0 
L 0.61088996 -2.02861998 0.69018996 -2.02861998 0 P 0 
L 0.61133002 -2.02761998 0.69073002 -2.02761998 0 P 0 
L 0.61176004 -2.02661998 0.69126998 -2.02661998 0 P 0 
L 0.6122 -2.02561998 0.69181004 -2.02561998 0 P 0 
L 0.61263002 -2.02461998 0.69235 -2.02461998 0 P 0 
L 0.61306004 -2.02361998 0.69288002 -2.02361998 0 P 0 
L 0.61348996 -2.02261998 0.69346998 -2.02261998 0 P 0 
L 0.61393002 -2.02161998 0.69408996 -2.02161998 0 P 0 
L 0.61436004 -2.02061998 0.6947 -2.02061998 0 P 0 
L 0.61478996 -2.01961998 0.69531998 -2.01961998 0 P 0 
L 0.61531004 -2.01861998 0.69593996 -2.01861998 0 P 0 
L 0.61583996 -2.01761998 0.69656004 -2.01761998 0 P 0 
L 0.61636004 -2.01661998 0.69718002 -2.01661998 0 P 0 
L 0.61688002 -2.01561998 0.69778996 -2.01561998 0 P 0 
L 0.6174 -2.01461998 0.69841998 -2.01461998 0 P 0 
L 0.61791998 -2.01361998 0.69911998 -2.01361998 0 P 0 
L 0.61843996 -2.01261998 0.69981998 -2.01261998 0 P 0 
L 0.61896004 -2.01161998 0.70051998 -2.01161998 0 P 0 
L 0.61948002 -2.01061998 0.70123002 -2.01061998 0 P 0 
L 0.62 -2.00961998 0.70193002 -2.00961998 0 P 0 
L 0.62051998 -2.00861998 0.70263002 -2.00861998 0 P 0 
L 0.62103996 -2.00761998 0.70333002 -2.00761998 0 P 0 
L 0.62163996 -2.00661998 0.70403996 -2.00661998 0 P 0 
L 0.62225 -2.00561998 0.70483002 -2.00561998 0 P 0 
L 0.62285 -2.00461998 0.70565 -2.00461998 0 P 0 
L 0.62346004 -2.00361998 0.70646004 -2.00361998 0 P 0 
L 0.62406004 -2.00261998 0.70726998 -2.00261998 0 P 0 
L 0.62466004 -2.00161998 0.70808996 -2.00161998 0 P 0 
L 0.62526998 -2.00061998 0.7089 -2.00061998 0 P 0 
L 0.62586998 -1.99961998 0.70971004 -1.99961998 0 P 0 
L 0.62648002 -1.99861998 0.71053002 -1.99861998 0 P 0 
L 0.62708002 -1.99761998 0.71133996 -1.99761998 0 P 0 
L 0.62768996 -1.99661998 0.71216004 -1.99661998 0 P 0 
L 0.62831998 -1.99561998 0.71296998 -1.99561998 0 P 0 
L 0.62901004 -1.99461998 0.71378996 -1.99461998 0 P 0 
L 0.62971004 -1.99361998 0.71466004 -1.99361998 0 P 0 
L 0.6304 -1.99261998 0.71561004 -1.99261998 0 P 0 
L 0.6311 -1.99161998 0.71656998 -1.99161998 0 P 0 
L 0.63178996 -1.99061998 0.71753002 -1.99061998 0 P 0 
L 0.63248996 -1.98961998 0.71848996 -1.98961998 0 P 0 
L 0.63318002 -1.98861998 0.71945 -1.98861998 0 P 0 
L 0.63388002 -1.98761998 0.72041004 -1.98761998 0 P 0 
L 0.63456998 -1.98661998 0.72136998 -1.98661998 0 P 0 
L 0.63526998 -1.98561998 0.72233002 -1.98561998 0 P 0 
L 0.63598002 -1.98461998 0.72328996 -1.98461998 0 P 0 
L 0.63678996 -1.98361998 0.72425 -1.98361998 0 P 0 
L 0.6376 -1.98261998 0.72521004 -1.98261998 0 P 0 
L 0.63841004 -1.98161998 0.72628002 -1.98161998 0 P 0 
L 0.63921998 -1.98061998 0.72738996 -1.98061998 0 P 0 
L 0.64003002 -1.97961998 0.7285 -1.97961998 0 P 0 
L 0.64083996 -1.97861998 0.72961004 -1.97861998 0 P 0 
L 0.64165 -1.97761998 0.73071004 -1.97761998 0 P 0 
L 0.64246004 -1.97661998 0.73181998 -1.97661998 0 P 0 
L 0.64326998 -1.97561998 0.73293002 -1.97561998 0 P 0 
L 0.64406998 -1.97461998 0.73403996 -1.97461998 0 P 0 
L 0.64488002 -1.97361998 0.73515 -1.97361998 0 P 0 
L 0.64568996 -1.97261998 0.73625 -1.97261998 0 P 0 
L 0.6465 -1.97161998 0.73736004 -1.97161998 0 P 0 
L 0.64731004 -1.97061998 0.73848002 -1.97061998 0 P 0 
L 0.64811998 -1.96961998 0.73973002 -1.96961998 0 P 0 
L 0.64893002 -1.96861998 0.74098996 -1.96861998 0 P 0 
L 0.64981004 -1.96761998 0.74225 -1.96761998 0 P 0 
L 0.65076004 -1.96661998 0.74351004 -1.96661998 0 P 0 
L 0.65171004 -1.96561998 0.74476998 -1.96561998 0 P 0 
L 0.65266998 -1.96461998 0.74603002 -1.96461998 0 P 0 
L 0.65361998 -1.96361998 0.74728996 -1.96361998 0 P 0 
L 0.65458002 -1.96261998 0.74855 -1.96261998 0 P 0 
L 0.65553002 -1.96161998 0.74981004 -1.96161998 0 P 0 
L 0.65648996 -1.96061998 0.75106004 -1.96061998 0 P 0 
L 0.65743996 -1.95961998 0.75233996 -1.95961998 0 P 0 
L 0.6584 -1.95861998 0.7537 -1.95861998 0 P 0 
L 0.65935 -1.95761998 0.75506004 -1.95761998 0 P 0 
L 0.66031004 -1.95661998 0.75641998 -1.95661998 0 P 0 
L 0.66126004 -1.95561998 0.75778996 -1.95561998 0 P 0 
L 0.66221004 -1.95461998 0.75916004 -1.95461998 0 P 0 
L 0.66316998 -1.95361998 0.76053996 -1.95361998 0 P 0 
L 0.66411998 -1.95261998 0.76193996 -1.95261998 0 P 0 
L 0.66523002 -1.95161998 0.76333996 -1.95161998 0 P 0 
L 0.66636004 -1.95061998 0.76406998 -1.95061998 0 P 0 
L 0.66746998 -1.94961998 0.76355 -1.94961998 0 P 0 
L 0.6686 -1.94861998 0.76291998 -1.94861998 0 P 0 
L 0.66971004 -1.94761998 0.76226998 -1.94761998 0 P 0 
L 0.67083996 -1.94661998 0.76161998 -1.94661998 0 P 0 
L 0.67196004 -1.94561998 0.76096998 -1.94561998 0 P 0 
L 0.67306998 -1.94461998 0.76033002 -1.94461998 0 P 0 
L 0.6742 -1.94361998 0.75968996 -1.94361998 0 P 0 
L 0.67531004 -1.94261998 0.75905 -1.94261998 0 P 0 
L 0.67643996 -1.94161998 0.75846004 -1.94161998 0 P 0 
L 0.67755 -1.94061998 0.75788996 -1.94061998 0 P 0 
L 0.67868002 -1.93961998 0.75731998 -1.93961998 0 P 0 
L 0.67978996 -1.93861998 0.75676998 -1.93861998 0 P 0 
L 0.68091998 -1.93761998 0.75626998 -1.93761998 0 P 0 
L 0.68221004 -1.93661998 0.75576998 -1.93661998 0 P 0 
L 0.68353002 -1.93561998 0.75528002 -1.93561998 0 P 0 
L 0.68483996 -1.93461998 0.75483996 -1.93461998 0 P 0 
L 0.68616004 -1.93361998 0.75441004 -1.93361998 0 P 0 
L 0.68746998 -1.93261998 0.75398002 -1.93261998 0 P 0 
L 0.68878002 -1.93161998 0.7536 -1.93161998 0 P 0 
L 0.6901 -1.93061998 0.75323996 -1.93061998 0 P 0 
L 0.69141004 -1.92961998 0.75286998 -1.92961998 0 P 0 
L 0.69271998 -1.92861998 0.75253996 -1.92861998 0 P 0 
L 0.69403002 -1.92761998 0.75223002 -1.92761998 0 P 0 
L 0.69535 -1.92661998 0.75193002 -1.92661998 0 P 0 
L 0.69666004 -1.92561998 0.75163002 -1.92561998 0 P 0 
L 0.69796998 -1.92461998 0.75138002 -1.92461998 0 P 0 
L 0.69936998 -1.92361998 0.75113996 -1.92361998 0 P 0 
L 0.70091004 -1.92261998 0.75088996 -1.92261998 0 P 0 
L 0.70243996 -1.92161998 0.75066004 -1.92161998 0 P 0 
L 0.70398002 -1.92061998 0.75046004 -1.92061998 0 P 0 
L 0.70551998 -1.91961998 0.75026004 -1.91961998 0 P 0 
L 0.70706004 -1.91861998 0.75006998 -1.91861998 0 P 0 
L 0.7086 -1.91761998 0.7499 -1.91761998 0 P 0 
L 0.71013996 -1.91661998 0.74976998 -1.91661998 0 P 0 
L 0.71166998 -1.91561998 0.74961998 -1.91561998 0 P 0 
L 0.71321004 -1.91461998 0.74951998 -1.91461998 0 P 0 
L 0.71475 -1.91361998 0.74945 -1.91361998 0 P 0 
L 0.61556998 -2.15661998 0.70655 -2.15661998 0 P 0 
L 0.61503002 -2.15561998 0.7056 -2.15561998 0 P 0 
L 0.61448996 -2.15461998 0.70465 -2.15461998 0 P 0 
L 0.61395 -2.15361998 0.7037 -2.15361998 0 P 0 
L 0.61341004 -2.15261998 0.70273996 -2.15261998 0 P 0 
L 0.61286998 -2.15161998 0.70178996 -2.15161998 0 P 0 
L 0.61233002 -2.15061998 0.70095 -2.15061998 0 P 0 
L 0.61188002 -2.14961998 0.70015 -2.14961998 0 P 0 
L 0.61143002 -2.14861998 0.69935 -2.14861998 0 P 0 
L 0.61098002 -2.14761998 0.69855 -2.14761998 0 P 0 
L 0.61053002 -2.14661998 0.69775 -2.14661998 0 P 0 
L 0.61008002 -2.14561998 0.69695 -2.14561998 0 P 0 
L 0.60963002 -2.14461998 0.69615 -2.14461998 0 P 0 
L 0.60918002 -2.14361998 0.69535 -2.14361998 0 P 0 
L 0.60873002 -2.14261998 0.69455 -2.14261998 0 P 0 
L 0.60831004 -2.14161998 0.69381998 -2.14161998 0 P 0 
L 0.60793996 -2.14061998 0.69315 -2.14061998 0 P 0 
L 0.60756998 -2.13961998 0.69248002 -2.13961998 0 P 0 
L 0.60721004 -2.13861998 0.69181004 -2.13861998 0 P 0 
L 0.60683996 -2.13761998 0.69115 -2.13761998 0 P 0 
L 0.60646998 -2.13661998 0.69048002 -2.13661998 0 P 0 
L 0.60611004 -2.13561998 0.68981004 -2.13561998 0 P 0 
L 0.60573996 -2.13461998 0.68918002 -2.13461998 0 P 0 
L 0.60538002 -2.13361998 0.68863002 -2.13361998 0 P 0 
L 0.60503996 -2.13261998 0.68808002 -2.13261998 0 P 0 
L 0.60476004 -2.13161998 0.68753002 -2.13161998 0 P 0 
L 0.60446998 -2.13061998 0.68698002 -2.13061998 0 P 0 
L 0.60418002 -2.12961998 0.68643002 -2.12961998 0 P 0 
L 0.6039 -2.12861998 0.68588002 -2.12861998 0 P 0 
L 0.60361004 -2.12761998 0.68533002 -2.12761998 0 P 0 
L 0.60331998 -2.12661998 0.68486004 -2.12661998 0 P 0 
L 0.60303002 -2.12561998 0.68441998 -2.12561998 0 P 0 
L 0.60275 -2.12461998 0.68396998 -2.12461998 0 P 0 
L 0.60246004 -2.12361998 0.68353002 -2.12361998 0 P 0 
L 0.60218002 -2.12261998 0.68308996 -2.12261998 0 P 0 
L 0.60188996 -2.12161998 0.68263996 -2.12161998 0 P 0 
L 0.60166998 -2.12061998 0.6822 -2.12061998 0 P 0 
L 0.60145 -2.11961998 0.68176004 -2.11961998 0 P 0 
L 0.60123002 -2.11861998 0.68138996 -2.11861998 0 P 0 
L 0.60101004 -2.11761998 0.68105 -2.11761998 0 P 0 
L 0.60078002 -2.11661998 0.68071004 -2.11661998 0 P 0 
L 0.6006 -2.11561998 0.68036004 -2.11561998 0 P 0 
L 0.60043002 -2.11461998 0.68001998 -2.11461998 0 P 0 
L 0.60025 -2.11361998 0.67968002 -2.11361998 0 P 0 
L 0.60008002 -2.11261998 0.67933002 -2.11261998 0 P 0 
L 0.59991004 -2.11161998 0.67898996 -2.11161998 0 P 0 
L 0.59976004 -2.11061998 0.6787 -2.11061998 0 P 0 
L 0.59963996 -2.10961998 0.67845 -2.10961998 0 P 0 
L 0.59951004 -2.10861998 0.6782 -2.10861998 0 P 0 
L 0.59938002 -2.10761998 0.67795 -2.10761998 0 P 0 
L 0.59925 -2.10661998 0.6777 -2.10661998 0 P 0 
L 0.59913002 -2.10561998 0.67746004 -2.10561998 0 P 0 
L 0.59905 -2.10461998 0.67721004 -2.10461998 0 P 0 
L 0.59896998 -2.10361998 0.67696004 -2.10361998 0 P 0 
L 0.59888002 -2.10261998 0.67671004 -2.10261998 0 P 0 
L 0.5988 -2.10161998 0.67653996 -2.10161998 0 P 0 
L 0.59871998 -2.10061998 0.67638002 -2.10061998 0 P 0 
L 0.59866998 -2.09961998 0.67621004 -2.09961998 0 P 0 
L 0.59863996 -2.09861998 0.67605 -2.09861998 0 P 0 
L 0.59861004 -2.09761998 0.67588996 -2.09761998 0 P 0 
L 0.59858996 -2.09661998 0.6758 -2.09661998 0 P 0 
L 0.59856004 -2.09561998 0.67571004 -2.09561998 0 P 0 
L 0.59853002 -2.09461998 0.67563002 -2.09461998 0 P 0 
L 0.5985 -2.09361998 0.67553996 -2.09361998 0 P 0 
L 0.59846998 -2.09261998 0.67546004 -2.09261998 0 P 0 
L 0.59843996 -2.09161998 0.67546004 -2.09161998 0 P 0 
L 0.59841998 -2.09061998 0.67545 -2.09061998 0 P 0 
L 0.59838002 -2.08961998 0.67543996 -2.08961998 0 P 0 
L 0.59836004 -2.08861998 0.67543002 -2.08861998 0 P 0 
L 0.59833002 -2.08761998 0.67543002 -2.08761998 0 P 0 
L 0.59835 -2.08661998 0.67541998 -2.08661998 0 P 0 
L 0.59836998 -2.08561998 0.67541004 -2.08561998 0 P 0 
L 0.5984 -2.08461998 0.67541004 -2.08461998 0 P 0 
L 0.80005 -2.25161998 0.85543996 -2.25161998 0 P 0 
L 0.78651998 -2.25061998 0.86596004 -2.25061998 0 P 0 
L 0.77878996 -2.24961998 0.87636004 -2.24961998 0 P 0 
L 0.77106004 -2.24861998 0.88285 -2.24861998 0 P 0 
L 0.76398996 -2.24761998 0.88933996 -2.24761998 0 P 0 
L 0.75891998 -2.24661998 0.89583996 -2.24661998 0 P 0 
L 0.73781004 -1.8982 0.71738996 -1.90951998 0 P 0 
L 0.71738996 -1.90951998 0.69766998 -1.92233996 0 P 0 
L 0.69766998 -1.92233996 0.67971004 -1.93601998 0 P 0 
L 0.67971004 -1.93601998 0.66278996 -1.95113002 0 P 0 
L 0.66278996 -1.95113002 0.64786998 -1.96675 0 P 0 
L 0.64786998 -1.96675 0.63423996 -1.98358996 0 P 0 
L 0.63423996 -1.98358996 0.62643996 -1.99483002 0 P 0 
L 0.62643996 -1.99483002 0.61933996 -2.00655 0 P 0 
L 0.61933996 -2.00655 0.61298996 -2.01873996 0 P 0 
L 0.61298996 -2.01873996 0.60503002 -2.03713002 0 P 0 
L 0.60503002 -2.03713002 0.60225 -2.04506004 0 P 0 
L 0.60225 -2.04506004 0.59998996 -2.05323002 0 P 0 
L 0.59998996 -2.05323002 0.59833996 -2.0612 0 P 0 
L 0.59833996 -2.0612 0.59725 -2.06928996 0 P 0 
L 0.59725 -2.06928996 0.59656998 -2.07833996 0 P 0 
L 0.59656998 -2.07833996 0.59633002 -2.0875 0 P 0 
L 0.59633002 -2.0875 0.59668996 -2.10036998 0 P 0 
L 0.59668996 -2.10036998 0.59715 -2.10596004 0 P 0 
L 0.59715 -2.10596004 0.59786004 -2.11151004 0 P 0 
L 0.59786004 -2.11151004 0.59878996 -2.11686998 0 P 0 
L 0.59878996 -2.11686998 0.59996998 -2.1222 0 P 0 
L 0.59996998 -2.1222 0.60326998 -2.13368996 0 P 0 
L 0.60326998 -2.13368996 0.60656998 -2.1427 0 P 0 
L 0.60656998 -2.1427 0.6105 -2.15143996 0 P 0 
L 0.6105 -2.15143996 0.61505 -2.15988002 0 P 0 
L 0.61505 -2.15988002 0.62023996 -2.16803996 0 P 0 
L 0.62023996 -2.16803996 0.62828996 -2.17873002 0 P 0 
L 0.62828996 -2.17873002 0.63718996 -2.18871004 0 P 0 
L 0.63718996 -2.18871004 0.64693002 -2.19795 0 P 0 
L 0.64693002 -2.19795 0.6582 -2.20701998 0 P 0 
L 0.6582 -2.20701998 0.67011004 -2.21518996 0 P 0 
L 0.67011004 -2.21518996 0.68261004 -2.22243002 0 P 0 
L 0.68261004 -2.22243002 0.69673996 -2.22936004 0 P 0 
L 0.69673996 -2.22936004 0.71123002 -2.23543996 0 P 0 
L 0.71123002 -2.23543996 0.72611998 -2.24066998 0 P 0 
L 0.72611998 -2.24066998 0.74536004 -2.24598996 0 P 0 
L 0.74536004 -2.24598996 0.76493002 -2.24985 0 P 0 
L 0.76493002 -2.24985 0.78671998 -2.25266998 0 P 0 
L 0.78671998 -2.25266998 0.80863002 -2.25425 0 P 0 
L 0.80863002 -2.25425 0.83146004 -2.25463002 0 P 0 
L 0.83146004 -2.25463002 0.85418002 -2.25375 0 P 0 
L 0.85418002 -2.25375 0.87641004 -2.25163996 0 P 0 
L 0.87641004 -2.25163996 0.89853002 -2.24823002 0 P 0 
L 0.89853002 -2.24823002 0.93045 -2.24101998 0 P 0 
L 0.93045 -2.24101998 0.96466004 -2.23063002 0 P 0 
L 0.96466004 -2.23063002 0.99911004 -2.2178 0 P 0 
L 0.99911004 -2.2178 1.03183002 -2.20318002 0 P 0 
L 1.03183002 -2.20318002 1.04391998 -2.19703002 0 P 0 
L 1.04391998 -2.19703002 1.05581004 -2.19048996 0 P 0 
L 1.05581004 -2.19048996 1.06676004 -2.18411998 0 P 0 
L 1.06676004 -2.18411998 1.06681004 -2.18408996 0 P 0 
L 1.06681004 -2.18408996 1.06685 -2.18405 0 P 0 
L 1.06685 -2.18405 1.0669 -2.18401004 0 P 0 
L 1.0669 -2.18401004 1.06693996 -2.18396998 0 P 0 
L 1.06693996 -2.18396998 1.06696998 -2.18391998 0 P 0 
L 1.06696998 -2.18391998 1.06701004 -2.18386998 0 P 0 
L 1.06701004 -2.18386998 1.06703002 -2.18381998 0 P 0 
L 1.06703002 -2.18381998 1.06706004 -2.18376004 0 P 0 
L 1.06706004 -2.18376004 1.06706998 -2.18371004 0 P 0 
L 1.06706998 -2.18371004 1.06708996 -2.18365 0 P 0 
L 1.06708996 -2.18365 1.06708996 -2.18358996 0 P 0 
L 1.06708996 -2.18358996 1.0671 -2.18353002 0 P 0 
L 1.0671 -2.18353002 1.0671 -2.18346998 0 P 0 
L 1.0671 -2.18346998 1.06708996 -2.18341004 0 P 0 
L 1.06708996 -2.18341004 1.06706998 -2.18336004 0 P 0 
L 1.06706998 -2.18336004 1.06706004 -2.1833 0 P 0 
L 1.06706004 -2.1833 1.06703002 -2.18323996 0 P 0 
L 1.06703002 -2.18323996 1.06701004 -2.18318996 0 P 0 
L 1.06701004 -2.18318996 1.06696998 -2.18313996 0 P 0 
L 1.06696998 -2.18313996 1.06693996 -2.18308996 0 P 0 
L 1.06693996 -2.18308996 1.06688002 -2.18303002 0 P 0 
L 1.06688002 -2.18303002 1.06678996 -2.18296998 0 P 0 
L 1.06678996 -2.18296998 1.06673002 -2.18295 0 P 0 
L 1.06673002 -2.18295 1.0667 -2.18295 0 P 0 
L 1.0667 -2.18295 1.06666004 -2.18293996 0 P 0 
L 1.06666004 -2.18293996 1.0666 -2.18293996 0 P 0 
L 1.0666 -2.18293996 1.06656998 -2.18295 0 P 0 
L 1.06656998 -2.18295 1.06653002 -2.18295 0 P 0 
L 1.06653002 -2.18295 1.06153002 -2.1842 0 P 0 
L 1.06153002 -2.1842 1.05583996 -2.18566998 0 P 0 
L 1.05583996 -2.18566998 1.04916998 -2.1875 0 P 0 
L 1.04916998 -2.1875 1.0153 -2.1962 0 P 0 
L 1.0153 -2.1962 0.9814 -2.20333996 0 P 0 
L 0.9814 -2.20333996 0.94881998 -2.2087 0 P 0 
L 0.94881998 -2.2087 0.9189 -2.21198996 0 P 0 
L 0.9189 -2.21198996 0.90113996 -2.21278996 0 P 0 
L 0.90113996 -2.21278996 0.87738002 -2.21265 0 P 0 
L 0.87738002 -2.21265 0.854 -2.21183002 0 P 0 
L 0.854 -2.21183002 0.83788996 -2.21033996 0 P 0 
L 0.83788996 -2.21033996 0.8174 -2.20693002 0 P 0 
L 0.8174 -2.20693002 0.79708996 -2.2023 0 P 0 
L 0.79708996 -2.2023 0.7769 -2.19641004 0 P 0 
L 0.7769 -2.19641004 0.76433002 -2.19183996 0 P 0 
L 0.76433002 -2.19183996 0.75208996 -2.18638002 0 P 0 
L 0.75208996 -2.18638002 0.74026998 -2.18006998 0 P 0 
L 0.74026998 -2.18006998 0.72886998 -2.17291004 0 P 0 
L 0.72886998 -2.17291004 0.71961998 -2.16603002 0 P 0 
L 0.71961998 -2.16603002 0.71098996 -2.15838996 0 P 0 
L 0.71098996 -2.15838996 0.70303002 -2.15003002 0 P 0 
L 0.70303002 -2.15003002 0.6958 -2.14098996 0 P 0 
L 0.6958 -2.14098996 0.69106998 -2.1339 0 P 0 
L 0.69106998 -2.1339 0.68696004 -2.12643002 0 P 0 
L 0.68696004 -2.12643002 0.68351004 -2.11863002 0 P 0 
L 0.68351004 -2.11863002 0.68073996 -2.11056004 0 P 0 
L 0.68073996 -2.11056004 0.67866004 -2.10218996 0 P 0 
L 0.67866004 -2.10218996 0.67788002 -2.09741998 0 P 0 
L 0.67788002 -2.09741998 0.67746004 -2.0926 0 P 0 
L 0.67746004 -2.0926 0.67738002 -2.08076004 0 P 0 
L 0.67738002 -2.08076004 0.67828002 -2.06891004 0 P 0 
L 0.67828002 -2.06891004 0.67903002 -2.06403996 0 P 0 
L 0.67903002 -2.06403996 0.68013002 -2.05923996 0 P 0 
L 0.68013002 -2.05923996 0.68288002 -2.05021998 0 P 0 
L 0.68288002 -2.05021998 0.68623996 -2.04141004 0 P 0 
L 0.68623996 -2.04141004 0.69018002 -2.03286004 0 P 0 
L 0.69018002 -2.03286004 0.69486004 -2.02418002 0 P 0 
L 0.69486004 -2.02418002 0.70003996 -2.0158 0 P 0 
L 0.70003996 -2.0158 0.70573002 -2.00768996 0 P 0 
L 0.70573002 -2.00768996 0.7158 -1.99531998 0 P 0 
L 0.7158 -1.99531998 0.72681004 -1.98385 0 P 0 
L 0.72681004 -1.98385 0.73971004 -1.9722 0 P 0 
L 0.73971004 -1.9722 0.7533 -1.9614 0 P 0 
L 0.7533 -1.9614 0.75753996 -1.95828002 0 P 0 
L 0.75753996 -1.95828002 0.76138002 -1.95548002 0 P 0 
L 0.76138002 -1.95548002 0.76463002 -1.95316004 0 P 0 
L 0.76463002 -1.95316004 0.76516004 -1.95281004 0 P 0 
L 0.76516004 -1.95281004 0.7657 -1.95248996 0 P 0 
L 0.7657 -1.95248996 0.76578002 -1.95243996 0 P 0 
L 0.76578002 -1.95243996 0.76586004 -1.95238002 0 P 0 
L 0.76586004 -1.95238002 0.76593002 -1.95231998 0 P 0 
L 0.76593002 -1.95231998 0.766 -1.95223996 0 P 0 
L 0.766 -1.95223996 0.76606004 -1.95216998 0 P 0 
L 0.76606004 -1.95216998 0.76616004 -1.95201004 0 P 0 
L 0.76616004 -1.95201004 0.7662 -1.95191998 0 P 0 
L 0.7662 -1.95191998 0.76626004 -1.95173996 0 P 0 
L 0.76626004 -1.95173996 0.76628002 -1.95163996 0 P 0 
L 0.76628002 -1.95163996 0.7663 -1.95143002 0 P 0 
L 0.7663 -1.95143002 0.7663 -1.95121004 0 P 0 
L 0.7663 -1.95121004 0.76628996 -1.951 0 P 0 
L 0.76628996 -1.951 0.76625 -1.95078996 0 P 0 
L 0.76625 -1.95078996 0.7662 -1.95058002 0 P 0 
L 0.7662 -1.95058002 0.76613002 -1.95036998 0 P 0 
L 0.76613002 -1.95036998 0.76583002 -1.94966998 0 P 0 
L 0.76583002 -1.94966998 0.76548996 -1.94896998 0 P 0 
L 0.76548996 -1.94896998 0.76508996 -1.9483 0 P 0 
L 0.76508996 -1.9483 0.76253002 -1.94436004 0 P 0 
L 0.76253002 -1.94436004 0.76056998 -1.94126998 0 P 0 
L 0.76056998 -1.94126998 0.75871998 -1.93806004 0 P 0 
L 0.75871998 -1.93806004 0.75716998 -1.93496998 0 P 0 
L 0.75716998 -1.93496998 0.7558 -1.93178002 0 P 0 
L 0.7558 -1.93178002 0.7546 -1.92853996 0 P 0 
L 0.7546 -1.92853996 0.75358996 -1.92521004 0 P 0 
L 0.75358996 -1.92521004 0.7527 -1.92161998 0 P 0 
L 0.7527 -1.92161998 0.75196998 -1.91796004 0 P 0 
L 0.75196998 -1.91796004 0.75155 -1.91496004 0 P 0 
L 0.75155 -1.91496004 0.75133002 -1.91193002 0 P 0 
L 0.75133002 -1.91193002 0.75126998 -1.9085 0 P 0 
L 0.75126998 -1.9085 0.75136004 -1.90506004 0 P 0 
L 0.75136004 -1.90506004 0.75161004 -1.90181998 0 P 0 
L 0.75161004 -1.90181998 0.752 -1.8986 0 P 0 
L 0.752 -1.8986 0.75228996 -1.89701998 0 P 0 
L 0.75228996 -1.89701998 0.75268996 -1.89546998 0 P 0 
L 0.75268996 -1.89546998 0.7532 -1.89395 0 P 0 
L 0.7532 -1.89395 0.75358996 -1.89281998 0 P 0 
L 0.75358996 -1.89281998 0.75373002 -1.89231998 0 P 0 
L 0.75373002 -1.89231998 0.75383996 -1.8918 0 P 0 
L 0.75383996 -1.8918 0.75391998 -1.89138996 0 P 0 
L 0.75391998 -1.89138996 0.75396998 -1.89098996 0 P 0 
L 0.75396998 -1.89098996 0.75396998 -1.89086004 0 P 0 
L 0.75396998 -1.89086004 0.75393996 -1.89076998 0 P 0 
L 0.75393996 -1.89076998 0.7539 -1.89071004 0 P 0 
L 0.7539 -1.89071004 0.75386004 -1.89066998 0 P 0 
L 0.75386004 -1.89066998 0.75381004 -1.89063002 0 P 0 
L 0.75381004 -1.89063002 0.75378996 -1.89061004 0 P 0 
L 0.75378996 -1.89061004 0.75373002 -1.89058996 0 P 0 
L 0.75373002 -1.89058996 0.75368002 -1.89056998 0 P 0 
L 0.75368002 -1.89056998 0.75356004 -1.89056998 0 P 0 
L 0.75356004 -1.89056998 0.75346998 -1.8906 0 P 0 
L 0.75346998 -1.8906 0.74898002 -1.8927 0 P 0 
L 0.74898002 -1.8927 0.74383002 -1.89518002 0 P 0 
L 0.74383002 -1.89518002 0.73781004 -1.8982 0 P 0 
L 0.69776998 -2.22761998 0.96701004 -2.22761998 0 P 0 
L 0.6957 -2.22661998 0.96968996 -2.22661998 0 P 0 
L 0.69366998 -2.22561998 0.97238002 -2.22561998 0 P 0 
L 0.69163002 -2.22461998 0.97506004 -2.22461998 0 P 0 
L 0.68958996 -2.22361998 0.97775 -2.22361998 0 P 0 
L 0.68756004 -2.22261998 0.98043002 -2.22261998 0 P 0 
L 0.68551998 -2.22161998 0.98311004 -2.22161998 0 P 0 
L 0.68348996 -2.22061998 0.9858 -2.22061998 0 P 0 
L 0.68176998 -2.21961998 0.98848002 -2.21961998 0 P 0 
L 0.68003996 -2.21861998 0.99116998 -2.21861998 0 P 0 
L 0.67831004 -2.21761998 0.99385 -2.21761998 0 P 0 
L 0.67658002 -2.21661998 0.99653996 -2.21661998 0 P 0 
L 0.67485 -2.21561998 0.99908002 -2.21561998 0 P 0 
L 0.67311998 -2.21461998 0.87665 -2.21461998 0 P 0 
L 0.6714 -2.21361998 0.85166004 -2.21361998 0 P 0 
L 0.6699 -2.21261998 0.84083002 -2.21261998 0 P 0 
L 0.66845 -2.21161998 0.8334 -2.21161998 0 P 0 
L 0.66698996 -2.21061998 0.8274 -2.21061998 0 P 0 
L 0.66553002 -2.20961998 0.82138996 -2.20961998 0 P 0 
L 0.66406998 -2.20861998 0.81583002 -2.20861998 0 P 0 
L 0.66261998 -2.20761998 0.81143996 -2.20761998 0 P 0 
L 0.66116004 -2.20661998 0.80706004 -2.20661998 0 P 0 
L 0.6597 -2.20561998 0.80266998 -2.20561998 0 P 0 
L 0.65841004 -2.20461998 0.79828996 -2.20461998 0 P 0 
L 0.65716998 -2.20361998 0.79448996 -2.20361998 0 P 0 
L 0.65593002 -2.20261998 0.79106004 -2.20261998 0 P 0 
L 0.65468996 -2.20161998 0.78763996 -2.20161998 0 P 0 
L 0.83143002 -2.25261998 0.80871998 -2.25225 0 P 0 
L 0.80871998 -2.25225 0.78691998 -2.25066998 0 P 0 
L 0.78691998 -2.25066998 0.76525 -2.24786998 0 P 0 
L 0.76525 -2.24786998 0.74581998 -2.24403996 0 P 0 
L 0.74581998 -2.24403996 0.72671004 -2.23876004 0 P 0 
L 0.72671004 -2.23876004 0.71196004 -2.23356998 0 P 0 
L 0.71196004 -2.23356998 0.69756998 -2.22753996 0 P 0 
L 0.69756998 -2.22753996 0.68355 -2.22066004 0 P 0 
L 0.68355 -2.22066004 0.67118002 -2.2135 0 P 0 
L 0.67118002 -2.2135 0.65938996 -2.20541004 0 P 0 
L 0.65938996 -2.20541004 0.64825 -2.19643996 0 P 0 
L 0.64825 -2.19643996 0.63861998 -2.18731998 0 P 0 
L 0.63861998 -2.18731998 0.62983002 -2.17746998 0 P 0 
L 0.62983002 -2.17746998 0.62188996 -2.1669 0 P 0 
L 0.62188996 -2.1669 0.61678002 -2.15886998 0 P 0 
L 0.61678002 -2.15886998 0.6123 -2.15056004 0 P 0 
L 0.6123 -2.15056004 0.60841998 -2.14193996 0 P 0 
L 0.60841998 -2.14193996 0.60516998 -2.13306998 0 P 0 
L 0.60516998 -2.13306998 0.60191004 -2.12171004 0 P 0 
L 0.60191004 -2.12171004 0.60075 -2.11648002 0 P 0 
L 0.60075 -2.11648002 0.59983996 -2.11121004 0 P 0 
L 0.59983996 -2.11121004 0.59913996 -2.10576004 0 P 0 
L 0.59913996 -2.10576004 0.59868996 -2.10026004 0 P 0 
L 0.59868996 -2.10026004 0.59833002 -2.0875 0 P 0 
L 0.59833002 -2.0875 0.59856998 -2.07843996 0 P 0 
L 0.59856998 -2.07843996 0.59923996 -2.0695 0 P 0 
L 0.59923996 -2.0695 0.60031998 -2.06153996 0 P 0 
L 0.60031998 -2.06153996 0.60193002 -2.05368996 0 P 0 
L 0.60193002 -2.05368996 0.60416004 -2.04566004 0 P 0 
L 0.60416004 -2.04566004 0.60688996 -2.03786004 0 P 0 
L 0.60688996 -2.03786004 0.6148 -2.01961004 0 P 0 
L 0.6148 -2.01961004 0.62108996 -2.00753002 0 P 0 
L 0.62108996 -2.00753002 0.62811998 -1.99591998 0 P 0 
L 0.62811998 -1.99591998 0.63583996 -1.98478996 0 P 0 
L 0.63583996 -1.98478996 0.64936998 -1.96808002 0 P 0 
L 0.64936998 -1.96808002 0.66418002 -1.95256998 0 P 0 
L 0.66418002 -1.95256998 0.68098002 -1.93756004 0 P 0 
L 0.68098002 -1.93756004 0.69881998 -1.92398002 0 P 0 
L 0.69881998 -1.92398002 0.71841998 -1.91123996 0 P 0 
L 0.71841998 -1.91123996 0.73875 -1.89996998 0 P 0 
L 0.73875 -1.89996998 0.74471004 -1.89696998 0 P 0 
L 0.74471004 -1.89696998 0.74983002 -1.89451004 0 P 0 
L 0.74983002 -1.89451004 0.7511 -1.89391004 0 P 0 
L 0.7511 -1.89391004 0.75076998 -1.89488996 0 P 0 
L 0.75076998 -1.89488996 0.75033996 -1.89658996 0 P 0 
L 0.75033996 -1.89658996 0.75003002 -1.8983 0 P 0 
L 0.75003002 -1.8983 0.74961998 -1.90161998 0 P 0 
L 0.74961998 -1.90161998 0.74936004 -1.90496004 0 P 0 
L 0.74936004 -1.90496004 0.74926998 -1.9085 0 P 0 
L 0.74926998 -1.9085 0.74933002 -1.91201998 0 P 0 
L 0.74933002 -1.91201998 0.74956004 -1.91516998 0 P 0 
L 0.74956004 -1.91516998 0.75 -1.91828996 0 P 0 
L 0.75 -1.91828996 0.75075 -1.92205 0 P 0 
L 0.75075 -1.92205 0.75166004 -1.92573996 0 P 0 
L 0.75166004 -1.92573996 0.7527 -1.92916998 0 P 0 
L 0.7527 -1.92916998 0.75393996 -1.93253002 0 P 0 
L 0.75393996 -1.93253002 0.75536004 -1.93581998 0 P 0 
L 0.75536004 -1.93581998 0.75696004 -1.939 0 P 0 
L 0.75696004 -1.939 0.75885 -1.94231004 0 P 0 
L 0.75885 -1.94231004 0.76083996 -1.94543996 0 P 0 
L 0.76083996 -1.94543996 0.76338996 -1.94933996 0 P 0 
L 0.76338996 -1.94933996 0.76371998 -1.94991998 0 P 0 
L 0.76371998 -1.94991998 0.76401004 -1.9505 0 P 0 
L 0.76401004 -1.9505 0.76423996 -1.95103002 0 P 0 
L 0.76423996 -1.95103002 0.76408996 -1.95111004 0 P 0 
L 0.76408996 -1.95111004 0.76348996 -1.95151004 0 P 0 
L 0.76348996 -1.95151004 0.76021004 -1.95386004 0 P 0 
L 0.76021004 -1.95386004 0.7602 -1.95386998 0 P 0 
L 0.7602 -1.95386998 0.75636998 -1.95666004 0 P 0 
L 0.75636998 -1.95666004 0.75636004 -1.95666998 0 P 0 
L 0.75636004 -1.95666998 0.75635 -1.95666998 0 P 0 
L 0.75635 -1.95666998 0.75208996 -1.95981004 0 P 0 
L 0.75208996 -1.95981004 0.73841004 -1.97066998 0 P 0 
L 0.73841004 -1.97066998 0.72541004 -1.98241004 0 P 0 
L 0.72541004 -1.98241004 0.7143 -1.994 0 P 0 
L 0.7143 -1.994 0.71425 -1.99406004 0 P 0 
L 0.71425 -1.99406004 0.70413996 -2.00648002 0 P 0 
L 0.70413996 -2.00648002 0.69836998 -2.01468996 0 P 0 
L 0.69836998 -2.01468996 0.69313002 -2.02318002 0 P 0 
L 0.69313002 -2.02318002 0.68838996 -2.03196004 0 P 0 
L 0.68838996 -2.03196004 0.68438996 -2.04063996 0 P 0 
L 0.68438996 -2.04063996 0.68098996 -2.04958002 0 P 0 
L 0.68098996 -2.04958002 0.6782 -2.05873002 0 P 0 
L 0.6782 -2.05873002 0.67706004 -2.06366004 0 P 0 
L 0.67706004 -2.06366004 0.67628996 -2.06866998 0 P 0 
L 0.67628996 -2.06866998 0.67538002 -2.08068996 0 P 0 
L 0.67538002 -2.08068996 0.67546004 -2.09268996 0 P 0 
L 0.67546004 -2.09268996 0.67588996 -2.09766998 0 P 0 
L 0.67588996 -2.09766998 0.6767 -2.10258996 0 P 0 
L 0.6767 -2.10258996 0.67881998 -2.11111998 0 P 0 
L 0.67881998 -2.11111998 0.68163996 -2.11936004 0 P 0 
L 0.68163996 -2.11936004 0.68516004 -2.12731998 0 P 0 
L 0.68516004 -2.12731998 0.68935 -2.13493996 0 P 0 
L 0.68935 -2.13493996 0.69418002 -2.14216998 0 P 0 
L 0.69418002 -2.14216998 0.70153002 -2.15135 0 P 0 
L 0.70153002 -2.15135 0.7096 -2.15983002 0 P 0 
L 0.7096 -2.15983002 0.71836004 -2.16758996 0 P 0 
L 0.71836004 -2.16758996 0.71843002 -2.16763996 0 P 0 
L 0.71843002 -2.16763996 0.72773996 -2.17456004 0 P 0 
L 0.72773996 -2.17456004 0.73926998 -2.1818 0 P 0 
L 0.73926998 -2.1818 0.75121004 -2.18818002 0 P 0 
L 0.75121004 -2.18818002 0.75128002 -2.18821004 0 P 0 
L 0.75128002 -2.18821004 0.76358002 -2.19368996 0 P 0 
L 0.76358002 -2.19368996 0.77628002 -2.19831004 0 P 0 
L 0.77628002 -2.19831004 0.79658996 -2.20423996 0 P 0 
L 0.79658996 -2.20423996 0.81701004 -2.20888996 0 P 0 
L 0.81701004 -2.20888996 0.83763996 -2.21233002 0 P 0 
L 0.83763996 -2.21233002 0.85388002 -2.21383002 0 P 0 
L 0.85388002 -2.21383002 0.87733996 -2.21465 0 P 0 
L 0.87733996 -2.21465 0.90118002 -2.21478996 0 P 0 
L 0.90118002 -2.21478996 0.91906004 -2.21398996 0 P 0 
L 0.91906004 -2.21398996 0.94908996 -2.21068002 0 P 0 
L 0.94908996 -2.21068002 0.98176998 -2.2053 0 P 0 
L 0.98176998 -2.2053 1.01575 -2.19815 0 P 0 
L 1.01575 -2.19815 1.04968002 -2.18943002 0 P 0 
L 1.04968002 -2.18943002 1.05633996 -2.18761004 0 P 0 
L 1.05633996 -2.18761004 1.05713996 -2.1874 0 P 0 
L 1.05713996 -2.1874 1.05483002 -2.18875 0 P 0 
L 1.05483002 -2.18875 1.04298996 -2.19526004 0 P 0 
L 1.04298996 -2.19526004 1.03096998 -2.20136998 0 P 0 
L 1.03096998 -2.20136998 0.99835 -2.21595 0 P 0 
L 0.99835 -2.21595 0.96401998 -2.22873996 0 P 0 
L 0.96401998 -2.22873996 0.92993996 -2.23908002 0 P 0 
L 0.92993996 -2.23908002 0.89816004 -2.24626004 0 P 0 
L 0.89816004 -2.24626004 0.87616004 -2.24965 0 P 0 
L 0.87616004 -2.24965 0.85405 -2.25176004 0 P 0 
L 0.85405 -2.25176004 0.83143002 -2.25261998 0 P 0 
L 0.65345 -2.20061998 0.78421004 -2.20061998 0 P 0 
L 0.65221004 -2.19961998 0.78078002 -2.19961998 0 P 0 
L 0.65096004 -2.19861998 0.77735 -2.19861998 0 P 0 
L 0.64971998 -2.19761998 0.77438996 -2.19761998 0 P 0 
L 0.64848002 -2.19661998 0.77163996 -2.19661998 0 P 0 
L 0.64738996 -2.19561998 0.76888996 -2.19561998 0 P 0 
L 0.64633996 -2.19461998 0.76613996 -2.19461998 0 P 0 
L 0.64528002 -2.19361998 0.76343002 -2.19361998 0 P 0 
L 0.64421998 -2.19261998 0.76118996 -2.19261998 0 P 0 
L 0.64316998 -2.19161998 0.75893996 -2.19161998 0 P 0 
L 0.64211004 -2.19061998 0.7567 -2.19061998 0 P 0 
L 0.64106004 -2.18961998 0.75446004 -2.18961998 0 P 0 
L 0.64 -2.18861998 0.75221004 -2.18861998 0 P 0 
L 0.63895 -2.18761998 0.75018002 -2.18761998 0 P 0 
L 0.63801004 -2.18661998 0.74831004 -2.18661998 0 P 0 
L 0.63711004 -2.18561998 0.74643002 -2.18561998 0 P 0 
L 0.63621998 -2.18461998 0.74456004 -2.18461998 0 P 0 
L 0.63533002 -2.18361998 0.74268002 -2.18361998 0 P 0 
L 0.63443996 -2.18261998 0.74081004 -2.18261998 0 P 0 
L 0.63353996 -2.18161998 0.73898996 -2.18161998 0 P 0 
L 0.63265 -2.18061998 0.73738996 -2.18061998 0 P 0 
L 0.63176004 -2.17961998 0.7358 -2.17961998 0 P 0 
L 0.63086998 -2.17861998 0.73421004 -2.17861998 0 P 0 
L 0.62996998 -2.17761998 0.73261998 -2.17761998 0 P 0 
L 0.6292 -2.17661998 0.73103002 -2.17661998 0 P 0 
L 0.62845 -2.17561998 0.72943996 -2.17561998 0 P 0 
L 0.6277 -2.17461998 0.72783996 -2.17461998 0 P 0 
L 0.62693996 -2.17361998 0.72648002 -2.17361998 0 P 0 
L 0.62618996 -2.17261998 0.72513996 -2.17261998 0 P 0 
L 0.62543996 -2.17161998 0.72378996 -2.17161998 0 P 0 
L 0.62468996 -2.17061998 0.72245 -2.17061998 0 P 0 
L 0.62393996 -2.16961998 0.7211 -2.16961998 0 P 0 
L 0.62318002 -2.16861998 0.71976004 -2.16861998 0 P 0 
L 0.62243996 -2.16761998 0.71841004 -2.16761998 0 P 0 
L 0.62171004 -2.16661998 0.71726998 -2.16661998 0 P 0 
L 0.62108002 -2.16561998 0.71613996 -2.16561998 0 P 0 
L 0.62043996 -2.16461998 0.71501004 -2.16461998 0 P 0 
L 0.61981004 -2.16361998 0.71388002 -2.16361998 0 P 0 
L 0.61916998 -2.16261998 0.71276004 -2.16261998 0 P 0 
L 0.61853002 -2.16161998 0.71163002 -2.16161998 0 P 0 
L 0.6179 -2.16061998 0.7105 -2.16061998 0 P 0 
L 0.61726004 -2.15961998 0.7094 -2.15961998 0 P 0 
L 0.61665 -2.15861998 0.70845 -2.15861998 0 P 0 
L 0.61611004 -2.15761998 0.7075 -2.15761998 0 P 0 
L 0.75383996 -2.24561998 0.901 -2.24561998 0 P 0 
L 0.74876998 -2.24461998 0.90541998 -2.24461998 0 P 0 
L 0.74431004 -2.24361998 0.90985 -2.24361998 0 P 0 
L 0.7407 -2.24261998 0.91426998 -2.24261998 0 P 0 
L 0.73708002 -2.24161998 0.9187 -2.24161998 0 P 0 
L 0.73346998 -2.24061998 0.92311998 -2.24061998 0 P 0 
L 0.72986004 -2.23961998 0.92753996 -2.23961998 0 P 0 
L 0.72633996 -2.23861998 0.93145 -2.23861998 0 P 0 
L 0.72348996 -2.23761998 0.93473996 -2.23761998 0 P 0 
L 0.72063996 -2.23661998 0.93803996 -2.23661998 0 P 0 
L 0.7178 -2.23561998 0.94133002 -2.23561998 0 P 0 
L 0.71495 -2.23461998 0.94461998 -2.23461998 0 P 0 
L 0.7121 -2.23361998 0.94791998 -2.23361998 0 P 0 
L 0.70968996 -2.23261998 0.95121004 -2.23261998 0 P 0 
L 0.70731004 -2.23161998 0.95451004 -2.23161998 0 P 0 
L 0.70491998 -2.23061998 0.9578 -2.23061998 0 P 0 
L 0.70253996 -2.22961998 0.9611 -2.22961998 0 P 0 
L 0.70015 -2.22861998 0.96431998 -2.22861998 0 P 0 
A 1.571 0.835 1.571 0.835 1.431 0.835 5 P 0 N
A 1.573 0.493 1.573 0.493 1.433 0.493 5 P 0 N
L 1.87086998 0.8365 2.29213002 0.8365 1 P 0 
A 2.29213002 0.8365 2.3315 0.79713002 2.29213002 0.79713002 1 P 0 Y
L 2.3315 0.79713002 2.3315 0.43886998 1 P 0 
A 2.3315 0.43886998 2.29213002 0.3995 2.29213002 0.43886998 1 P 0 Y
L 2.29213002 0.3995 1.87086998 0.3995 1 P 0 
A 1.87086998 0.3995 1.8315 0.43886998 1.87086998 0.43886998 1 P 0 Y
L 1.8315 0.43886998 1.8315 0.79713002 1 P 0 
A 1.8315 0.79713002 1.87086998 0.8365 1.87086998 0.79713002 1 P 0 Y
L 2.64493996 0.57161998 3.28493996 0.57161998 1 P 0 
L 3.28493996 0.57161998 3.28493996 0.37161998 1 P 0 
L 3.28493996 0.37161998 2.64493996 0.37161998 1 P 0 
L 2.64493996 0.37161998 2.64493996 0.57161998 1 P 0 
L 2.64993996 0.63161998 2.64993996 0.89161998 1 P 0 
L 2.64993996 0.89161998 2.96993996 0.89161998 1 P 0 
L 2.96993996 0.89161998 2.96993996 0.63161998 1 P 0 
L 2.96993996 0.63161998 2.64993996 0.63161998 1 P 0 
L 11.69566624 5.856 11.69566624 5.946 8 P 0 ;0,1=0,2=0.000000
L 11.69566624 5.946 11.72366673 5.946 8 P 0 ;0,1=0,2=0.000000
L 11.72366673 5.946 11.7330002 5.94149813 8 P 0 ;0,1=0,2=0.000000
L 11.7330002 5.94149813 11.74000079 5.93100039 8 P 0 ;0,1=0,2=0.000000
L 11.74000079 5.93100039 11.74233366 5.9190002 8 P 0 ;0,1=0,2=0.000000
L 11.74233366 5.9190002 11.74000079 5.907 8 P 0 ;0,1=0,2=0.000000
L 11.74000079 5.907 11.73416654 5.89799921 8 P 0 ;0,1=0,2=0.000000
L 11.73416654 5.89799921 11.72366673 5.89349744 8 P 0 ;0,1=0,2=0.000000
L 11.72366673 5.89349744 11.69566624 5.89349744 8 P 0 ;0,1=0,2=0.000000
L 11.774 5.946 11.79033189 5.856 8 P 0 ;0,1=0,2=0.000000
L 11.79033189 5.856 11.80899892 5.946 8 P 0 ;0,1=0,2=0.000000
L 11.80899892 5.946 11.82766585 5.856 8 P 0 ;0,1=0,2=0.000000
L 11.82766585 5.856 11.844 5.946 8 P 0 ;0,1=0,2=0.000000
L 11.87566624 5.856 11.87566624 5.946 8 P 0 ;0,1=0,2=0.000000
L 11.87566624 5.946 11.90483307 5.946 8 P 0 ;0,1=0,2=0.000000
L 11.90483307 5.946 11.91416654 5.94149813 8 P 0 ;0,1=0,2=0.000000
L 11.91416654 5.94149813 11.92000079 5.93549941 8 P 0 ;0,1=0,2=0.000000
L 11.92000079 5.93549941 11.92233366 5.92349931 8 P 0 ;0,1=0,2=0.000000
L 11.92233366 5.92349931 11.92000079 5.91149911 8 P 0 ;0,1=0,2=0.000000
L 11.92000079 5.91149911 11.9130002 5.90400069 8 P 0 ;0,1=0,2=0.000000
L 11.9130002 5.90400069 11.90483307 5.89949892 8 P 0 ;0,1=0,2=0.000000
L 11.90483307 5.89949892 11.87566624 5.89949892 8 P 0 ;0,1=0,2=0.000000
L 11.90483307 5.89949892 11.92233366 5.856 8 P 0 ;0,1=0,2=0.000000
L 12.10466644 5.93849882 12.09766585 5.94300059 8 P 0 ;0,1=0,2=0.000000
L 12.09766585 5.94300059 12.08950089 5.946 8 P 0 ;0,1=0,2=0.000000
L 12.08950089 5.946 12.08016742 5.946 8 P 0 ;0,1=0,2=0.000000
L 12.08016742 5.946 12.06966545 5.94149813 8 P 0 ;0,1=0,2=0.000000
L 12.06966545 5.94149813 12.06150049 5.9339998 8 P 0 ;0,1=0,2=0.000000
L 12.06150049 5.9339998 12.05566624 5.92499892 8 P 0 ;0,1=0,2=0.000000
L 12.05566624 5.92499892 12.05099843 5.90999941 8 P 0 ;0,1=0,2=0.000000
L 12.05099843 5.90999941 12.04983209 5.89649951 8 P 0 ;0,1=0,2=0.000000
L 12.04983209 5.89649951 12.05216703 5.8829997 8 P 0 ;0,1=0,2=0.000000
L 12.05216703 5.8829997 12.05566624 5.87399882 8 P 0 ;0,1=0,2=0.000000
L 12.05566624 5.87399882 12.06266693 5.86499803 8 P 0 ;0,1=0,2=0.000000
L 12.06266693 5.86499803 12.07083396 5.85899931 8 P 0 ;0,1=0,2=0.000000
L 12.07083396 5.85899931 12.07899892 5.856 8 P 0 ;0,1=0,2=0.000000
L 12.07899892 5.856 12.08716594 5.856 8 P 0 ;0,1=0,2=0.000000
L 12.08716594 5.856 12.09533297 5.85899931 8 P 0 ;0,1=0,2=0.000000
L 12.09533297 5.85899931 12.10233366 5.86349833 8 P 0 ;0,1=0,2=0.000000
L 12.10233366 5.86349833 12.10816782 5.86949705 8 P 0 ;0,1=0,2=0.000000
L 12.16899892 5.856 12.15966545 5.85749961 8 P 0 ;0,1=0,2=0.000000
L 12.15966545 5.85749961 12.15150049 5.86349833 8 P 0 ;0,1=0,2=0.000000
L 12.15150049 5.86349833 12.1444998 5.87249921 8 P 0 ;0,1=0,2=0.000000
L 12.1444998 5.87249921 12.13983209 5.8829997 8 P 0 ;0,1=0,2=0.000000
L 12.13983209 5.8829997 12.13749921 5.8949999 8 P 0 ;0,1=0,2=0.000000
L 12.13749921 5.8949999 12.13749921 5.907 8 P 0 ;0,1=0,2=0.000000
L 12.13749921 5.907 12.13983209 5.9190002 8 P 0 ;0,1=0,2=0.000000
L 12.13983209 5.9190002 12.1444998 5.92950069 8 P 0 ;0,1=0,2=0.000000
L 12.1444998 5.92950069 12.15150049 5.93849882 8 P 0 ;0,1=0,2=0.000000
L 12.15150049 5.93849882 12.15966545 5.9445003 8 P 0 ;0,1=0,2=0.000000
L 12.15966545 5.9445003 12.16899892 5.946 8 P 0 ;0,1=0,2=0.000000
L 12.16899892 5.946 12.17833238 5.9445003 8 P 0 ;0,1=0,2=0.000000
L 12.17833238 5.9445003 12.18649941 5.93849882 8 P 0 ;0,1=0,2=0.000000
L 12.18649941 5.93849882 12.1935001 5.92950069 8 P 0 ;0,1=0,2=0.000000
L 12.1935001 5.92950069 12.19816782 5.9190002 8 P 0 ;0,1=0,2=0.000000
L 12.19816782 5.9190002 12.20050069 5.907 8 P 0 ;0,1=0,2=0.000000
L 12.20050069 5.907 12.20050069 5.8949999 8 P 0 ;0,1=0,2=0.000000
L 12.20050069 5.8949999 12.19816782 5.8829997 8 P 0 ;0,1=0,2=0.000000
L 12.19816782 5.8829997 12.1935001 5.87249921 8 P 0 ;0,1=0,2=0.000000
L 12.1935001 5.87249921 12.18649941 5.86349833 8 P 0 ;0,1=0,2=0.000000
L 12.18649941 5.86349833 12.17833238 5.85749961 8 P 0 ;0,1=0,2=0.000000
L 12.17833238 5.85749961 12.16899892 5.856 8 P 0 ;0,1=0,2=0.000000
L 12.23216703 5.856 12.23216703 5.946 8 P 0 ;0,1=0,2=0.000000
L 12.23216703 5.946 12.28583287 5.856 8 P 0 ;0,1=0,2=0.000000
L 12.28583287 5.856 12.28583287 5.946 8 P 0 ;0,1=0,2=0.000000
L 12.32216703 5.856 12.32216703 5.946 8 P 0 ;0,1=0,2=0.000000
L 12.32216703 5.946 12.37583287 5.856 8 P 0 ;0,1=0,2=0.000000
L 12.37583287 5.856 12.37583287 5.946 8 P 0 ;0,1=0,2=0.000000
L 8.70466644 5.41849882 8.69766585 5.42300059 8 P 0 ;0,1=1,2=0.000000
L 8.69766585 5.42300059 8.68950089 5.426 8 P 0 ;0,1=1,2=0.000000
L 8.68950089 5.426 8.68016742 5.426 8 P 0 ;0,1=1,2=0.000000
L 8.68016742 5.426 8.66966545 5.42149813 8 P 0 ;0,1=1,2=0.000000
L 8.66966545 5.42149813 8.66150049 5.4139998 8 P 0 ;0,1=1,2=0.000000
L 8.66150049 5.4139998 8.65566624 5.40499892 8 P 0 ;0,1=1,2=0.000000
L 8.65566624 5.40499892 8.65099843 5.38999941 8 P 0 ;0,1=1,2=0.000000
L 8.65099843 5.38999941 8.64983209 5.37649951 8 P 0 ;0,1=1,2=0.000000
L 8.64983209 5.37649951 8.65216703 5.3629997 8 P 0 ;0,1=1,2=0.000000
L 8.65216703 5.3629997 8.65566624 5.35399882 8 P 0 ;0,1=1,2=0.000000
L 8.65566624 5.35399882 8.66266693 5.34499803 8 P 0 ;0,1=1,2=0.000000
L 8.66266693 5.34499803 8.67083396 5.33899931 8 P 0 ;0,1=1,2=0.000000
L 8.67083396 5.33899931 8.67899892 5.336 8 P 0 ;0,1=1,2=0.000000
L 8.67899892 5.336 8.68716594 5.336 8 P 0 ;0,1=1,2=0.000000
L 8.68716594 5.336 8.69533297 5.33899931 8 P 0 ;0,1=1,2=0.000000
L 8.69533297 5.33899931 8.70233366 5.34349833 8 P 0 ;0,1=1,2=0.000000
L 8.70233366 5.34349833 8.70816782 5.34949705 8 P 0 ;0,1=1,2=0.000000
L 8.74566624 5.336 8.74566624 5.426 8 P 0 ;0,1=1,2=0.000000
L 8.74566624 5.426 8.77366673 5.426 8 P 0 ;0,1=1,2=0.000000
L 8.77366673 5.426 8.7830002 5.42149813 8 P 0 ;0,1=1,2=0.000000
L 8.7830002 5.42149813 8.79000079 5.41100039 8 P 0 ;0,1=1,2=0.000000
L 8.79000079 5.41100039 8.79233366 5.3990002 8 P 0 ;0,1=1,2=0.000000
L 8.79233366 5.3990002 8.79000079 5.387 8 P 0 ;0,1=1,2=0.000000
L 8.79000079 5.387 8.78416654 5.37799921 8 P 0 ;0,1=1,2=0.000000
L 8.78416654 5.37799921 8.77366673 5.37349744 8 P 0 ;0,1=1,2=0.000000
L 8.77366673 5.37349744 8.74566624 5.37349744 8 P 0 ;0,1=1,2=0.000000
L 8.83333346 5.426 8.83333346 5.3615 8 P 0 ;0,1=1,2=0.000000
L 8.83333346 5.3615 8.83799911 5.34799734 8 P 0 ;0,1=1,2=0.000000
L 8.83799911 5.34799734 8.84733258 5.33899931 8 P 0 ;0,1=1,2=0.000000
L 8.84733258 5.33899931 8.85899892 5.336 8 P 0 ;0,1=1,2=0.000000
L 8.85899892 5.336 8.87066732 5.33899931 8 P 0 ;0,1=1,2=0.000000
L 8.87066732 5.33899931 8.88000079 5.34799734 8 P 0 ;0,1=1,2=0.000000
L 8.88000079 5.34799734 8.88466644 5.3615 8 P 0 ;0,1=1,2=0.000000
L 8.88466644 5.3615 8.88466644 5.426 8 P 0 ;0,1=1,2=0.000000
L 8.94899892 5.336 8.94899892 5.426 8 P 0 ;0,1=1,2=0.000000
L 8.94899892 5.426 8.9349997 5.40800108 8 P 0 ;0,1=1,2=0.000000
L 8.9349997 5.336 8.96299803 5.336 8 P 0 ;0,1=1,2=0.000000
L 9.004 5.30600098 9.074 5.30600098 8 P 0 ;0,1=1,2=0.000000
L 9.10216703 5.336 9.10216703 5.426 8 P 0 ;0,1=1,2=0.000000
L 9.10216703 5.426 9.15583287 5.336 8 P 0 ;0,1=1,2=0.000000
L 9.15583287 5.336 9.15583287 5.426 8 P 0 ;0,1=1,2=0.000000
L 9.18983209 5.426 9.21899892 5.336 8 P 0 ;0,1=1,2=0.000000
L 9.21899892 5.336 9.24816782 5.426 8 P 0 ;0,1=1,2=0.000000
L 9.274 5.30600098 9.344 5.30600098 8 P 0 ;0,1=1,2=0.000000
L 9.40833238 5.38400069 9.4130002 5.3884997 8 P 0 ;0,1=1,2=0.000000
L 9.4130002 5.3884997 9.41649941 5.39599813 8 P 0 ;0,1=1,2=0.000000
L 9.41649941 5.39599813 9.41883435 5.40650138 8 P 0 ;0,1=1,2=0.000000
L 9.41883435 5.40650138 9.41649941 5.41549941 8 P 0 ;0,1=1,2=0.000000
L 9.41649941 5.41549941 9.41183376 5.42149813 8 P 0 ;0,1=1,2=0.000000
L 9.41183376 5.42149813 9.40366673 5.426 8 P 0 ;0,1=1,2=0.000000
L 9.40366673 5.426 9.37216703 5.426 8 P 0 ;0,1=1,2=0.000000
L 9.37216703 5.426 9.37216703 5.336 8 P 0 ;0,1=1,2=0.000000
L 9.37216703 5.336 9.41066732 5.336 8 P 0 ;0,1=1,2=0.000000
L 9.41066732 5.336 9.41883435 5.34199862 8 P 0 ;0,1=1,2=0.000000
L 9.41883435 5.34199862 9.4235001 5.35099951 8 P 0 ;0,1=1,2=0.000000
L 9.4235001 5.35099951 9.42583287 5.3615 8 P 0 ;0,1=1,2=0.000000
L 9.42583287 5.3615 9.4235001 5.37199774 8 P 0 ;0,1=1,2=0.000000
L 9.4235001 5.37199774 9.41649941 5.38099862 8 P 0 ;0,1=1,2=0.000000
L 9.41649941 5.38099862 9.40833238 5.38400069 8 P 0 ;0,1=1,2=0.000000
L 9.40833238 5.38400069 9.37216703 5.38400069 8 P 0 ;0,1=1,2=0.000000
L 9.48899892 5.336 9.47966545 5.33749961 8 P 0 ;0,1=1,2=0.000000
L 9.47966545 5.33749961 9.47150049 5.34349833 8 P 0 ;0,1=1,2=0.000000
L 9.47150049 5.34349833 9.4644998 5.35249921 8 P 0 ;0,1=1,2=0.000000
L 9.4644998 5.35249921 9.45983209 5.3629997 8 P 0 ;0,1=1,2=0.000000
L 9.45983209 5.3629997 9.45749921 5.3749999 8 P 0 ;0,1=1,2=0.000000
L 9.45749921 5.3749999 9.45749921 5.387 8 P 0 ;0,1=1,2=0.000000
L 9.45749921 5.387 9.45983209 5.3990002 8 P 0 ;0,1=1,2=0.000000
L 9.45983209 5.3990002 9.4644998 5.40950069 8 P 0 ;0,1=1,2=0.000000
L 9.4644998 5.40950069 9.47150049 5.41849882 8 P 0 ;0,1=1,2=0.000000
L 9.47150049 5.41849882 9.47966545 5.4245003 8 P 0 ;0,1=1,2=0.000000
L 9.47966545 5.4245003 9.48899892 5.426 8 P 0 ;0,1=1,2=0.000000
L 9.48899892 5.426 9.49833238 5.4245003 8 P 0 ;0,1=1,2=0.000000
L 9.49833238 5.4245003 9.50649941 5.41849882 8 P 0 ;0,1=1,2=0.000000
L 9.50649941 5.41849882 9.5135001 5.40950069 8 P 0 ;0,1=1,2=0.000000
L 9.5135001 5.40950069 9.51816782 5.3990002 8 P 0 ;0,1=1,2=0.000000
L 9.51816782 5.3990002 9.52050069 5.387 8 P 0 ;0,1=1,2=0.000000
L 9.52050069 5.387 9.52050069 5.3749999 8 P 0 ;0,1=1,2=0.000000
L 9.52050069 5.3749999 9.51816782 5.3629997 8 P 0 ;0,1=1,2=0.000000
L 9.51816782 5.3629997 9.5135001 5.35249921 8 P 0 ;0,1=1,2=0.000000
L 9.5135001 5.35249921 9.50649941 5.34349833 8 P 0 ;0,1=1,2=0.000000
L 9.50649941 5.34349833 9.49833238 5.33749961 8 P 0 ;0,1=1,2=0.000000
L 9.49833238 5.33749961 9.48899892 5.336 8 P 0 ;0,1=1,2=0.000000
L 9.57899892 5.426 9.57899892 5.336 8 P 0 ;0,1=1,2=0.000000
L 9.55216703 5.426 9.60583287 5.426 8 P 0 ;0,1=1,2=0.000000
L 7.57566644 5.42549882 7.56866585 5.43000059 8 P 0 ;0,1=2,2=0.000000
L 7.56866585 5.43000059 7.56050089 5.433 8 P 0 ;0,1=2,2=0.000000
L 7.56050089 5.433 7.55116742 5.433 8 P 0 ;0,1=2,2=0.000000
L 7.55116742 5.433 7.54066545 5.42849813 8 P 0 ;0,1=2,2=0.000000
L 7.54066545 5.42849813 7.53250049 5.4209998 8 P 0 ;0,1=2,2=0.000000
L 7.53250049 5.4209998 7.52666624 5.41199892 8 P 0 ;0,1=2,2=0.000000
L 7.52666624 5.41199892 7.52199843 5.39699941 8 P 0 ;0,1=2,2=0.000000
L 7.52199843 5.39699941 7.52083209 5.38349951 8 P 0 ;0,1=2,2=0.000000
L 7.52083209 5.38349951 7.52316703 5.3699997 8 P 0 ;0,1=2,2=0.000000
L 7.52316703 5.3699997 7.52666624 5.36099882 8 P 0 ;0,1=2,2=0.000000
L 7.52666624 5.36099882 7.53366693 5.35199803 8 P 0 ;0,1=2,2=0.000000
L 7.53366693 5.35199803 7.54183396 5.34599931 8 P 0 ;0,1=2,2=0.000000
L 7.54183396 5.34599931 7.54999892 5.343 8 P 0 ;0,1=2,2=0.000000
L 7.54999892 5.343 7.55816594 5.343 8 P 0 ;0,1=2,2=0.000000
L 7.55816594 5.343 7.56633297 5.34599931 8 P 0 ;0,1=2,2=0.000000
L 7.56633297 5.34599931 7.57333366 5.35049833 8 P 0 ;0,1=2,2=0.000000
L 7.57333366 5.35049833 7.57916782 5.35649705 8 P 0 ;0,1=2,2=0.000000
L 7.61666624 5.343 7.61666624 5.433 8 P 0 ;0,1=2,2=0.000000
L 7.61666624 5.433 7.64466673 5.433 8 P 0 ;0,1=2,2=0.000000
L 7.64466673 5.433 7.6540002 5.42849813 8 P 0 ;0,1=2,2=0.000000
L 7.6540002 5.42849813 7.66100079 5.41800039 8 P 0 ;0,1=2,2=0.000000
L 7.66100079 5.41800039 7.66333366 5.4060002 8 P 0 ;0,1=2,2=0.000000
L 7.66333366 5.4060002 7.66100079 5.394 8 P 0 ;0,1=2,2=0.000000
L 7.66100079 5.394 7.65516654 5.38499921 8 P 0 ;0,1=2,2=0.000000
L 7.65516654 5.38499921 7.64466673 5.38049744 8 P 0 ;0,1=2,2=0.000000
L 7.64466673 5.38049744 7.61666624 5.38049744 8 P 0 ;0,1=2,2=0.000000
L 7.70433346 5.433 7.70433346 5.3685 8 P 0 ;0,1=2,2=0.000000
L 7.70433346 5.3685 7.70899911 5.35499734 8 P 0 ;0,1=2,2=0.000000
L 7.70899911 5.35499734 7.71833258 5.34599931 8 P 0 ;0,1=2,2=0.000000
L 7.71833258 5.34599931 7.72999892 5.343 8 P 0 ;0,1=2,2=0.000000
L 7.72999892 5.343 7.74166732 5.34599931 8 P 0 ;0,1=2,2=0.000000
L 7.74166732 5.34599931 7.75100079 5.35499734 8 P 0 ;0,1=2,2=0.000000
L 7.75100079 5.35499734 7.75566644 5.3685 8 P 0 ;0,1=2,2=0.000000
L 7.75566644 5.3685 7.75566644 5.433 8 P 0 ;0,1=2,2=0.000000
L 7.81999892 5.343 7.81999892 5.433 8 P 0 ;0,1=2,2=0.000000
L 7.81999892 5.433 7.8059997 5.41500108 8 P 0 ;0,1=2,2=0.000000
L 7.8059997 5.343 7.83399803 5.343 8 P 0 ;0,1=2,2=0.000000
L 7.875 5.31300098 7.945 5.31300098 8 P 0 ;0,1=2,2=0.000000
L 7.97316703 5.343 7.97316703 5.433 8 P 0 ;0,1=2,2=0.000000
L 7.97316703 5.433 8.02683287 5.343 8 P 0 ;0,1=2,2=0.000000
L 8.02683287 5.343 8.02683287 5.433 8 P 0 ;0,1=2,2=0.000000
L 8.06083209 5.433 8.08999892 5.343 8 P 0 ;0,1=2,2=0.000000
L 8.08999892 5.343 8.11916782 5.433 8 P 0 ;0,1=2,2=0.000000
L 8.145 5.31300098 8.215 5.31300098 8 P 0 ;0,1=2,2=0.000000
L 8.26999892 5.433 8.26999892 5.343 8 P 0 ;0,1=2,2=0.000000
L 8.24316703 5.433 8.29683287 5.433 8 P 0 ;0,1=2,2=0.000000
L 8.35999892 5.343 8.35066545 5.34449961 8 P 0 ;0,1=2,2=0.000000
L 8.35066545 5.34449961 8.34250049 5.35049833 8 P 0 ;0,1=2,2=0.000000
L 8.34250049 5.35049833 8.3354998 5.35949921 8 P 0 ;0,1=2,2=0.000000
L 8.3354998 5.35949921 8.33083209 5.3699997 8 P 0 ;0,1=2,2=0.000000
L 8.33083209 5.3699997 8.32849921 5.3819999 8 P 0 ;0,1=2,2=0.000000
L 8.32849921 5.3819999 8.32849921 5.394 8 P 0 ;0,1=2,2=0.000000
L 8.32849921 5.394 8.33083209 5.4060002 8 P 0 ;0,1=2,2=0.000000
L 8.33083209 5.4060002 8.3354998 5.41650069 8 P 0 ;0,1=2,2=0.000000
L 8.3354998 5.41650069 8.34250049 5.42549882 8 P 0 ;0,1=2,2=0.000000
L 8.34250049 5.42549882 8.35066545 5.4315003 8 P 0 ;0,1=2,2=0.000000
L 8.35066545 5.4315003 8.35999892 5.433 8 P 0 ;0,1=2,2=0.000000
L 8.35999892 5.433 8.36933238 5.4315003 8 P 0 ;0,1=2,2=0.000000
L 8.36933238 5.4315003 8.37749941 5.42549882 8 P 0 ;0,1=2,2=0.000000
L 8.37749941 5.42549882 8.3845001 5.41650069 8 P 0 ;0,1=2,2=0.000000
L 8.3845001 5.41650069 8.38916782 5.4060002 8 P 0 ;0,1=2,2=0.000000
L 8.38916782 5.4060002 8.39150069 5.394 8 P 0 ;0,1=2,2=0.000000
L 8.39150069 5.394 8.39150069 5.3819999 8 P 0 ;0,1=2,2=0.000000
L 8.39150069 5.3819999 8.38916782 5.3699997 8 P 0 ;0,1=2,2=0.000000
L 8.38916782 5.3699997 8.3845001 5.35949921 8 P 0 ;0,1=2,2=0.000000
L 8.3845001 5.35949921 8.37749941 5.35049833 8 P 0 ;0,1=2,2=0.000000
L 8.37749941 5.35049833 8.36933238 5.34449961 8 P 0 ;0,1=2,2=0.000000
L 8.36933238 5.34449961 8.35999892 5.343 8 P 0 ;0,1=2,2=0.000000
L 8.42666624 5.343 8.42666624 5.433 8 P 0 ;0,1=2,2=0.000000
L 8.42666624 5.433 8.45466673 5.433 8 P 0 ;0,1=2,2=0.000000
L 8.45466673 5.433 8.4640002 5.42849813 8 P 0 ;0,1=2,2=0.000000
L 8.4640002 5.42849813 8.47100079 5.41800039 8 P 0 ;0,1=2,2=0.000000
L 8.47100079 5.41800039 8.47333366 5.4060002 8 P 0 ;0,1=2,2=0.000000
L 8.47333366 5.4060002 8.47100079 5.394 8 P 0 ;0,1=2,2=0.000000
L 8.47100079 5.394 8.46516654 5.38499921 8 P 0 ;0,1=2,2=0.000000
L 8.46516654 5.38499921 8.45466673 5.38049744 8 P 0 ;0,1=2,2=0.000000
L 8.45466673 5.38049744 8.42666624 5.38049744 8 P 0 ;0,1=2,2=0.000000
L 2.66866644 5.40249882 2.66166585 5.40700059 8 P 0 ;0,1=3,2=0.000000
L 2.66166585 5.40700059 2.65350089 5.41 8 P 0 ;0,1=3,2=0.000000
L 2.65350089 5.41 2.64416742 5.41 8 P 0 ;0,1=3,2=0.000000
L 2.64416742 5.41 2.63366545 5.40549813 8 P 0 ;0,1=3,2=0.000000
L 2.63366545 5.40549813 2.62550049 5.3979998 8 P 0 ;0,1=3,2=0.000000
L 2.62550049 5.3979998 2.61966624 5.38899892 8 P 0 ;0,1=3,2=0.000000
L 2.61966624 5.38899892 2.61499843 5.37399941 8 P 0 ;0,1=3,2=0.000000
L 2.61499843 5.37399941 2.61383209 5.36049951 8 P 0 ;0,1=3,2=0.000000
L 2.61383209 5.36049951 2.61616703 5.3469997 8 P 0 ;0,1=3,2=0.000000
L 2.61616703 5.3469997 2.61966624 5.33799882 8 P 0 ;0,1=3,2=0.000000
L 2.61966624 5.33799882 2.62666693 5.32899803 8 P 0 ;0,1=3,2=0.000000
L 2.62666693 5.32899803 2.63483396 5.32299931 8 P 0 ;0,1=3,2=0.000000
L 2.63483396 5.32299931 2.64299892 5.32 8 P 0 ;0,1=3,2=0.000000
L 2.64299892 5.32 2.65116594 5.32 8 P 0 ;0,1=3,2=0.000000
L 2.65116594 5.32 2.65933297 5.32299931 8 P 0 ;0,1=3,2=0.000000
L 2.65933297 5.32299931 2.66633366 5.32749833 8 P 0 ;0,1=3,2=0.000000
L 2.66633366 5.32749833 2.67216782 5.33349705 8 P 0 ;0,1=3,2=0.000000
L 2.70966624 5.32 2.70966624 5.41 8 P 0 ;0,1=3,2=0.000000
L 2.70966624 5.41 2.73766673 5.41 8 P 0 ;0,1=3,2=0.000000
L 2.73766673 5.41 2.7470002 5.40549813 8 P 0 ;0,1=3,2=0.000000
L 2.7470002 5.40549813 2.75400079 5.39500039 8 P 0 ;0,1=3,2=0.000000
L 2.75400079 5.39500039 2.75633366 5.3830002 8 P 0 ;0,1=3,2=0.000000
L 2.75633366 5.3830002 2.75400079 5.371 8 P 0 ;0,1=3,2=0.000000
L 2.75400079 5.371 2.74816654 5.36199921 8 P 0 ;0,1=3,2=0.000000
L 2.74816654 5.36199921 2.73766673 5.35749744 8 P 0 ;0,1=3,2=0.000000
L 2.73766673 5.35749744 2.70966624 5.35749744 8 P 0 ;0,1=3,2=0.000000
L 2.79733346 5.41 2.79733346 5.3455 8 P 0 ;0,1=3,2=0.000000
L 2.79733346 5.3455 2.80199911 5.33199734 8 P 0 ;0,1=3,2=0.000000
L 2.80199911 5.33199734 2.81133258 5.32299931 8 P 0 ;0,1=3,2=0.000000
L 2.81133258 5.32299931 2.82299892 5.32 8 P 0 ;0,1=3,2=0.000000
L 2.82299892 5.32 2.83466732 5.32299931 8 P 0 ;0,1=3,2=0.000000
L 2.83466732 5.32299931 2.84400079 5.33199734 8 P 0 ;0,1=3,2=0.000000
L 2.84400079 5.33199734 2.84866644 5.3455 8 P 0 ;0,1=3,2=0.000000
L 2.84866644 5.3455 2.84866644 5.41 8 P 0 ;0,1=3,2=0.000000
L 2.91299892 5.41 2.90366545 5.40700059 8 P 0 ;0,1=3,2=0.000000
L 2.90366545 5.40700059 2.89666693 5.39949941 8 P 0 ;0,1=3,2=0.000000
L 2.89666693 5.39949941 2.89199911 5.39050138 8 P 0 ;0,1=3,2=0.000000
L 2.89199911 5.39050138 2.8884998 5.37849843 8 P 0 ;0,1=3,2=0.000000
L 2.8884998 5.37849843 2.88733346 5.36499862 8 P 0 ;0,1=3,2=0.000000
L 2.88733346 5.36499862 2.8884998 5.35149872 8 P 0 ;0,1=3,2=0.000000
L 2.8884998 5.35149872 2.89199911 5.33949852 8 P 0 ;0,1=3,2=0.000000
L 2.89199911 5.33949852 2.89666693 5.33049774 8 P 0 ;0,1=3,2=0.000000
L 2.89666693 5.33049774 2.90366545 5.32299931 8 P 0 ;0,1=3,2=0.000000
L 2.90366545 5.32299931 2.91299892 5.32 8 P 0 ;0,1=3,2=0.000000
L 2.91299892 5.32 2.92233238 5.32299931 8 P 0 ;0,1=3,2=0.000000
L 2.92233238 5.32299931 2.92933297 5.33049774 8 P 0 ;0,1=3,2=0.000000
L 2.92933297 5.33049774 2.93400079 5.33949852 8 P 0 ;0,1=3,2=0.000000
L 2.93400079 5.33949852 2.9375001 5.35149872 8 P 0 ;0,1=3,2=0.000000
L 2.9375001 5.35149872 2.93866644 5.36499862 8 P 0 ;0,1=3,2=0.000000
L 2.93866644 5.36499862 2.9375001 5.37849843 8 P 0 ;0,1=3,2=0.000000
L 2.9375001 5.37849843 2.93400079 5.39050138 8 P 0 ;0,1=3,2=0.000000
L 2.93400079 5.39050138 2.92933297 5.39949941 8 P 0 ;0,1=3,2=0.000000
L 2.92933297 5.39949941 2.92233238 5.40700059 8 P 0 ;0,1=3,2=0.000000
L 2.92233238 5.40700059 2.91299892 5.41 8 P 0 ;0,1=3,2=0.000000
L 2.968 5.29000098 3.038 5.29000098 8 P 0 ;0,1=3,2=0.000000
L 3.06616703 5.32 3.06616703 5.41 8 P 0 ;0,1=3,2=0.000000
L 3.06616703 5.41 3.11983287 5.32 8 P 0 ;0,1=3,2=0.000000
L 3.11983287 5.32 3.11983287 5.41 8 P 0 ;0,1=3,2=0.000000
L 3.15383209 5.41 3.18299892 5.32 8 P 0 ;0,1=3,2=0.000000
L 3.18299892 5.32 3.21216782 5.41 8 P 0 ;0,1=3,2=0.000000
L 3.238 5.29000098 3.308 5.29000098 8 P 0 ;0,1=3,2=0.000000
L 3.37233238 5.36800069 3.3770002 5.3724997 8 P 0 ;0,1=3,2=0.000000
L 3.3770002 5.3724997 3.38049941 5.37999813 8 P 0 ;0,1=3,2=0.000000
L 3.38049941 5.37999813 3.38283435 5.39050138 8 P 0 ;0,1=3,2=0.000000
L 3.38283435 5.39050138 3.38049941 5.39949941 8 P 0 ;0,1=3,2=0.000000
L 3.38049941 5.39949941 3.37583376 5.40549813 8 P 0 ;0,1=3,2=0.000000
L 3.37583376 5.40549813 3.36766673 5.41 8 P 0 ;0,1=3,2=0.000000
L 3.36766673 5.41 3.33616703 5.41 8 P 0 ;0,1=3,2=0.000000
L 3.33616703 5.41 3.33616703 5.32 8 P 0 ;0,1=3,2=0.000000
L 3.33616703 5.32 3.37466732 5.32 8 P 0 ;0,1=3,2=0.000000
L 3.37466732 5.32 3.38283435 5.32599862 8 P 0 ;0,1=3,2=0.000000
L 3.38283435 5.32599862 3.3875001 5.33499951 8 P 0 ;0,1=3,2=0.000000
L 3.3875001 5.33499951 3.38983287 5.3455 8 P 0 ;0,1=3,2=0.000000
L 3.38983287 5.3455 3.3875001 5.35599774 8 P 0 ;0,1=3,2=0.000000
L 3.3875001 5.35599774 3.38049941 5.36499862 8 P 0 ;0,1=3,2=0.000000
L 3.38049941 5.36499862 3.37233238 5.36800069 8 P 0 ;0,1=3,2=0.000000
L 3.37233238 5.36800069 3.33616703 5.36800069 8 P 0 ;0,1=3,2=0.000000
L 3.45299892 5.32 3.44366545 5.32149961 8 P 0 ;0,1=3,2=0.000000
L 3.44366545 5.32149961 3.43550049 5.32749833 8 P 0 ;0,1=3,2=0.000000
L 3.43550049 5.32749833 3.4284998 5.33649921 8 P 0 ;0,1=3,2=0.000000
L 3.4284998 5.33649921 3.42383209 5.3469997 8 P 0 ;0,1=3,2=0.000000
L 3.42383209 5.3469997 3.42149921 5.3589999 8 P 0 ;0,1=3,2=0.000000
L 3.42149921 5.3589999 3.42149921 5.371 8 P 0 ;0,1=3,2=0.000000
L 3.42149921 5.371 3.42383209 5.3830002 8 P 0 ;0,1=3,2=0.000000
L 3.42383209 5.3830002 3.4284998 5.39350069 8 P 0 ;0,1=3,2=0.000000
L 3.4284998 5.39350069 3.43550049 5.40249882 8 P 0 ;0,1=3,2=0.000000
L 3.43550049 5.40249882 3.44366545 5.4085003 8 P 0 ;0,1=3,2=0.000000
L 3.44366545 5.4085003 3.45299892 5.41 8 P 0 ;0,1=3,2=0.000000
L 3.45299892 5.41 3.46233238 5.4085003 8 P 0 ;0,1=3,2=0.000000
L 3.46233238 5.4085003 3.47049941 5.40249882 8 P 0 ;0,1=3,2=0.000000
L 3.47049941 5.40249882 3.4775001 5.39350069 8 P 0 ;0,1=3,2=0.000000
L 3.4775001 5.39350069 3.48216782 5.3830002 8 P 0 ;0,1=3,2=0.000000
L 3.48216782 5.3830002 3.48450069 5.371 8 P 0 ;0,1=3,2=0.000000
L 3.48450069 5.371 3.48450069 5.3589999 8 P 0 ;0,1=3,2=0.000000
L 3.48450069 5.3589999 3.48216782 5.3469997 8 P 0 ;0,1=3,2=0.000000
L 3.48216782 5.3469997 3.4775001 5.33649921 8 P 0 ;0,1=3,2=0.000000
L 3.4775001 5.33649921 3.47049941 5.32749833 8 P 0 ;0,1=3,2=0.000000
L 3.47049941 5.32749833 3.46233238 5.32149961 8 P 0 ;0,1=3,2=0.000000
L 3.46233238 5.32149961 3.45299892 5.32 8 P 0 ;0,1=3,2=0.000000
L 3.54299892 5.41 3.54299892 5.32 8 P 0 ;0,1=3,2=0.000000
L 3.51616703 5.41 3.56983287 5.41 8 P 0 ;0,1=3,2=0.000000
L 1.59866644 5.40149882 1.59166585 5.40600059 8 P 0 ;0,1=4,2=0.000000
L 1.59166585 5.40600059 1.58350089 5.409 8 P 0 ;0,1=4,2=0.000000
L 1.58350089 5.409 1.57416742 5.409 8 P 0 ;0,1=4,2=0.000000
L 1.57416742 5.409 1.56366545 5.40449813 8 P 0 ;0,1=4,2=0.000000
L 1.56366545 5.40449813 1.55550049 5.3969998 8 P 0 ;0,1=4,2=0.000000
L 1.55550049 5.3969998 1.54966624 5.38799892 8 P 0 ;0,1=4,2=0.000000
L 1.54966624 5.38799892 1.54499843 5.37299941 8 P 0 ;0,1=4,2=0.000000
L 1.54499843 5.37299941 1.54383209 5.35949951 8 P 0 ;0,1=4,2=0.000000
L 1.54383209 5.35949951 1.54616703 5.3459997 8 P 0 ;0,1=4,2=0.000000
L 1.54616703 5.3459997 1.54966624 5.33699882 8 P 0 ;0,1=4,2=0.000000
L 1.54966624 5.33699882 1.55666693 5.32799803 8 P 0 ;0,1=4,2=0.000000
L 1.55666693 5.32799803 1.56483396 5.32199931 8 P 0 ;0,1=4,2=0.000000
L 1.56483396 5.32199931 1.57299892 5.319 8 P 0 ;0,1=4,2=0.000000
L 1.57299892 5.319 1.58116594 5.319 8 P 0 ;0,1=4,2=0.000000
L 1.58116594 5.319 1.58933297 5.32199931 8 P 0 ;0,1=4,2=0.000000
L 1.58933297 5.32199931 1.59633366 5.32649833 8 P 0 ;0,1=4,2=0.000000
L 1.59633366 5.32649833 1.60216782 5.33249705 8 P 0 ;0,1=4,2=0.000000
L 1.63966624 5.319 1.63966624 5.409 8 P 0 ;0,1=4,2=0.000000
L 1.63966624 5.409 1.66766673 5.409 8 P 0 ;0,1=4,2=0.000000
L 1.66766673 5.409 1.6770002 5.40449813 8 P 0 ;0,1=4,2=0.000000
L 1.6770002 5.40449813 1.68400079 5.39400039 8 P 0 ;0,1=4,2=0.000000
L 1.68400079 5.39400039 1.68633366 5.3820002 8 P 0 ;0,1=4,2=0.000000
L 1.68633366 5.3820002 1.68400079 5.37 8 P 0 ;0,1=4,2=0.000000
L 1.68400079 5.37 1.67816654 5.36099921 8 P 0 ;0,1=4,2=0.000000
L 1.67816654 5.36099921 1.66766673 5.35649744 8 P 0 ;0,1=4,2=0.000000
L 1.66766673 5.35649744 1.63966624 5.35649744 8 P 0 ;0,1=4,2=0.000000
L 1.72733346 5.409 1.72733346 5.3445 8 P 0 ;0,1=4,2=0.000000
L 1.72733346 5.3445 1.73199911 5.33099734 8 P 0 ;0,1=4,2=0.000000
L 1.73199911 5.33099734 1.74133258 5.32199931 8 P 0 ;0,1=4,2=0.000000
L 1.74133258 5.32199931 1.75299892 5.319 8 P 0 ;0,1=4,2=0.000000
L 1.75299892 5.319 1.76466732 5.32199931 8 P 0 ;0,1=4,2=0.000000
L 1.76466732 5.32199931 1.77400079 5.33099734 8 P 0 ;0,1=4,2=0.000000
L 1.77400079 5.33099734 1.77866644 5.3445 8 P 0 ;0,1=4,2=0.000000
L 1.77866644 5.3445 1.77866644 5.409 8 P 0 ;0,1=4,2=0.000000
L 1.84299892 5.409 1.83366545 5.40600059 8 P 0 ;0,1=4,2=0.000000
L 1.83366545 5.40600059 1.82666693 5.39849941 8 P 0 ;0,1=4,2=0.000000
L 1.82666693 5.39849941 1.82199911 5.38950138 8 P 0 ;0,1=4,2=0.000000
L 1.82199911 5.38950138 1.8184998 5.37749843 8 P 0 ;0,1=4,2=0.000000
L 1.8184998 5.37749843 1.81733346 5.36399862 8 P 0 ;0,1=4,2=0.000000
L 1.81733346 5.36399862 1.8184998 5.35049872 8 P 0 ;0,1=4,2=0.000000
L 1.8184998 5.35049872 1.82199911 5.33849852 8 P 0 ;0,1=4,2=0.000000
L 1.82199911 5.33849852 1.82666693 5.32949774 8 P 0 ;0,1=4,2=0.000000
L 1.82666693 5.32949774 1.83366545 5.32199931 8 P 0 ;0,1=4,2=0.000000
L 1.83366545 5.32199931 1.84299892 5.319 8 P 0 ;0,1=4,2=0.000000
L 1.84299892 5.319 1.85233238 5.32199931 8 P 0 ;0,1=4,2=0.000000
L 1.85233238 5.32199931 1.85933297 5.32949774 8 P 0 ;0,1=4,2=0.000000
L 1.85933297 5.32949774 1.86400079 5.33849852 8 P 0 ;0,1=4,2=0.000000
L 1.86400079 5.33849852 1.8675001 5.35049872 8 P 0 ;0,1=4,2=0.000000
L 1.8675001 5.35049872 1.86866644 5.36399862 8 P 0 ;0,1=4,2=0.000000
L 1.86866644 5.36399862 1.8675001 5.37749843 8 P 0 ;0,1=4,2=0.000000
L 1.8675001 5.37749843 1.86400079 5.38950138 8 P 0 ;0,1=4,2=0.000000
L 1.86400079 5.38950138 1.85933297 5.39849941 8 P 0 ;0,1=4,2=0.000000
L 1.85933297 5.39849941 1.85233238 5.40600059 8 P 0 ;0,1=4,2=0.000000
L 1.85233238 5.40600059 1.84299892 5.409 8 P 0 ;0,1=4,2=0.000000
L 1.898 5.28900098 1.968 5.28900098 8 P 0 ;0,1=4,2=0.000000
L 1.99616703 5.319 1.99616703 5.409 8 P 0 ;0,1=4,2=0.000000
L 1.99616703 5.409 2.04983287 5.319 8 P 0 ;0,1=4,2=0.000000
L 2.04983287 5.319 2.04983287 5.409 8 P 0 ;0,1=4,2=0.000000
L 2.08383209 5.409 2.11299892 5.319 8 P 0 ;0,1=4,2=0.000000
L 2.11299892 5.319 2.14216782 5.409 8 P 0 ;0,1=4,2=0.000000
L 2.168 5.28900098 2.238 5.28900098 8 P 0 ;0,1=4,2=0.000000
L 2.29299892 5.409 2.29299892 5.319 8 P 0 ;0,1=4,2=0.000000
L 2.26616703 5.409 2.31983287 5.409 8 P 0 ;0,1=4,2=0.000000
L 2.38299892 5.319 2.37366545 5.32049961 8 P 0 ;0,1=4,2=0.000000
L 2.37366545 5.32049961 2.36550049 5.32649833 8 P 0 ;0,1=4,2=0.000000
L 2.36550049 5.32649833 2.3584998 5.33549921 8 P 0 ;0,1=4,2=0.000000
L 2.3584998 5.33549921 2.35383209 5.3459997 8 P 0 ;0,1=4,2=0.000000
L 2.35383209 5.3459997 2.35149921 5.3579999 8 P 0 ;0,1=4,2=0.000000
L 2.35149921 5.3579999 2.35149921 5.37 8 P 0 ;0,1=4,2=0.000000
L 2.35149921 5.37 2.35383209 5.3820002 8 P 0 ;0,1=4,2=0.000000
L 2.35383209 5.3820002 2.3584998 5.39250069 8 P 0 ;0,1=4,2=0.000000
L 2.3584998 5.39250069 2.36550049 5.40149882 8 P 0 ;0,1=4,2=0.000000
L 2.36550049 5.40149882 2.37366545 5.4075003 8 P 0 ;0,1=4,2=0.000000
L 2.37366545 5.4075003 2.38299892 5.409 8 P 0 ;0,1=4,2=0.000000
L 2.38299892 5.409 2.39233238 5.4075003 8 P 0 ;0,1=4,2=0.000000
L 2.39233238 5.4075003 2.40049941 5.40149882 8 P 0 ;0,1=4,2=0.000000
L 2.40049941 5.40149882 2.4075001 5.39250069 8 P 0 ;0,1=4,2=0.000000
L 2.4075001 5.39250069 2.41216782 5.3820002 8 P 0 ;0,1=4,2=0.000000
L 2.41216782 5.3820002 2.41450069 5.37 8 P 0 ;0,1=4,2=0.000000
L 2.41450069 5.37 2.41450069 5.3579999 8 P 0 ;0,1=4,2=0.000000
L 2.41450069 5.3579999 2.41216782 5.3459997 8 P 0 ;0,1=4,2=0.000000
L 2.41216782 5.3459997 2.4075001 5.33549921 8 P 0 ;0,1=4,2=0.000000
L 2.4075001 5.33549921 2.40049941 5.32649833 8 P 0 ;0,1=4,2=0.000000
L 2.40049941 5.32649833 2.39233238 5.32049961 8 P 0 ;0,1=4,2=0.000000
L 2.39233238 5.32049961 2.38299892 5.319 8 P 0 ;0,1=4,2=0.000000
L 2.44966624 5.319 2.44966624 5.409 8 P 0 ;0,1=4,2=0.000000
L 2.44966624 5.409 2.47766673 5.409 8 P 0 ;0,1=4,2=0.000000
L 2.47766673 5.409 2.4870002 5.40449813 8 P 0 ;0,1=4,2=0.000000
L 2.4870002 5.40449813 2.49400079 5.39400039 8 P 0 ;0,1=4,2=0.000000
L 2.49400079 5.39400039 2.49633366 5.3820002 8 P 0 ;0,1=4,2=0.000000
L 2.49633366 5.3820002 2.49400079 5.37 8 P 0 ;0,1=4,2=0.000000
L 2.49400079 5.37 2.48816654 5.36099921 8 P 0 ;0,1=4,2=0.000000
L 2.48816654 5.36099921 2.47766673 5.35649744 8 P 0 ;0,1=4,2=0.000000
L 2.47766673 5.35649744 2.44966624 5.35649744 8 P 0 ;0,1=4,2=0.000000
L 1.6954998 5.76799734 1.70483337 5.76049902 8 P 0 ;0,1=5,2=0.000000
L 1.70483337 5.76049902 1.71533317 5.756 8 P 0 ;0,1=5,2=0.000000
L 1.71533317 5.756 1.72466673 5.756 8 P 0 ;0,1=5,2=0.000000
L 1.72466673 5.756 1.7340002 5.76049902 8 P 0 ;0,1=5,2=0.000000
L 1.7340002 5.76049902 1.74100079 5.76799734 8 P 0 ;0,1=5,2=0.000000
L 1.74100079 5.76799734 1.7445001 5.77850059 8 P 0 ;0,1=5,2=0.000000
L 1.7445001 5.77850059 1.74216722 5.78899843 8 P 0 ;0,1=5,2=0.000000
L 1.74216722 5.78899843 1.73633297 5.79799921 8 P 0 ;0,1=5,2=0.000000
L 1.73633297 5.79799921 1.72583307 5.80400069 8 P 0 ;0,1=5,2=0.000000
L 1.72583307 5.80400069 1.71183396 5.807 8 P 0 ;0,1=5,2=0.000000
L 1.71183396 5.807 1.70366693 5.81299872 8 P 0 ;0,1=5,2=0.000000
L 1.70366693 5.81299872 1.70016555 5.82349931 8 P 0 ;0,1=5,2=0.000000
L 1.70016555 5.82349931 1.70250049 5.8339998 8 P 0 ;0,1=5,2=0.000000
L 1.70250049 5.8339998 1.70833258 5.84149813 8 P 0 ;0,1=5,2=0.000000
L 1.70833258 5.84149813 1.71649961 5.846 8 P 0 ;0,1=5,2=0.000000
L 1.71649961 5.846 1.72466673 5.846 8 P 0 ;0,1=5,2=0.000000
L 1.72466673 5.846 1.73283376 5.84300059 8 P 0 ;0,1=5,2=0.000000
L 1.73283376 5.84300059 1.73983435 5.83549941 8 P 0 ;0,1=5,2=0.000000
L 1.80999892 5.81599813 1.80999892 5.756 8 P 0 ;0,1=5,2=0.000000
L 1.80999892 5.83999852 1.80766604 5.84149813 8 P 0 ;0,1=5,2=0.000000
L 1.80766604 5.84149813 1.80766604 5.8445003 8 P 0 ;0,1=5,2=0.000000
L 1.80766604 5.8445003 1.80999892 5.846 8 P 0 ;0,1=5,2=0.000000
L 1.80999892 5.846 1.81233386 5.8445003 8 P 0 ;0,1=5,2=0.000000
L 1.81233386 5.8445003 1.81233386 5.84149813 8 P 0 ;0,1=5,2=0.000000
L 1.81233386 5.84149813 1.80999892 5.83999852 8 P 0 ;0,1=5,2=0.000000
L 1.92100079 5.846 1.92100079 5.756 8 P 0 ;0,1=5,2=0.000000
L 1.92100079 5.76949705 1.91633297 5.76199862 8 P 0 ;0,1=5,2=0.000000
L 1.91633297 5.76199862 1.90933238 5.75749961 8 P 0 ;0,1=5,2=0.000000
L 1.90933238 5.75749961 1.90116742 5.756 8 P 0 ;0,1=5,2=0.000000
L 1.90116742 5.756 1.89183396 5.75899931 8 P 0 ;0,1=5,2=0.000000
L 1.89183396 5.75899931 1.88483337 5.76649774 8 P 0 ;0,1=5,2=0.000000
L 1.88483337 5.76649774 1.88016555 5.77549852 8 P 0 ;0,1=5,2=0.000000
L 1.88016555 5.77549852 1.87899911 5.78599902 8 P 0 ;0,1=5,2=0.000000
L 1.87899911 5.78599902 1.88016555 5.79649951 8 P 0 ;0,1=5,2=0.000000
L 1.88016555 5.79649951 1.88483337 5.80550039 8 P 0 ;0,1=5,2=0.000000
L 1.88483337 5.80550039 1.89183396 5.81299872 8 P 0 ;0,1=5,2=0.000000
L 1.89183396 5.81299872 1.90116742 5.81599813 8 P 0 ;0,1=5,2=0.000000
L 1.90116742 5.81599813 1.90933238 5.81449843 8 P 0 ;0,1=5,2=0.000000
L 1.90933238 5.81449843 1.91516654 5.81149911 8 P 0 ;0,1=5,2=0.000000
L 1.91516654 5.81149911 1.92100079 5.80550039 8 P 0 ;0,1=5,2=0.000000
L 1.97250049 5.79649951 2.00983435 5.79649951 8 P 0 ;0,1=5,2=0.000000
L 2.00983435 5.79649951 2.00633297 5.807 8 P 0 ;0,1=5,2=0.000000
L 2.00633297 5.807 2.00050089 5.81299872 8 P 0 ;0,1=5,2=0.000000
L 2.00050089 5.81299872 1.99233386 5.81599813 8 P 0 ;0,1=5,2=0.000000
L 1.99233386 5.81599813 1.98416683 5.81449843 8 P 0 ;0,1=5,2=0.000000
L 1.98416683 5.81449843 1.97716614 5.80999941 8 P 0 ;0,1=5,2=0.000000
L 1.97716614 5.80999941 1.97250049 5.79949892 8 P 0 ;0,1=5,2=0.000000
L 1.97250049 5.79949892 1.97016555 5.79049803 8 P 0 ;0,1=5,2=0.000000
L 1.97016555 5.79049803 1.97016555 5.7815 8 P 0 ;0,1=5,2=0.000000
L 1.97016555 5.7815 1.97250049 5.77249921 8 P 0 ;0,1=5,2=0.000000
L 1.97250049 5.77249921 1.97833258 5.76349833 8 P 0 ;0,1=5,2=0.000000
L 1.97833258 5.76349833 1.98533317 5.75749961 8 P 0 ;0,1=5,2=0.000000
L 1.98533317 5.75749961 1.9935003 5.756 8 P 0 ;0,1=5,2=0.000000
L 1.9935003 5.756 2.00166732 5.75899931 8 P 0 ;0,1=5,2=0.000000
L 2.00166732 5.75899931 2.00983435 5.76799734 8 P 0 ;0,1=5,2=0.000000
L 2.05899911 5.756 2.05899911 5.846 8 P 0 ;0,1=5,2=0.000000
L 2.05899911 5.80099862 2.06483337 5.80999941 8 P 0 ;0,1=5,2=0.000000
L 2.06483337 5.80999941 2.07183396 5.81449843 8 P 0 ;0,1=5,2=0.000000
L 2.07183396 5.81449843 2.07883248 5.81599813 8 P 0 ;0,1=5,2=0.000000
L 2.07883248 5.81599813 2.08933238 5.81299872 8 P 0 ;0,1=5,2=0.000000
L 2.08933238 5.81299872 2.09633297 5.807 8 P 0 ;0,1=5,2=0.000000
L 2.09633297 5.807 2.10100079 5.79649951 8 P 0 ;0,1=5,2=0.000000
L 2.10100079 5.79649951 2.10100079 5.78449931 8 P 0 ;0,1=5,2=0.000000
L 2.10100079 5.78449931 2.09866585 5.77249921 8 P 0 ;0,1=5,2=0.000000
L 2.09866585 5.77249921 2.0940002 5.76349833 8 P 0 ;0,1=5,2=0.000000
L 2.0940002 5.76349833 2.08583307 5.75749961 8 P 0 ;0,1=5,2=0.000000
L 2.08583307 5.75749961 2.07883248 5.756 8 P 0 ;0,1=5,2=0.000000
L 2.07883248 5.756 2.07183396 5.75749961 8 P 0 ;0,1=5,2=0.000000
L 2.07183396 5.75749961 2.06483337 5.76199862 8 P 0 ;0,1=5,2=0.000000
L 2.06483337 5.76199862 2.05899911 5.76949705 8 P 0 ;0,1=5,2=0.000000
L 2.19100079 5.756 2.19100079 5.81599813 8 P 0 ;0,1=5,2=0.000000
L 2.19100079 5.80550039 2.18633297 5.81149911 8 P 0 ;0,1=5,2=0.000000
L 2.18633297 5.81149911 2.17933238 5.81449843 8 P 0 ;0,1=5,2=0.000000
L 2.17933238 5.81449843 2.17116742 5.81599813 8 P 0 ;0,1=5,2=0.000000
L 2.17116742 5.81599813 2.16300039 5.81299872 8 P 0 ;0,1=5,2=0.000000
L 2.16300039 5.81299872 2.1559997 5.807 8 P 0 ;0,1=5,2=0.000000
L 2.1559997 5.807 2.15133189 5.79799921 8 P 0 ;0,1=5,2=0.000000
L 2.15133189 5.79799921 2.14899911 5.78599902 8 P 0 ;0,1=5,2=0.000000
L 2.14899911 5.78599902 2.15133189 5.77399882 8 P 0 ;0,1=5,2=0.000000
L 2.15133189 5.77399882 2.1559997 5.76499803 8 P 0 ;0,1=5,2=0.000000
L 2.1559997 5.76499803 2.16300039 5.75899931 8 P 0 ;0,1=5,2=0.000000
L 2.16300039 5.75899931 2.17116742 5.756 8 P 0 ;0,1=5,2=0.000000
L 2.17116742 5.756 2.17933238 5.75749961 8 P 0 ;0,1=5,2=0.000000
L 2.17933238 5.75749961 2.18633297 5.76199862 8 P 0 ;0,1=5,2=0.000000
L 2.18633297 5.76199862 2.19100079 5.76799734 8 P 0 ;0,1=5,2=0.000000
L 2.24016555 5.756 2.24016555 5.81599813 8 P 0 ;0,1=5,2=0.000000
L 2.24016555 5.80099862 2.24483337 5.8084997 8 P 0 ;0,1=5,2=0.000000
L 2.24483337 5.8084997 2.25183396 5.81449843 8 P 0 ;0,1=5,2=0.000000
L 2.25183396 5.81449843 2.26116742 5.81599813 8 P 0 ;0,1=5,2=0.000000
L 2.26116742 5.81599813 2.26933238 5.81449843 8 P 0 ;0,1=5,2=0.000000
L 2.26933238 5.81449843 2.27633297 5.8084997 8 P 0 ;0,1=5,2=0.000000
L 2.27633297 5.8084997 2.27983435 5.79799921 8 P 0 ;0,1=5,2=0.000000
L 2.27983435 5.79799921 2.27983435 5.756 8 P 0 ;0,1=5,2=0.000000
L 2.37100079 5.846 2.37100079 5.756 8 P 0 ;0,1=5,2=0.000000
L 2.37100079 5.76949705 2.36633297 5.76199862 8 P 0 ;0,1=5,2=0.000000
L 2.36633297 5.76199862 2.35933238 5.75749961 8 P 0 ;0,1=5,2=0.000000
L 2.35933238 5.75749961 2.35116742 5.756 8 P 0 ;0,1=5,2=0.000000
L 2.35116742 5.756 2.34183396 5.75899931 8 P 0 ;0,1=5,2=0.000000
L 2.34183396 5.75899931 2.33483337 5.76649774 8 P 0 ;0,1=5,2=0.000000
L 2.33483337 5.76649774 2.33016555 5.77549852 8 P 0 ;0,1=5,2=0.000000
L 2.33016555 5.77549852 2.32899911 5.78599902 8 P 0 ;0,1=5,2=0.000000
L 2.32899911 5.78599902 2.33016555 5.79649951 8 P 0 ;0,1=5,2=0.000000
L 2.33016555 5.79649951 2.33483337 5.80550039 8 P 0 ;0,1=5,2=0.000000
L 2.33483337 5.80550039 2.34183396 5.81299872 8 P 0 ;0,1=5,2=0.000000
L 2.34183396 5.81299872 2.35116742 5.81599813 8 P 0 ;0,1=5,2=0.000000
L 2.35116742 5.81599813 2.35933238 5.81449843 8 P 0 ;0,1=5,2=0.000000
L 2.35933238 5.81449843 2.36516654 5.81149911 8 P 0 ;0,1=5,2=0.000000
L 2.36516654 5.81149911 2.37100079 5.80550039 8 P 0 ;0,1=5,2=0.000000
L 2.55566644 5.83849882 2.54866585 5.84300059 8 P 0 ;0,1=5,2=0.000000
L 2.54866585 5.84300059 2.54050089 5.846 8 P 0 ;0,1=5,2=0.000000
L 2.54050089 5.846 2.53116742 5.846 8 P 0 ;0,1=5,2=0.000000
L 2.53116742 5.846 2.52066545 5.84149813 8 P 0 ;0,1=5,2=0.000000
L 2.52066545 5.84149813 2.51250049 5.8339998 8 P 0 ;0,1=5,2=0.000000
L 2.51250049 5.8339998 2.50666624 5.82499892 8 P 0 ;0,1=5,2=0.000000
L 2.50666624 5.82499892 2.50199843 5.80999941 8 P 0 ;0,1=5,2=0.000000
L 2.50199843 5.80999941 2.50083209 5.79649951 8 P 0 ;0,1=5,2=0.000000
L 2.50083209 5.79649951 2.50316703 5.7829997 8 P 0 ;0,1=5,2=0.000000
L 2.50316703 5.7829997 2.50666624 5.77399882 8 P 0 ;0,1=5,2=0.000000
L 2.50666624 5.77399882 2.51366693 5.76499803 8 P 0 ;0,1=5,2=0.000000
L 2.51366693 5.76499803 2.52183396 5.75899931 8 P 0 ;0,1=5,2=0.000000
L 2.52183396 5.75899931 2.52999892 5.756 8 P 0 ;0,1=5,2=0.000000
L 2.52999892 5.756 2.53816594 5.756 8 P 0 ;0,1=5,2=0.000000
L 2.53816594 5.756 2.54633297 5.75899931 8 P 0 ;0,1=5,2=0.000000
L 2.54633297 5.75899931 2.55333366 5.76349833 8 P 0 ;0,1=5,2=0.000000
L 2.55333366 5.76349833 2.55916782 5.76949705 8 P 0 ;0,1=5,2=0.000000
L 2.61999892 5.756 2.61066545 5.75749961 8 P 0 ;0,1=5,2=0.000000
L 2.61066545 5.75749961 2.60250049 5.76349833 8 P 0 ;0,1=5,2=0.000000
L 2.60250049 5.76349833 2.5954998 5.77249921 8 P 0 ;0,1=5,2=0.000000
L 2.5954998 5.77249921 2.59083209 5.7829997 8 P 0 ;0,1=5,2=0.000000
L 2.59083209 5.7829997 2.58849921 5.7949999 8 P 0 ;0,1=5,2=0.000000
L 2.58849921 5.7949999 2.58849921 5.807 8 P 0 ;0,1=5,2=0.000000
L 2.58849921 5.807 2.59083209 5.8190002 8 P 0 ;0,1=5,2=0.000000
L 2.59083209 5.8190002 2.5954998 5.82950069 8 P 0 ;0,1=5,2=0.000000
L 2.5954998 5.82950069 2.60250049 5.83849882 8 P 0 ;0,1=5,2=0.000000
L 2.60250049 5.83849882 2.61066545 5.8445003 8 P 0 ;0,1=5,2=0.000000
L 2.61066545 5.8445003 2.61999892 5.846 8 P 0 ;0,1=5,2=0.000000
L 2.61999892 5.846 2.62933238 5.8445003 8 P 0 ;0,1=5,2=0.000000
L 2.62933238 5.8445003 2.63749941 5.83849882 8 P 0 ;0,1=5,2=0.000000
L 2.63749941 5.83849882 2.6445001 5.82950069 8 P 0 ;0,1=5,2=0.000000
L 2.6445001 5.82950069 2.64916782 5.8190002 8 P 0 ;0,1=5,2=0.000000
L 2.64916782 5.8190002 2.65150069 5.807 8 P 0 ;0,1=5,2=0.000000
L 2.65150069 5.807 2.65150069 5.7949999 8 P 0 ;0,1=5,2=0.000000
L 2.65150069 5.7949999 2.64916782 5.7829997 8 P 0 ;0,1=5,2=0.000000
L 2.64916782 5.7829997 2.6445001 5.77249921 8 P 0 ;0,1=5,2=0.000000
L 2.6445001 5.77249921 2.63749941 5.76349833 8 P 0 ;0,1=5,2=0.000000
L 2.63749941 5.76349833 2.62933238 5.75749961 8 P 0 ;0,1=5,2=0.000000
L 2.62933238 5.75749961 2.61999892 5.756 8 P 0 ;0,1=5,2=0.000000
L 2.68316703 5.756 2.68316703 5.846 8 P 0 ;0,1=5,2=0.000000
L 2.68316703 5.846 2.73683287 5.756 8 P 0 ;0,1=5,2=0.000000
L 2.73683287 5.756 2.73683287 5.846 8 P 0 ;0,1=5,2=0.000000
L 2.77316703 5.756 2.77316703 5.846 8 P 0 ;0,1=5,2=0.000000
L 2.77316703 5.846 2.82683287 5.756 8 P 0 ;0,1=5,2=0.000000
L 2.82683287 5.756 2.82683287 5.846 8 P 0 ;0,1=5,2=0.000000
L 1.3729998 0.51633002 1.38899882 0.51633002 4 P 0 ;0,1=6,2=0.000000
L 1.38099931 0.51633002 1.38099931 0.46633002 4 P 0 ;0,1=6,2=0.000000
L 1.3729998 0.46633002 1.38899882 0.46633002 4 P 0 ;0,1=6,2=0.000000
L 1.44766654 0.5121627 1.44366614 0.51466368 4 P 0 ;0,1=6,2=0.000000
L 1.44366614 0.51466368 1.43900049 0.51633002 4 P 0 ;0,1=6,2=0.000000
L 1.43900049 0.51633002 1.43366713 0.51633002 4 P 0 ;0,1=6,2=0.000000
L 1.43366713 0.51633002 1.42766594 0.51382894 4 P 0 ;0,1=6,2=0.000000
L 1.42766594 0.51382894 1.4230003 0.50966319 4 P 0 ;0,1=6,2=0.000000
L 1.4230003 0.50966319 1.41966644 0.5046627 4 P 0 ;0,1=6,2=0.000000
L 1.41966644 0.5046627 1.41699911 0.49632963 4 P 0 ;0,1=6,2=0.000000
L 1.41699911 0.49632963 1.41633258 0.48882972 4 P 0 ;0,1=6,2=0.000000
L 1.41633258 0.48882972 1.41766683 0.48132982 4 P 0 ;0,1=6,2=0.000000
L 1.41766683 0.48132982 1.41966644 0.47632933 4 P 0 ;0,1=6,2=0.000000
L 1.41966644 0.47632933 1.42366673 0.47132894 4 P 0 ;0,1=6,2=0.000000
L 1.42366673 0.47132894 1.42833366 0.46799626 4 P 0 ;0,1=6,2=0.000000
L 1.42833366 0.46799626 1.43299931 0.46633002 4 P 0 ;0,1=6,2=0.000000
L 1.43299931 0.46633002 1.43766624 0.46633002 4 P 0 ;0,1=6,2=0.000000
L 1.43766624 0.46633002 1.44233317 0.46799626 4 P 0 ;0,1=6,2=0.000000
L 1.44233317 0.46799626 1.44633346 0.47049577 4 P 0 ;0,1=6,2=0.000000
L 1.44633346 0.47049577 1.44966732 0.47382835 4 P 0 ;0,1=6,2=0.000000
L 1.48499931 0.51633002 1.48499931 0.46633002 4 P 0 ;0,1=6,2=0.000000
L 1.46966683 0.51633002 1.50033307 0.51633002 4 P 0 ;0,1=6,2=0.000000
L 1.36633297 0.80833002 1.36633297 0.85833002 4 P 0 ;0,1=7,2=0.000000
L 1.36633297 0.85833002 1.39166693 0.85833002 4 P 0 ;0,1=7,2=0.000000
L 1.38233317 0.83416388 1.36633297 0.83416388 4 P 0 ;0,1=7,2=0.000000
L 1.41433258 0.85833002 1.43099931 0.80833002 4 P 0 ;0,1=7,2=0.000000
L 1.43099931 0.80833002 1.44766732 0.85833002 4 P 0 ;0,1=7,2=0.000000
L 1.4689999 0.81499518 1.47433327 0.81082943 4 P 0 ;0,1=7,2=0.000000
L 1.47433327 0.81082943 1.48033327 0.80833002 4 P 0 ;0,1=7,2=0.000000
L 1.48033327 0.80833002 1.48566663 0.80833002 4 P 0 ;0,1=7,2=0.000000
L 1.48566663 0.80833002 1.4910001 0.81082943 4 P 0 ;0,1=7,2=0.000000
L 1.4910001 0.81082943 1.49500039 0.81499518 4 P 0 ;0,1=7,2=0.000000
L 1.49500039 0.81499518 1.497 0.82083032 4 P 0 ;0,1=7,2=0.000000
L 1.497 0.82083032 1.49566693 0.8266624 4 P 0 ;0,1=7,2=0.000000
L 1.49566693 0.8266624 1.49233317 0.83166289 4 P 0 ;0,1=7,2=0.000000
L 1.49233317 0.83166289 1.48633317 0.83499705 4 P 0 ;0,1=7,2=0.000000
L 1.48633317 0.83499705 1.47833366 0.83666339 4 P 0 ;0,1=7,2=0.000000
L 1.47833366 0.83666339 1.47366673 0.83999596 4 P 0 ;0,1=7,2=0.000000
L 1.47366673 0.83999596 1.47166594 0.84582963 4 P 0 ;0,1=7,2=0.000000
L 1.47166594 0.84582963 1.4730003 0.85166319 4 P 0 ;0,1=7,2=0.000000
L 1.4730003 0.85166319 1.47633287 0.85582894 4 P 0 ;0,1=7,2=0.000000
L 1.47633287 0.85582894 1.4809998 0.85833002 4 P 0 ;0,1=7,2=0.000000
L 1.4809998 0.85833002 1.48566663 0.85833002 4 P 0 ;0,1=7,2=0.000000
L 1.48566663 0.85833002 1.49033356 0.85666368 4 P 0 ;0,1=7,2=0.000000
L 1.49033356 0.85666368 1.49433396 0.85249636 4 P 0 ;0,1=7,2=0.000000
L 1.97816644 0.5965 1.97816644 0.5465 4 P 0 ;0,1=8,2=0.000000
L 1.97816644 0.5465 2.00483346 0.5465 4 P 0 ;0,1=8,2=0.000000
L 2.05550039 0.5465 2.05550039 0.57983228 4 P 0 ;0,1=8,2=0.000000
L 2.05550039 0.5740002 2.05283317 0.57733278 4 P 0 ;0,1=8,2=0.000000
L 2.05283317 0.57733278 2.04883278 0.57899911 4 P 0 ;0,1=8,2=0.000000
L 2.04883278 0.57899911 2.04416713 0.57983228 4 P 0 ;0,1=8,2=0.000000
L 2.04416713 0.57983228 2.0395002 0.57816594 4 P 0 ;0,1=8,2=0.000000
L 2.0395002 0.57816594 2.0354998 0.57483337 4 P 0 ;0,1=8,2=0.000000
L 2.0354998 0.57483337 2.03283248 0.56983287 4 P 0 ;0,1=8,2=0.000000
L 2.03283248 0.56983287 2.03149951 0.56316614 4 P 0 ;0,1=8,2=0.000000
L 2.03149951 0.56316614 2.03283248 0.55649931 4 P 0 ;0,1=8,2=0.000000
L 2.03283248 0.55649931 2.0354998 0.55149892 4 P 0 ;0,1=8,2=0.000000
L 2.0354998 0.55149892 2.0395002 0.54816624 4 P 0 ;0,1=8,2=0.000000
L 2.0395002 0.54816624 2.04416713 0.5465 4 P 0 ;0,1=8,2=0.000000
L 2.04416713 0.5465 2.04883278 0.54733307 4 P 0 ;0,1=8,2=0.000000
L 2.04883278 0.54733307 2.05283317 0.54983258 4 P 0 ;0,1=8,2=0.000000
L 2.05283317 0.54983258 2.05550039 0.55316516 4 P 0 ;0,1=8,2=0.000000
L 2.08349951 0.5465 2.08349951 0.5965 4 P 0 ;0,1=8,2=0.000000
L 2.08349951 0.57149921 2.08683327 0.57649961 4 P 0 ;0,1=8,2=0.000000
L 2.08683327 0.57649961 2.09083366 0.57899911 4 P 0 ;0,1=8,2=0.000000
L 2.09083366 0.57899911 2.09483278 0.57983228 4 P 0 ;0,1=8,2=0.000000
L 2.09483278 0.57983228 2.10083278 0.57816594 4 P 0 ;0,1=8,2=0.000000
L 2.10083278 0.57816594 2.10483317 0.57483337 4 P 0 ;0,1=8,2=0.000000
L 2.10483317 0.57483337 2.10750039 0.5689997 4 P 0 ;0,1=8,2=0.000000
L 2.10750039 0.5689997 2.10750039 0.56233297 4 P 0 ;0,1=8,2=0.000000
L 2.10750039 0.56233297 2.10616614 0.55566614 4 P 0 ;0,1=8,2=0.000000
L 2.10616614 0.55566614 2.1035001 0.55066575 4 P 0 ;0,1=8,2=0.000000
L 2.1035001 0.55066575 2.09883317 0.54733307 4 P 0 ;0,1=8,2=0.000000
L 2.09883317 0.54733307 2.09483278 0.5465 4 P 0 ;0,1=8,2=0.000000
L 2.09483278 0.5465 2.09083366 0.54733307 4 P 0 ;0,1=8,2=0.000000
L 2.09083366 0.54733307 2.08683327 0.54983258 4 P 0 ;0,1=8,2=0.000000
L 2.08683327 0.54983258 2.08349951 0.55399833 4 P 0 ;0,1=8,2=0.000000
L 2.1375003 0.5689997 2.15883396 0.5689997 4 P 0 ;0,1=8,2=0.000000
L 2.15883396 0.5689997 2.15683317 0.57483337 4 P 0 ;0,1=8,2=0.000000
L 2.15683317 0.57483337 2.15350049 0.57816594 4 P 0 ;0,1=8,2=0.000000
L 2.15350049 0.57816594 2.14883356 0.57983228 4 P 0 ;0,1=8,2=0.000000
L 2.14883356 0.57983228 2.14416673 0.57899911 4 P 0 ;0,1=8,2=0.000000
L 2.14416673 0.57899911 2.14016634 0.57649961 4 P 0 ;0,1=8,2=0.000000
L 2.14016634 0.57649961 2.1375003 0.57066604 4 P 0 ;0,1=8,2=0.000000
L 2.1375003 0.57066604 2.13616594 0.56566555 4 P 0 ;0,1=8,2=0.000000
L 2.13616594 0.56566555 2.13616594 0.56066663 4 P 0 ;0,1=8,2=0.000000
L 2.13616594 0.56066663 2.1375003 0.55566614 4 P 0 ;0,1=8,2=0.000000
L 2.1375003 0.55566614 2.14083287 0.55066575 4 P 0 ;0,1=8,2=0.000000
L 2.14083287 0.55066575 2.14483327 0.54733307 4 P 0 ;0,1=8,2=0.000000
L 2.14483327 0.54733307 2.1495001 0.5465 4 P 0 ;0,1=8,2=0.000000
L 2.1495001 0.5465 2.15416703 0.54816624 4 P 0 ;0,1=8,2=0.000000
L 2.15416703 0.54816624 2.15883396 0.55316516 4 P 0 ;0,1=8,2=0.000000
L 2.19949931 0.5465 2.19949931 0.5965 4 P 0 ;0,1=8,2=0.000000
L 2.0434998 0.7115 2.05949882 0.7115 4 P 0 ;0,1=9,2=0.000000
L 2.05149931 0.7115 2.05149931 0.6615 4 P 0 ;0,1=9,2=0.000000
L 2.0434998 0.6615 2.05949882 0.6615 4 P 0 ;0,1=9,2=0.000000
L 2.08883337 0.6615 2.08883337 0.7115 4 P 0 ;0,1=9,2=0.000000
L 2.08883337 0.7115 2.10216634 0.7115 4 P 0 ;0,1=9,2=0.000000
L 2.10216634 0.7115 2.1074997 0.70899892 4 P 0 ;0,1=9,2=0.000000
L 2.1074997 0.70899892 2.1115001 0.70566634 4 P 0 ;0,1=9,2=0.000000
L 2.1115001 0.70566634 2.11483396 0.70066742 4 P 0 ;0,1=9,2=0.000000
L 2.11483396 0.70066742 2.1175 0.69483228 4 P 0 ;0,1=9,2=0.000000
L 2.1175 0.69483228 2.11816654 0.68649921 4 P 0 ;0,1=9,2=0.000000
L 2.11816654 0.68649921 2.1175 0.67816614 4 P 0 ;0,1=9,2=0.000000
L 2.1175 0.67816614 2.11483396 0.67233248 4 P 0 ;0,1=9,2=0.000000
L 2.11483396 0.67233248 2.1115001 0.66733209 4 P 0 ;0,1=9,2=0.000000
L 2.1115001 0.66733209 2.1074997 0.66399941 4 P 0 ;0,1=9,2=0.000000
L 2.1074997 0.66399941 2.10216634 0.6615 4 P 0 ;0,1=9,2=0.000000
L 2.10216634 0.6615 2.08883337 0.6615 4 P 0 ;0,1=9,2=0.000000
L 10.73549951 1.13249862 10.75883425 1.13249862 8 P 0 ;0,1=10,2=0.000000
L 10.75883425 1.13249862 10.75883425 1.10549882 8 P 0 ;0,1=10,2=0.000000
L 10.75883425 1.10549882 10.75183366 1.09649803 8 P 0 ;0,1=10,2=0.000000
L 10.75183366 1.09649803 10.74366654 1.09049931 8 P 0 ;0,1=10,2=0.000000
L 10.74366654 1.09049931 10.7320003 1.0875 8 P 0 ;0,1=10,2=0.000000
L 10.7320003 1.0875 10.72033396 1.09049931 8 P 0 ;0,1=10,2=0.000000
L 10.72033396 1.09049931 10.71216693 1.09649803 8 P 0 ;0,1=10,2=0.000000
L 10.71216693 1.09649803 10.70516624 1.10549882 8 P 0 ;0,1=10,2=0.000000
L 10.70516624 1.10549882 10.70049843 1.11599931 8 P 0 ;0,1=10,2=0.000000
L 10.70049843 1.11599931 10.69816565 1.12799951 8 P 0 ;0,1=10,2=0.000000
L 10.69816565 1.12799951 10.69816565 1.1385 8 P 0 ;0,1=10,2=0.000000
L 10.69816565 1.1385 10.70049843 1.14749813 8 P 0 ;0,1=10,2=0.000000
L 10.70049843 1.14749813 10.70516624 1.15800138 8 P 0 ;0,1=10,2=0.000000
L 10.70516624 1.15800138 10.71216693 1.16699941 8 P 0 ;0,1=10,2=0.000000
L 10.71216693 1.16699941 10.71916545 1.17299813 8 P 0 ;0,1=10,2=0.000000
L 10.71916545 1.17299813 10.72849892 1.1775 8 P 0 ;0,1=10,2=0.000000
L 10.72849892 1.1775 10.73666594 1.1775 8 P 0 ;0,1=10,2=0.000000
L 10.73666594 1.1775 10.74599941 1.17450059 8 P 0 ;0,1=10,2=0.000000
L 10.74599941 1.17450059 10.7530001 1.16849911 8 P 0 ;0,1=10,2=0.000000
L 10.79516624 1.0875 10.79516624 1.1775 8 P 0 ;0,1=10,2=0.000000
L 10.79516624 1.1775 10.82316673 1.1775 8 P 0 ;0,1=10,2=0.000000
L 10.82316673 1.1775 10.8325002 1.17299813 8 P 0 ;0,1=10,2=0.000000
L 10.8325002 1.17299813 10.83950079 1.16250039 8 P 0 ;0,1=10,2=0.000000
L 10.83950079 1.16250039 10.84183366 1.1505002 8 P 0 ;0,1=10,2=0.000000
L 10.84183366 1.1505002 10.83950079 1.1385 8 P 0 ;0,1=10,2=0.000000
L 10.83950079 1.1385 10.83366654 1.12949921 8 P 0 ;0,1=10,2=0.000000
L 10.83366654 1.12949921 10.82316673 1.12499744 8 P 0 ;0,1=10,2=0.000000
L 10.82316673 1.12499744 10.79516624 1.12499744 8 P 0 ;0,1=10,2=0.000000
L 10.88283346 1.1775 10.88283346 1.113 8 P 0 ;0,1=10,2=0.000000
L 10.88283346 1.113 10.88749911 1.09949734 8 P 0 ;0,1=10,2=0.000000
L 10.88749911 1.09949734 10.89683258 1.09049931 8 P 0 ;0,1=10,2=0.000000
L 10.89683258 1.09049931 10.90849892 1.0875 8 P 0 ;0,1=10,2=0.000000
L 10.90849892 1.0875 10.92016732 1.09049931 8 P 0 ;0,1=10,2=0.000000
L 10.92016732 1.09049931 10.92950079 1.09949734 8 P 0 ;0,1=10,2=0.000000
L 10.92950079 1.09949734 10.93416644 1.113 8 P 0 ;0,1=10,2=0.000000
L 10.93416644 1.113 10.93416644 1.1775 8 P 0 ;0,1=10,2=0.000000
L 10.99849892 1.0875 10.99849892 1.1775 8 P 0 ;0,1=10,2=0.000000
L 10.99849892 1.1775 10.9844997 1.15950108 8 P 0 ;0,1=10,2=0.000000
L 10.9844997 1.0875 11.01249803 1.0875 8 P 0 ;0,1=10,2=0.000000
L 2.11149951 1.17149862 2.13483425 1.17149862 8 P 0 ;0,1=11,2=0.000000
L 2.13483425 1.17149862 2.13483425 1.14449882 8 P 0 ;0,1=11,2=0.000000
L 2.13483425 1.14449882 2.12783366 1.13549803 8 P 0 ;0,1=11,2=0.000000
L 2.12783366 1.13549803 2.11966654 1.12949931 8 P 0 ;0,1=11,2=0.000000
L 2.11966654 1.12949931 2.1080003 1.1265 8 P 0 ;0,1=11,2=0.000000
L 2.1080003 1.1265 2.09633396 1.12949931 8 P 0 ;0,1=11,2=0.000000
L 2.09633396 1.12949931 2.08816693 1.13549803 8 P 0 ;0,1=11,2=0.000000
L 2.08816693 1.13549803 2.08116624 1.14449882 8 P 0 ;0,1=11,2=0.000000
L 2.08116624 1.14449882 2.07649843 1.15499931 8 P 0 ;0,1=11,2=0.000000
L 2.07649843 1.15499931 2.07416565 1.16699951 8 P 0 ;0,1=11,2=0.000000
L 2.07416565 1.16699951 2.07416565 1.1775 8 P 0 ;0,1=11,2=0.000000
L 2.07416565 1.1775 2.07649843 1.18649813 8 P 0 ;0,1=11,2=0.000000
L 2.07649843 1.18649813 2.08116624 1.19700138 8 P 0 ;0,1=11,2=0.000000
L 2.08116624 1.19700138 2.08816693 1.20599941 8 P 0 ;0,1=11,2=0.000000
L 2.08816693 1.20599941 2.09516545 1.21199813 8 P 0 ;0,1=11,2=0.000000
L 2.09516545 1.21199813 2.10449892 1.2165 8 P 0 ;0,1=11,2=0.000000
L 2.10449892 1.2165 2.11266594 1.2165 8 P 0 ;0,1=11,2=0.000000
L 2.11266594 1.2165 2.12199941 1.21350059 8 P 0 ;0,1=11,2=0.000000
L 2.12199941 1.21350059 2.1290001 1.20749911 8 P 0 ;0,1=11,2=0.000000
L 2.17116624 1.1265 2.17116624 1.2165 8 P 0 ;0,1=11,2=0.000000
L 2.17116624 1.2165 2.19916673 1.2165 8 P 0 ;0,1=11,2=0.000000
L 2.19916673 1.2165 2.2085002 1.21199813 8 P 0 ;0,1=11,2=0.000000
L 2.2085002 1.21199813 2.21550079 1.20150039 8 P 0 ;0,1=11,2=0.000000
L 2.21550079 1.20150039 2.21783366 1.1895002 8 P 0 ;0,1=11,2=0.000000
L 2.21783366 1.1895002 2.21550079 1.1775 8 P 0 ;0,1=11,2=0.000000
L 2.21550079 1.1775 2.20966654 1.16849921 8 P 0 ;0,1=11,2=0.000000
L 2.20966654 1.16849921 2.19916673 1.16399744 8 P 0 ;0,1=11,2=0.000000
L 2.19916673 1.16399744 2.17116624 1.16399744 8 P 0 ;0,1=11,2=0.000000
L 2.25883346 1.2165 2.25883346 1.152 8 P 0 ;0,1=11,2=0.000000
L 2.25883346 1.152 2.26349911 1.13849734 8 P 0 ;0,1=11,2=0.000000
L 2.26349911 1.13849734 2.27283258 1.12949931 8 P 0 ;0,1=11,2=0.000000
L 2.27283258 1.12949931 2.28449892 1.1265 8 P 0 ;0,1=11,2=0.000000
L 2.28449892 1.1265 2.29616732 1.12949931 8 P 0 ;0,1=11,2=0.000000
L 2.29616732 1.12949931 2.30550079 1.13849734 8 P 0 ;0,1=11,2=0.000000
L 2.30550079 1.13849734 2.31016644 1.152 8 P 0 ;0,1=11,2=0.000000
L 2.31016644 1.152 2.31016644 1.2165 8 P 0 ;0,1=11,2=0.000000
L 2.37449892 1.2165 2.36516545 1.21350059 8 P 0 ;0,1=11,2=0.000000
L 2.36516545 1.21350059 2.35816693 1.20599941 8 P 0 ;0,1=11,2=0.000000
L 2.35816693 1.20599941 2.35349911 1.19700138 8 P 0 ;0,1=11,2=0.000000
L 2.35349911 1.19700138 2.3499998 1.18499843 8 P 0 ;0,1=11,2=0.000000
L 2.3499998 1.18499843 2.34883346 1.17149862 8 P 0 ;0,1=11,2=0.000000
L 2.34883346 1.17149862 2.3499998 1.15799872 8 P 0 ;0,1=11,2=0.000000
L 2.3499998 1.15799872 2.35349911 1.14599852 8 P 0 ;0,1=11,2=0.000000
L 2.35349911 1.14599852 2.35816693 1.13699774 8 P 0 ;0,1=11,2=0.000000
L 2.35816693 1.13699774 2.36516545 1.12949931 8 P 0 ;0,1=11,2=0.000000
L 2.36516545 1.12949931 2.37449892 1.1265 8 P 0 ;0,1=11,2=0.000000
L 2.37449892 1.1265 2.38383238 1.12949931 8 P 0 ;0,1=11,2=0.000000
L 2.38383238 1.12949931 2.39083297 1.13699774 8 P 0 ;0,1=11,2=0.000000
L 2.39083297 1.13699774 2.39550079 1.14599852 8 P 0 ;0,1=11,2=0.000000
L 2.39550079 1.14599852 2.3990001 1.15799872 8 P 0 ;0,1=11,2=0.000000
L 2.3990001 1.15799872 2.40016644 1.17149862 8 P 0 ;0,1=11,2=0.000000
L 2.40016644 1.17149862 2.3990001 1.18499843 8 P 0 ;0,1=11,2=0.000000
L 2.3990001 1.18499843 2.39550079 1.19700138 8 P 0 ;0,1=11,2=0.000000
L 2.39550079 1.19700138 2.39083297 1.20599941 8 P 0 ;0,1=11,2=0.000000
L 2.39083297 1.20599941 2.38383238 1.21350059 8 P 0 ;0,1=11,2=0.000000
L 2.38383238 1.21350059 2.37449892 1.2165 8 P 0 ;0,1=11,2=0.000000
L 2.6966064 0.44161998 2.6966064 0.49161998 4 P 0 ;0,1=12,2=0.000000
L 2.6966064 0.49161998 2.71327313 0.49161998 4 P 0 ;0,1=12,2=0.000000
L 2.71327313 0.49161998 2.71860659 0.4891189 4 P 0 ;0,1=12,2=0.000000
L 2.71860659 0.4891189 2.72194035 0.48578632 4 P 0 ;0,1=12,2=0.000000
L 2.72194035 0.48578632 2.72327343 0.47911959 4 P 0 ;0,1=12,2=0.000000
L 2.72327343 0.47911959 2.72194035 0.47245276 4 P 0 ;0,1=12,2=0.000000
L 2.72194035 0.47245276 2.71794006 0.46828701 4 P 0 ;0,1=12,2=0.000000
L 2.71794006 0.46828701 2.71327313 0.46578602 4 P 0 ;0,1=12,2=0.000000
L 2.71327313 0.46578602 2.6966064 0.46578602 4 P 0 ;0,1=12,2=0.000000
L 2.71327313 0.46578602 2.72327343 0.44161998 4 P 0 ;0,1=12,2=0.000000
L 2.75194026 0.46411969 2.77327392 0.46411969 4 P 0 ;0,1=12,2=0.000000
L 2.77327392 0.46411969 2.77127313 0.46995335 4 P 0 ;0,1=12,2=0.000000
L 2.77127313 0.46995335 2.76794045 0.47328593 4 P 0 ;0,1=12,2=0.000000
L 2.76794045 0.47328593 2.76327352 0.47495226 4 P 0 ;0,1=12,2=0.000000
L 2.76327352 0.47495226 2.75860669 0.47411909 4 P 0 ;0,1=12,2=0.000000
L 2.75860669 0.47411909 2.7546063 0.47161959 4 P 0 ;0,1=12,2=0.000000
L 2.7546063 0.47161959 2.75194026 0.46578602 4 P 0 ;0,1=12,2=0.000000
L 2.75194026 0.46578602 2.75060591 0.46078553 4 P 0 ;0,1=12,2=0.000000
L 2.75060591 0.46078553 2.75060591 0.45578661 4 P 0 ;0,1=12,2=0.000000
L 2.75060591 0.45578661 2.75194026 0.45078612 4 P 0 ;0,1=12,2=0.000000
L 2.75194026 0.45078612 2.75527283 0.44578573 4 P 0 ;0,1=12,2=0.000000
L 2.75527283 0.44578573 2.75927323 0.44245305 4 P 0 ;0,1=12,2=0.000000
L 2.75927323 0.44245305 2.76394006 0.44161998 4 P 0 ;0,1=12,2=0.000000
L 2.76394006 0.44161998 2.76860699 0.44328622 4 P 0 ;0,1=12,2=0.000000
L 2.76860699 0.44328622 2.77327392 0.44828514 4 P 0 ;0,1=12,2=0.000000
L 2.79727254 0.47495226 2.80527323 0.44161998 4 P 0 ;0,1=12,2=0.000000
L 2.80527323 0.44161998 2.81393927 0.47495226 4 P 0 ;0,1=12,2=0.000000
L 2.81393927 0.47495226 2.82260659 0.44161998 4 P 0 ;0,1=12,2=0.000000
L 2.82260659 0.44161998 2.83060728 0.47495226 4 P 0 ;0,1=12,2=0.000000
L 2.86593927 0.44161998 2.86194016 0.44245305 4 P 0 ;0,1=12,2=0.000000
L 2.86194016 0.44245305 2.85793976 0.44578573 4 P 0 ;0,1=12,2=0.000000
L 2.85793976 0.44578573 2.85527244 0.45161929 4 P 0 ;0,1=12,2=0.000000
L 2.85527244 0.45161929 2.85393947 0.45828612 4 P 0 ;0,1=12,2=0.000000
L 2.85393947 0.45828612 2.85527244 0.46495285 4 P 0 ;0,1=12,2=0.000000
L 2.85527244 0.46495285 2.85793976 0.47078652 4 P 0 ;0,1=12,2=0.000000
L 2.85793976 0.47078652 2.86194016 0.47411909 4 P 0 ;0,1=12,2=0.000000
L 2.86194016 0.47411909 2.86593927 0.47495226 4 P 0 ;0,1=12,2=0.000000
L 2.86593927 0.47495226 2.86993967 0.47411909 4 P 0 ;0,1=12,2=0.000000
L 2.86993967 0.47411909 2.87394006 0.47078652 4 P 0 ;0,1=12,2=0.000000
L 2.87394006 0.47078652 2.8766061 0.46495285 4 P 0 ;0,1=12,2=0.000000
L 2.8766061 0.46495285 2.87727392 0.45828612 4 P 0 ;0,1=12,2=0.000000
L 2.87727392 0.45828612 2.8766061 0.45161929 4 P 0 ;0,1=12,2=0.000000
L 2.8766061 0.45161929 2.87394006 0.44578573 4 P 0 ;0,1=12,2=0.000000
L 2.87394006 0.44578573 2.86993967 0.44245305 4 P 0 ;0,1=12,2=0.000000
L 2.86993967 0.44245305 2.86593927 0.44161998 4 P 0 ;0,1=12,2=0.000000
L 2.90860669 0.44161998 2.90860669 0.47495226 4 P 0 ;0,1=12,2=0.000000
L 2.90860669 0.46828701 2.91193937 0.47161959 4 P 0 ;0,1=12,2=0.000000
L 2.91193937 0.47161959 2.91527323 0.47411909 4 P 0 ;0,1=12,2=0.000000
L 2.91527323 0.47411909 2.91994006 0.47495226 4 P 0 ;0,1=12,2=0.000000
L 2.91994006 0.47495226 2.92327274 0.47411909 4 P 0 ;0,1=12,2=0.000000
L 2.92327274 0.47411909 2.92727313 0.47161959 4 P 0 ;0,1=12,2=0.000000
L 2.95860591 0.44161998 2.95860591 0.49161998 4 P 0 ;0,1=12,2=0.000000
L 2.97993957 0.47495226 2.95860591 0.45578661 4 P 0 ;0,1=12,2=0.000000
L 2.96727323 0.46328652 2.98127392 0.44161998 4 P 0 ;0,1=12,2=0.000000
L 3.07393927 0.44161998 3.07393927 0.49161998 4 P 0 ;0,1=12,2=0.000000
L 3.07393927 0.49161998 3.06593976 0.48162057 4 P 0 ;0,1=12,2=0.000000
L 3.06593976 0.44161998 3.08193878 0.44161998 4 P 0 ;0,1=12,2=0.000000
L 3.11327293 0.48328681 3.11727323 0.48828583 4 P 0 ;0,1=12,2=0.000000
L 3.11727323 0.48828583 3.12194016 0.49078681 4 P 0 ;0,1=12,2=0.000000
L 3.12194016 0.49078681 3.12727352 0.49161998 4 P 0 ;0,1=12,2=0.000000
L 3.12727352 0.49161998 3.13394006 0.48995364 4 P 0 ;0,1=12,2=0.000000
L 3.13394006 0.48995364 3.13860689 0.48578632 4 P 0 ;0,1=12,2=0.000000
L 3.13860689 0.48578632 3.13993996 0.4807874 4 P 0 ;0,1=12,2=0.000000
L 3.13993996 0.4807874 3.13927343 0.47578543 4 P 0 ;0,1=12,2=0.000000
L 3.13927343 0.47578543 3.1366061 0.47161959 4 P 0 ;0,1=12,2=0.000000
L 3.1366061 0.47161959 3.12327323 0.46328652 4 P 0 ;0,1=12,2=0.000000
L 3.12327323 0.46328652 3.11727323 0.45745295 4 P 0 ;0,1=12,2=0.000000
L 3.11727323 0.45745295 3.11327293 0.44911831 4 P 0 ;0,1=12,2=0.000000
L 3.11327293 0.44911831 3.11193986 0.44161998 4 P 0 ;0,1=12,2=0.000000
L 3.11193986 0.44161998 3.13993996 0.44161998 4 P 0 ;0,1=12,2=0.000000
L 3.16327333 0.45161929 3.16727244 0.44578573 4 P 0 ;0,1=12,2=0.000000
L 3.16727244 0.44578573 3.17260591 0.44245305 4 P 0 ;0,1=12,2=0.000000
L 3.17260591 0.44245305 3.17860709 0.44161998 4 P 0 ;0,1=12,2=0.000000
L 3.17860709 0.44161998 3.18394045 0.44245305 4 P 0 ;0,1=12,2=0.000000
L 3.18394045 0.44245305 3.18927392 0.4466189 4 P 0 ;0,1=12,2=0.000000
L 3.18927392 0.4466189 3.1926065 0.45161929 4 P 0 ;0,1=12,2=0.000000
L 3.1926065 0.45161929 3.19327303 0.45661978 4 P 0 ;0,1=12,2=0.000000
L 3.19327303 0.45661978 3.19193996 0.46245187 4 P 0 ;0,1=12,2=0.000000
L 3.19193996 0.46245187 3.18727313 0.46661919 4 P 0 ;0,1=12,2=0.000000
L 3.18727313 0.46661919 3.1826062 0.46828701 4 P 0 ;0,1=12,2=0.000000
L 3.1826062 0.46828701 3.1766063 0.46828701 4 P 0 ;0,1=12,2=0.000000
L 3.1826062 0.46828701 3.18660659 0.47078652 4 P 0 ;0,1=12,2=0.000000
L 3.18660659 0.47078652 3.18994035 0.47495226 4 P 0 ;0,1=12,2=0.000000
L 3.18994035 0.47495226 3.19127343 0.47995266 4 P 0 ;0,1=12,2=0.000000
L 3.19127343 0.47995266 3.18994035 0.48495315 4 P 0 ;0,1=12,2=0.000000
L 3.18994035 0.48495315 3.18660659 0.4891189 4 P 0 ;0,1=12,2=0.000000
L 3.18660659 0.4891189 3.18060659 0.49161998 4 P 0 ;0,1=12,2=0.000000
L 3.18060659 0.49161998 3.17460669 0.49078681 4 P 0 ;0,1=12,2=0.000000
L 3.17460669 0.49078681 3.16860669 0.48745266 4 P 0 ;0,1=12,2=0.000000
L 2.682856 0.78161998 2.69743937 0.73661998 4 P 0 ;0,1=13,2=0.000000
L 2.69743937 0.73661998 2.71202382 0.78161998 4 P 0 ;0,1=13,2=0.000000
L 2.75610679 0.73661998 2.73277303 0.73661998 4 P 0 ;0,1=13,2=0.000000
L 2.73277303 0.73661998 2.73277303 0.78161998 4 P 0 ;0,1=13,2=0.000000
L 2.73277303 0.78161998 2.75610679 0.78161998 4 P 0 ;0,1=13,2=0.000000
L 2.74677333 0.75987047 2.73277303 0.75987047 4 P 0 ;0,1=13,2=0.000000
L 2.77802343 0.73661998 2.77802343 0.78161998 4 P 0 ;0,1=13,2=0.000000
L 2.77802343 0.78161998 2.8048564 0.73661998 4 P 0 ;0,1=13,2=0.000000
L 2.8048564 0.73661998 2.8048564 0.78161998 4 P 0 ;0,1=13,2=0.000000
L 2.82560669 0.73661998 2.82560669 0.78161998 4 P 0 ;0,1=13,2=0.000000
L 2.82560669 0.78161998 2.83727293 0.78161998 4 P 0 ;0,1=13,2=0.000000
L 2.83727293 0.78161998 2.84193967 0.779369 4 P 0 ;0,1=13,2=0.000000
L 2.84193967 0.779369 2.84544006 0.77636969 4 P 0 ;0,1=13,2=0.000000
L 2.84544006 0.77636969 2.84835709 0.77187067 4 P 0 ;0,1=13,2=0.000000
L 2.84835709 0.77187067 2.85068996 0.766619 4 P 0 ;0,1=13,2=0.000000
L 2.85068996 0.766619 2.85127313 0.75911929 4 P 0 ;0,1=13,2=0.000000
L 2.85127313 0.75911929 2.85068996 0.75161949 4 P 0 ;0,1=13,2=0.000000
L 2.85068996 0.75161949 2.84835709 0.74636919 4 P 0 ;0,1=13,2=0.000000
L 2.84835709 0.74636919 2.84544006 0.7418688 4 P 0 ;0,1=13,2=0.000000
L 2.84544006 0.7418688 2.84193967 0.73886949 4 P 0 ;0,1=13,2=0.000000
L 2.84193967 0.73886949 2.83727293 0.73661998 4 P 0 ;0,1=13,2=0.000000
L 2.83727293 0.73661998 2.82560669 0.73661998 4 P 0 ;0,1=13,2=0.000000
L 2.88543937 0.73661998 2.88077264 0.73736978 4 P 0 ;0,1=13,2=0.000000
L 2.88077264 0.73736978 2.87669016 0.74036909 4 P 0 ;0,1=13,2=0.000000
L 2.87669016 0.74036909 2.87318986 0.74486959 4 P 0 ;0,1=13,2=0.000000
L 2.87318986 0.74486959 2.870856 0.75011978 4 P 0 ;0,1=13,2=0.000000
L 2.870856 0.75011978 2.86968957 0.75611988 4 P 0 ;0,1=13,2=0.000000
L 2.86968957 0.75611988 2.86968957 0.76211998 4 P 0 ;0,1=13,2=0.000000
L 2.86968957 0.76211998 2.870856 0.76812008 4 P 0 ;0,1=13,2=0.000000
L 2.870856 0.76812008 2.87318986 0.77337028 4 P 0 ;0,1=13,2=0.000000
L 2.87318986 0.77337028 2.87669016 0.77786939 4 P 0 ;0,1=13,2=0.000000
L 2.87669016 0.77786939 2.88077264 0.78087008 4 P 0 ;0,1=13,2=0.000000
L 2.88077264 0.78087008 2.88543937 0.78161998 4 P 0 ;0,1=13,2=0.000000
L 2.88543937 0.78161998 2.8901061 0.78087008 4 P 0 ;0,1=13,2=0.000000
L 2.8901061 0.78087008 2.89418967 0.77786939 4 P 0 ;0,1=13,2=0.000000
L 2.89418967 0.77786939 2.89768996 0.77337028 4 P 0 ;0,1=13,2=0.000000
L 2.89768996 0.77337028 2.90002382 0.76812008 4 P 0 ;0,1=13,2=0.000000
L 2.90002382 0.76812008 2.90119026 0.76211998 4 P 0 ;0,1=13,2=0.000000
L 2.90119026 0.76211998 2.90119026 0.75611988 4 P 0 ;0,1=13,2=0.000000
L 2.90119026 0.75611988 2.90002382 0.75011978 4 P 0 ;0,1=13,2=0.000000
L 2.90002382 0.75011978 2.89768996 0.74486959 4 P 0 ;0,1=13,2=0.000000
L 2.89768996 0.74486959 2.89418967 0.74036909 4 P 0 ;0,1=13,2=0.000000
L 2.89418967 0.74036909 2.8901061 0.73736978 4 P 0 ;0,1=13,2=0.000000
L 2.8901061 0.73736978 2.88543937 0.73661998 4 P 0 ;0,1=13,2=0.000000
L 2.92077303 0.73661998 2.92077303 0.78161998 4 P 0 ;0,1=13,2=0.000000
L 2.92077303 0.78161998 2.9353565 0.78161998 4 P 0 ;0,1=13,2=0.000000
L 2.9353565 0.78161998 2.94002323 0.779369 4 P 0 ;0,1=13,2=0.000000
L 2.94002323 0.779369 2.94294035 0.77636969 4 P 0 ;0,1=13,2=0.000000
L 2.94294035 0.77636969 2.94410679 0.77036959 4 P 0 ;0,1=13,2=0.000000
L 2.94410679 0.77036959 2.94294035 0.76436949 4 P 0 ;0,1=13,2=0.000000
L 2.94294035 0.76436949 2.93944006 0.76062028 4 P 0 ;0,1=13,2=0.000000
L 2.93944006 0.76062028 2.9353565 0.75836939 4 P 0 ;0,1=13,2=0.000000
L 2.9353565 0.75836939 2.92077303 0.75836939 4 P 0 ;0,1=13,2=0.000000
L 2.9353565 0.75836939 2.94410679 0.73661998 4 P 0 ;0,1=13,2=0.000000
L 5.15966644 0.67733002 5.15966644 0.72733002 4 P 0 ;0,1=14,2=0.000000
L 5.15966644 0.72733002 5.17566663 0.72733002 4 P 0 ;0,1=14,2=0.000000
L 5.17566663 0.72733002 5.1810001 0.72482894 4 P 0 ;0,1=14,2=0.000000
L 5.1810001 0.72482894 5.18500039 0.71899685 4 P 0 ;0,1=14,2=0.000000
L 5.18500039 0.71899685 5.18633346 0.71233012 4 P 0 ;0,1=14,2=0.000000
L 5.18633346 0.71233012 5.18500039 0.70566339 4 P 0 ;0,1=14,2=0.000000
L 5.18500039 0.70566339 5.18166663 0.70066289 4 P 0 ;0,1=14,2=0.000000
L 5.18166663 0.70066289 5.17566663 0.69816191 4 P 0 ;0,1=14,2=0.000000
L 5.17566663 0.69816191 5.15966644 0.69816191 4 P 0 ;0,1=14,2=0.000000
L 5.21299951 0.67566378 5.23700039 0.72733002 4 P 0 ;0,1=14,2=0.000000
L 5.26166683 0.67733002 5.26166683 0.72733002 4 P 0 ;0,1=14,2=0.000000
L 5.26166683 0.72733002 5.29233307 0.67733002 4 P 0 ;0,1=14,2=0.000000
L 5.29233307 0.67733002 5.29233307 0.72733002 4 P 0 ;0,1=14,2=0.000000
L 5.32899931 0.67566378 5.32766634 0.67649695 4 P 0 ;0,1=14,2=0.000000
L 5.32766634 0.67649695 5.32766634 0.67816309 4 P 0 ;0,1=14,2=0.000000
L 5.32766634 0.67816309 5.32899931 0.67899626 4 P 0 ;0,1=14,2=0.000000
L 5.32899931 0.67899626 5.33033356 0.67816309 4 P 0 ;0,1=14,2=0.000000
L 5.33033356 0.67816309 5.33033356 0.67649695 4 P 0 ;0,1=14,2=0.000000
L 5.33033356 0.67649695 5.32899931 0.67566378 4 P 0 ;0,1=14,2=0.000000
L 5.32899931 0.69816191 5.32766634 0.69899656 4 P 0 ;0,1=14,2=0.000000
L 5.32766634 0.69899656 5.32766634 0.70066289 4 P 0 ;0,1=14,2=0.000000
L 5.32766634 0.70066289 5.32899931 0.70149606 4 P 0 ;0,1=14,2=0.000000
L 5.32899931 0.70149606 5.33033356 0.70066289 4 P 0 ;0,1=14,2=0.000000
L 5.33033356 0.70066289 5.33033356 0.69899656 4 P 0 ;0,1=14,2=0.000000
L 5.33033356 0.69899656 5.32899931 0.69816191 4 P 0 ;0,1=14,2=0.000000
L 5.38099931 0.72733002 5.37566594 0.72566368 4 P 0 ;0,1=14,2=0.000000
L 5.37566594 0.72566368 5.37166673 0.72149636 4 P 0 ;0,1=14,2=0.000000
L 5.37166673 0.72149636 5.36899951 0.71649744 4 P 0 ;0,1=14,2=0.000000
L 5.36899951 0.71649744 5.3669999 0.70982913 4 P 0 ;0,1=14,2=0.000000
L 5.3669999 0.70982913 5.36633337 0.70232923 4 P 0 ;0,1=14,2=0.000000
L 5.36633337 0.70232923 5.3669999 0.69482933 4 P 0 ;0,1=14,2=0.000000
L 5.3669999 0.69482933 5.36899951 0.6881625 4 P 0 ;0,1=14,2=0.000000
L 5.36899951 0.6881625 5.37166673 0.68316211 4 P 0 ;0,1=14,2=0.000000
L 5.37166673 0.68316211 5.37566594 0.67899626 4 P 0 ;0,1=14,2=0.000000
L 5.37566594 0.67899626 5.38099931 0.67733002 4 P 0 ;0,1=14,2=0.000000
L 5.38099931 0.67733002 5.38633278 0.67899626 4 P 0 ;0,1=14,2=0.000000
L 5.38633278 0.67899626 5.39033317 0.68316211 4 P 0 ;0,1=14,2=0.000000
L 5.39033317 0.68316211 5.39300039 0.6881625 4 P 0 ;0,1=14,2=0.000000
L 5.39300039 0.6881625 5.395 0.69482933 4 P 0 ;0,1=14,2=0.000000
L 5.395 0.69482933 5.39566654 0.70232923 4 P 0 ;0,1=14,2=0.000000
L 5.39566654 0.70232923 5.395 0.70982913 4 P 0 ;0,1=14,2=0.000000
L 5.395 0.70982913 5.39300039 0.71649744 4 P 0 ;0,1=14,2=0.000000
L 5.39300039 0.71649744 5.39033317 0.72149636 4 P 0 ;0,1=14,2=0.000000
L 5.39033317 0.72149636 5.38633278 0.72566368 4 P 0 ;0,1=14,2=0.000000
L 5.38633278 0.72566368 5.38099931 0.72733002 4 P 0 ;0,1=14,2=0.000000
L 5.43299931 0.67733002 5.43299931 0.72733002 4 P 0 ;0,1=14,2=0.000000
L 5.43299931 0.72733002 5.4249998 0.71733061 4 P 0 ;0,1=14,2=0.000000
L 5.4249998 0.67733002 5.44099882 0.67733002 4 P 0 ;0,1=14,2=0.000000
L 5.48499931 0.72733002 5.47966594 0.72566368 4 P 0 ;0,1=14,2=0.000000
L 5.47966594 0.72566368 5.47566673 0.72149636 4 P 0 ;0,1=14,2=0.000000
L 5.47566673 0.72149636 5.47299951 0.71649744 4 P 0 ;0,1=14,2=0.000000
L 5.47299951 0.71649744 5.4709999 0.70982913 4 P 0 ;0,1=14,2=0.000000
L 5.4709999 0.70982913 5.47033337 0.70232923 4 P 0 ;0,1=14,2=0.000000
L 5.47033337 0.70232923 5.4709999 0.69482933 4 P 0 ;0,1=14,2=0.000000
L 5.4709999 0.69482933 5.47299951 0.6881625 4 P 0 ;0,1=14,2=0.000000
L 5.47299951 0.6881625 5.47566673 0.68316211 4 P 0 ;0,1=14,2=0.000000
L 5.47566673 0.68316211 5.47966594 0.67899626 4 P 0 ;0,1=14,2=0.000000
L 5.47966594 0.67899626 5.48499931 0.67733002 4 P 0 ;0,1=14,2=0.000000
L 5.48499931 0.67733002 5.49033278 0.67899626 4 P 0 ;0,1=14,2=0.000000
L 5.49033278 0.67899626 5.49433317 0.68316211 4 P 0 ;0,1=14,2=0.000000
L 5.49433317 0.68316211 5.49700039 0.6881625 4 P 0 ;0,1=14,2=0.000000
L 5.49700039 0.6881625 5.499 0.69482933 4 P 0 ;0,1=14,2=0.000000
L 5.499 0.69482933 5.49966654 0.70232923 4 P 0 ;0,1=14,2=0.000000
L 5.49966654 0.70232923 5.499 0.70982913 4 P 0 ;0,1=14,2=0.000000
L 5.499 0.70982913 5.49700039 0.71649744 4 P 0 ;0,1=14,2=0.000000
L 5.49700039 0.71649744 5.49433317 0.72149636 4 P 0 ;0,1=14,2=0.000000
L 5.49433317 0.72149636 5.49033278 0.72566368 4 P 0 ;0,1=14,2=0.000000
L 5.49033278 0.72566368 5.48499931 0.72733002 4 P 0 ;0,1=14,2=0.000000
L 5.53699931 0.67733002 5.53699931 0.72733002 4 P 0 ;0,1=14,2=0.000000
L 5.53699931 0.72733002 5.5289998 0.71733061 4 P 0 ;0,1=14,2=0.000000
L 5.5289998 0.67733002 5.54499882 0.67733002 4 P 0 ;0,1=14,2=0.000000
L 5.57633297 0.67733002 5.57633297 0.72733002 4 P 0 ;0,1=14,2=0.000000
L 5.57633297 0.72733002 5.60166693 0.72733002 4 P 0 ;0,1=14,2=0.000000
L 5.59233317 0.70316388 5.57633297 0.70316388 4 P 0 ;0,1=14,2=0.000000
L 5.62833297 0.67733002 5.62833297 0.72733002 4 P 0 ;0,1=14,2=0.000000
L 5.62833297 0.72733002 5.65366693 0.72733002 4 P 0 ;0,1=14,2=0.000000
L 5.64433317 0.70316388 5.62833297 0.70316388 4 P 0 ;0,1=14,2=0.000000
L 5.6789999 0.68399518 5.68433327 0.67982943 4 P 0 ;0,1=14,2=0.000000
L 5.68433327 0.67982943 5.69033327 0.67733002 4 P 0 ;0,1=14,2=0.000000
L 5.69033327 0.67733002 5.69566663 0.67733002 4 P 0 ;0,1=14,2=0.000000
L 5.69566663 0.67733002 5.7010001 0.67982943 4 P 0 ;0,1=14,2=0.000000
L 5.7010001 0.67982943 5.70500039 0.68399518 4 P 0 ;0,1=14,2=0.000000
L 5.70500039 0.68399518 5.707 0.68983032 4 P 0 ;0,1=14,2=0.000000
L 5.707 0.68983032 5.70566693 0.6956624 4 P 0 ;0,1=14,2=0.000000
L 5.70566693 0.6956624 5.70233317 0.70066289 4 P 0 ;0,1=14,2=0.000000
L 5.70233317 0.70066289 5.69633317 0.70399705 4 P 0 ;0,1=14,2=0.000000
L 5.69633317 0.70399705 5.68833366 0.70566339 4 P 0 ;0,1=14,2=0.000000
L 5.68833366 0.70566339 5.68366673 0.70899596 4 P 0 ;0,1=14,2=0.000000
L 5.68366673 0.70899596 5.68166594 0.71482963 4 P 0 ;0,1=14,2=0.000000
L 5.68166594 0.71482963 5.6830003 0.72066319 4 P 0 ;0,1=14,2=0.000000
L 5.6830003 0.72066319 5.68633287 0.72482894 4 P 0 ;0,1=14,2=0.000000
L 5.68633287 0.72482894 5.6909998 0.72733002 4 P 0 ;0,1=14,2=0.000000
L 5.6909998 0.72733002 5.69566663 0.72733002 4 P 0 ;0,1=14,2=0.000000
L 5.69566663 0.72733002 5.70033356 0.72566368 4 P 0 ;0,1=14,2=0.000000
L 5.70033356 0.72566368 5.70433396 0.72149636 4 P 0 ;0,1=14,2=0.000000
L 5.74499931 0.72733002 5.73966594 0.72566368 4 P 0 ;0,1=14,2=0.000000
L 5.73966594 0.72566368 5.73566673 0.72149636 4 P 0 ;0,1=14,2=0.000000
L 5.73566673 0.72149636 5.73299951 0.71649744 4 P 0 ;0,1=14,2=0.000000
L 5.73299951 0.71649744 5.7309999 0.70982913 4 P 0 ;0,1=14,2=0.000000
L 5.7309999 0.70982913 5.73033337 0.70232923 4 P 0 ;0,1=14,2=0.000000
L 5.73033337 0.70232923 5.7309999 0.69482933 4 P 0 ;0,1=14,2=0.000000
L 5.7309999 0.69482933 5.73299951 0.6881625 4 P 0 ;0,1=14,2=0.000000
L 5.73299951 0.6881625 5.73566673 0.68316211 4 P 0 ;0,1=14,2=0.000000
L 5.73566673 0.68316211 5.73966594 0.67899626 4 P 0 ;0,1=14,2=0.000000
L 5.73966594 0.67899626 5.74499931 0.67733002 4 P 0 ;0,1=14,2=0.000000
L 5.74499931 0.67733002 5.75033278 0.67899626 4 P 0 ;0,1=14,2=0.000000
L 5.75033278 0.67899626 5.75433317 0.68316211 4 P 0 ;0,1=14,2=0.000000
L 5.75433317 0.68316211 5.75700039 0.6881625 4 P 0 ;0,1=14,2=0.000000
L 5.75700039 0.6881625 5.759 0.69482933 4 P 0 ;0,1=14,2=0.000000
L 5.759 0.69482933 5.75966654 0.70232923 4 P 0 ;0,1=14,2=0.000000
L 5.75966654 0.70232923 5.759 0.70982913 4 P 0 ;0,1=14,2=0.000000
L 5.759 0.70982913 5.75700039 0.71649744 4 P 0 ;0,1=14,2=0.000000
L 5.75700039 0.71649744 5.75433317 0.72149636 4 P 0 ;0,1=14,2=0.000000
L 5.75433317 0.72149636 5.75033278 0.72566368 4 P 0 ;0,1=14,2=0.000000
L 5.75033278 0.72566368 5.74499931 0.72733002 4 P 0 ;0,1=14,2=0.000000
L 5.79699931 0.72733002 5.79166594 0.72566368 4 P 0 ;0,1=14,2=0.000000
L 5.79166594 0.72566368 5.78766673 0.72149636 4 P 0 ;0,1=14,2=0.000000
L 5.78766673 0.72149636 5.78499951 0.71649744 4 P 0 ;0,1=14,2=0.000000
L 5.78499951 0.71649744 5.7829999 0.70982913 4 P 0 ;0,1=14,2=0.000000
L 5.7829999 0.70982913 5.78233337 0.70232923 4 P 0 ;0,1=14,2=0.000000
L 5.78233337 0.70232923 5.7829999 0.69482933 4 P 0 ;0,1=14,2=0.000000
L 5.7829999 0.69482933 5.78499951 0.6881625 4 P 0 ;0,1=14,2=0.000000
L 5.78499951 0.6881625 5.78766673 0.68316211 4 P 0 ;0,1=14,2=0.000000
L 5.78766673 0.68316211 5.79166594 0.67899626 4 P 0 ;0,1=14,2=0.000000
L 5.79166594 0.67899626 5.79699931 0.67733002 4 P 0 ;0,1=14,2=0.000000
L 5.79699931 0.67733002 5.80233278 0.67899626 4 P 0 ;0,1=14,2=0.000000
L 5.80233278 0.67899626 5.80633317 0.68316211 4 P 0 ;0,1=14,2=0.000000
L 5.80633317 0.68316211 5.80900039 0.6881625 4 P 0 ;0,1=14,2=0.000000
L 5.80900039 0.6881625 5.811 0.69482933 4 P 0 ;0,1=14,2=0.000000
L 5.811 0.69482933 5.81166654 0.70232923 4 P 0 ;0,1=14,2=0.000000
L 5.81166654 0.70232923 5.811 0.70982913 4 P 0 ;0,1=14,2=0.000000
L 5.811 0.70982913 5.80900039 0.71649744 4 P 0 ;0,1=14,2=0.000000
L 5.80900039 0.71649744 5.80633317 0.72149636 4 P 0 ;0,1=14,2=0.000000
L 5.80633317 0.72149636 5.80233278 0.72566368 4 P 0 ;0,1=14,2=0.000000
L 5.80233278 0.72566368 5.79699931 0.72733002 4 P 0 ;0,1=14,2=0.000000
L 5.84033327 0.69399616 5.85766663 0.69399616 4 P 0 ;0,1=14,2=0.000000
L 5.90099931 0.72733002 5.89566594 0.72566368 4 P 0 ;0,1=14,2=0.000000
L 5.89566594 0.72566368 5.89166673 0.72149636 4 P 0 ;0,1=14,2=0.000000
L 5.89166673 0.72149636 5.88899951 0.71649744 4 P 0 ;0,1=14,2=0.000000
L 5.88899951 0.71649744 5.8869999 0.70982913 4 P 0 ;0,1=14,2=0.000000
L 5.8869999 0.70982913 5.88633337 0.70232923 4 P 0 ;0,1=14,2=0.000000
L 5.88633337 0.70232923 5.8869999 0.69482933 4 P 0 ;0,1=14,2=0.000000
L 5.8869999 0.69482933 5.88899951 0.6881625 4 P 0 ;0,1=14,2=0.000000
L 5.88899951 0.6881625 5.89166673 0.68316211 4 P 0 ;0,1=14,2=0.000000
L 5.89166673 0.68316211 5.89566594 0.67899626 4 P 0 ;0,1=14,2=0.000000
L 5.89566594 0.67899626 5.90099931 0.67733002 4 P 0 ;0,1=14,2=0.000000
L 5.90099931 0.67733002 5.90633278 0.67899626 4 P 0 ;0,1=14,2=0.000000
L 5.90633278 0.67899626 5.91033317 0.68316211 4 P 0 ;0,1=14,2=0.000000
L 5.91033317 0.68316211 5.91300039 0.6881625 4 P 0 ;0,1=14,2=0.000000
L 5.91300039 0.6881625 5.915 0.69482933 4 P 0 ;0,1=14,2=0.000000
L 5.915 0.69482933 5.91566654 0.70232923 4 P 0 ;0,1=14,2=0.000000
L 5.91566654 0.70232923 5.915 0.70982913 4 P 0 ;0,1=14,2=0.000000
L 5.915 0.70982913 5.91300039 0.71649744 4 P 0 ;0,1=14,2=0.000000
L 5.91300039 0.71649744 5.91033317 0.72149636 4 P 0 ;0,1=14,2=0.000000
L 5.91033317 0.72149636 5.90633278 0.72566368 4 P 0 ;0,1=14,2=0.000000
L 5.90633278 0.72566368 5.90099931 0.72733002 4 P 0 ;0,1=14,2=0.000000
L 5.95299931 0.72733002 5.94766594 0.72566368 4 P 0 ;0,1=14,2=0.000000
L 5.94766594 0.72566368 5.94366673 0.72149636 4 P 0 ;0,1=14,2=0.000000
L 5.94366673 0.72149636 5.94099951 0.71649744 4 P 0 ;0,1=14,2=0.000000
L 5.94099951 0.71649744 5.9389999 0.70982913 4 P 0 ;0,1=14,2=0.000000
L 5.9389999 0.70982913 5.93833337 0.70232923 4 P 0 ;0,1=14,2=0.000000
L 5.93833337 0.70232923 5.9389999 0.69482933 4 P 0 ;0,1=14,2=0.000000
L 5.9389999 0.69482933 5.94099951 0.6881625 4 P 0 ;0,1=14,2=0.000000
L 5.94099951 0.6881625 5.94366673 0.68316211 4 P 0 ;0,1=14,2=0.000000
L 5.94366673 0.68316211 5.94766594 0.67899626 4 P 0 ;0,1=14,2=0.000000
L 5.94766594 0.67899626 5.95299931 0.67733002 4 P 0 ;0,1=14,2=0.000000
L 5.95299931 0.67733002 5.95833278 0.67899626 4 P 0 ;0,1=14,2=0.000000
L 5.95833278 0.67899626 5.96233317 0.68316211 4 P 0 ;0,1=14,2=0.000000
L 5.96233317 0.68316211 5.96500039 0.6881625 4 P 0 ;0,1=14,2=0.000000
L 5.96500039 0.6881625 5.967 0.69482933 4 P 0 ;0,1=14,2=0.000000
L 5.967 0.69482933 5.96766654 0.70232923 4 P 0 ;0,1=14,2=0.000000
L 5.96766654 0.70232923 5.967 0.70982913 4 P 0 ;0,1=14,2=0.000000
L 5.967 0.70982913 5.96500039 0.71649744 4 P 0 ;0,1=14,2=0.000000
L 5.96500039 0.71649744 5.96233317 0.72149636 4 P 0 ;0,1=14,2=0.000000
L 5.96233317 0.72149636 5.95833278 0.72566368 4 P 0 ;0,1=14,2=0.000000
L 5.95833278 0.72566368 5.95299931 0.72733002 4 P 0 ;0,1=14,2=0.000000
L 6.00499931 0.72733002 5.99966594 0.72566368 4 P 0 ;0,1=14,2=0.000000
L 5.99966594 0.72566368 5.99566673 0.72149636 4 P 0 ;0,1=14,2=0.000000
L 5.99566673 0.72149636 5.99299951 0.71649744 4 P 0 ;0,1=14,2=0.000000
L 5.99299951 0.71649744 5.9909999 0.70982913 4 P 0 ;0,1=14,2=0.000000
L 5.9909999 0.70982913 5.99033337 0.70232923 4 P 0 ;0,1=14,2=0.000000
L 5.99033337 0.70232923 5.9909999 0.69482933 4 P 0 ;0,1=14,2=0.000000
L 5.9909999 0.69482933 5.99299951 0.6881625 4 P 0 ;0,1=14,2=0.000000
L 5.99299951 0.6881625 5.99566673 0.68316211 4 P 0 ;0,1=14,2=0.000000
L 5.99566673 0.68316211 5.99966594 0.67899626 4 P 0 ;0,1=14,2=0.000000
L 5.99966594 0.67899626 6.00499931 0.67733002 4 P 0 ;0,1=14,2=0.000000
L 6.00499931 0.67733002 6.01033278 0.67899626 4 P 0 ;0,1=14,2=0.000000
L 6.01033278 0.67899626 6.01433317 0.68316211 4 P 0 ;0,1=14,2=0.000000
L 6.01433317 0.68316211 6.01700039 0.6881625 4 P 0 ;0,1=14,2=0.000000
L 6.01700039 0.6881625 6.019 0.69482933 4 P 0 ;0,1=14,2=0.000000
L 6.019 0.69482933 6.01966654 0.70232923 4 P 0 ;0,1=14,2=0.000000
L 6.01966654 0.70232923 6.019 0.70982913 4 P 0 ;0,1=14,2=0.000000
L 6.019 0.70982913 6.01700039 0.71649744 4 P 0 ;0,1=14,2=0.000000
L 6.01700039 0.71649744 6.01433317 0.72149636 4 P 0 ;0,1=14,2=0.000000
L 6.01433317 0.72149636 6.01033278 0.72566368 4 P 0 ;0,1=14,2=0.000000
L 6.01033278 0.72566368 6.00499931 0.72733002 4 P 0 ;0,1=14,2=0.000000
L 6.04833327 0.69399616 6.06566663 0.69399616 4 P 0 ;0,1=14,2=0.000000
L 6.1129997 0.70232923 6.12633386 0.70232923 4 P 0 ;0,1=14,2=0.000000
L 6.12633386 0.70232923 6.12633386 0.68732933 4 P 0 ;0,1=14,2=0.000000
L 6.12633386 0.68732933 6.12233346 0.68232894 4 P 0 ;0,1=14,2=0.000000
L 6.12233346 0.68232894 6.11766663 0.67899626 4 P 0 ;0,1=14,2=0.000000
L 6.11766663 0.67899626 6.1110001 0.67733002 4 P 0 ;0,1=14,2=0.000000
L 6.1110001 0.67733002 6.10433366 0.67899626 4 P 0 ;0,1=14,2=0.000000
L 6.10433366 0.67899626 6.09966673 0.68232894 4 P 0 ;0,1=14,2=0.000000
L 6.09966673 0.68232894 6.09566644 0.68732933 4 P 0 ;0,1=14,2=0.000000
L 6.09566644 0.68732933 6.09299911 0.69316299 4 P 0 ;0,1=14,2=0.000000
L 6.09299911 0.69316299 6.09166604 0.69982972 4 P 0 ;0,1=14,2=0.000000
L 6.09166604 0.69982972 6.09166604 0.70566339 4 P 0 ;0,1=14,2=0.000000
L 6.09166604 0.70566339 6.09299911 0.7106623 4 P 0 ;0,1=14,2=0.000000
L 6.09299911 0.7106623 6.09566644 0.71649744 4 P 0 ;0,1=14,2=0.000000
L 6.09566644 0.71649744 6.09966673 0.72149636 4 P 0 ;0,1=14,2=0.000000
L 6.09966673 0.72149636 6.10366594 0.72482894 4 P 0 ;0,1=14,2=0.000000
L 6.10366594 0.72482894 6.10899931 0.72733002 4 P 0 ;0,1=14,2=0.000000
L 6.10899931 0.72733002 6.11366624 0.72733002 4 P 0 ;0,1=14,2=0.000000
L 6.11366624 0.72733002 6.11899961 0.72566368 4 P 0 ;0,1=14,2=0.000000
L 6.11899961 0.72566368 6.123 0.72232953 4 P 0 ;0,1=14,2=0.000000
L 5.15666644 0.89233002 5.15666644 0.94233002 4 P 0 ;0,1=15,2=0.000000
L 5.15666644 0.94233002 5.17333317 0.94233002 4 P 0 ;0,1=15,2=0.000000
L 5.17333317 0.94233002 5.17866663 0.93982894 4 P 0 ;0,1=15,2=0.000000
L 5.17866663 0.93982894 5.18200039 0.93649636 4 P 0 ;0,1=15,2=0.000000
L 5.18200039 0.93649636 5.18333346 0.92982963 4 P 0 ;0,1=15,2=0.000000
L 5.18333346 0.92982963 5.18200039 0.9231628 4 P 0 ;0,1=15,2=0.000000
L 5.18200039 0.9231628 5.1780001 0.91899705 4 P 0 ;0,1=15,2=0.000000
L 5.1780001 0.91899705 5.17333317 0.91649606 4 P 0 ;0,1=15,2=0.000000
L 5.17333317 0.91649606 5.15666644 0.91649606 4 P 0 ;0,1=15,2=0.000000
L 5.17333317 0.91649606 5.18333346 0.89233002 4 P 0 ;0,1=15,2=0.000000
L 5.23533346 0.89233002 5.20866644 0.89233002 4 P 0 ;0,1=15,2=0.000000
L 5.20866644 0.89233002 5.20866644 0.94233002 4 P 0 ;0,1=15,2=0.000000
L 5.20866644 0.94233002 5.23533346 0.94233002 4 P 0 ;0,1=15,2=0.000000
L 5.22466663 0.91816388 5.20866644 0.91816388 4 P 0 ;0,1=15,2=0.000000
L 5.25733258 0.94233002 5.27399931 0.89233002 4 P 0 ;0,1=15,2=0.000000
L 5.27399931 0.89233002 5.29066732 0.94233002 4 P 0 ;0,1=15,2=0.000000
L 5.32599931 0.89066378 5.32466634 0.89149695 4 P 0 ;0,1=15,2=0.000000
L 5.32466634 0.89149695 5.32466634 0.89316309 4 P 0 ;0,1=15,2=0.000000
L 5.32466634 0.89316309 5.32599931 0.89399626 4 P 0 ;0,1=15,2=0.000000
L 5.32599931 0.89399626 5.32733356 0.89316309 4 P 0 ;0,1=15,2=0.000000
L 5.32733356 0.89316309 5.32733356 0.89149695 4 P 0 ;0,1=15,2=0.000000
L 5.32733356 0.89149695 5.32599931 0.89066378 4 P 0 ;0,1=15,2=0.000000
L 5.32599931 0.91316191 5.32466634 0.91399656 4 P 0 ;0,1=15,2=0.000000
L 5.32466634 0.91399656 5.32466634 0.91566289 4 P 0 ;0,1=15,2=0.000000
L 5.32466634 0.91566289 5.32599931 0.91649606 4 P 0 ;0,1=15,2=0.000000
L 5.32599931 0.91649606 5.32733356 0.91566289 4 P 0 ;0,1=15,2=0.000000
L 5.32733356 0.91566289 5.32733356 0.91399656 4 P 0 ;0,1=15,2=0.000000
L 5.32733356 0.91399656 5.32599931 0.91316191 4 P 0 ;0,1=15,2=0.000000
L 5.3639999 0.89233002 5.392 0.94233002 4 P 0 ;0,1=15,2=0.000000
L 5.3639999 0.94233002 5.392 0.89233002 4 P 0 ;0,1=15,2=0.000000
L 5.42999931 0.94233002 5.42466594 0.94066368 4 P 0 ;0,1=15,2=0.000000
L 5.42466594 0.94066368 5.42066673 0.93649636 4 P 0 ;0,1=15,2=0.000000
L 5.42066673 0.93649636 5.41799951 0.93149744 4 P 0 ;0,1=15,2=0.000000
L 5.41799951 0.93149744 5.4159999 0.92482913 4 P 0 ;0,1=15,2=0.000000
L 5.4159999 0.92482913 5.41533337 0.91732923 4 P 0 ;0,1=15,2=0.000000
L 5.41533337 0.91732923 5.4159999 0.90982933 4 P 0 ;0,1=15,2=0.000000
L 5.4159999 0.90982933 5.41799951 0.9031625 4 P 0 ;0,1=15,2=0.000000
L 5.41799951 0.9031625 5.42066673 0.89816211 4 P 0 ;0,1=15,2=0.000000
L 5.42066673 0.89816211 5.42466594 0.89399626 4 P 0 ;0,1=15,2=0.000000
L 5.42466594 0.89399626 5.42999931 0.89233002 4 P 0 ;0,1=15,2=0.000000
L 5.42999931 0.89233002 5.43533278 0.89399626 4 P 0 ;0,1=15,2=0.000000
L 5.43533278 0.89399626 5.43933317 0.89816211 4 P 0 ;0,1=15,2=0.000000
L 5.43933317 0.89816211 5.44200039 0.9031625 4 P 0 ;0,1=15,2=0.000000
L 5.44200039 0.9031625 5.444 0.90982933 4 P 0 ;0,1=15,2=0.000000
L 5.444 0.90982933 5.44466654 0.91732923 4 P 0 ;0,1=15,2=0.000000
L 5.44466654 0.91732923 5.444 0.92482913 4 P 0 ;0,1=15,2=0.000000
L 5.444 0.92482913 5.44200039 0.93149744 4 P 0 ;0,1=15,2=0.000000
L 5.44200039 0.93149744 5.43933317 0.93649636 4 P 0 ;0,1=15,2=0.000000
L 5.43933317 0.93649636 5.43533278 0.94066368 4 P 0 ;0,1=15,2=0.000000
L 5.43533278 0.94066368 5.42999931 0.94233002 4 P 0 ;0,1=15,2=0.000000
L 5.48199931 0.94233002 5.47666594 0.94066368 4 P 0 ;0,1=15,2=0.000000
L 5.47666594 0.94066368 5.47266673 0.93649636 4 P 0 ;0,1=15,2=0.000000
L 5.47266673 0.93649636 5.46999951 0.93149744 4 P 0 ;0,1=15,2=0.000000
L 5.46999951 0.93149744 5.4679999 0.92482913 4 P 0 ;0,1=15,2=0.000000
L 5.4679999 0.92482913 5.46733337 0.91732923 4 P 0 ;0,1=15,2=0.000000
L 5.46733337 0.91732923 5.4679999 0.90982933 4 P 0 ;0,1=15,2=0.000000
L 5.4679999 0.90982933 5.46999951 0.9031625 4 P 0 ;0,1=15,2=0.000000
L 5.46999951 0.9031625 5.47266673 0.89816211 4 P 0 ;0,1=15,2=0.000000
L 5.47266673 0.89816211 5.47666594 0.89399626 4 P 0 ;0,1=15,2=0.000000
L 5.47666594 0.89399626 5.48199931 0.89233002 4 P 0 ;0,1=15,2=0.000000
L 5.48199931 0.89233002 5.48733278 0.89399626 4 P 0 ;0,1=15,2=0.000000
L 5.48733278 0.89399626 5.49133317 0.89816211 4 P 0 ;0,1=15,2=0.000000
L 5.49133317 0.89816211 5.49400039 0.9031625 4 P 0 ;0,1=15,2=0.000000
L 5.49400039 0.9031625 5.496 0.90982933 4 P 0 ;0,1=15,2=0.000000
L 5.496 0.90982933 5.49666654 0.91732923 4 P 0 ;0,1=15,2=0.000000
L 5.49666654 0.91732923 5.496 0.92482913 4 P 0 ;0,1=15,2=0.000000
L 5.496 0.92482913 5.49400039 0.93149744 4 P 0 ;0,1=15,2=0.000000
L 5.49400039 0.93149744 5.49133317 0.93649636 4 P 0 ;0,1=15,2=0.000000
L 5.49133317 0.93649636 5.48733278 0.94066368 4 P 0 ;0,1=15,2=0.000000
L 5.48733278 0.94066368 5.48199931 0.94233002 4 P 0 ;0,1=15,2=0.000000
L 5.15666604 0.78733002 5.15666604 0.83733002 4 P 0 ;0,1=16,2=0.000000
L 5.15666604 0.83733002 5.17399931 0.79566309 4 P 0 ;0,1=16,2=0.000000
L 5.17399931 0.79566309 5.19133386 0.83733002 4 P 0 ;0,1=16,2=0.000000
L 5.19133386 0.83733002 5.19133386 0.78733002 4 P 0 ;0,1=16,2=0.000000
L 5.20933258 0.78733002 5.22599931 0.83733002 4 P 0 ;0,1=16,2=0.000000
L 5.22599931 0.83733002 5.24266732 0.78733002 4 P 0 ;0,1=16,2=0.000000
L 5.23666614 0.80482933 5.21533248 0.80482933 4 P 0 ;0,1=16,2=0.000000
L 5.26333337 0.78733002 5.26333337 0.83733002 4 P 0 ;0,1=16,2=0.000000
L 5.26333337 0.83733002 5.27666634 0.83733002 4 P 0 ;0,1=16,2=0.000000
L 5.27666634 0.83733002 5.2819997 0.83482894 4 P 0 ;0,1=16,2=0.000000
L 5.2819997 0.83482894 5.2860001 0.83149636 4 P 0 ;0,1=16,2=0.000000
L 5.2860001 0.83149636 5.28933396 0.82649744 4 P 0 ;0,1=16,2=0.000000
L 5.28933396 0.82649744 5.292 0.8206623 4 P 0 ;0,1=16,2=0.000000
L 5.292 0.8206623 5.29266654 0.81232923 4 P 0 ;0,1=16,2=0.000000
L 5.29266654 0.81232923 5.292 0.80399616 4 P 0 ;0,1=16,2=0.000000
L 5.292 0.80399616 5.28933396 0.7981625 4 P 0 ;0,1=16,2=0.000000
L 5.28933396 0.7981625 5.2860001 0.79316211 4 P 0 ;0,1=16,2=0.000000
L 5.2860001 0.79316211 5.2819997 0.78982943 4 P 0 ;0,1=16,2=0.000000
L 5.2819997 0.78982943 5.27666634 0.78733002 4 P 0 ;0,1=16,2=0.000000
L 5.27666634 0.78733002 5.26333337 0.78733002 4 P 0 ;0,1=16,2=0.000000
L 5.34333346 0.78733002 5.31666644 0.78733002 4 P 0 ;0,1=16,2=0.000000
L 5.31666644 0.78733002 5.31666644 0.83733002 4 P 0 ;0,1=16,2=0.000000
L 5.31666644 0.83733002 5.34333346 0.83733002 4 P 0 ;0,1=16,2=0.000000
L 5.33266663 0.81316388 5.31666644 0.81316388 4 P 0 ;0,1=16,2=0.000000
L 5.4259998 0.83733002 5.44199882 0.83733002 4 P 0 ;0,1=16,2=0.000000
L 5.43399931 0.83733002 5.43399931 0.78733002 4 P 0 ;0,1=16,2=0.000000
L 5.4259998 0.78733002 5.44199882 0.78733002 4 P 0 ;0,1=16,2=0.000000
L 5.47066683 0.78733002 5.47066683 0.83733002 4 P 0 ;0,1=16,2=0.000000
L 5.47066683 0.83733002 5.50133307 0.78733002 4 P 0 ;0,1=16,2=0.000000
L 5.50133307 0.78733002 5.50133307 0.83733002 4 P 0 ;0,1=16,2=0.000000
L 5.57 0.77066388 5.61 0.77066388 4 P 0 ;0,1=16,2=0.000000
L 5.622 0.77066388 5.662 0.77066388 4 P 0 ;0,1=16,2=0.000000
L 5.674 0.77066388 5.714 0.77066388 4 P 0 ;0,1=16,2=0.000000
L 5.726 0.77066388 5.766 0.77066388 4 P 0 ;0,1=16,2=0.000000
L 5.778 0.77066388 5.818 0.77066388 4 P 0 ;0,1=16,2=0.000000
A 7.36693002 5.7874 7.36693002 5.7874 7.17716998 5.7874 3 P 0 N
A 7.40433996 5.7874 7.40433996 5.7874 7.17716998 5.7874 3 P 0 N
L 7.3784499 5.925 7.3784499 5.957 2 P 0 ;0,1=17,2=0.000000
L 7.39455 5.957 7.39455 5.925 2 P 0 ;0,1=17,2=0.000000
L 7.39455 5.94099951 7.3784499 5.94099951 2 P 0 ;0,1=17,2=0.000000
L 7.41749961 5.925 7.41749961 5.957 2 P 0 ;0,1=17,2=0.000000
L 7.41749961 5.957 7.4128999 5.9506003 2 P 0 ;0,1=17,2=0.000000
L 7.4128999 5.925 7.42209931 5.925 2 P 0 ;0,1=17,2=0.000000
L 7.44849961 5.925 7.44849961 5.957 2 P 0 ;0,1=17,2=0.000000
L 7.44849961 5.957 7.4438999 5.9506003 2 P 0 ;0,1=17,2=0.000000
L 7.4438999 5.925 7.45309931 5.925 2 P 0 ;0,1=17,2=0.000000
A 7.36693002 0.23621998 7.36693002 0.23621998 7.17716998 0.23621998 3 P 0 N
A 7.40433996 0.23621998 7.40433996 0.23621998 7.17716998 0.23621998 3 P 0 N
L 6.8934499 0.065 6.8934499 0.097 2 P 0 ;0,1=18,2=0.000000
L 6.90955 0.097 6.90955 0.065 2 P 0 ;0,1=18,2=0.000000
L 6.90955 0.08099951 6.8934499 0.08099951 2 P 0 ;0,1=18,2=0.000000
L 6.93249961 0.065 6.93249961 0.097 2 P 0 ;0,1=18,2=0.000000
L 6.93249961 0.097 6.9278999 0.0906003 2 P 0 ;0,1=18,2=0.000000
L 6.9278999 0.065 6.93709931 0.065 2 P 0 ;0,1=18,2=0.000000
L 6.9681 0.065 6.9681 0.097 2 P 0 ;0,1=18,2=0.000000
L 6.9681 0.097 6.95391624 0.07406663 2 P 0 ;0,1=18,2=0.000000
L 6.95391624 0.07406663 6.97308366 0.07406663 2 P 0 ;0,1=18,2=0.000000
A 0.39213996 0.68898002 0.39213996 0.68898002 0.22245 0.68898002 3 P 0 N
A 0.42993002 0.68898002 0.42993002 0.68898002 0.22245 0.68898002 3 P 0 N
L 0.4434499 0.68 0.4434499 0.712 2 P 0 ;0,1=19,2=0.000000
L 0.45955 0.712 0.45955 0.68 2 P 0 ;0,1=19,2=0.000000
L 0.45955 0.69599951 0.4434499 0.69599951 2 P 0 ;0,1=19,2=0.000000
L 0.48249961 0.68 0.48249961 0.712 2 P 0 ;0,1=19,2=0.000000
L 0.48249961 0.712 0.4778999 0.7056003 2 P 0 ;0,1=19,2=0.000000
L 0.4778999 0.68 0.48709931 0.68 2 P 0 ;0,1=19,2=0.000000
L 0.51349961 0.712 0.51043287 0.71093346 2 P 0 ;0,1=19,2=0.000000
L 0.51043287 0.71093346 0.50813337 0.70826644 2 P 0 ;0,1=19,2=0.000000
L 0.50813337 0.70826644 0.5065997 0.70506713 2 P 0 ;0,1=19,2=0.000000
L 0.5065997 0.70506713 0.5054499 0.70079941 2 P 0 ;0,1=19,2=0.000000
L 0.5054499 0.70079941 0.50506663 0.69599951 2 P 0 ;0,1=19,2=0.000000
L 0.50506663 0.69599951 0.5054499 0.69119951 2 P 0 ;0,1=19,2=0.000000
L 0.5054499 0.69119951 0.5065997 0.68693278 2 P 0 ;0,1=19,2=0.000000
L 0.5065997 0.68693278 0.50813337 0.68373248 2 P 0 ;0,1=19,2=0.000000
L 0.50813337 0.68373248 0.51043287 0.68106644 2 P 0 ;0,1=19,2=0.000000
L 0.51043287 0.68106644 0.51349961 0.68 2 P 0 ;0,1=19,2=0.000000
L 0.51349961 0.68 0.51656634 0.68106644 2 P 0 ;0,1=19,2=0.000000
L 0.51656634 0.68106644 0.51886654 0.68373248 2 P 0 ;0,1=19,2=0.000000
L 0.51886654 0.68373248 0.5204002 0.68693278 2 P 0 ;0,1=19,2=0.000000
L 0.5204002 0.68693278 0.52155 0.69119951 2 P 0 ;0,1=19,2=0.000000
L 0.52155 0.69119951 0.52193327 0.69599951 2 P 0 ;0,1=19,2=0.000000
L 0.52193327 0.69599951 0.52155 0.70079941 2 P 0 ;0,1=19,2=0.000000
L 0.52155 0.70079941 0.5204002 0.70506713 2 P 0 ;0,1=19,2=0.000000
L 0.5204002 0.70506713 0.51886654 0.70826644 2 P 0 ;0,1=19,2=0.000000
L 0.51886654 0.70826644 0.51656634 0.71093346 2 P 0 ;0,1=19,2=0.000000
L 0.51656634 0.71093346 0.51349961 0.712 2 P 0 ;0,1=19,2=0.000000
A 0.39213996 5.11811004 0.39213996 5.11811004 0.22245 5.11811004 3 P 0 N
A 0.42993002 5.11811004 0.42993002 5.11811004 0.22245 5.11811004 3 P 0 N
L 0.4534499 5.12 0.4534499 5.152 2 P 0 ;0,1=20,2=0.000000
L 0.46955 5.152 0.46955 5.12 2 P 0 ;0,1=20,2=0.000000
L 0.46955 5.13599951 0.4534499 5.13599951 2 P 0 ;0,1=20,2=0.000000
L 0.49249961 5.12 0.49249961 5.152 2 P 0 ;0,1=20,2=0.000000
L 0.49249961 5.152 0.4878999 5.1456003 2 P 0 ;0,1=20,2=0.000000
L 0.4878999 5.12 0.49709931 5.12 2 P 0 ;0,1=20,2=0.000000
L 0.51506663 5.12639961 0.51736614 5.12266604 2 P 0 ;0,1=20,2=0.000000
L 0.51736614 5.12266604 0.52043287 5.12053317 2 P 0 ;0,1=20,2=0.000000
L 0.52043287 5.12053317 0.52388356 5.12 2 P 0 ;0,1=20,2=0.000000
L 0.52388356 5.12 0.5269503 5.12053317 2 P 0 ;0,1=20,2=0.000000
L 0.5269503 5.12053317 0.53001703 5.12319931 2 P 0 ;0,1=20,2=0.000000
L 0.53001703 5.12319931 0.53193327 5.12639961 2 P 0 ;0,1=20,2=0.000000
L 0.53193327 5.12639961 0.53231654 5.1295999 2 P 0 ;0,1=20,2=0.000000
L 0.53231654 5.1295999 0.53155 5.13333238 2 P 0 ;0,1=20,2=0.000000
L 0.53155 5.13333238 0.52886654 5.13599951 2 P 0 ;0,1=20,2=0.000000
L 0.52886654 5.13599951 0.52618307 5.13706683 2 P 0 ;0,1=20,2=0.000000
L 0.52618307 5.13706683 0.52273307 5.13706683 2 P 0 ;0,1=20,2=0.000000
L 0.52618307 5.13706683 0.52848327 5.13866654 2 P 0 ;0,1=20,2=0.000000
L 0.52848327 5.13866654 0.5304002 5.14133268 2 P 0 ;0,1=20,2=0.000000
L 0.5304002 5.14133268 0.53116673 5.14453297 2 P 0 ;0,1=20,2=0.000000
L 0.53116673 5.14453297 0.5304002 5.14773327 2 P 0 ;0,1=20,2=0.000000
L 0.5304002 5.14773327 0.52848327 5.15039931 2 P 0 ;0,1=20,2=0.000000
L 0.52848327 5.15039931 0.52503327 5.152 2 P 0 ;0,1=20,2=0.000000
L 0.52503327 5.152 0.52158337 5.15146673 2 P 0 ;0,1=20,2=0.000000
L 0.52158337 5.15146673 0.51813337 5.14933287 2 P 0 ;0,1=20,2=0.000000
A 12.85671004 5.15748002 12.85671004 5.15748002 12.68701998 5.15748002 3 P 0 N
A 12.8945 5.15748002 12.8945 5.15748002 12.68701998 5.15748002 3 P 0 N
L 12.3684499 5.15 12.3684499 5.182 2 P 0 ;0,1=21,2=0.000000
L 12.38455 5.182 12.38455 5.15 2 P 0 ;0,1=21,2=0.000000
L 12.38455 5.16599951 12.3684499 5.16599951 2 P 0 ;0,1=21,2=0.000000
L 12.40749961 5.15 12.40749961 5.182 2 P 0 ;0,1=21,2=0.000000
L 12.40749961 5.182 12.4028999 5.1756003 2 P 0 ;0,1=21,2=0.000000
L 12.4028999 5.15 12.41209931 5.15 2 P 0 ;0,1=21,2=0.000000
L 12.43006663 5.15479892 12.43236614 5.15213287 2 P 0 ;0,1=21,2=0.000000
L 12.43236614 5.15213287 12.43504961 5.15053317 2 P 0 ;0,1=21,2=0.000000
L 12.43504961 5.15053317 12.43849961 5.15 2 P 0 ;0,1=21,2=0.000000
L 12.43849961 5.15 12.4419503 5.15106644 2 P 0 ;0,1=21,2=0.000000
L 12.4419503 5.15106644 12.44463307 5.15319931 2 P 0 ;0,1=21,2=0.000000
L 12.44463307 5.15319931 12.44655 5.15693278 2 P 0 ;0,1=21,2=0.000000
L 12.44655 5.15693278 12.44693327 5.16119951 2 P 0 ;0,1=21,2=0.000000
L 12.44693327 5.16119951 12.44616673 5.16546624 2 P 0 ;0,1=21,2=0.000000
L 12.44616673 5.16546624 12.4442498 5.16813327 2 P 0 ;0,1=21,2=0.000000
L 12.4442498 5.16813327 12.44156634 5.17026624 2 P 0 ;0,1=21,2=0.000000
L 12.44156634 5.17026624 12.43888356 5.17079941 2 P 0 ;0,1=21,2=0.000000
L 12.43888356 5.17079941 12.4362001 5.17026624 2 P 0 ;0,1=21,2=0.000000
L 12.4362001 5.17026624 12.4327501 5.16813327 2 P 0 ;0,1=21,2=0.000000
L 12.4327501 5.16813327 12.4338999 5.182 2 P 0 ;0,1=21,2=0.000000
L 12.4338999 5.182 12.4442498 5.182 2 P 0 ;0,1=21,2=0.000000
A 12.85671004 0.72835 12.85671004 0.72835 12.68701998 0.72835 3 P 0 N
A 12.8945 0.72835 12.8945 0.72835 12.68701998 0.72835 3 P 0 N
L 12.3734499 0.735 12.3734499 0.767 2 P 0 ;0,1=22,2=0.000000
L 12.38955 0.767 12.38955 0.735 2 P 0 ;0,1=22,2=0.000000
L 12.38955 0.75099951 12.3734499 0.75099951 2 P 0 ;0,1=22,2=0.000000
L 12.41249961 0.735 12.41249961 0.767 2 P 0 ;0,1=22,2=0.000000
L 12.41249961 0.767 12.4078999 0.7606003 2 P 0 ;0,1=22,2=0.000000
L 12.4078999 0.735 12.41709931 0.735 2 P 0 ;0,1=22,2=0.000000
L 12.43621644 0.74833238 12.4388999 0.75206683 2 P 0 ;0,1=22,2=0.000000
L 12.4388999 0.75206683 12.4412001 0.7541998 2 P 0 ;0,1=22,2=0.000000
L 12.4412001 0.7541998 12.44426683 0.75526624 2 P 0 ;0,1=22,2=0.000000
L 12.44426683 0.75526624 12.4469503 0.7541998 2 P 0 ;0,1=22,2=0.000000
L 12.4469503 0.7541998 12.44886654 0.75206683 2 P 0 ;0,1=22,2=0.000000
L 12.44886654 0.75206683 12.4504002 0.74886663 2 P 0 ;0,1=22,2=0.000000
L 12.4504002 0.74886663 12.45078346 0.74513307 2 P 0 ;0,1=22,2=0.000000
L 12.45078346 0.74513307 12.4504002 0.74193278 2 P 0 ;0,1=22,2=0.000000
L 12.4504002 0.74193278 12.44886654 0.73873248 2 P 0 ;0,1=22,2=0.000000
L 12.44886654 0.73873248 12.44656634 0.73606644 2 P 0 ;0,1=22,2=0.000000
L 12.44656634 0.73606644 12.44388356 0.735 2 P 0 ;0,1=22,2=0.000000
L 12.44388356 0.735 12.44081683 0.73606644 2 P 0 ;0,1=22,2=0.000000
L 12.44081683 0.73606644 12.43813337 0.73926575 2 P 0 ;0,1=22,2=0.000000
L 12.43813337 0.73926575 12.4365997 0.74406663 2 P 0 ;0,1=22,2=0.000000
L 12.4365997 0.74406663 12.43621644 0.7493998 2 P 0 ;0,1=22,2=0.000000
L 12.43621644 0.7493998 12.43698287 0.75633268 2 P 0 ;0,1=22,2=0.000000
L 12.43698287 0.75633268 12.43813337 0.76006713 2 P 0 ;0,1=22,2=0.000000
L 12.43813337 0.76006713 12.44004961 0.7637997 2 P 0 ;0,1=22,2=0.000000
L 12.44004961 0.7637997 12.44273307 0.76646673 2 P 0 ;0,1=22,2=0.000000
L 12.44273307 0.76646673 12.44541654 0.767 2 P 0 ;0,1=22,2=0.000000
L 12.44541654 0.767 12.4481 0.76593346 2 P 0 ;0,1=22,2=0.000000
L 12.4481 0.76593346 12.45001703 0.76326644 2 P 0 ;0,1=22,2=0.000000
A 6.32558996 1.52756004 6.32558996 1.52756004 6.11811004 1.52756004 3 P 0 N
A 6.28818996 1.52756004 6.28818996 1.52756004 6.11811004 1.52756004 3 P 0 N
A 5.00275 1.50786998 5.00275 1.50786998 4.83268002 1.50786998 3 P 0 N
A 5.04016004 1.50786998 5.04016004 1.50786998 4.83268002 1.50786998 3 P 0 N
A 2.45355 1.50786998 2.45355 1.50786998 2.24606004 1.50786998 3 P 0 N
A 2.41615 1.50786998 2.41615 1.50786998 2.24606004 1.50786998 3 P 0 N
A 1.16811004 1.52756004 1.16811004 1.52756004 0.96063002 1.52756004 3 P 0 N
A 1.13071004 1.52756004 1.13071004 1.52756004 0.96063002 1.52756004 3 P 0 N
A 1.16811004 4.20473002 1.16811004 4.20473002 0.96063002 4.20473002 3 P 0 N
A 1.13071004 4.20473002 1.13071004 4.20473002 0.96063002 4.20473002 3 P 0 N
A 2.45353996 4.22441004 2.45353996 4.22441004 2.24606004 4.22441004 3 P 0 N
A 2.41615 4.22441004 2.41615 4.22441004 2.24606004 4.22441004 3 P 0 N
A 5.04016004 4.22441004 5.04016004 4.22441004 4.83268002 4.22441004 3 P 0 N
A 5.00275 4.22441004 5.00275 4.22441004 4.83268002 4.22441004 3 P 0 N
A 6.32558996 4.20473002 6.32558996 4.20473002 6.11811004 4.20473002 3 P 0 N
A 6.28818996 4.20473002 6.28818996 4.20473002 6.11811004 4.20473002 3 P 0 N
A 6.13603996 2.58268002 6.13603996 2.58268002 6.04921004 2.58268002 3 P 0 N
A 1.08858002 2.67251004 1.17841506 2.58268002 1.08858494 2.58268002 3 P 0 Y
A 1.17841506 2.58268002 1.08858002 2.49283996 1.08858002 2.582675 3 P 0 Y
L 1.08858002 2.49283996 1.02953002 2.49283996 3 P 0 
A 1.02953002 2.49283996 0.93969498 2.58268002 1.02953002 2.582675 3 P 0 Y
A 0.93969498 2.58268002 1.02953002 2.67251004 1.029525 2.58268002 3 P 0 Y
L 1.02953002 2.67251004 1.08858002 2.67251004 3 P 0 
L 4.42795 2.04646004 4.16653996 2.04646004 3 P 0 
L 4.16653996 2.04646004 4.16653996 3.68583002 3 P 0 
L 4.16653996 3.68583002 4.42795 3.68583002 3 P 0 
L 4.42795 3.68583002 4.42795 2.04646004 3 P 0 
L 4.45471998 3.7126 4.13976004 3.7126 3 P 0 
L 4.13976004 3.7126 4.13976004 2.01968996 3 P 0 
L 4.13976004 2.01968996 4.45471998 2.01968996 3 P 0 
L 4.45471998 2.01968996 4.45471998 3.7126 3 P 0 
L 2.93898002 3.7126 2.62401998 3.7126 3 P 0 
L 2.62401998 3.7126 2.62401998 2.01968996 3 P 0 
L 2.62401998 2.01968996 2.93898002 2.01968996 3 P 0 
L 2.93898002 2.01968996 2.93898002 3.7126 3 P 0 
L 2.9122 2.04646004 2.65078996 2.04646004 3 P 0 
L 2.65078996 2.04646004 2.65078996 3.68583002 3 P 0 
L 2.65078996 3.68583002 2.9122 3.68583002 3 P 0 
L 2.9122 3.68583002 2.9122 2.04646004 3 P 0 
L 6.0495999 1.25749961 6.05493346 1.25749961 2 P 0 ;0,1=23,2=0.000000
L 6.05493346 1.25749961 6.05493346 1.24999961 2 P 0 ;0,1=23,2=0.000000
L 6.05493346 1.24999961 6.05333337 1.24749941 2 P 0 ;0,1=23,2=0.000000
L 6.05333337 1.24749941 6.05146663 1.24583307 2 P 0 ;0,1=23,2=0.000000
L 6.05146663 1.24583307 6.0488 1.245 2 P 0 ;0,1=23,2=0.000000
L 6.0488 1.245 6.04613346 1.24583307 2 P 0 ;0,1=23,2=0.000000
L 6.04613346 1.24583307 6.04426663 1.24749941 2 P 0 ;0,1=23,2=0.000000
L 6.04426663 1.24749941 6.04266654 1.24999961 2 P 0 ;0,1=23,2=0.000000
L 6.04266654 1.24999961 6.04159961 1.25291644 2 P 0 ;0,1=23,2=0.000000
L 6.04159961 1.25291644 6.04106644 1.2562498 2 P 0 ;0,1=23,2=0.000000
L 6.04106644 1.2562498 6.04106644 1.25916663 2 P 0 ;0,1=23,2=0.000000
L 6.04106644 1.25916663 6.04159961 1.26166614 2 P 0 ;0,1=23,2=0.000000
L 6.04159961 1.26166614 6.04266654 1.26458366 2 P 0 ;0,1=23,2=0.000000
L 6.04266654 1.26458366 6.04426663 1.26708317 2 P 0 ;0,1=23,2=0.000000
L 6.04426663 1.26708317 6.04586634 1.26874941 2 P 0 ;0,1=23,2=0.000000
L 6.04586634 1.26874941 6.0479997 1.27 2 P 0 ;0,1=23,2=0.000000
L 6.0479997 1.27 6.04986644 1.27 2 P 0 ;0,1=23,2=0.000000
L 6.04986644 1.27 6.0519998 1.26916683 2 P 0 ;0,1=23,2=0.000000
L 6.0519998 1.26916683 6.0536 1.2674997 2 P 0 ;0,1=23,2=0.000000
L 6.06666654 1.245 6.06666654 1.27 2 P 0 ;0,1=23,2=0.000000
L 6.06666654 1.27 6.07306663 1.27 2 P 0 ;0,1=23,2=0.000000
L 6.07306663 1.27 6.0752 1.26874941 2 P 0 ;0,1=23,2=0.000000
L 6.0752 1.26874941 6.0768001 1.26583337 2 P 0 ;0,1=23,2=0.000000
L 6.0768001 1.26583337 6.07733337 1.2625 2 P 0 ;0,1=23,2=0.000000
L 6.07733337 1.2625 6.0768001 1.25916663 2 P 0 ;0,1=23,2=0.000000
L 6.0768001 1.25916663 6.07546663 1.25666644 2 P 0 ;0,1=23,2=0.000000
L 6.07546663 1.25666644 6.07306663 1.25541594 2 P 0 ;0,1=23,2=0.000000
L 6.07306663 1.25541594 6.06666654 1.25541594 2 P 0 ;0,1=23,2=0.000000
L 6.09013327 1.27 6.09013327 1.25208327 2 P 0 ;0,1=23,2=0.000000
L 6.09013327 1.25208327 6.0911998 1.24833258 2 P 0 ;0,1=23,2=0.000000
L 6.0911998 1.24833258 6.09333317 1.24583307 2 P 0 ;0,1=23,2=0.000000
L 6.09333317 1.24583307 6.0959997 1.245 2 P 0 ;0,1=23,2=0.000000
L 6.0959997 1.245 6.09866673 1.24583307 2 P 0 ;0,1=23,2=0.000000
L 6.09866673 1.24583307 6.1008001 1.24833258 2 P 0 ;0,1=23,2=0.000000
L 6.1008001 1.24833258 6.10186663 1.25208327 2 P 0 ;0,1=23,2=0.000000
L 6.10186663 1.25208327 6.10186663 1.27 2 P 0 ;0,1=23,2=0.000000
L 6.1199997 1.27 6.11786634 1.26916683 2 P 0 ;0,1=23,2=0.000000
L 6.11786634 1.26916683 6.11626663 1.26708317 2 P 0 ;0,1=23,2=0.000000
L 6.11626663 1.26708317 6.1151998 1.26458366 2 P 0 ;0,1=23,2=0.000000
L 6.1151998 1.26458366 6.1143999 1.26124951 2 P 0 ;0,1=23,2=0.000000
L 6.1143999 1.26124951 6.11413327 1.25749961 2 P 0 ;0,1=23,2=0.000000
L 6.11413327 1.25749961 6.1143999 1.25374961 2 P 0 ;0,1=23,2=0.000000
L 6.1143999 1.25374961 6.1151998 1.25041624 2 P 0 ;0,1=23,2=0.000000
L 6.1151998 1.25041624 6.11626663 1.24791604 2 P 0 ;0,1=23,2=0.000000
L 6.11626663 1.24791604 6.11786634 1.24583307 2 P 0 ;0,1=23,2=0.000000
L 6.11786634 1.24583307 6.1199997 1.245 2 P 0 ;0,1=23,2=0.000000
L 6.1199997 1.245 6.12213307 1.24583307 2 P 0 ;0,1=23,2=0.000000
L 6.12213307 1.24583307 6.12373327 1.24791604 2 P 0 ;0,1=23,2=0.000000
L 6.12373327 1.24791604 6.1248001 1.25041624 2 P 0 ;0,1=23,2=0.000000
L 6.1248001 1.25041624 6.1256 1.25374961 2 P 0 ;0,1=23,2=0.000000
L 6.1256 1.25374961 6.12586663 1.25749961 2 P 0 ;0,1=23,2=0.000000
L 6.12586663 1.25749961 6.1256 1.26124951 2 P 0 ;0,1=23,2=0.000000
L 6.1256 1.26124951 6.1248001 1.26458366 2 P 0 ;0,1=23,2=0.000000
L 6.1248001 1.26458366 6.12373327 1.26708317 2 P 0 ;0,1=23,2=0.000000
L 6.12373327 1.26708317 6.12213307 1.26916683 2 P 0 ;0,1=23,2=0.000000
L 6.12213307 1.26916683 6.1199997 1.27 2 P 0 ;0,1=23,2=0.000000
L 6.136 1.23666693 6.152 1.23666693 2 P 0 ;0,1=23,2=0.000000
L 6.1623999 1.245 6.1623999 1.27 2 P 0 ;0,1=23,2=0.000000
L 6.1736 1.27 6.1736 1.245 2 P 0 ;0,1=23,2=0.000000
L 6.1736 1.25749961 6.1623999 1.25749961 2 P 0 ;0,1=23,2=0.000000
L 6.1919997 1.27 6.18986634 1.26916683 2 P 0 ;0,1=23,2=0.000000
L 6.18986634 1.26916683 6.18826663 1.26708317 2 P 0 ;0,1=23,2=0.000000
L 6.18826663 1.26708317 6.1871998 1.26458366 2 P 0 ;0,1=23,2=0.000000
L 6.1871998 1.26458366 6.1863999 1.26124951 2 P 0 ;0,1=23,2=0.000000
L 6.1863999 1.26124951 6.18613327 1.25749961 2 P 0 ;0,1=23,2=0.000000
L 6.18613327 1.25749961 6.1863999 1.25374961 2 P 0 ;0,1=23,2=0.000000
L 6.1863999 1.25374961 6.1871998 1.25041624 2 P 0 ;0,1=23,2=0.000000
L 6.1871998 1.25041624 6.18826663 1.24791604 2 P 0 ;0,1=23,2=0.000000
L 6.18826663 1.24791604 6.18986634 1.24583307 2 P 0 ;0,1=23,2=0.000000
L 6.18986634 1.24583307 6.1919997 1.245 2 P 0 ;0,1=23,2=0.000000
L 6.1919997 1.245 6.19413307 1.24583307 2 P 0 ;0,1=23,2=0.000000
L 6.19413307 1.24583307 6.19573327 1.24791604 2 P 0 ;0,1=23,2=0.000000
L 6.19573327 1.24791604 6.1968001 1.25041624 2 P 0 ;0,1=23,2=0.000000
L 6.1968001 1.25041624 6.1976 1.25374961 2 P 0 ;0,1=23,2=0.000000
L 6.1976 1.25374961 6.19786663 1.25749961 2 P 0 ;0,1=23,2=0.000000
L 6.19786663 1.25749961 6.1976 1.26124951 2 P 0 ;0,1=23,2=0.000000
L 6.1976 1.26124951 6.1968001 1.26458366 2 P 0 ;0,1=23,2=0.000000
L 6.1968001 1.26458366 6.19573327 1.26708317 2 P 0 ;0,1=23,2=0.000000
L 6.19573327 1.26708317 6.19413307 1.26916683 2 P 0 ;0,1=23,2=0.000000
L 6.19413307 1.26916683 6.1919997 1.27 2 P 0 ;0,1=23,2=0.000000
A 12.32953002 1.52756004 12.32953002 1.52756004 12.12205 1.52756004 3 P 0 N
A 12.29213002 1.52756004 12.29213002 1.52756004 12.12205 1.52756004 3 P 0 N
A 11.00668996 1.50786998 11.00668996 1.50786998 10.83661998 1.50786998 3 P 0 N
A 11.0441 1.50786998 11.0441 1.50786998 10.83661998 1.50786998 3 P 0 N
A 8.45748996 1.50786998 8.45748996 1.50786998 8.25 1.50786998 3 P 0 N
A 8.42008996 1.50786998 8.42008996 1.50786998 8.25 1.50786998 3 P 0 N
A 7.17205 1.52756004 7.17205 1.52756004 6.96456998 1.52756004 3 P 0 N
A 7.13465 1.52756004 7.13465 1.52756004 6.96456998 1.52756004 3 P 0 N
A 7.17205 4.20473002 7.17205 4.20473002 6.96456998 4.20473002 3 P 0 N
A 7.13465 4.20473002 7.13465 4.20473002 6.96456998 4.20473002 3 P 0 N
A 8.45748002 4.22441004 8.45748002 4.22441004 8.25 4.22441004 3 P 0 N
A 8.42008996 4.22441004 8.42008996 4.22441004 8.25 4.22441004 3 P 0 N
A 11.0441 4.22441004 11.0441 4.22441004 10.83661998 4.22441004 3 P 0 N
A 11.00668996 4.22441004 11.00668996 4.22441004 10.83661998 4.22441004 3 P 0 N
A 12.32953002 4.20473002 12.32953002 4.20473002 12.12205 4.20473002 3 P 0 N
A 12.29213002 4.20473002 12.29213002 4.20473002 12.12205 4.20473002 3 P 0 N
A 12.13998002 2.58268002 12.13998002 2.58268002 12.05315 2.58268002 3 P 0 N
A 7.09251998 2.67251004 7.18235502 2.58268002 7.0925249 2.58268002 3 P 0 Y
A 7.18235502 2.58268002 7.09251998 2.49283996 7.09251998 2.582675 3 P 0 Y
L 7.09251998 2.49283996 7.03346998 2.49283996 3 P 0 
A 7.03346998 2.49283996 6.94363494 2.58268002 7.03346998 2.582675 3 P 0 Y
A 6.94363494 2.58268002 7.03346998 2.67251004 7.03346496 2.58268002 3 P 0 Y
L 7.03346998 2.67251004 7.09251998 2.67251004 3 P 0 
L 10.43188996 2.04646004 10.17048002 2.04646004 3 P 0 
L 10.17048002 2.04646004 10.17048002 3.68583002 3 P 0 
L 10.17048002 3.68583002 10.43188996 3.68583002 3 P 0 
L 10.43188996 3.68583002 10.43188996 2.04646004 3 P 0 
L 10.45866004 3.7126 10.1437 3.7126 3 P 0 
L 10.1437 3.7126 10.1437 2.01968996 3 P 0 
L 10.1437 2.01968996 10.45866004 2.01968996 3 P 0 
L 10.45866004 2.01968996 10.45866004 3.7126 3 P 0 
L 8.94291998 3.7126 8.62796004 3.7126 3 P 0 
L 8.62796004 3.7126 8.62796004 2.01968996 3 P 0 
L 8.62796004 2.01968996 8.94291998 2.01968996 3 P 0 
L 8.94291998 2.01968996 8.94291998 3.7126 3 P 0 
L 8.91613996 2.04646004 8.65473002 2.04646004 3 P 0 
L 8.65473002 2.04646004 8.65473002 3.68583002 3 P 0 
L 8.65473002 3.68583002 8.91613996 3.68583002 3 P 0 
L 8.91613996 3.68583002 8.91613996 2.04646004 3 P 0 
L 12.0495999 1.27749961 12.05493346 1.27749961 2 P 0 ;0,1=24,2=0.000000
L 12.05493346 1.27749961 12.05493346 1.26999961 2 P 0 ;0,1=24,2=0.000000
L 12.05493346 1.26999961 12.05333337 1.26749941 2 P 0 ;0,1=24,2=0.000000
L 12.05333337 1.26749941 12.05146663 1.26583307 2 P 0 ;0,1=24,2=0.000000
L 12.05146663 1.26583307 12.0488 1.265 2 P 0 ;0,1=24,2=0.000000
L 12.0488 1.265 12.04613346 1.26583307 2 P 0 ;0,1=24,2=0.000000
L 12.04613346 1.26583307 12.04426663 1.26749941 2 P 0 ;0,1=24,2=0.000000
L 12.04426663 1.26749941 12.04266654 1.26999961 2 P 0 ;0,1=24,2=0.000000
L 12.04266654 1.26999961 12.04159961 1.27291644 2 P 0 ;0,1=24,2=0.000000
L 12.04159961 1.27291644 12.04106644 1.2762498 2 P 0 ;0,1=24,2=0.000000
L 12.04106644 1.2762498 12.04106644 1.27916663 2 P 0 ;0,1=24,2=0.000000
L 12.04106644 1.27916663 12.04159961 1.28166614 2 P 0 ;0,1=24,2=0.000000
L 12.04159961 1.28166614 12.04266654 1.28458366 2 P 0 ;0,1=24,2=0.000000
L 12.04266654 1.28458366 12.04426663 1.28708317 2 P 0 ;0,1=24,2=0.000000
L 12.04426663 1.28708317 12.04586634 1.28874941 2 P 0 ;0,1=24,2=0.000000
L 12.04586634 1.28874941 12.0479997 1.29 2 P 0 ;0,1=24,2=0.000000
L 12.0479997 1.29 12.04986644 1.29 2 P 0 ;0,1=24,2=0.000000
L 12.04986644 1.29 12.0519998 1.28916683 2 P 0 ;0,1=24,2=0.000000
L 12.0519998 1.28916683 12.0536 1.2874997 2 P 0 ;0,1=24,2=0.000000
L 12.06666654 1.265 12.06666654 1.29 2 P 0 ;0,1=24,2=0.000000
L 12.06666654 1.29 12.07306663 1.29 2 P 0 ;0,1=24,2=0.000000
L 12.07306663 1.29 12.0752 1.28874941 2 P 0 ;0,1=24,2=0.000000
L 12.0752 1.28874941 12.0768001 1.28583337 2 P 0 ;0,1=24,2=0.000000
L 12.0768001 1.28583337 12.07733337 1.2825 2 P 0 ;0,1=24,2=0.000000
L 12.07733337 1.2825 12.0768001 1.27916663 2 P 0 ;0,1=24,2=0.000000
L 12.0768001 1.27916663 12.07546663 1.27666644 2 P 0 ;0,1=24,2=0.000000
L 12.07546663 1.27666644 12.07306663 1.27541594 2 P 0 ;0,1=24,2=0.000000
L 12.07306663 1.27541594 12.06666654 1.27541594 2 P 0 ;0,1=24,2=0.000000
L 12.09013327 1.29 12.09013327 1.27208327 2 P 0 ;0,1=24,2=0.000000
L 12.09013327 1.27208327 12.0911998 1.26833258 2 P 0 ;0,1=24,2=0.000000
L 12.0911998 1.26833258 12.09333317 1.26583307 2 P 0 ;0,1=24,2=0.000000
L 12.09333317 1.26583307 12.0959997 1.265 2 P 0 ;0,1=24,2=0.000000
L 12.0959997 1.265 12.09866673 1.26583307 2 P 0 ;0,1=24,2=0.000000
L 12.09866673 1.26583307 12.1008001 1.26833258 2 P 0 ;0,1=24,2=0.000000
L 12.1008001 1.26833258 12.10186663 1.27208327 2 P 0 ;0,1=24,2=0.000000
L 12.10186663 1.27208327 12.10186663 1.29 2 P 0 ;0,1=24,2=0.000000
L 12.1199997 1.265 12.1199997 1.29 2 P 0 ;0,1=24,2=0.000000
L 12.1199997 1.29 12.1167999 1.2850003 2 P 0 ;0,1=24,2=0.000000
L 12.1167999 1.265 12.12319951 1.265 2 P 0 ;0,1=24,2=0.000000
L 12.136 1.25666693 12.152 1.25666693 2 P 0 ;0,1=24,2=0.000000
L 12.1623999 1.265 12.1623999 1.29 2 P 0 ;0,1=24,2=0.000000
L 12.1736 1.29 12.1736 1.265 2 P 0 ;0,1=24,2=0.000000
L 12.1736 1.27749961 12.1623999 1.27749961 2 P 0 ;0,1=24,2=0.000000
L 12.1919997 1.265 12.1919997 1.29 2 P 0 ;0,1=24,2=0.000000
L 12.1919997 1.29 12.1887999 1.2850003 2 P 0 ;0,1=24,2=0.000000
L 12.1887999 1.265 12.19519951 1.265 2 P 0 ;0,1=24,2=0.000000
L 12.37795 5.62598996 12.37795 5.59448996 3 P 0 
L 12.37795 5.59448996 12.25983996 5.59448996 3 P 0 
L 12.25983996 5.59448996 12.25983996 5.40551004 3 P 0 
L 12.25983996 5.40551004 10.71653996 5.40551004 3 P 0 
L 10.71653996 5.40551004 10.71653996 5.79133996 3 P 0 
L 10.71653996 5.79133996 11.41731998 5.79133996 3 P 0 
L 11.41731998 5.79133996 11.41731998 5.84646004 3 P 0 
L 11.41731998 5.84646004 11.55906004 5.84646004 3 P 0 
L 11.55906004 5.84646004 11.55906004 5.79133996 3 P 0 
L 11.55906004 5.79133996 12.37795 5.79133996 3 P 0 
L 12.37795 5.79133996 12.37795 5.75236004 3 P 0 
L 12.14961004 5.3937 12.18306998 5.3563 3 P 0 
L 12.18306998 5.3563 12.11613996 5.3563 3 P 0 
L 12.11613996 5.3563 12.14961004 5.3937 3 P 0 
L 12.14961004 5.3937 12.17323002 5.36023996 3 P 0 
L 12.17323002 5.36023996 12.12401998 5.36023996 3 P 0 
L 12.12401998 5.36023996 12.14961004 5.38583002 3 P 0 
L 12.14961004 5.38583002 12.16338996 5.36418002 3 P 0 
L 12.16338996 5.36418002 12.13386004 5.36418002 3 P 0 
L 12.13386004 5.36418002 12.14961004 5.37795 3 P 0 
L 12.14961004 5.37795 12.15551004 5.37008002 3 P 0 
L 12.15551004 5.37008002 12.14763996 5.37205 3 P 0 
L 12.14763996 5.37205 12.1437 5.36613996 3 P 0 
L 10.71483317 5.87139961 10.7167501 5.86819931 2 P 0 ;0,1=25,2=0.000000
L 10.7167501 5.86819931 10.71904961 5.86606644 2 P 0 ;0,1=25,2=0.000000
L 10.71904961 5.86606644 10.72173307 5.865 2 P 0 ;0,1=25,2=0.000000
L 10.72173307 5.865 10.7247998 5.86606644 2 P 0 ;0,1=25,2=0.000000
L 10.7247998 5.86606644 10.7271 5.86819931 2 P 0 ;0,1=25,2=0.000000
L 10.7271 5.86819931 10.7294002 5.87139961 2 P 0 ;0,1=25,2=0.000000
L 10.7294002 5.87139961 10.73016673 5.87566634 2 P 0 ;0,1=25,2=0.000000
L 10.73016673 5.87566634 10.73016673 5.897 2 P 0 ;0,1=25,2=0.000000
L 10.742 5.85433366 10.765 5.85433366 2 P 0 ;0,1=25,2=0.000000
L 10.7867998 5.88099951 10.79446693 5.88099951 2 P 0 ;0,1=25,2=0.000000
L 10.79446693 5.88099951 10.79446693 5.87139961 2 P 0 ;0,1=25,2=0.000000
L 10.79446693 5.87139961 10.79216673 5.86819931 2 P 0 ;0,1=25,2=0.000000
L 10.79216673 5.86819931 10.78948327 5.86606644 2 P 0 ;0,1=25,2=0.000000
L 10.78948327 5.86606644 10.7856501 5.865 2 P 0 ;0,1=25,2=0.000000
L 10.7856501 5.865 10.78181683 5.86606644 2 P 0 ;0,1=25,2=0.000000
L 10.78181683 5.86606644 10.77913337 5.86819931 2 P 0 ;0,1=25,2=0.000000
L 10.77913337 5.86819931 10.77683317 5.87139961 2 P 0 ;0,1=25,2=0.000000
L 10.77683317 5.87139961 10.77529951 5.87513307 2 P 0 ;0,1=25,2=0.000000
L 10.77529951 5.87513307 10.77453297 5.8793998 2 P 0 ;0,1=25,2=0.000000
L 10.77453297 5.8793998 10.77453297 5.88313327 2 P 0 ;0,1=25,2=0.000000
L 10.77453297 5.88313327 10.77529951 5.88633268 2 P 0 ;0,1=25,2=0.000000
L 10.77529951 5.88633268 10.77683317 5.89006713 2 P 0 ;0,1=25,2=0.000000
L 10.77683317 5.89006713 10.77913337 5.89326644 2 P 0 ;0,1=25,2=0.000000
L 10.77913337 5.89326644 10.78143287 5.89539931 2 P 0 ;0,1=25,2=0.000000
L 10.78143287 5.89539931 10.78449961 5.897 2 P 0 ;0,1=25,2=0.000000
L 10.78449961 5.897 10.78718307 5.897 2 P 0 ;0,1=25,2=0.000000
L 10.78718307 5.897 10.7902498 5.89593346 2 P 0 ;0,1=25,2=0.000000
L 10.7902498 5.89593346 10.79255 5.8937997 2 P 0 ;0,1=25,2=0.000000
L 10.80783317 5.865 10.80783317 5.897 2 P 0 ;0,1=25,2=0.000000
L 10.80783317 5.897 10.81703327 5.897 2 P 0 ;0,1=25,2=0.000000
L 10.81703327 5.897 10.8201 5.89539931 2 P 0 ;0,1=25,2=0.000000
L 10.8201 5.89539931 10.8224002 5.89166673 2 P 0 ;0,1=25,2=0.000000
L 10.8224002 5.89166673 10.82316673 5.8874 2 P 0 ;0,1=25,2=0.000000
L 10.82316673 5.8874 10.8224002 5.88313327 2 P 0 ;0,1=25,2=0.000000
L 10.8224002 5.88313327 10.82048327 5.87993307 2 P 0 ;0,1=25,2=0.000000
L 10.82048327 5.87993307 10.81703327 5.87833238 2 P 0 ;0,1=25,2=0.000000
L 10.81703327 5.87833238 10.80783317 5.87833238 2 P 0 ;0,1=25,2=0.000000
L 10.83806663 5.897 10.83806663 5.87406663 2 P 0 ;0,1=25,2=0.000000
L 10.83806663 5.87406663 10.8395997 5.86926575 2 P 0 ;0,1=25,2=0.000000
L 10.8395997 5.86926575 10.84266634 5.86606644 2 P 0 ;0,1=25,2=0.000000
L 10.84266634 5.86606644 10.84649961 5.865 2 P 0 ;0,1=25,2=0.000000
L 10.84649961 5.865 10.85033356 5.86606644 2 P 0 ;0,1=25,2=0.000000
L 10.85033356 5.86606644 10.8534002 5.86926575 2 P 0 ;0,1=25,2=0.000000
L 10.8534002 5.86926575 10.85493327 5.87406663 2 P 0 ;0,1=25,2=0.000000
L 10.85493327 5.87406663 10.85493327 5.897 2 P 0 ;0,1=25,2=0.000000
L 10.866 5.85433366 10.889 5.85433366 2 P 0 ;0,1=25,2=0.000000
L 10.90083317 5.865 10.90083317 5.897 2 P 0 ;0,1=25,2=0.000000
L 10.90083317 5.897 10.91003327 5.897 2 P 0 ;0,1=25,2=0.000000
L 10.91003327 5.897 10.9131 5.89539931 2 P 0 ;0,1=25,2=0.000000
L 10.9131 5.89539931 10.9154002 5.89166673 2 P 0 ;0,1=25,2=0.000000
L 10.9154002 5.89166673 10.91616673 5.8874 2 P 0 ;0,1=25,2=0.000000
L 10.91616673 5.8874 10.9154002 5.88313327 2 P 0 ;0,1=25,2=0.000000
L 10.9154002 5.88313327 10.91348327 5.87993307 2 P 0 ;0,1=25,2=0.000000
L 10.91348327 5.87993307 10.91003327 5.87833238 2 P 0 ;0,1=25,2=0.000000
L 10.91003327 5.87833238 10.90083317 5.87833238 2 P 0 ;0,1=25,2=0.000000
L 10.928 5.897 10.93336614 5.865 2 P 0 ;0,1=25,2=0.000000
L 10.93336614 5.865 10.93949961 5.897 2 P 0 ;0,1=25,2=0.000000
L 10.93949961 5.897 10.94563307 5.865 2 P 0 ;0,1=25,2=0.000000
L 10.94563307 5.865 10.951 5.897 2 P 0 ;0,1=25,2=0.000000
L 10.96283317 5.865 10.96283317 5.897 2 P 0 ;0,1=25,2=0.000000
L 10.96283317 5.897 10.97241654 5.897 2 P 0 ;0,1=25,2=0.000000
L 10.97241654 5.897 10.97548327 5.89539931 2 P 0 ;0,1=25,2=0.000000
L 10.97548327 5.89539931 10.9774002 5.89326644 2 P 0 ;0,1=25,2=0.000000
L 10.9774002 5.89326644 10.97816673 5.8889997 2 P 0 ;0,1=25,2=0.000000
L 10.97816673 5.8889997 10.9774002 5.88473297 2 P 0 ;0,1=25,2=0.000000
L 10.9774002 5.88473297 10.9751 5.88206683 2 P 0 ;0,1=25,2=0.000000
L 10.9751 5.88206683 10.97241654 5.88046624 2 P 0 ;0,1=25,2=0.000000
L 10.97241654 5.88046624 10.96283317 5.88046624 2 P 0 ;0,1=25,2=0.000000
L 10.97241654 5.88046624 10.97816673 5.865 2 P 0 ;0,1=25,2=0.000000
L 12.1379997 5.81 12.1379997 5.835 2 P 0 ;0,1=26,2=0.000000
L 12.1379997 5.835 12.1347999 5.8300003 2 P 0 ;0,1=26,2=0.000000
L 12.1347999 5.81 12.14119951 5.81 2 P 0 ;0,1=26,2=0.000000
L 12.1619997 5.835 12.15986634 5.83416683 2 P 0 ;0,1=26,2=0.000000
L 12.15986634 5.83416683 12.15826663 5.83208317 2 P 0 ;0,1=26,2=0.000000
L 12.15826663 5.83208317 12.1571998 5.82958366 2 P 0 ;0,1=26,2=0.000000
L 12.1571998 5.82958366 12.1563999 5.82624951 2 P 0 ;0,1=26,2=0.000000
L 12.1563999 5.82624951 12.15613327 5.82249961 2 P 0 ;0,1=26,2=0.000000
L 12.15613327 5.82249961 12.1563999 5.81874961 2 P 0 ;0,1=26,2=0.000000
L 12.1563999 5.81874961 12.1571998 5.81541624 2 P 0 ;0,1=26,2=0.000000
L 12.1571998 5.81541624 12.15826663 5.81291604 2 P 0 ;0,1=26,2=0.000000
L 12.15826663 5.81291604 12.15986634 5.81083307 2 P 0 ;0,1=26,2=0.000000
L 12.15986634 5.81083307 12.1619997 5.81 2 P 0 ;0,1=26,2=0.000000
L 12.1619997 5.81 12.16413307 5.81083307 2 P 0 ;0,1=26,2=0.000000
L 12.16413307 5.81083307 12.16573327 5.81291604 2 P 0 ;0,1=26,2=0.000000
L 12.16573327 5.81291604 12.1668001 5.81541624 2 P 0 ;0,1=26,2=0.000000
L 12.1668001 5.81541624 12.1676 5.81874961 2 P 0 ;0,1=26,2=0.000000
L 12.1676 5.81874961 12.16786663 5.82249961 2 P 0 ;0,1=26,2=0.000000
L 12.16786663 5.82249961 12.1676 5.82624951 2 P 0 ;0,1=26,2=0.000000
L 12.1676 5.82624951 12.1668001 5.82958366 2 P 0 ;0,1=26,2=0.000000
L 12.1668001 5.82958366 12.16573327 5.83208317 2 P 0 ;0,1=26,2=0.000000
L 12.16573327 5.83208317 12.16413307 5.83416683 2 P 0 ;0,1=26,2=0.000000
L 12.16413307 5.83416683 12.1619997 5.835 2 P 0 ;0,1=26,2=0.000000
L 10.8079997 5.81 10.8079997 5.835 2 P 0 ;0,1=27,2=0.000000
L 10.8079997 5.835 10.8047999 5.8300003 2 P 0 ;0,1=27,2=0.000000
L 10.8047999 5.81 10.81119951 5.81 2 P 0 ;0,1=27,2=0.000000
L 10.8319997 5.81 10.83386644 5.81041654 2 P 0 ;0,1=27,2=0.000000
L 10.83386644 5.81041654 10.8359998 5.81166624 2 P 0 ;0,1=27,2=0.000000
L 10.8359998 5.81166624 10.83733337 5.81374911 2 P 0 ;0,1=27,2=0.000000
L 10.83733337 5.81374911 10.83786663 5.81666673 2 P 0 ;0,1=27,2=0.000000
L 10.83786663 5.81666673 10.83733337 5.81958278 2 P 0 ;0,1=27,2=0.000000
L 10.83733337 5.81958278 10.83573327 5.82208297 2 P 0 ;0,1=27,2=0.000000
L 10.83573327 5.82208297 10.83333327 5.82333346 2 P 0 ;0,1=27,2=0.000000
L 10.83333327 5.82333346 10.83066663 5.82333346 2 P 0 ;0,1=27,2=0.000000
L 10.83066663 5.82333346 10.82906654 5.82416663 2 P 0 ;0,1=27,2=0.000000
L 10.82906654 5.82416663 10.82773297 5.82624951 2 P 0 ;0,1=27,2=0.000000
L 10.82773297 5.82624951 10.8271998 5.82916634 2 P 0 ;0,1=27,2=0.000000
L 10.8271998 5.82916634 10.8280001 5.83208317 2 P 0 ;0,1=27,2=0.000000
L 10.8280001 5.83208317 10.82986634 5.83416683 2 P 0 ;0,1=27,2=0.000000
L 10.82986634 5.83416683 10.8319997 5.835 2 P 0 ;0,1=27,2=0.000000
L 10.8319997 5.835 10.83413307 5.83416683 2 P 0 ;0,1=27,2=0.000000
L 10.83413307 5.83416683 10.8359998 5.83208317 2 P 0 ;0,1=27,2=0.000000
L 10.8359998 5.83208317 10.8368001 5.82916634 2 P 0 ;0,1=27,2=0.000000
L 10.8368001 5.82916634 10.83626644 5.82624951 2 P 0 ;0,1=27,2=0.000000
L 10.83626644 5.82624951 10.83493337 5.82416663 2 P 0 ;0,1=27,2=0.000000
L 10.83493337 5.82416663 10.83333327 5.82333346 2 P 0 ;0,1=27,2=0.000000
L 10.83333327 5.82333346 10.83066663 5.82333346 2 P 0 ;0,1=27,2=0.000000
L 10.83066663 5.82333346 10.82826663 5.82208297 2 P 0 ;0,1=27,2=0.000000
L 10.82826663 5.82208297 10.82666654 5.81958278 2 P 0 ;0,1=27,2=0.000000
L 10.82666654 5.81958278 10.82613327 5.81666673 2 P 0 ;0,1=27,2=0.000000
L 10.82613327 5.81666673 10.82666654 5.81374911 2 P 0 ;0,1=27,2=0.000000
L 10.82666654 5.81374911 10.8280001 5.81166624 2 P 0 ;0,1=27,2=0.000000
L 10.8280001 5.81166624 10.83013346 5.81041654 2 P 0 ;0,1=27,2=0.000000
L 10.83013346 5.81041654 10.8319997 5.81 2 P 0 ;0,1=27,2=0.000000
L 10.81846634 5.36791604 10.82033317 5.36583307 2 P 0 ;0,1=28,2=0.000000
L 10.82033317 5.36583307 10.82246654 5.365 2 P 0 ;0,1=28,2=0.000000
L 10.82246654 5.365 10.8245999 5.36583307 2 P 0 ;0,1=28,2=0.000000
L 10.8245999 5.36583307 10.82646663 5.36833258 2 P 0 ;0,1=28,2=0.000000
L 10.82646663 5.36833258 10.8278001 5.37208327 2 P 0 ;0,1=28,2=0.000000
L 10.8278001 5.37208327 10.82833337 5.37583327 2 P 0 ;0,1=28,2=0.000000
L 10.82833337 5.37583327 10.82833337 5.38041634 2 P 0 ;0,1=28,2=0.000000
L 10.82833337 5.38041634 10.8278001 5.38416634 2 P 0 ;0,1=28,2=0.000000
L 10.8278001 5.38416634 10.82646663 5.3874997 2 P 0 ;0,1=28,2=0.000000
L 10.82646663 5.3874997 10.82486644 5.38916683 2 P 0 ;0,1=28,2=0.000000
L 10.82486644 5.38916683 10.8229997 5.39 2 P 0 ;0,1=28,2=0.000000
L 10.8229997 5.39 10.82086634 5.38916683 2 P 0 ;0,1=28,2=0.000000
L 10.82086634 5.38916683 10.81926663 5.3874997 2 P 0 ;0,1=28,2=0.000000
L 10.81926663 5.3874997 10.8181998 5.3850003 2 P 0 ;0,1=28,2=0.000000
L 10.8181998 5.3850003 10.81766654 5.38166614 2 P 0 ;0,1=28,2=0.000000
L 10.81766654 5.38166614 10.8181998 5.3787501 2 P 0 ;0,1=28,2=0.000000
L 10.8181998 5.3787501 10.81953327 5.37583327 2 P 0 ;0,1=28,2=0.000000
L 10.81953327 5.37583327 10.82113346 5.37416614 2 P 0 ;0,1=28,2=0.000000
L 10.82113346 5.37416614 10.8229997 5.37374961 2 P 0 ;0,1=28,2=0.000000
L 10.8229997 5.37374961 10.82513307 5.37458278 2 P 0 ;0,1=28,2=0.000000
L 10.82513307 5.37458278 10.82673327 5.37666644 2 P 0 ;0,1=28,2=0.000000
L 10.82673327 5.37666644 10.82833337 5.38041634 2 P 0 ;0,1=28,2=0.000000
A 5.99825 5.4441 5.99825 5.4441 5.78346004 5.4441 3 P 0 N
L 5.7673999 5.7 5.7673999 5.725 2 P 0 ;0,1=29,2=0.000000
L 5.7786 5.725 5.7786 5.7 2 P 0 ;0,1=29,2=0.000000
L 5.7786 5.71249961 5.7673999 5.71249961 2 P 0 ;0,1=29,2=0.000000
L 5.79193317 5.72083337 5.79353327 5.72333287 2 P 0 ;0,1=29,2=0.000000
L 5.79353327 5.72333287 5.7954 5.72458337 2 P 0 ;0,1=29,2=0.000000
L 5.7954 5.72458337 5.79753337 5.725 2 P 0 ;0,1=29,2=0.000000
L 5.79753337 5.725 5.8002 5.72416683 2 P 0 ;0,1=29,2=0.000000
L 5.8002 5.72416683 5.80206673 5.72208317 2 P 0 ;0,1=29,2=0.000000
L 5.80206673 5.72208317 5.8026 5.71958366 2 P 0 ;0,1=29,2=0.000000
L 5.8026 5.71958366 5.80233337 5.71708268 2 P 0 ;0,1=29,2=0.000000
L 5.80233337 5.71708268 5.80126644 5.7149998 2 P 0 ;0,1=29,2=0.000000
L 5.80126644 5.7149998 5.79593327 5.71083327 2 P 0 ;0,1=29,2=0.000000
L 5.79593327 5.71083327 5.79353327 5.70791644 2 P 0 ;0,1=29,2=0.000000
L 5.79353327 5.70791644 5.79193317 5.70374911 2 P 0 ;0,1=29,2=0.000000
L 5.79193317 5.70374911 5.7913999 5.7 2 P 0 ;0,1=29,2=0.000000
L 5.7913999 5.7 5.8026 5.7 2 P 0 ;0,1=29,2=0.000000
L 5.8209997 5.725 5.81886634 5.72416683 2 P 0 ;0,1=29,2=0.000000
L 5.81886634 5.72416683 5.81726663 5.72208317 2 P 0 ;0,1=29,2=0.000000
L 5.81726663 5.72208317 5.8161998 5.71958366 2 P 0 ;0,1=29,2=0.000000
L 5.8161998 5.71958366 5.8153999 5.71624951 2 P 0 ;0,1=29,2=0.000000
L 5.8153999 5.71624951 5.81513327 5.71249961 2 P 0 ;0,1=29,2=0.000000
L 5.81513327 5.71249961 5.8153999 5.70874961 2 P 0 ;0,1=29,2=0.000000
L 5.8153999 5.70874961 5.8161998 5.70541624 2 P 0 ;0,1=29,2=0.000000
L 5.8161998 5.70541624 5.81726663 5.70291604 2 P 0 ;0,1=29,2=0.000000
L 5.81726663 5.70291604 5.81886634 5.70083307 2 P 0 ;0,1=29,2=0.000000
L 5.81886634 5.70083307 5.8209997 5.7 2 P 0 ;0,1=29,2=0.000000
L 5.8209997 5.7 5.82313307 5.70083307 2 P 0 ;0,1=29,2=0.000000
L 5.82313307 5.70083307 5.82473327 5.70291604 2 P 0 ;0,1=29,2=0.000000
L 5.82473327 5.70291604 5.8258001 5.70541624 2 P 0 ;0,1=29,2=0.000000
L 5.8258001 5.70541624 5.8266 5.70874961 2 P 0 ;0,1=29,2=0.000000
L 5.8266 5.70874961 5.82686663 5.71249961 2 P 0 ;0,1=29,2=0.000000
L 5.82686663 5.71249961 5.8266 5.71624951 2 P 0 ;0,1=29,2=0.000000
L 5.8266 5.71624951 5.8258001 5.71958366 2 P 0 ;0,1=29,2=0.000000
L 5.8258001 5.71958366 5.82473327 5.72208317 2 P 0 ;0,1=29,2=0.000000
L 5.82473327 5.72208317 5.82313307 5.72416683 2 P 0 ;0,1=29,2=0.000000
L 5.82313307 5.72416683 5.8209997 5.725 2 P 0 ;0,1=29,2=0.000000
A 10.42345 5.4441 10.42345 5.4441 10.20866004 5.4441 3 P 0 N
L 10.1773999 5.69 10.1773999 5.715 2 P 0 ;0,1=30,2=0.000000
L 10.1886 5.715 10.1886 5.69 2 P 0 ;0,1=30,2=0.000000
L 10.1886 5.70249961 10.1773999 5.70249961 2 P 0 ;0,1=30,2=0.000000
L 10.20193317 5.71083337 10.20353327 5.71333287 2 P 0 ;0,1=30,2=0.000000
L 10.20353327 5.71333287 10.2054 5.71458337 2 P 0 ;0,1=30,2=0.000000
L 10.2054 5.71458337 10.20753337 5.715 2 P 0 ;0,1=30,2=0.000000
L 10.20753337 5.715 10.2102 5.71416683 2 P 0 ;0,1=30,2=0.000000
L 10.2102 5.71416683 10.21206673 5.71208317 2 P 0 ;0,1=30,2=0.000000
L 10.21206673 5.71208317 10.2126 5.70958366 2 P 0 ;0,1=30,2=0.000000
L 10.2126 5.70958366 10.21233337 5.70708268 2 P 0 ;0,1=30,2=0.000000
L 10.21233337 5.70708268 10.21126644 5.7049998 2 P 0 ;0,1=30,2=0.000000
L 10.21126644 5.7049998 10.20593327 5.70083327 2 P 0 ;0,1=30,2=0.000000
L 10.20593327 5.70083327 10.20353327 5.69791644 2 P 0 ;0,1=30,2=0.000000
L 10.20353327 5.69791644 10.20193317 5.69374911 2 P 0 ;0,1=30,2=0.000000
L 10.20193317 5.69374911 10.2013999 5.69 2 P 0 ;0,1=30,2=0.000000
L 10.2013999 5.69 10.2126 5.69 2 P 0 ;0,1=30,2=0.000000
L 10.2309997 5.69 10.2309997 5.715 2 P 0 ;0,1=30,2=0.000000
L 10.2309997 5.715 10.2277999 5.7100003 2 P 0 ;0,1=30,2=0.000000
L 10.2277999 5.69 10.23419951 5.69 2 P 0 ;0,1=30,2=0.000000
L 0.3034499 4.865 0.3034499 4.897 2 P 0 ;0,1=31,2=0.000000
L 0.31955 4.897 0.31955 4.865 2 P 0 ;0,1=31,2=0.000000
L 0.31955 4.88099951 0.3034499 4.88099951 2 P 0 ;0,1=31,2=0.000000
L 0.33598287 4.86873248 0.33866634 4.86606644 2 P 0 ;0,1=31,2=0.000000
L 0.33866634 4.86606644 0.34173307 4.865 2 P 0 ;0,1=31,2=0.000000
L 0.34173307 4.865 0.3447998 4.86606644 2 P 0 ;0,1=31,2=0.000000
L 0.3447998 4.86606644 0.34748327 4.86926575 2 P 0 ;0,1=31,2=0.000000
L 0.34748327 4.86926575 0.3494002 4.87406663 2 P 0 ;0,1=31,2=0.000000
L 0.3494002 4.87406663 0.35016673 4.87886663 2 P 0 ;0,1=31,2=0.000000
L 0.35016673 4.87886663 0.35016673 4.88473297 2 P 0 ;0,1=31,2=0.000000
L 0.35016673 4.88473297 0.3494002 4.88953297 2 P 0 ;0,1=31,2=0.000000
L 0.3494002 4.88953297 0.34748327 4.8937997 2 P 0 ;0,1=31,2=0.000000
L 0.34748327 4.8937997 0.34518307 4.89593346 2 P 0 ;0,1=31,2=0.000000
L 0.34518307 4.89593346 0.34249961 4.897 2 P 0 ;0,1=31,2=0.000000
L 0.34249961 4.897 0.33943287 4.89593346 2 P 0 ;0,1=31,2=0.000000
L 0.33943287 4.89593346 0.33713337 4.8937997 2 P 0 ;0,1=31,2=0.000000
L 0.33713337 4.8937997 0.3355997 4.8906003 2 P 0 ;0,1=31,2=0.000000
L 0.3355997 4.8906003 0.33483317 4.88633268 2 P 0 ;0,1=31,2=0.000000
L 0.33483317 4.88633268 0.3355997 4.8826001 2 P 0 ;0,1=31,2=0.000000
L 0.3355997 4.8826001 0.33751663 4.87886663 2 P 0 ;0,1=31,2=0.000000
L 0.33751663 4.87886663 0.33981683 4.87673278 2 P 0 ;0,1=31,2=0.000000
L 0.33981683 4.87673278 0.34249961 4.87619951 2 P 0 ;0,1=31,2=0.000000
L 0.34249961 4.87619951 0.34556634 4.87726594 2 P 0 ;0,1=31,2=0.000000
L 0.34556634 4.87726594 0.34786654 4.87993307 2 P 0 ;0,1=31,2=0.000000
L 0.34786654 4.87993307 0.35016673 4.88473297 2 P 0 ;0,1=31,2=0.000000
L 12.5184499 4.895 12.5184499 4.927 2 P 0 ;0,1=32,2=0.000000
L 12.53455 4.927 12.53455 4.895 2 P 0 ;0,1=32,2=0.000000
L 12.53455 4.91099951 12.5184499 4.91099951 2 P 0 ;0,1=32,2=0.000000
L 12.55749961 4.895 12.55749961 4.927 2 P 0 ;0,1=32,2=0.000000
L 12.55749961 4.927 12.5528999 4.9206003 2 P 0 ;0,1=32,2=0.000000
L 12.5528999 4.895 12.56209931 4.895 2 P 0 ;0,1=32,2=0.000000
L 12.58198287 4.89873248 12.58466634 4.89606644 2 P 0 ;0,1=32,2=0.000000
L 12.58466634 4.89606644 12.58773307 4.895 2 P 0 ;0,1=32,2=0.000000
L 12.58773307 4.895 12.5907998 4.89606644 2 P 0 ;0,1=32,2=0.000000
L 12.5907998 4.89606644 12.59348327 4.89926575 2 P 0 ;0,1=32,2=0.000000
L 12.59348327 4.89926575 12.5954002 4.90406663 2 P 0 ;0,1=32,2=0.000000
L 12.5954002 4.90406663 12.59616673 4.90886663 2 P 0 ;0,1=32,2=0.000000
L 12.59616673 4.90886663 12.59616673 4.91473297 2 P 0 ;0,1=32,2=0.000000
L 12.59616673 4.91473297 12.5954002 4.91953297 2 P 0 ;0,1=32,2=0.000000
L 12.5954002 4.91953297 12.59348327 4.9237997 2 P 0 ;0,1=32,2=0.000000
L 12.59348327 4.9237997 12.59118307 4.92593346 2 P 0 ;0,1=32,2=0.000000
L 12.59118307 4.92593346 12.58849961 4.927 2 P 0 ;0,1=32,2=0.000000
L 12.58849961 4.927 12.58543287 4.92593346 2 P 0 ;0,1=32,2=0.000000
L 12.58543287 4.92593346 12.58313337 4.9237997 2 P 0 ;0,1=32,2=0.000000
L 12.58313337 4.9237997 12.5815997 4.9206003 2 P 0 ;0,1=32,2=0.000000
L 12.5815997 4.9206003 12.58083317 4.91633268 2 P 0 ;0,1=32,2=0.000000
L 12.58083317 4.91633268 12.5815997 4.9126001 2 P 0 ;0,1=32,2=0.000000
L 12.5815997 4.9126001 12.58351663 4.90886663 2 P 0 ;0,1=32,2=0.000000
L 12.58351663 4.90886663 12.58581683 4.90673278 2 P 0 ;0,1=32,2=0.000000
L 12.58581683 4.90673278 12.58849961 4.90619951 2 P 0 ;0,1=32,2=0.000000
L 12.58849961 4.90619951 12.59156634 4.90726594 2 P 0 ;0,1=32,2=0.000000
L 12.59156634 4.90726594 12.59386654 4.90993307 2 P 0 ;0,1=32,2=0.000000
L 12.59386654 4.90993307 12.59616673 4.91473297 2 P 0 ;0,1=32,2=0.000000
L 0.3134499 0.93 0.3134499 0.962 2 P 0 ;0,1=33,2=0.000000
L 0.32955 0.962 0.32955 0.93 2 P 0 ;0,1=33,2=0.000000
L 0.32955 0.94599951 0.3134499 0.94599951 2 P 0 ;0,1=33,2=0.000000
L 0.35249961 0.93 0.35249961 0.962 2 P 0 ;0,1=33,2=0.000000
L 0.35249961 0.962 0.3478999 0.9556003 2 P 0 ;0,1=33,2=0.000000
L 0.3478999 0.93 0.35709931 0.93 2 P 0 ;0,1=33,2=0.000000
L 0.38349961 0.93 0.38618307 0.93053317 2 P 0 ;0,1=33,2=0.000000
L 0.38618307 0.93053317 0.3892498 0.93213287 2 P 0 ;0,1=33,2=0.000000
L 0.3892498 0.93213287 0.39116673 0.93479892 2 P 0 ;0,1=33,2=0.000000
L 0.39116673 0.93479892 0.39193327 0.93853337 2 P 0 ;0,1=33,2=0.000000
L 0.39193327 0.93853337 0.39116673 0.94226594 2 P 0 ;0,1=33,2=0.000000
L 0.39116673 0.94226594 0.38886654 0.94546624 2 P 0 ;0,1=33,2=0.000000
L 0.38886654 0.94546624 0.38541654 0.94706683 2 P 0 ;0,1=33,2=0.000000
L 0.38541654 0.94706683 0.38158337 0.94706683 2 P 0 ;0,1=33,2=0.000000
L 0.38158337 0.94706683 0.37928317 0.94813327 2 P 0 ;0,1=33,2=0.000000
L 0.37928317 0.94813327 0.37736614 0.95079941 2 P 0 ;0,1=33,2=0.000000
L 0.37736614 0.95079941 0.3765997 0.95453297 2 P 0 ;0,1=33,2=0.000000
L 0.3765997 0.95453297 0.3777501 0.95826644 2 P 0 ;0,1=33,2=0.000000
L 0.3777501 0.95826644 0.38043287 0.96093346 2 P 0 ;0,1=33,2=0.000000
L 0.38043287 0.96093346 0.38349961 0.962 2 P 0 ;0,1=33,2=0.000000
L 0.38349961 0.962 0.38656634 0.96093346 2 P 0 ;0,1=33,2=0.000000
L 0.38656634 0.96093346 0.3892498 0.95826644 2 P 0 ;0,1=33,2=0.000000
L 0.3892498 0.95826644 0.3904002 0.95453297 2 P 0 ;0,1=33,2=0.000000
L 0.3904002 0.95453297 0.38963307 0.95079941 2 P 0 ;0,1=33,2=0.000000
L 0.38963307 0.95079941 0.38771673 0.94813327 2 P 0 ;0,1=33,2=0.000000
L 0.38771673 0.94813327 0.38541654 0.94706683 2 P 0 ;0,1=33,2=0.000000
L 0.38541654 0.94706683 0.38158337 0.94706683 2 P 0 ;0,1=33,2=0.000000
L 0.38158337 0.94706683 0.37813337 0.94546624 2 P 0 ;0,1=33,2=0.000000
L 0.37813337 0.94546624 0.37583317 0.94226594 2 P 0 ;0,1=33,2=0.000000
L 0.37583317 0.94226594 0.37506663 0.93853337 2 P 0 ;0,1=33,2=0.000000
L 0.37506663 0.93853337 0.37583317 0.93479892 2 P 0 ;0,1=33,2=0.000000
L 0.37583317 0.93479892 0.3777501 0.93213287 2 P 0 ;0,1=33,2=0.000000
L 0.3777501 0.93213287 0.38081683 0.93053317 2 P 0 ;0,1=33,2=0.000000
L 0.38081683 0.93053317 0.38349961 0.93 2 P 0 ;0,1=33,2=0.000000
L 12.5034499 0.965 12.5034499 0.997 2 P 0 ;0,1=34,2=0.000000
L 12.51955 0.997 12.51955 0.965 2 P 0 ;0,1=34,2=0.000000
L 12.51955 0.98099951 12.5034499 0.98099951 2 P 0 ;0,1=34,2=0.000000
L 12.54249961 0.965 12.54249961 0.997 2 P 0 ;0,1=34,2=0.000000
L 12.54249961 0.997 12.5378999 0.9906003 2 P 0 ;0,1=34,2=0.000000
L 12.5378999 0.965 12.54709931 0.965 2 P 0 ;0,1=34,2=0.000000
L 12.57273307 0.965 12.57349961 0.97193278 2 P 0 ;0,1=34,2=0.000000
L 12.57349961 0.97193278 12.5746501 0.97779921 2 P 0 ;0,1=34,2=0.000000
L 12.5746501 0.97779921 12.57618307 0.98313327 2 P 0 ;0,1=34,2=0.000000
L 12.57618307 0.98313327 12.5781 0.9889997 2 P 0 ;0,1=34,2=0.000000
L 12.5781 0.9889997 12.58116673 0.997 2 P 0 ;0,1=34,2=0.000000
L 12.58116673 0.997 12.56583317 0.997 2 P 0 ;0,1=34,2=0.000000
A 0.30545 5.38583002 0.30545 5.38583002 0.22255 5.38583002 3 P 0 N
L 0.3334499 5.375 0.3334499 5.407 2 P 0 ;0,1=35,2=0.000000
L 0.34955 5.407 0.34955 5.375 2 P 0 ;0,1=35,2=0.000000
L 0.34955 5.39099951 0.3334499 5.39099951 2 P 0 ;0,1=35,2=0.000000
L 0.36521644 5.40166673 0.36751663 5.40486614 2 P 0 ;0,1=35,2=0.000000
L 0.36751663 5.40486614 0.3702001 5.40646673 2 P 0 ;0,1=35,2=0.000000
L 0.3702001 5.40646673 0.37326683 5.407 2 P 0 ;0,1=35,2=0.000000
L 0.37326683 5.407 0.3771 5.40593346 2 P 0 ;0,1=35,2=0.000000
L 0.3771 5.40593346 0.37978346 5.40326644 2 P 0 ;0,1=35,2=0.000000
L 0.37978346 5.40326644 0.38055 5.40006713 2 P 0 ;0,1=35,2=0.000000
L 0.38055 5.40006713 0.38016673 5.39686585 2 P 0 ;0,1=35,2=0.000000
L 0.38016673 5.39686585 0.37863307 5.3941998 2 P 0 ;0,1=35,2=0.000000
L 0.37863307 5.3941998 0.37096663 5.38886663 2 P 0 ;0,1=35,2=0.000000
L 0.37096663 5.38886663 0.36751663 5.38513307 2 P 0 ;0,1=35,2=0.000000
L 0.36751663 5.38513307 0.36521644 5.37979892 2 P 0 ;0,1=35,2=0.000000
L 0.36521644 5.37979892 0.3644499 5.375 2 P 0 ;0,1=35,2=0.000000
L 0.3644499 5.375 0.38055 5.375 2 P 0 ;0,1=35,2=0.000000
L 0.39506663 5.37979892 0.39736614 5.37713287 2 P 0 ;0,1=35,2=0.000000
L 0.39736614 5.37713287 0.40004961 5.37553317 2 P 0 ;0,1=35,2=0.000000
L 0.40004961 5.37553317 0.40349961 5.375 2 P 0 ;0,1=35,2=0.000000
L 0.40349961 5.375 0.4069503 5.37606644 2 P 0 ;0,1=35,2=0.000000
L 0.4069503 5.37606644 0.40963307 5.37819931 2 P 0 ;0,1=35,2=0.000000
L 0.40963307 5.37819931 0.41155 5.38193278 2 P 0 ;0,1=35,2=0.000000
L 0.41155 5.38193278 0.41193327 5.38619951 2 P 0 ;0,1=35,2=0.000000
L 0.41193327 5.38619951 0.41116673 5.39046624 2 P 0 ;0,1=35,2=0.000000
L 0.41116673 5.39046624 0.4092498 5.39313327 2 P 0 ;0,1=35,2=0.000000
L 0.4092498 5.39313327 0.40656634 5.39526624 2 P 0 ;0,1=35,2=0.000000
L 0.40656634 5.39526624 0.40388356 5.39579941 2 P 0 ;0,1=35,2=0.000000
L 0.40388356 5.39579941 0.4012001 5.39526624 2 P 0 ;0,1=35,2=0.000000
L 0.4012001 5.39526624 0.3977501 5.39313327 2 P 0 ;0,1=35,2=0.000000
L 0.3977501 5.39313327 0.3988999 5.407 2 P 0 ;0,1=35,2=0.000000
L 0.3988999 5.407 0.4092498 5.407 2 P 0 ;0,1=35,2=0.000000
A 0.30535 0.42126004 0.30535 0.42126004 0.22245 0.42126004 3 P 0 N
L 0.3384499 0.415 0.3384499 0.447 2 P 0 ;0,1=36,2=0.000000
L 0.35455 0.447 0.35455 0.415 2 P 0 ;0,1=36,2=0.000000
L 0.35455 0.43099951 0.3384499 0.43099951 2 P 0 ;0,1=36,2=0.000000
L 0.37021644 0.44166673 0.37251663 0.44486614 2 P 0 ;0,1=36,2=0.000000
L 0.37251663 0.44486614 0.3752001 0.44646673 2 P 0 ;0,1=36,2=0.000000
L 0.3752001 0.44646673 0.37826683 0.447 2 P 0 ;0,1=36,2=0.000000
L 0.37826683 0.447 0.3821 0.44593346 2 P 0 ;0,1=36,2=0.000000
L 0.3821 0.44593346 0.38478346 0.44326644 2 P 0 ;0,1=36,2=0.000000
L 0.38478346 0.44326644 0.38555 0.44006713 2 P 0 ;0,1=36,2=0.000000
L 0.38555 0.44006713 0.38516673 0.43686585 2 P 0 ;0,1=36,2=0.000000
L 0.38516673 0.43686585 0.38363307 0.4341998 2 P 0 ;0,1=36,2=0.000000
L 0.38363307 0.4341998 0.37596663 0.42886663 2 P 0 ;0,1=36,2=0.000000
L 0.37596663 0.42886663 0.37251663 0.42513307 2 P 0 ;0,1=36,2=0.000000
L 0.37251663 0.42513307 0.37021644 0.41979892 2 P 0 ;0,1=36,2=0.000000
L 0.37021644 0.41979892 0.3694499 0.415 2 P 0 ;0,1=36,2=0.000000
L 0.3694499 0.415 0.38555 0.415 2 P 0 ;0,1=36,2=0.000000
L 0.40121644 0.42833238 0.4038999 0.43206683 2 P 0 ;0,1=36,2=0.000000
L 0.4038999 0.43206683 0.4062001 0.4341998 2 P 0 ;0,1=36,2=0.000000
L 0.4062001 0.4341998 0.40926683 0.43526624 2 P 0 ;0,1=36,2=0.000000
L 0.40926683 0.43526624 0.4119503 0.4341998 2 P 0 ;0,1=36,2=0.000000
L 0.4119503 0.4341998 0.41386654 0.43206683 2 P 0 ;0,1=36,2=0.000000
L 0.41386654 0.43206683 0.4154002 0.42886663 2 P 0 ;0,1=36,2=0.000000
L 0.4154002 0.42886663 0.41578346 0.42513307 2 P 0 ;0,1=36,2=0.000000
L 0.41578346 0.42513307 0.4154002 0.42193278 2 P 0 ;0,1=36,2=0.000000
L 0.4154002 0.42193278 0.41386654 0.41873248 2 P 0 ;0,1=36,2=0.000000
L 0.41386654 0.41873248 0.41156634 0.41606644 2 P 0 ;0,1=36,2=0.000000
L 0.41156634 0.41606644 0.40888356 0.415 2 P 0 ;0,1=36,2=0.000000
L 0.40888356 0.415 0.40581683 0.41606644 2 P 0 ;0,1=36,2=0.000000
L 0.40581683 0.41606644 0.40313337 0.41926575 2 P 0 ;0,1=36,2=0.000000
L 0.40313337 0.41926575 0.4015997 0.42406663 2 P 0 ;0,1=36,2=0.000000
L 0.4015997 0.42406663 0.40121644 0.4293998 2 P 0 ;0,1=36,2=0.000000
L 0.40121644 0.4293998 0.40198287 0.43633268 2 P 0 ;0,1=36,2=0.000000
L 0.40198287 0.43633268 0.40313337 0.44006713 2 P 0 ;0,1=36,2=0.000000
L 0.40313337 0.44006713 0.40504961 0.4437997 2 P 0 ;0,1=36,2=0.000000
L 0.40504961 0.4437997 0.40773307 0.44646673 2 P 0 ;0,1=36,2=0.000000
L 0.40773307 0.44646673 0.41041654 0.447 2 P 0 ;0,1=36,2=0.000000
L 0.41041654 0.447 0.4131 0.44593346 2 P 0 ;0,1=36,2=0.000000
L 0.4131 0.44593346 0.41501703 0.44326644 2 P 0 ;0,1=36,2=0.000000
A 12.76991998 5.4252 12.76991998 5.4252 12.68701998 5.4252 3 P 0 N
L 12.5034499 5.415 12.5034499 5.447 2 P 0 ;0,1=37,2=0.000000
L 12.51955 5.447 12.51955 5.415 2 P 0 ;0,1=37,2=0.000000
L 12.51955 5.43099951 12.5034499 5.43099951 2 P 0 ;0,1=37,2=0.000000
L 12.53521644 5.44166673 12.53751663 5.44486614 2 P 0 ;0,1=37,2=0.000000
L 12.53751663 5.44486614 12.5402001 5.44646673 2 P 0 ;0,1=37,2=0.000000
L 12.5402001 5.44646673 12.54326683 5.447 2 P 0 ;0,1=37,2=0.000000
L 12.54326683 5.447 12.5471 5.44593346 2 P 0 ;0,1=37,2=0.000000
L 12.5471 5.44593346 12.54978346 5.44326644 2 P 0 ;0,1=37,2=0.000000
L 12.54978346 5.44326644 12.55055 5.44006713 2 P 0 ;0,1=37,2=0.000000
L 12.55055 5.44006713 12.55016673 5.43686585 2 P 0 ;0,1=37,2=0.000000
L 12.55016673 5.43686585 12.54863307 5.4341998 2 P 0 ;0,1=37,2=0.000000
L 12.54863307 5.4341998 12.54096663 5.42886663 2 P 0 ;0,1=37,2=0.000000
L 12.54096663 5.42886663 12.53751663 5.42513307 2 P 0 ;0,1=37,2=0.000000
L 12.53751663 5.42513307 12.53521644 5.41979892 2 P 0 ;0,1=37,2=0.000000
L 12.53521644 5.41979892 12.5344499 5.415 2 P 0 ;0,1=37,2=0.000000
L 12.5344499 5.415 12.55055 5.415 2 P 0 ;0,1=37,2=0.000000
L 12.57273307 5.415 12.57349961 5.42193278 2 P 0 ;0,1=37,2=0.000000
L 12.57349961 5.42193278 12.5746501 5.42779921 2 P 0 ;0,1=37,2=0.000000
L 12.5746501 5.42779921 12.57618307 5.43313327 2 P 0 ;0,1=37,2=0.000000
L 12.57618307 5.43313327 12.5781 5.4389997 2 P 0 ;0,1=37,2=0.000000
L 12.5781 5.4389997 12.58116673 5.447 2 P 0 ;0,1=37,2=0.000000
L 12.58116673 5.447 12.56583317 5.447 2 P 0 ;0,1=37,2=0.000000
A 12.76991004 0.46063002 12.76991004 0.46063002 12.68701004 0.46063002 3 P 0 N
L 12.4884499 0.435 12.4884499 0.467 2 P 0 ;0,1=38,2=0.000000
L 12.50455 0.467 12.50455 0.435 2 P 0 ;0,1=38,2=0.000000
L 12.50455 0.45099951 12.4884499 0.45099951 2 P 0 ;0,1=38,2=0.000000
L 12.52021644 0.46166673 12.52251663 0.46486614 2 P 0 ;0,1=38,2=0.000000
L 12.52251663 0.46486614 12.5252001 0.46646673 2 P 0 ;0,1=38,2=0.000000
L 12.5252001 0.46646673 12.52826683 0.467 2 P 0 ;0,1=38,2=0.000000
L 12.52826683 0.467 12.5321 0.46593346 2 P 0 ;0,1=38,2=0.000000
L 12.5321 0.46593346 12.53478346 0.46326644 2 P 0 ;0,1=38,2=0.000000
L 12.53478346 0.46326644 12.53555 0.46006713 2 P 0 ;0,1=38,2=0.000000
L 12.53555 0.46006713 12.53516673 0.45686585 2 P 0 ;0,1=38,2=0.000000
L 12.53516673 0.45686585 12.53363307 0.4541998 2 P 0 ;0,1=38,2=0.000000
L 12.53363307 0.4541998 12.52596663 0.44886663 2 P 0 ;0,1=38,2=0.000000
L 12.52596663 0.44886663 12.52251663 0.44513307 2 P 0 ;0,1=38,2=0.000000
L 12.52251663 0.44513307 12.52021644 0.43979892 2 P 0 ;0,1=38,2=0.000000
L 12.52021644 0.43979892 12.5194499 0.435 2 P 0 ;0,1=38,2=0.000000
L 12.5194499 0.435 12.53555 0.435 2 P 0 ;0,1=38,2=0.000000
L 12.55849961 0.435 12.56118307 0.43553317 2 P 0 ;0,1=38,2=0.000000
L 12.56118307 0.43553317 12.5642498 0.43713287 2 P 0 ;0,1=38,2=0.000000
L 12.5642498 0.43713287 12.56616673 0.43979892 2 P 0 ;0,1=38,2=0.000000
L 12.56616673 0.43979892 12.56693327 0.44353337 2 P 0 ;0,1=38,2=0.000000
L 12.56693327 0.44353337 12.56616673 0.44726594 2 P 0 ;0,1=38,2=0.000000
L 12.56616673 0.44726594 12.56386654 0.45046624 2 P 0 ;0,1=38,2=0.000000
L 12.56386654 0.45046624 12.56041654 0.45206683 2 P 0 ;0,1=38,2=0.000000
L 12.56041654 0.45206683 12.55658337 0.45206683 2 P 0 ;0,1=38,2=0.000000
L 12.55658337 0.45206683 12.55428317 0.45313327 2 P 0 ;0,1=38,2=0.000000
L 12.55428317 0.45313327 12.55236614 0.45579941 2 P 0 ;0,1=38,2=0.000000
L 12.55236614 0.45579941 12.5515997 0.45953297 2 P 0 ;0,1=38,2=0.000000
L 12.5515997 0.45953297 12.5527501 0.46326644 2 P 0 ;0,1=38,2=0.000000
L 12.5527501 0.46326644 12.55543287 0.46593346 2 P 0 ;0,1=38,2=0.000000
L 12.55543287 0.46593346 12.55849961 0.467 2 P 0 ;0,1=38,2=0.000000
L 12.55849961 0.467 12.56156634 0.46593346 2 P 0 ;0,1=38,2=0.000000
L 12.56156634 0.46593346 12.5642498 0.46326644 2 P 0 ;0,1=38,2=0.000000
L 12.5642498 0.46326644 12.5654002 0.45953297 2 P 0 ;0,1=38,2=0.000000
L 12.5654002 0.45953297 12.56463307 0.45579941 2 P 0 ;0,1=38,2=0.000000
L 12.56463307 0.45579941 12.56271673 0.45313327 2 P 0 ;0,1=38,2=0.000000
L 12.56271673 0.45313327 12.56041654 0.45206683 2 P 0 ;0,1=38,2=0.000000
L 12.56041654 0.45206683 12.55658337 0.45206683 2 P 0 ;0,1=38,2=0.000000
L 12.55658337 0.45206683 12.55313337 0.45046624 2 P 0 ;0,1=38,2=0.000000
L 12.55313337 0.45046624 12.55083317 0.44726594 2 P 0 ;0,1=38,2=0.000000
L 12.55083317 0.44726594 12.55006663 0.44353337 2 P 0 ;0,1=38,2=0.000000
L 12.55006663 0.44353337 12.55083317 0.43979892 2 P 0 ;0,1=38,2=0.000000
L 12.55083317 0.43979892 12.5527501 0.43713287 2 P 0 ;0,1=38,2=0.000000
L 12.5527501 0.43713287 12.55581683 0.43553317 2 P 0 ;0,1=38,2=0.000000
L 12.55581683 0.43553317 12.55849961 0.435 2 P 0 ;0,1=38,2=0.000000
L 2.777 4.77008002 2.797 4.77008002 3 P 0 
L 2.866 4.77008002 2.924 4.77008002 3 P 0 
L 2.98 4.77008002 3.028 4.77008002 3 P 0 
L 3.061 4.77008002 3.093 4.77008002 3 P 0 
L 3.138 4.77008002 3.157 4.77008002 3 P 0 
L 3.22 4.77008002 3.242 4.77008002 3 P 0 
L 3.274 4.77008002 3.368 4.77008002 3 P 0 
L 3.429 4.77008002 3.455 4.77008002 3 P 0 
L 3.457 4.77008002 3.4417 4.77008002 3 P 0 
L 3.527 4.77008002 3.485 4.77008002 3 P 0 
L 3.525 5.08111004 3.48 5.08111004 3 P 0 
L 3.457 5.08111004 3.415 5.08111004 3 P 0 
L 3.385 5.08111004 3.346 5.08111004 3 P 0 
L 3.313 5.08111004 3.275 5.08111004 3 P 0 
L 3.207 5.08111004 3.24336998 5.08111004 3 P 0 
L 3.214 5.08111004 3.211 5.08111004 3 P 0 
L 3.164 5.08111004 3.066 5.08111004 3 P 0 
L 3.023 5.08111004 2.896 5.08111004 3 P 0 
L 2.851 5.08111004 2.781 5.08111004 3 P 0 
L 2.744 5.08111004 2.72833996 5.08111004 3 P 0 
L 2.66578996 4.90243996 2.66578996 4.81053996 3 P 0 
L 3.57958002 5.08111004 3.557 5.08111004 3 P 0 
L 3.0617 5.08111004 3.166 5.08111004 3 P 0 
L 3.63823002 4.89915 3.63823002 4.79418002 3 P 0 
L 3.63823002 5.04176004 3.63823002 4.87375 3 P 0 
L 3.57166998 4.77008002 3.557 4.77008002 3 P 0 
L 2.71338002 4.77008002 2.749 4.77008002 3 P 0 
L 2.66578996 5.04351998 2.66578996 4.88888002 3 P 0 
L 2.77983317 5.46939961 2.7817501 5.46619931 2 P 0 ;0,1=39,2=0.000000
L 2.7817501 5.46619931 2.78404961 5.46406644 2 P 0 ;0,1=39,2=0.000000
L 2.78404961 5.46406644 2.78673307 5.463 2 P 0 ;0,1=39,2=0.000000
L 2.78673307 5.463 2.7897998 5.46406644 2 P 0 ;0,1=39,2=0.000000
L 2.7897998 5.46406644 2.7921 5.46619931 2 P 0 ;0,1=39,2=0.000000
L 2.7921 5.46619931 2.7944002 5.46939961 2 P 0 ;0,1=39,2=0.000000
L 2.7944002 5.46939961 2.79516673 5.47366634 2 P 0 ;0,1=39,2=0.000000
L 2.79516673 5.47366634 2.79516673 5.495 2 P 0 ;0,1=39,2=0.000000
L 2.807 5.45233366 2.83 5.45233366 2 P 0 ;0,1=39,2=0.000000
L 2.85793327 5.49233287 2.85563307 5.49393346 2 P 0 ;0,1=39,2=0.000000
L 2.85563307 5.49393346 2.8529503 5.495 2 P 0 ;0,1=39,2=0.000000
L 2.8529503 5.495 2.84988356 5.495 2 P 0 ;0,1=39,2=0.000000
L 2.84988356 5.495 2.84643287 5.49339931 2 P 0 ;0,1=39,2=0.000000
L 2.84643287 5.49339931 2.8437501 5.49073327 2 P 0 ;0,1=39,2=0.000000
L 2.8437501 5.49073327 2.84183317 5.48753297 2 P 0 ;0,1=39,2=0.000000
L 2.84183317 5.48753297 2.84029951 5.4821998 2 P 0 ;0,1=39,2=0.000000
L 2.84029951 5.4821998 2.83991624 5.4773998 2 P 0 ;0,1=39,2=0.000000
L 2.83991624 5.4773998 2.84068337 5.4725999 2 P 0 ;0,1=39,2=0.000000
L 2.84068337 5.4725999 2.84183317 5.46939961 2 P 0 ;0,1=39,2=0.000000
L 2.84183317 5.46939961 2.84413337 5.46619931 2 P 0 ;0,1=39,2=0.000000
L 2.84413337 5.46619931 2.84681683 5.46406644 2 P 0 ;0,1=39,2=0.000000
L 2.84681683 5.46406644 2.84949961 5.463 2 P 0 ;0,1=39,2=0.000000
L 2.84949961 5.463 2.85218307 5.463 2 P 0 ;0,1=39,2=0.000000
L 2.85218307 5.463 2.85486654 5.46406644 2 P 0 ;0,1=39,2=0.000000
L 2.85486654 5.46406644 2.85716673 5.46566604 2 P 0 ;0,1=39,2=0.000000
L 2.85716673 5.46566604 2.85908366 5.46779892 2 P 0 ;0,1=39,2=0.000000
L 2.87283317 5.463 2.87283317 5.495 2 P 0 ;0,1=39,2=0.000000
L 2.87283317 5.495 2.88203327 5.495 2 P 0 ;0,1=39,2=0.000000
L 2.88203327 5.495 2.8851 5.49339931 2 P 0 ;0,1=39,2=0.000000
L 2.8851 5.49339931 2.8874002 5.48966673 2 P 0 ;0,1=39,2=0.000000
L 2.8874002 5.48966673 2.88816673 5.4854 2 P 0 ;0,1=39,2=0.000000
L 2.88816673 5.4854 2.8874002 5.48113327 2 P 0 ;0,1=39,2=0.000000
L 2.8874002 5.48113327 2.88548327 5.47793307 2 P 0 ;0,1=39,2=0.000000
L 2.88548327 5.47793307 2.88203327 5.47633238 2 P 0 ;0,1=39,2=0.000000
L 2.88203327 5.47633238 2.87283317 5.47633238 2 P 0 ;0,1=39,2=0.000000
L 2.91149961 5.495 2.90843287 5.49393346 2 P 0 ;0,1=39,2=0.000000
L 2.90843287 5.49393346 2.90613337 5.49126644 2 P 0 ;0,1=39,2=0.000000
L 2.90613337 5.49126644 2.9045997 5.48806713 2 P 0 ;0,1=39,2=0.000000
L 2.9045997 5.48806713 2.9034499 5.48379941 2 P 0 ;0,1=39,2=0.000000
L 2.9034499 5.48379941 2.90306663 5.47899951 2 P 0 ;0,1=39,2=0.000000
L 2.90306663 5.47899951 2.9034499 5.47419951 2 P 0 ;0,1=39,2=0.000000
L 2.9034499 5.47419951 2.9045997 5.46993278 2 P 0 ;0,1=39,2=0.000000
L 2.9045997 5.46993278 2.90613337 5.46673248 2 P 0 ;0,1=39,2=0.000000
L 2.90613337 5.46673248 2.90843287 5.46406644 2 P 0 ;0,1=39,2=0.000000
L 2.90843287 5.46406644 2.91149961 5.463 2 P 0 ;0,1=39,2=0.000000
L 2.91149961 5.463 2.91456634 5.46406644 2 P 0 ;0,1=39,2=0.000000
L 2.91456634 5.46406644 2.91686654 5.46673248 2 P 0 ;0,1=39,2=0.000000
L 2.91686654 5.46673248 2.9184002 5.46993278 2 P 0 ;0,1=39,2=0.000000
L 2.9184002 5.46993278 2.91955 5.47419951 2 P 0 ;0,1=39,2=0.000000
L 2.91955 5.47419951 2.91993327 5.47899951 2 P 0 ;0,1=39,2=0.000000
L 2.91993327 5.47899951 2.91955 5.48379941 2 P 0 ;0,1=39,2=0.000000
L 2.91955 5.48379941 2.9184002 5.48806713 2 P 0 ;0,1=39,2=0.000000
L 2.9184002 5.48806713 2.91686654 5.49126644 2 P 0 ;0,1=39,2=0.000000
L 2.91686654 5.49126644 2.91456634 5.49393346 2 P 0 ;0,1=39,2=0.000000
L 2.91456634 5.49393346 2.91149961 5.495 2 P 0 ;0,1=39,2=0.000000
L 2.931 5.45233366 2.954 5.45233366 2 P 0 ;0,1=39,2=0.000000
L 2.96468337 5.463 2.96468337 5.495 2 P 0 ;0,1=39,2=0.000000
L 2.96468337 5.495 2.98231654 5.463 2 P 0 ;0,1=39,2=0.000000
L 2.98231654 5.463 2.98231654 5.495 2 P 0 ;0,1=39,2=0.000000
L 2.99491624 5.495 3.00449961 5.463 2 P 0 ;0,1=39,2=0.000000
L 3.00449961 5.463 3.01408366 5.495 2 P 0 ;0,1=39,2=0.000000
L 3.02783317 5.495 3.02783317 5.463 2 P 0 ;0,1=39,2=0.000000
L 3.02783317 5.463 3.04316673 5.463 2 P 0 ;0,1=39,2=0.000000
L 3.0618999 5.495 3.07109931 5.495 2 P 0 ;0,1=39,2=0.000000
L 3.06649961 5.495 3.06649961 5.463 2 P 0 ;0,1=39,2=0.000000
L 3.0618999 5.463 3.07109931 5.463 2 P 0 ;0,1=39,2=0.000000
L 3.08868337 5.463 3.08868337 5.495 2 P 0 ;0,1=39,2=0.000000
L 3.08868337 5.495 3.10631654 5.463 2 P 0 ;0,1=39,2=0.000000
L 3.10631654 5.463 3.10631654 5.495 2 P 0 ;0,1=39,2=0.000000
L 3.12006663 5.463 3.12006663 5.495 2 P 0 ;0,1=39,2=0.000000
L 3.13463307 5.495 3.12006663 5.47526594 2 P 0 ;0,1=39,2=0.000000
L 3.13693327 5.463 3.12658337 5.48433268 2 P 0 ;0,1=39,2=0.000000
L 3.148 5.45233366 3.171 5.45233366 2 P 0 ;0,1=39,2=0.000000
L 3.19356634 5.48006683 3.1951 5.48166654 2 P 0 ;0,1=39,2=0.000000
L 3.1951 5.48166654 3.1962498 5.48433268 2 P 0 ;0,1=39,2=0.000000
L 3.1962498 5.48433268 3.19701703 5.48806713 2 P 0 ;0,1=39,2=0.000000
L 3.19701703 5.48806713 3.1962498 5.49126644 2 P 0 ;0,1=39,2=0.000000
L 3.1962498 5.49126644 3.19471673 5.49339931 2 P 0 ;0,1=39,2=0.000000
L 3.19471673 5.49339931 3.19203327 5.495 2 P 0 ;0,1=39,2=0.000000
L 3.19203327 5.495 3.18168337 5.495 2 P 0 ;0,1=39,2=0.000000
L 3.18168337 5.495 3.18168337 5.463 2 P 0 ;0,1=39,2=0.000000
L 3.18168337 5.463 3.19433356 5.463 2 P 0 ;0,1=39,2=0.000000
L 3.19433356 5.463 3.19701703 5.46513287 2 P 0 ;0,1=39,2=0.000000
L 3.19701703 5.46513287 3.19855 5.46833317 2 P 0 ;0,1=39,2=0.000000
L 3.19855 5.46833317 3.19931654 5.47206663 2 P 0 ;0,1=39,2=0.000000
L 3.19931654 5.47206663 3.19855 5.47579921 2 P 0 ;0,1=39,2=0.000000
L 3.19855 5.47579921 3.1962498 5.47899951 2 P 0 ;0,1=39,2=0.000000
L 3.1962498 5.47899951 3.19356634 5.48006683 2 P 0 ;0,1=39,2=0.000000
L 3.19356634 5.48006683 3.18168337 5.48006683 2 P 0 ;0,1=39,2=0.000000
L 3.22149961 5.463 3.21843287 5.46353317 2 P 0 ;0,1=39,2=0.000000
L 3.21843287 5.46353317 3.2157501 5.46566604 2 P 0 ;0,1=39,2=0.000000
L 3.2157501 5.46566604 3.2134499 5.46886634 2 P 0 ;0,1=39,2=0.000000
L 3.2134499 5.46886634 3.21191624 5.4725999 2 P 0 ;0,1=39,2=0.000000
L 3.21191624 5.4725999 3.2111497 5.47686663 2 P 0 ;0,1=39,2=0.000000
L 3.2111497 5.47686663 3.2111497 5.48113327 2 P 0 ;0,1=39,2=0.000000
L 3.2111497 5.48113327 3.21191624 5.4854 2 P 0 ;0,1=39,2=0.000000
L 3.21191624 5.4854 3.2134499 5.48913356 2 P 0 ;0,1=39,2=0.000000
L 3.2134499 5.48913356 3.2157501 5.49233287 2 P 0 ;0,1=39,2=0.000000
L 3.2157501 5.49233287 3.21843287 5.49446673 2 P 0 ;0,1=39,2=0.000000
L 3.21843287 5.49446673 3.22149961 5.495 2 P 0 ;0,1=39,2=0.000000
L 3.22149961 5.495 3.22456634 5.49446673 2 P 0 ;0,1=39,2=0.000000
L 3.22456634 5.49446673 3.2272498 5.49233287 2 P 0 ;0,1=39,2=0.000000
L 3.2272498 5.49233287 3.22955 5.48913356 2 P 0 ;0,1=39,2=0.000000
L 3.22955 5.48913356 3.23108366 5.4854 2 P 0 ;0,1=39,2=0.000000
L 3.23108366 5.4854 3.2318502 5.48113327 2 P 0 ;0,1=39,2=0.000000
L 3.2318502 5.48113327 3.2318502 5.47686663 2 P 0 ;0,1=39,2=0.000000
L 3.2318502 5.47686663 3.23108366 5.4725999 2 P 0 ;0,1=39,2=0.000000
L 3.23108366 5.4725999 3.22955 5.46886634 2 P 0 ;0,1=39,2=0.000000
L 3.22955 5.46886634 3.2272498 5.46566604 2 P 0 ;0,1=39,2=0.000000
L 3.2272498 5.46566604 3.22456634 5.46353317 2 P 0 ;0,1=39,2=0.000000
L 3.22456634 5.46353317 3.22149961 5.463 2 P 0 ;0,1=39,2=0.000000
L 3.25249961 5.495 3.25249961 5.463 2 P 0 ;0,1=39,2=0.000000
L 3.24368337 5.495 3.26131654 5.495 2 P 0 ;0,1=39,2=0.000000
L 3.28349961 5.495 3.28349961 5.463 2 P 0 ;0,1=39,2=0.000000
L 3.27468337 5.495 3.29231654 5.495 2 P 0 ;0,1=39,2=0.000000
L 3.31449961 5.463 3.31143287 5.46353317 2 P 0 ;0,1=39,2=0.000000
L 3.31143287 5.46353317 3.3087501 5.46566604 2 P 0 ;0,1=39,2=0.000000
L 3.3087501 5.46566604 3.3064499 5.46886634 2 P 0 ;0,1=39,2=0.000000
L 3.3064499 5.46886634 3.30491624 5.4725999 2 P 0 ;0,1=39,2=0.000000
L 3.30491624 5.4725999 3.3041497 5.47686663 2 P 0 ;0,1=39,2=0.000000
L 3.3041497 5.47686663 3.3041497 5.48113327 2 P 0 ;0,1=39,2=0.000000
L 3.3041497 5.48113327 3.30491624 5.4854 2 P 0 ;0,1=39,2=0.000000
L 3.30491624 5.4854 3.3064499 5.48913356 2 P 0 ;0,1=39,2=0.000000
L 3.3064499 5.48913356 3.3087501 5.49233287 2 P 0 ;0,1=39,2=0.000000
L 3.3087501 5.49233287 3.31143287 5.49446673 2 P 0 ;0,1=39,2=0.000000
L 3.31143287 5.49446673 3.31449961 5.495 2 P 0 ;0,1=39,2=0.000000
L 3.31449961 5.495 3.31756634 5.49446673 2 P 0 ;0,1=39,2=0.000000
L 3.31756634 5.49446673 3.3202498 5.49233287 2 P 0 ;0,1=39,2=0.000000
L 3.3202498 5.49233287 3.32255 5.48913356 2 P 0 ;0,1=39,2=0.000000
L 3.32255 5.48913356 3.32408366 5.4854 2 P 0 ;0,1=39,2=0.000000
L 3.32408366 5.4854 3.3248502 5.48113327 2 P 0 ;0,1=39,2=0.000000
L 3.3248502 5.48113327 3.3248502 5.47686663 2 P 0 ;0,1=39,2=0.000000
L 3.3248502 5.47686663 3.32408366 5.4725999 2 P 0 ;0,1=39,2=0.000000
L 3.32408366 5.4725999 3.32255 5.46886634 2 P 0 ;0,1=39,2=0.000000
L 3.32255 5.46886634 3.3202498 5.46566604 2 P 0 ;0,1=39,2=0.000000
L 3.3202498 5.46566604 3.31756634 5.46353317 2 P 0 ;0,1=39,2=0.000000
L 3.31756634 5.46353317 3.31449961 5.463 2 P 0 ;0,1=39,2=0.000000
L 3.33553297 5.463 3.33553297 5.495 2 P 0 ;0,1=39,2=0.000000
L 3.33553297 5.495 3.34549961 5.46833317 2 P 0 ;0,1=39,2=0.000000
L 3.34549961 5.46833317 3.35546693 5.495 2 P 0 ;0,1=39,2=0.000000
L 3.35546693 5.495 3.35546693 5.463 2 P 0 ;0,1=39,2=0.000000
L 2.62158297 4.8476 2.6282497 4.8726 1 P 0 ;0,1=40,2=0.000000
L 2.6282497 4.8726 2.63491693 4.8476 1 P 0 ;0,1=40,2=0.000000
L 2.63251644 4.85634961 2.62398297 4.85634961 1 P 0 ;0,1=40,2=0.000000
L 2.6502497 4.8476 2.6502497 4.8726 1 P 0 ;0,1=40,2=0.000000
L 2.6502497 4.8726 2.6470499 4.8676003 1 P 0 ;0,1=40,2=0.000000
L 2.6470499 4.8476 2.65344951 4.8476 1 P 0 ;0,1=40,2=0.000000
L 2.62904311 4.97658346 2.63011004 4.97783327 1 P 0 ;0,1=41,2=0.000000
L 2.63011004 4.97783327 2.63090984 4.97991614 1 P 0 ;0,1=41,2=0.000000
L 2.63090984 4.97991614 2.6314436 4.98283366 1 P 0 ;0,1=41,2=0.000000
L 2.6314436 4.98283366 2.63090984 4.98533317 1 P 0 ;0,1=41,2=0.000000
L 2.63090984 4.98533317 2.62984341 4.98699941 1 P 0 ;0,1=41,2=0.000000
L 2.62984341 4.98699941 2.62797667 4.98825 1 P 0 ;0,1=41,2=0.000000
L 2.62797667 4.98825 2.62077677 4.98825 1 P 0 ;0,1=41,2=0.000000
L 2.62077677 4.98825 2.62077677 4.96325 1 P 0 ;0,1=41,2=0.000000
L 2.62077677 4.96325 2.62957677 4.96325 1 P 0 ;0,1=41,2=0.000000
L 2.62957677 4.96325 2.6314436 4.96491624 1 P 0 ;0,1=41,2=0.000000
L 2.6314436 4.96491624 2.63251004 4.96741654 1 P 0 ;0,1=41,2=0.000000
L 2.63251004 4.96741654 2.63304321 4.97033327 1 P 0 ;0,1=41,2=0.000000
L 2.63304321 4.97033327 2.63251004 4.97324931 1 P 0 ;0,1=41,2=0.000000
L 2.63251004 4.97324931 2.63090984 4.97574961 1 P 0 ;0,1=41,2=0.000000
L 2.63090984 4.97574961 2.62904311 4.97658346 1 P 0 ;0,1=41,2=0.000000
L 2.62904311 4.97658346 2.62077677 4.97658346 1 P 0 ;0,1=41,2=0.000000
L 2.64890974 4.96325 2.64890974 4.98825 1 P 0 ;0,1=41,2=0.000000
L 2.64890974 4.98825 2.64570994 4.9832503 1 P 0 ;0,1=41,2=0.000000
L 2.64570994 4.96325 2.65210955 4.96325 1 P 0 ;0,1=41,2=0.000000
L 3.65688307 4.98187343 3.65795 4.98312323 1 P 0 ;0,1=42,2=0.000000
L 3.65795 4.98312323 3.6587498 4.9852061 1 P 0 ;0,1=42,2=0.000000
L 3.6587498 4.9852061 3.65928356 4.98812362 1 P 0 ;0,1=42,2=0.000000
L 3.65928356 4.98812362 3.6587498 4.99062313 1 P 0 ;0,1=42,2=0.000000
L 3.6587498 4.99062313 3.65768337 4.99228937 1 P 0 ;0,1=42,2=0.000000
L 3.65768337 4.99228937 3.65581663 4.99353996 1 P 0 ;0,1=42,2=0.000000
L 3.65581663 4.99353996 3.64861673 4.99353996 1 P 0 ;0,1=42,2=0.000000
L 3.64861673 4.99353996 3.64861673 4.96853996 1 P 0 ;0,1=42,2=0.000000
L 3.64861673 4.96853996 3.65741673 4.96853996 1 P 0 ;0,1=42,2=0.000000
L 3.65741673 4.96853996 3.65928356 4.9702062 1 P 0 ;0,1=42,2=0.000000
L 3.65928356 4.9702062 3.66035 4.9727065 1 P 0 ;0,1=42,2=0.000000
L 3.66035 4.9727065 3.66088317 4.97562323 1 P 0 ;0,1=42,2=0.000000
L 3.66088317 4.97562323 3.66035 4.97853927 1 P 0 ;0,1=42,2=0.000000
L 3.66035 4.97853927 3.6587498 4.98103957 1 P 0 ;0,1=42,2=0.000000
L 3.6587498 4.98103957 3.65688307 4.98187343 1 P 0 ;0,1=42,2=0.000000
L 3.65688307 4.98187343 3.64861673 4.98187343 1 P 0 ;0,1=42,2=0.000000
L 3.67088327 4.97353957 3.67248297 4.97062283 1 P 0 ;0,1=42,2=0.000000
L 3.67248297 4.97062283 3.67461634 4.9689565 1 P 0 ;0,1=42,2=0.000000
L 3.67461634 4.9689565 3.67701683 4.96853996 1 P 0 ;0,1=42,2=0.000000
L 3.67701683 4.96853996 3.6791502 4.9689565 1 P 0 ;0,1=42,2=0.000000
L 3.6791502 4.9689565 3.68128356 4.97103937 1 P 0 ;0,1=42,2=0.000000
L 3.68128356 4.97103937 3.68261663 4.97353957 1 P 0 ;0,1=42,2=0.000000
L 3.68261663 4.97353957 3.68288317 4.97603986 1 P 0 ;0,1=42,2=0.000000
L 3.68288317 4.97603986 3.68235 4.97895591 1 P 0 ;0,1=42,2=0.000000
L 3.68235 4.97895591 3.68048327 4.98103957 1 P 0 ;0,1=42,2=0.000000
L 3.68048327 4.98103957 3.67861644 4.98187343 1 P 0 ;0,1=42,2=0.000000
L 3.67861644 4.98187343 3.67621654 4.98187343 1 P 0 ;0,1=42,2=0.000000
L 3.67861644 4.98187343 3.68021663 4.98312323 1 P 0 ;0,1=42,2=0.000000
L 3.68021663 4.98312323 3.6815501 4.9852061 1 P 0 ;0,1=42,2=0.000000
L 3.6815501 4.9852061 3.68208337 4.9877063 1 P 0 ;0,1=42,2=0.000000
L 3.68208337 4.9877063 3.6815501 4.9902065 1 P 0 ;0,1=42,2=0.000000
L 3.6815501 4.9902065 3.68021663 4.99228937 1 P 0 ;0,1=42,2=0.000000
L 3.68021663 4.99228937 3.67781663 4.99353996 1 P 0 ;0,1=42,2=0.000000
L 3.67781663 4.99353996 3.67541663 4.99312333 1 P 0 ;0,1=42,2=0.000000
L 3.67541663 4.99312333 3.67301663 4.9914563 1 P 0 ;0,1=42,2=0.000000
L 3.69821654 4.96853996 3.6987497 4.9739562 1 P 0 ;0,1=42,2=0.000000
L 3.6987497 4.9739562 3.69955 4.97853927 1 P 0 ;0,1=42,2=0.000000
L 3.69955 4.97853927 3.70061644 4.98270659 1 P 0 ;0,1=42,2=0.000000
L 3.70061644 4.98270659 3.70195 4.98728976 1 P 0 ;0,1=42,2=0.000000
L 3.70195 4.98728976 3.70408337 4.99353996 1 P 0 ;0,1=42,2=0.000000
L 3.70408337 4.99353996 3.69341654 4.99353996 1 P 0 ;0,1=42,2=0.000000
L 3.64942293 4.84886004 3.65608967 4.87386004 1 P 0 ;0,1=43,2=0.000000
L 3.65608967 4.87386004 3.66275689 4.84886004 1 P 0 ;0,1=43,2=0.000000
L 3.6603564 4.85760965 3.65182293 4.85760965 1 P 0 ;0,1=43,2=0.000000
L 3.67222323 4.85385965 3.67382293 4.85094291 1 P 0 ;0,1=43,2=0.000000
L 3.67382293 4.85094291 3.6759563 4.84927657 1 P 0 ;0,1=43,2=0.000000
L 3.6759563 4.84927657 3.67835679 4.84886004 1 P 0 ;0,1=43,2=0.000000
L 3.67835679 4.84886004 3.68049016 4.84927657 1 P 0 ;0,1=43,2=0.000000
L 3.68049016 4.84927657 3.68262352 4.85135945 1 P 0 ;0,1=43,2=0.000000
L 3.68262352 4.85135945 3.68395659 4.85385965 1 P 0 ;0,1=43,2=0.000000
L 3.68395659 4.85385965 3.68422313 4.85635994 1 P 0 ;0,1=43,2=0.000000
L 3.68422313 4.85635994 3.68368996 4.85927598 1 P 0 ;0,1=43,2=0.000000
L 3.68368996 4.85927598 3.68182323 4.86135965 1 P 0 ;0,1=43,2=0.000000
L 3.68182323 4.86135965 3.6799564 4.8621935 1 P 0 ;0,1=43,2=0.000000
L 3.6799564 4.8621935 3.6775565 4.8621935 1 P 0 ;0,1=43,2=0.000000
L 3.6799564 4.8621935 3.68155659 4.86344331 1 P 0 ;0,1=43,2=0.000000
L 3.68155659 4.86344331 3.68289006 4.86552618 1 P 0 ;0,1=43,2=0.000000
L 3.68289006 4.86552618 3.68342333 4.86802638 1 P 0 ;0,1=43,2=0.000000
L 3.68342333 4.86802638 3.68289006 4.87052657 1 P 0 ;0,1=43,2=0.000000
L 3.68289006 4.87052657 3.68155659 4.87260945 1 P 0 ;0,1=43,2=0.000000
L 3.68155659 4.87260945 3.67915659 4.87386004 1 P 0 ;0,1=43,2=0.000000
L 3.67915659 4.87386004 3.67675659 4.87344341 1 P 0 ;0,1=43,2=0.000000
L 3.67675659 4.87344341 3.67435659 4.87177638 1 P 0 ;0,1=43,2=0.000000
L 3.6995565 4.84886004 3.70008967 4.85427628 1 P 0 ;0,1=43,2=0.000000
L 3.70008967 4.85427628 3.70088996 4.85885935 1 P 0 ;0,1=43,2=0.000000
L 3.70088996 4.85885935 3.7019564 4.86302667 1 P 0 ;0,1=43,2=0.000000
L 3.7019564 4.86302667 3.70328996 4.86760984 1 P 0 ;0,1=43,2=0.000000
L 3.70328996 4.86760984 3.70542333 4.87386004 1 P 0 ;0,1=43,2=0.000000
L 3.70542333 4.87386004 3.6947565 4.87386004 1 P 0 ;0,1=43,2=0.000000
L 8.75 5.08111004 8.73188002 5.08111004 3 P 0 
L 8.85 5.08111004 8.78 5.08111004 3 P 0 
L 9.03 5.08111004 8.9 5.08111004 3 P 0 
L 9.17 5.08111004 9.065 5.08111004 3 P 0 
L 9.245 5.08111004 9.21 5.08111004 3 P 0 
L 9.315 5.08111004 9.28 5.08111004 3 P 0 
L 9.39 5.08111004 9.345 5.08111004 3 P 0 
L 9.46 5.08111004 9.42 5.08111004 3 P 0 
L 9.53 5.08111004 9.48 5.08111004 3 P 0 
L 9.53 4.77008002 9.49 4.77008002 3 P 0 
L 9.43 4.77008002 9.46 4.77008002 3 P 0 
L 9.28 4.77008002 9.375 4.77008002 3 P 0 
L 9.22 4.77008002 9.245 4.77008002 3 P 0 
L 9.14 4.77008002 9.165 4.77008002 3 P 0 
L 9.065 4.77008002 9.095 4.77008002 3 P 0 
L 8.98 4.77008002 9.035 4.77008002 3 P 0 
L 8.87 4.77008002 8.94 4.77008002 3 P 0 
L 8.78 4.77008002 8.805 4.77008002 3 P 0 
L 8.66933002 4.90243996 8.66933002 4.81053996 3 P 0 
L 9.58311998 5.08111004 9.56 5.08111004 3 P 0 
L 9.64176998 4.89915 9.64176998 4.79418002 3 P 0 
L 9.64176998 5.04176004 9.64176998 4.87375 3 P 0 
L 9.57521004 4.77008002 9.56 4.77008002 3 P 0 
L 8.71691998 4.77008002 8.75 4.77008002 3 P 0 
L 8.66933002 5.04351998 8.66933002 4.88888002 3 P 0 
L 8.81383317 5.48639961 8.8157501 5.48319931 2 P 0 ;0,1=44,2=0.000000
L 8.8157501 5.48319931 8.81804961 5.48106644 2 P 0 ;0,1=44,2=0.000000
L 8.81804961 5.48106644 8.82073307 5.48 2 P 0 ;0,1=44,2=0.000000
L 8.82073307 5.48 8.8237998 5.48106644 2 P 0 ;0,1=44,2=0.000000
L 8.8237998 5.48106644 8.8261 5.48319931 2 P 0 ;0,1=44,2=0.000000
L 8.8261 5.48319931 8.8284002 5.48639961 2 P 0 ;0,1=44,2=0.000000
L 8.8284002 5.48639961 8.82916673 5.49066634 2 P 0 ;0,1=44,2=0.000000
L 8.82916673 5.49066634 8.82916673 5.512 2 P 0 ;0,1=44,2=0.000000
L 8.841 5.46933366 8.864 5.46933366 2 P 0 ;0,1=44,2=0.000000
L 8.89193327 5.50933287 8.88963307 5.51093346 2 P 0 ;0,1=44,2=0.000000
L 8.88963307 5.51093346 8.8869503 5.512 2 P 0 ;0,1=44,2=0.000000
L 8.8869503 5.512 8.88388356 5.512 2 P 0 ;0,1=44,2=0.000000
L 8.88388356 5.512 8.88043287 5.51039931 2 P 0 ;0,1=44,2=0.000000
L 8.88043287 5.51039931 8.8777501 5.50773327 2 P 0 ;0,1=44,2=0.000000
L 8.8777501 5.50773327 8.87583317 5.50453297 2 P 0 ;0,1=44,2=0.000000
L 8.87583317 5.50453297 8.87429951 5.4991998 2 P 0 ;0,1=44,2=0.000000
L 8.87429951 5.4991998 8.87391624 5.4943998 2 P 0 ;0,1=44,2=0.000000
L 8.87391624 5.4943998 8.87468337 5.4895999 2 P 0 ;0,1=44,2=0.000000
L 8.87468337 5.4895999 8.87583317 5.48639961 2 P 0 ;0,1=44,2=0.000000
L 8.87583317 5.48639961 8.87813337 5.48319931 2 P 0 ;0,1=44,2=0.000000
L 8.87813337 5.48319931 8.88081683 5.48106644 2 P 0 ;0,1=44,2=0.000000
L 8.88081683 5.48106644 8.88349961 5.48 2 P 0 ;0,1=44,2=0.000000
L 8.88349961 5.48 8.88618307 5.48 2 P 0 ;0,1=44,2=0.000000
L 8.88618307 5.48 8.88886654 5.48106644 2 P 0 ;0,1=44,2=0.000000
L 8.88886654 5.48106644 8.89116673 5.48266604 2 P 0 ;0,1=44,2=0.000000
L 8.89116673 5.48266604 8.89308366 5.48479892 2 P 0 ;0,1=44,2=0.000000
L 8.90683317 5.48 8.90683317 5.512 2 P 0 ;0,1=44,2=0.000000
L 8.90683317 5.512 8.91603327 5.512 2 P 0 ;0,1=44,2=0.000000
L 8.91603327 5.512 8.9191 5.51039931 2 P 0 ;0,1=44,2=0.000000
L 8.9191 5.51039931 8.9214002 5.50666673 2 P 0 ;0,1=44,2=0.000000
L 8.9214002 5.50666673 8.92216673 5.5024 2 P 0 ;0,1=44,2=0.000000
L 8.92216673 5.5024 8.9214002 5.49813327 2 P 0 ;0,1=44,2=0.000000
L 8.9214002 5.49813327 8.91948327 5.49493307 2 P 0 ;0,1=44,2=0.000000
L 8.91948327 5.49493307 8.91603327 5.49333238 2 P 0 ;0,1=44,2=0.000000
L 8.91603327 5.49333238 8.90683317 5.49333238 2 P 0 ;0,1=44,2=0.000000
L 8.94549961 5.48 8.94549961 5.512 2 P 0 ;0,1=44,2=0.000000
L 8.94549961 5.512 8.9408999 5.5056003 2 P 0 ;0,1=44,2=0.000000
L 8.9408999 5.48 8.95009931 5.48 2 P 0 ;0,1=44,2=0.000000
L 8.965 5.46933366 8.988 5.46933366 2 P 0 ;0,1=44,2=0.000000
L 8.99868337 5.48 8.99868337 5.512 2 P 0 ;0,1=44,2=0.000000
L 8.99868337 5.512 9.01631654 5.48 2 P 0 ;0,1=44,2=0.000000
L 9.01631654 5.48 9.01631654 5.512 2 P 0 ;0,1=44,2=0.000000
L 9.02891624 5.512 9.03849961 5.48 2 P 0 ;0,1=44,2=0.000000
L 9.03849961 5.48 9.04808366 5.512 2 P 0 ;0,1=44,2=0.000000
L 9.06183317 5.512 9.06183317 5.48 2 P 0 ;0,1=44,2=0.000000
L 9.06183317 5.48 9.07716673 5.48 2 P 0 ;0,1=44,2=0.000000
L 9.0958999 5.512 9.10509931 5.512 2 P 0 ;0,1=44,2=0.000000
L 9.10049961 5.512 9.10049961 5.48 2 P 0 ;0,1=44,2=0.000000
L 9.0958999 5.48 9.10509931 5.48 2 P 0 ;0,1=44,2=0.000000
L 9.12268337 5.48 9.12268337 5.512 2 P 0 ;0,1=44,2=0.000000
L 9.12268337 5.512 9.14031654 5.48 2 P 0 ;0,1=44,2=0.000000
L 9.14031654 5.48 9.14031654 5.512 2 P 0 ;0,1=44,2=0.000000
L 9.15406663 5.48 9.15406663 5.512 2 P 0 ;0,1=44,2=0.000000
L 9.16863307 5.512 9.15406663 5.49226594 2 P 0 ;0,1=44,2=0.000000
L 9.17093327 5.48 9.16058337 5.50133268 2 P 0 ;0,1=44,2=0.000000
L 9.182 5.46933366 9.205 5.46933366 2 P 0 ;0,1=44,2=0.000000
L 9.22756634 5.49706683 9.2291 5.49866654 2 P 0 ;0,1=44,2=0.000000
L 9.2291 5.49866654 9.2302498 5.50133268 2 P 0 ;0,1=44,2=0.000000
L 9.2302498 5.50133268 9.23101703 5.50506713 2 P 0 ;0,1=44,2=0.000000
L 9.23101703 5.50506713 9.2302498 5.50826644 2 P 0 ;0,1=44,2=0.000000
L 9.2302498 5.50826644 9.22871673 5.51039931 2 P 0 ;0,1=44,2=0.000000
L 9.22871673 5.51039931 9.22603327 5.512 2 P 0 ;0,1=44,2=0.000000
L 9.22603327 5.512 9.21568337 5.512 2 P 0 ;0,1=44,2=0.000000
L 9.21568337 5.512 9.21568337 5.48 2 P 0 ;0,1=44,2=0.000000
L 9.21568337 5.48 9.22833356 5.48 2 P 0 ;0,1=44,2=0.000000
L 9.22833356 5.48 9.23101703 5.48213287 2 P 0 ;0,1=44,2=0.000000
L 9.23101703 5.48213287 9.23255 5.48533317 2 P 0 ;0,1=44,2=0.000000
L 9.23255 5.48533317 9.23331654 5.48906663 2 P 0 ;0,1=44,2=0.000000
L 9.23331654 5.48906663 9.23255 5.49279921 2 P 0 ;0,1=44,2=0.000000
L 9.23255 5.49279921 9.2302498 5.49599951 2 P 0 ;0,1=44,2=0.000000
L 9.2302498 5.49599951 9.22756634 5.49706683 2 P 0 ;0,1=44,2=0.000000
L 9.22756634 5.49706683 9.21568337 5.49706683 2 P 0 ;0,1=44,2=0.000000
L 9.25549961 5.48 9.25243287 5.48053317 2 P 0 ;0,1=44,2=0.000000
L 9.25243287 5.48053317 9.2497501 5.48266604 2 P 0 ;0,1=44,2=0.000000
L 9.2497501 5.48266604 9.2474499 5.48586634 2 P 0 ;0,1=44,2=0.000000
L 9.2474499 5.48586634 9.24591624 5.4895999 2 P 0 ;0,1=44,2=0.000000
L 9.24591624 5.4895999 9.2451497 5.49386663 2 P 0 ;0,1=44,2=0.000000
L 9.2451497 5.49386663 9.2451497 5.49813327 2 P 0 ;0,1=44,2=0.000000
L 9.2451497 5.49813327 9.24591624 5.5024 2 P 0 ;0,1=44,2=0.000000
L 9.24591624 5.5024 9.2474499 5.50613356 2 P 0 ;0,1=44,2=0.000000
L 9.2474499 5.50613356 9.2497501 5.50933287 2 P 0 ;0,1=44,2=0.000000
L 9.2497501 5.50933287 9.25243287 5.51146673 2 P 0 ;0,1=44,2=0.000000
L 9.25243287 5.51146673 9.25549961 5.512 2 P 0 ;0,1=44,2=0.000000
L 9.25549961 5.512 9.25856634 5.51146673 2 P 0 ;0,1=44,2=0.000000
L 9.25856634 5.51146673 9.2612498 5.50933287 2 P 0 ;0,1=44,2=0.000000
L 9.2612498 5.50933287 9.26355 5.50613356 2 P 0 ;0,1=44,2=0.000000
L 9.26355 5.50613356 9.26508366 5.5024 2 P 0 ;0,1=44,2=0.000000
L 9.26508366 5.5024 9.2658502 5.49813327 2 P 0 ;0,1=44,2=0.000000
L 9.2658502 5.49813327 9.2658502 5.49386663 2 P 0 ;0,1=44,2=0.000000
L 9.2658502 5.49386663 9.26508366 5.4895999 2 P 0 ;0,1=44,2=0.000000
L 9.26508366 5.4895999 9.26355 5.48586634 2 P 0 ;0,1=44,2=0.000000
L 9.26355 5.48586634 9.2612498 5.48266604 2 P 0 ;0,1=44,2=0.000000
L 9.2612498 5.48266604 9.25856634 5.48053317 2 P 0 ;0,1=44,2=0.000000
L 9.25856634 5.48053317 9.25549961 5.48 2 P 0 ;0,1=44,2=0.000000
L 9.28649961 5.512 9.28649961 5.48 2 P 0 ;0,1=44,2=0.000000
L 9.27768337 5.512 9.29531654 5.512 2 P 0 ;0,1=44,2=0.000000
L 9.31749961 5.512 9.31749961 5.48 2 P 0 ;0,1=44,2=0.000000
L 9.30868337 5.512 9.32631654 5.512 2 P 0 ;0,1=44,2=0.000000
L 9.34849961 5.48 9.34543287 5.48053317 2 P 0 ;0,1=44,2=0.000000
L 9.34543287 5.48053317 9.3427501 5.48266604 2 P 0 ;0,1=44,2=0.000000
L 9.3427501 5.48266604 9.3404499 5.48586634 2 P 0 ;0,1=44,2=0.000000
L 9.3404499 5.48586634 9.33891624 5.4895999 2 P 0 ;0,1=44,2=0.000000
L 9.33891624 5.4895999 9.3381497 5.49386663 2 P 0 ;0,1=44,2=0.000000
L 9.3381497 5.49386663 9.3381497 5.49813327 2 P 0 ;0,1=44,2=0.000000
L 9.3381497 5.49813327 9.33891624 5.5024 2 P 0 ;0,1=44,2=0.000000
L 9.33891624 5.5024 9.3404499 5.50613356 2 P 0 ;0,1=44,2=0.000000
L 9.3404499 5.50613356 9.3427501 5.50933287 2 P 0 ;0,1=44,2=0.000000
L 9.3427501 5.50933287 9.34543287 5.51146673 2 P 0 ;0,1=44,2=0.000000
L 9.34543287 5.51146673 9.34849961 5.512 2 P 0 ;0,1=44,2=0.000000
L 9.34849961 5.512 9.35156634 5.51146673 2 P 0 ;0,1=44,2=0.000000
L 9.35156634 5.51146673 9.3542498 5.50933287 2 P 0 ;0,1=44,2=0.000000
L 9.3542498 5.50933287 9.35655 5.50613356 2 P 0 ;0,1=44,2=0.000000
L 9.35655 5.50613356 9.35808366 5.5024 2 P 0 ;0,1=44,2=0.000000
L 9.35808366 5.5024 9.3588502 5.49813327 2 P 0 ;0,1=44,2=0.000000
L 9.3588502 5.49813327 9.3588502 5.49386663 2 P 0 ;0,1=44,2=0.000000
L 9.3588502 5.49386663 9.35808366 5.4895999 2 P 0 ;0,1=44,2=0.000000
L 9.35808366 5.4895999 9.35655 5.48586634 2 P 0 ;0,1=44,2=0.000000
L 9.35655 5.48586634 9.3542498 5.48266604 2 P 0 ;0,1=44,2=0.000000
L 9.3542498 5.48266604 9.35156634 5.48053317 2 P 0 ;0,1=44,2=0.000000
L 9.35156634 5.48053317 9.34849961 5.48 2 P 0 ;0,1=44,2=0.000000
L 9.36953297 5.48 9.36953297 5.512 2 P 0 ;0,1=44,2=0.000000
L 9.36953297 5.512 9.37949961 5.48533317 2 P 0 ;0,1=44,2=0.000000
L 9.37949961 5.48533317 9.38946693 5.512 2 P 0 ;0,1=44,2=0.000000
L 9.38946693 5.512 9.38946693 5.48 2 P 0 ;0,1=44,2=0.000000
L 8.62512293 4.8476 8.63178967 4.8726 1 P 0 ;0,1=40,2=0.000000
L 8.63178967 4.8726 8.63845689 4.8476 1 P 0 ;0,1=40,2=0.000000
L 8.6360564 4.85634961 8.62752293 4.85634961 1 P 0 ;0,1=40,2=0.000000
L 8.65378967 4.8476 8.65378967 4.8726 1 P 0 ;0,1=40,2=0.000000
L 8.65378967 4.8726 8.65058986 4.8676003 1 P 0 ;0,1=40,2=0.000000
L 8.65058986 4.8476 8.65698947 4.8476 1 P 0 ;0,1=40,2=0.000000
L 8.63258307 4.97658346 8.63365 4.97783327 1 P 0 ;0,1=41,2=0.000000
L 8.63365 4.97783327 8.6344498 4.97991614 1 P 0 ;0,1=41,2=0.000000
L 8.6344498 4.97991614 8.63498356 4.98283366 1 P 0 ;0,1=41,2=0.000000
L 8.63498356 4.98283366 8.6344498 4.98533317 1 P 0 ;0,1=41,2=0.000000
L 8.6344498 4.98533317 8.63338337 4.98699941 1 P 0 ;0,1=41,2=0.000000
L 8.63338337 4.98699941 8.63151663 4.98825 1 P 0 ;0,1=41,2=0.000000
L 8.63151663 4.98825 8.62431673 4.98825 1 P 0 ;0,1=41,2=0.000000
L 8.62431673 4.98825 8.62431673 4.96325 1 P 0 ;0,1=41,2=0.000000
L 8.62431673 4.96325 8.63311673 4.96325 1 P 0 ;0,1=41,2=0.000000
L 8.63311673 4.96325 8.63498356 4.96491624 1 P 0 ;0,1=41,2=0.000000
L 8.63498356 4.96491624 8.63605 4.96741654 1 P 0 ;0,1=41,2=0.000000
L 8.63605 4.96741654 8.63658317 4.97033327 1 P 0 ;0,1=41,2=0.000000
L 8.63658317 4.97033327 8.63605 4.97324931 1 P 0 ;0,1=41,2=0.000000
L 8.63605 4.97324931 8.6344498 4.97574961 1 P 0 ;0,1=41,2=0.000000
L 8.6344498 4.97574961 8.63258307 4.97658346 1 P 0 ;0,1=41,2=0.000000
L 8.63258307 4.97658346 8.62431673 4.97658346 1 P 0 ;0,1=41,2=0.000000
L 8.6524497 4.96325 8.6524497 4.98825 1 P 0 ;0,1=41,2=0.000000
L 8.6524497 4.98825 8.6492499 4.9832503 1 P 0 ;0,1=41,2=0.000000
L 8.6492499 4.96325 8.65564951 4.96325 1 P 0 ;0,1=41,2=0.000000
L 9.66042303 4.98187343 9.66148996 4.98312323 1 P 0 ;0,1=42,2=0.000000
L 9.66148996 4.98312323 9.66228976 4.9852061 1 P 0 ;0,1=42,2=0.000000
L 9.66228976 4.9852061 9.66282352 4.98812362 1 P 0 ;0,1=42,2=0.000000
L 9.66282352 4.98812362 9.66228976 4.99062313 1 P 0 ;0,1=42,2=0.000000
L 9.66228976 4.99062313 9.66122333 4.99228937 1 P 0 ;0,1=42,2=0.000000
L 9.66122333 4.99228937 9.65935659 4.99353996 1 P 0 ;0,1=42,2=0.000000
L 9.65935659 4.99353996 9.65215669 4.99353996 1 P 0 ;0,1=42,2=0.000000
L 9.65215669 4.99353996 9.65215669 4.96853996 1 P 0 ;0,1=42,2=0.000000
L 9.65215669 4.96853996 9.66095669 4.96853996 1 P 0 ;0,1=42,2=0.000000
L 9.66095669 4.96853996 9.66282352 4.9702062 1 P 0 ;0,1=42,2=0.000000
L 9.66282352 4.9702062 9.66388996 4.9727065 1 P 0 ;0,1=42,2=0.000000
L 9.66388996 4.9727065 9.66442313 4.97562323 1 P 0 ;0,1=42,2=0.000000
L 9.66442313 4.97562323 9.66388996 4.97853927 1 P 0 ;0,1=42,2=0.000000
L 9.66388996 4.97853927 9.66228976 4.98103957 1 P 0 ;0,1=42,2=0.000000
L 9.66228976 4.98103957 9.66042303 4.98187343 1 P 0 ;0,1=42,2=0.000000
L 9.66042303 4.98187343 9.65215669 4.98187343 1 P 0 ;0,1=42,2=0.000000
L 9.67442323 4.97353957 9.67602293 4.97062283 1 P 0 ;0,1=42,2=0.000000
L 9.67602293 4.97062283 9.6781563 4.9689565 1 P 0 ;0,1=42,2=0.000000
L 9.6781563 4.9689565 9.68055679 4.96853996 1 P 0 ;0,1=42,2=0.000000
L 9.68055679 4.96853996 9.68269016 4.9689565 1 P 0 ;0,1=42,2=0.000000
L 9.68269016 4.9689565 9.68482352 4.97103937 1 P 0 ;0,1=42,2=0.000000
L 9.68482352 4.97103937 9.68615659 4.97353957 1 P 0 ;0,1=42,2=0.000000
L 9.68615659 4.97353957 9.68642313 4.97603986 1 P 0 ;0,1=42,2=0.000000
L 9.68642313 4.97603986 9.68588996 4.97895591 1 P 0 ;0,1=42,2=0.000000
L 9.68588996 4.97895591 9.68402323 4.98103957 1 P 0 ;0,1=42,2=0.000000
L 9.68402323 4.98103957 9.6821564 4.98187343 1 P 0 ;0,1=42,2=0.000000
L 9.6821564 4.98187343 9.6797565 4.98187343 1 P 0 ;0,1=42,2=0.000000
L 9.6821564 4.98187343 9.68375659 4.98312323 1 P 0 ;0,1=42,2=0.000000
L 9.68375659 4.98312323 9.68509006 4.9852061 1 P 0 ;0,1=42,2=0.000000
L 9.68509006 4.9852061 9.68562333 4.9877063 1 P 0 ;0,1=42,2=0.000000
L 9.68562333 4.9877063 9.68509006 4.9902065 1 P 0 ;0,1=42,2=0.000000
L 9.68509006 4.9902065 9.68375659 4.99228937 1 P 0 ;0,1=42,2=0.000000
L 9.68375659 4.99228937 9.68135659 4.99353996 1 P 0 ;0,1=42,2=0.000000
L 9.68135659 4.99353996 9.67895659 4.99312333 1 P 0 ;0,1=42,2=0.000000
L 9.67895659 4.99312333 9.67655659 4.9914563 1 P 0 ;0,1=42,2=0.000000
L 9.7017565 4.96853996 9.70228967 4.9739562 1 P 0 ;0,1=42,2=0.000000
L 9.70228967 4.9739562 9.70308996 4.97853927 1 P 0 ;0,1=42,2=0.000000
L 9.70308996 4.97853927 9.7041564 4.98270659 1 P 0 ;0,1=42,2=0.000000
L 9.7041564 4.98270659 9.70548996 4.98728976 1 P 0 ;0,1=42,2=0.000000
L 9.70548996 4.98728976 9.70762333 4.99353996 1 P 0 ;0,1=42,2=0.000000
L 9.70762333 4.99353996 9.6969565 4.99353996 1 P 0 ;0,1=42,2=0.000000
L 9.65296299 4.84886004 9.65962972 4.87386004 1 P 0 ;0,1=43,2=0.000000
L 9.65962972 4.87386004 9.66629695 4.84886004 1 P 0 ;0,1=43,2=0.000000
L 9.66389646 4.85760965 9.65536299 4.85760965 1 P 0 ;0,1=43,2=0.000000
L 9.67576329 4.85385965 9.67736299 4.85094291 1 P 0 ;0,1=43,2=0.000000
L 9.67736299 4.85094291 9.67949636 4.84927657 1 P 0 ;0,1=43,2=0.000000
L 9.67949636 4.84927657 9.68189685 4.84886004 1 P 0 ;0,1=43,2=0.000000
L 9.68189685 4.84886004 9.68403022 4.84927657 1 P 0 ;0,1=43,2=0.000000
L 9.68403022 4.84927657 9.68616358 4.85135945 1 P 0 ;0,1=43,2=0.000000
L 9.68616358 4.85135945 9.68749665 4.85385965 1 P 0 ;0,1=43,2=0.000000
L 9.68749665 4.85385965 9.68776319 4.85635994 1 P 0 ;0,1=43,2=0.000000
L 9.68776319 4.85635994 9.68723002 4.85927598 1 P 0 ;0,1=43,2=0.000000
L 9.68723002 4.85927598 9.68536329 4.86135965 1 P 0 ;0,1=43,2=0.000000
L 9.68536329 4.86135965 9.68349646 4.8621935 1 P 0 ;0,1=43,2=0.000000
L 9.68349646 4.8621935 9.68109656 4.8621935 1 P 0 ;0,1=43,2=0.000000
L 9.68349646 4.8621935 9.68509665 4.86344331 1 P 0 ;0,1=43,2=0.000000
L 9.68509665 4.86344331 9.68643012 4.86552618 1 P 0 ;0,1=43,2=0.000000
L 9.68643012 4.86552618 9.68696339 4.86802638 1 P 0 ;0,1=43,2=0.000000
L 9.68696339 4.86802638 9.68643012 4.87052657 1 P 0 ;0,1=43,2=0.000000
L 9.68643012 4.87052657 9.68509665 4.87260945 1 P 0 ;0,1=43,2=0.000000
L 9.68509665 4.87260945 9.68269665 4.87386004 1 P 0 ;0,1=43,2=0.000000
L 9.68269665 4.87386004 9.68029665 4.87344341 1 P 0 ;0,1=43,2=0.000000
L 9.68029665 4.87344341 9.67789665 4.87177638 1 P 0 ;0,1=43,2=0.000000
L 9.70309656 4.84886004 9.70362972 4.85427628 1 P 0 ;0,1=43,2=0.000000
L 9.70362972 4.85427628 9.70443002 4.85885935 1 P 0 ;0,1=43,2=0.000000
L 9.70443002 4.85885935 9.70549646 4.86302667 1 P 0 ;0,1=43,2=0.000000
L 9.70549646 4.86302667 9.70683002 4.86760984 1 P 0 ;0,1=43,2=0.000000
L 9.70683002 4.86760984 9.70896339 4.87386004 1 P 0 ;0,1=43,2=0.000000
L 9.70896339 4.87386004 9.69829656 4.87386004 1 P 0 ;0,1=43,2=0.000000
L 2.359 4.77008002 2.321 4.77008002 3 P 0 
L 2.266 4.77008002 2.291 4.77008002 3 P 0 
L 2.123 4.77008002 2.207 4.77008002 3 P 0 
L 2.041 4.77008002 2.063 4.77008002 3 P 0 
L 1.972 4.77008002 2.009 4.77008002 3 P 0 
L 1.897 4.77008002 1.934 4.77008002 3 P 0 
L 1.839 4.77008002 1.865 4.77008002 3 P 0 
L 1.696 4.77008002 1.778 4.77008002 3 P 0 
L 1.612 4.77008002 1.639 4.77008002 3 P 0 
L 1.578 5.08111004 1.56373996 5.08111004 3 P 0 
L 1.863 5.08111004 1.615 5.08111004 3 P 0 
L 2.042 5.08111004 2.07876998 5.08111004 3 P 0 
L 2.004 5.08111004 1.899 5.08111004 3 P 0 
L 2.362 5.08111004 2.113 5.08111004 3 P 0 
L 1.50118996 4.90243996 1.50118996 4.81053996 3 P 0 
L 2.41498002 5.08111004 2.393 5.08111004 3 P 0 
L 2.47363002 4.89915 2.47363002 4.81071004 3 P 0 
L 2.47363002 5.04176004 2.47363002 4.87375 3 P 0 
L 2.42726004 4.77008002 2.394 4.77008002 3 P 0 
L 1.54878002 4.77008002 1.582 4.77008002 3 P 0 
L 1.50118996 5.04351998 1.50118996 4.88888002 3 P 0 
L 1.80783317 5.47039961 1.8097501 5.46719931 2 P 0 ;0,1=45,2=0.000000
L 1.8097501 5.46719931 1.81204961 5.46506644 2 P 0 ;0,1=45,2=0.000000
L 1.81204961 5.46506644 1.81473307 5.464 2 P 0 ;0,1=45,2=0.000000
L 1.81473307 5.464 1.8177998 5.46506644 2 P 0 ;0,1=45,2=0.000000
L 1.8177998 5.46506644 1.8201 5.46719931 2 P 0 ;0,1=45,2=0.000000
L 1.8201 5.46719931 1.8224002 5.47039961 2 P 0 ;0,1=45,2=0.000000
L 1.8224002 5.47039961 1.82316673 5.47466634 2 P 0 ;0,1=45,2=0.000000
L 1.82316673 5.47466634 1.82316673 5.496 2 P 0 ;0,1=45,2=0.000000
L 1.835 5.45333366 1.858 5.45333366 2 P 0 ;0,1=45,2=0.000000
L 1.88593327 5.49333287 1.88363307 5.49493346 2 P 0 ;0,1=45,2=0.000000
L 1.88363307 5.49493346 1.8809503 5.496 2 P 0 ;0,1=45,2=0.000000
L 1.8809503 5.496 1.87788356 5.496 2 P 0 ;0,1=45,2=0.000000
L 1.87788356 5.496 1.87443287 5.49439931 2 P 0 ;0,1=45,2=0.000000
L 1.87443287 5.49439931 1.8717501 5.49173327 2 P 0 ;0,1=45,2=0.000000
L 1.8717501 5.49173327 1.86983317 5.48853297 2 P 0 ;0,1=45,2=0.000000
L 1.86983317 5.48853297 1.86829951 5.4831998 2 P 0 ;0,1=45,2=0.000000
L 1.86829951 5.4831998 1.86791624 5.4783998 2 P 0 ;0,1=45,2=0.000000
L 1.86791624 5.4783998 1.86868337 5.4735999 2 P 0 ;0,1=45,2=0.000000
L 1.86868337 5.4735999 1.86983317 5.47039961 2 P 0 ;0,1=45,2=0.000000
L 1.86983317 5.47039961 1.87213337 5.46719931 2 P 0 ;0,1=45,2=0.000000
L 1.87213337 5.46719931 1.87481683 5.46506644 2 P 0 ;0,1=45,2=0.000000
L 1.87481683 5.46506644 1.87749961 5.464 2 P 0 ;0,1=45,2=0.000000
L 1.87749961 5.464 1.88018307 5.464 2 P 0 ;0,1=45,2=0.000000
L 1.88018307 5.464 1.88286654 5.46506644 2 P 0 ;0,1=45,2=0.000000
L 1.88286654 5.46506644 1.88516673 5.46666604 2 P 0 ;0,1=45,2=0.000000
L 1.88516673 5.46666604 1.88708366 5.46879892 2 P 0 ;0,1=45,2=0.000000
L 1.90083317 5.464 1.90083317 5.496 2 P 0 ;0,1=45,2=0.000000
L 1.90083317 5.496 1.91003327 5.496 2 P 0 ;0,1=45,2=0.000000
L 1.91003327 5.496 1.9131 5.49439931 2 P 0 ;0,1=45,2=0.000000
L 1.9131 5.49439931 1.9154002 5.49066673 2 P 0 ;0,1=45,2=0.000000
L 1.9154002 5.49066673 1.91616673 5.4864 2 P 0 ;0,1=45,2=0.000000
L 1.91616673 5.4864 1.9154002 5.48213327 2 P 0 ;0,1=45,2=0.000000
L 1.9154002 5.48213327 1.91348327 5.47893307 2 P 0 ;0,1=45,2=0.000000
L 1.91348327 5.47893307 1.91003327 5.47733238 2 P 0 ;0,1=45,2=0.000000
L 1.91003327 5.47733238 1.90083317 5.47733238 2 P 0 ;0,1=45,2=0.000000
L 1.93949961 5.496 1.93643287 5.49493346 2 P 0 ;0,1=45,2=0.000000
L 1.93643287 5.49493346 1.93413337 5.49226644 2 P 0 ;0,1=45,2=0.000000
L 1.93413337 5.49226644 1.9325997 5.48906713 2 P 0 ;0,1=45,2=0.000000
L 1.9325997 5.48906713 1.9314499 5.48479941 2 P 0 ;0,1=45,2=0.000000
L 1.9314499 5.48479941 1.93106663 5.47999951 2 P 0 ;0,1=45,2=0.000000
L 1.93106663 5.47999951 1.9314499 5.47519951 2 P 0 ;0,1=45,2=0.000000
L 1.9314499 5.47519951 1.9325997 5.47093278 2 P 0 ;0,1=45,2=0.000000
L 1.9325997 5.47093278 1.93413337 5.46773248 2 P 0 ;0,1=45,2=0.000000
L 1.93413337 5.46773248 1.93643287 5.46506644 2 P 0 ;0,1=45,2=0.000000
L 1.93643287 5.46506644 1.93949961 5.464 2 P 0 ;0,1=45,2=0.000000
L 1.93949961 5.464 1.94256634 5.46506644 2 P 0 ;0,1=45,2=0.000000
L 1.94256634 5.46506644 1.94486654 5.46773248 2 P 0 ;0,1=45,2=0.000000
L 1.94486654 5.46773248 1.9464002 5.47093278 2 P 0 ;0,1=45,2=0.000000
L 1.9464002 5.47093278 1.94755 5.47519951 2 P 0 ;0,1=45,2=0.000000
L 1.94755 5.47519951 1.94793327 5.47999951 2 P 0 ;0,1=45,2=0.000000
L 1.94793327 5.47999951 1.94755 5.48479941 2 P 0 ;0,1=45,2=0.000000
L 1.94755 5.48479941 1.9464002 5.48906713 2 P 0 ;0,1=45,2=0.000000
L 1.9464002 5.48906713 1.94486654 5.49226644 2 P 0 ;0,1=45,2=0.000000
L 1.94486654 5.49226644 1.94256634 5.49493346 2 P 0 ;0,1=45,2=0.000000
L 1.94256634 5.49493346 1.93949961 5.496 2 P 0 ;0,1=45,2=0.000000
L 1.959 5.45333366 1.982 5.45333366 2 P 0 ;0,1=45,2=0.000000
L 1.99268337 5.464 1.99268337 5.496 2 P 0 ;0,1=45,2=0.000000
L 1.99268337 5.496 2.01031654 5.464 2 P 0 ;0,1=45,2=0.000000
L 2.01031654 5.464 2.01031654 5.496 2 P 0 ;0,1=45,2=0.000000
L 2.02291624 5.496 2.03249961 5.464 2 P 0 ;0,1=45,2=0.000000
L 2.03249961 5.464 2.04208366 5.496 2 P 0 ;0,1=45,2=0.000000
L 2.05583317 5.496 2.05583317 5.464 2 P 0 ;0,1=45,2=0.000000
L 2.05583317 5.464 2.07116673 5.464 2 P 0 ;0,1=45,2=0.000000
L 2.0898999 5.496 2.09909931 5.496 2 P 0 ;0,1=45,2=0.000000
L 2.09449961 5.496 2.09449961 5.464 2 P 0 ;0,1=45,2=0.000000
L 2.0898999 5.464 2.09909931 5.464 2 P 0 ;0,1=45,2=0.000000
L 2.11668337 5.464 2.11668337 5.496 2 P 0 ;0,1=45,2=0.000000
L 2.11668337 5.496 2.13431654 5.464 2 P 0 ;0,1=45,2=0.000000
L 2.13431654 5.464 2.13431654 5.496 2 P 0 ;0,1=45,2=0.000000
L 2.14806663 5.464 2.14806663 5.496 2 P 0 ;0,1=45,2=0.000000
L 2.16263307 5.496 2.14806663 5.47626594 2 P 0 ;0,1=45,2=0.000000
L 2.16493327 5.464 2.15458337 5.48533268 2 P 0 ;0,1=45,2=0.000000
L 2.176 5.45333366 2.199 5.45333366 2 P 0 ;0,1=45,2=0.000000
L 2.21849961 5.496 2.21849961 5.464 2 P 0 ;0,1=45,2=0.000000
L 2.20968337 5.496 2.22731654 5.496 2 P 0 ;0,1=45,2=0.000000
L 2.24949961 5.464 2.24643287 5.46453317 2 P 0 ;0,1=45,2=0.000000
L 2.24643287 5.46453317 2.2437501 5.46666604 2 P 0 ;0,1=45,2=0.000000
L 2.2437501 5.46666604 2.2414499 5.46986634 2 P 0 ;0,1=45,2=0.000000
L 2.2414499 5.46986634 2.23991624 5.4735999 2 P 0 ;0,1=45,2=0.000000
L 2.23991624 5.4735999 2.2391497 5.47786663 2 P 0 ;0,1=45,2=0.000000
L 2.2391497 5.47786663 2.2391497 5.48213327 2 P 0 ;0,1=45,2=0.000000
L 2.2391497 5.48213327 2.23991624 5.4864 2 P 0 ;0,1=45,2=0.000000
L 2.23991624 5.4864 2.2414499 5.49013356 2 P 0 ;0,1=45,2=0.000000
L 2.2414499 5.49013356 2.2437501 5.49333287 2 P 0 ;0,1=45,2=0.000000
L 2.2437501 5.49333287 2.24643287 5.49546673 2 P 0 ;0,1=45,2=0.000000
L 2.24643287 5.49546673 2.24949961 5.496 2 P 0 ;0,1=45,2=0.000000
L 2.24949961 5.496 2.25256634 5.49546673 2 P 0 ;0,1=45,2=0.000000
L 2.25256634 5.49546673 2.2552498 5.49333287 2 P 0 ;0,1=45,2=0.000000
L 2.2552498 5.49333287 2.25755 5.49013356 2 P 0 ;0,1=45,2=0.000000
L 2.25755 5.49013356 2.25908366 5.4864 2 P 0 ;0,1=45,2=0.000000
L 2.25908366 5.4864 2.2598502 5.48213327 2 P 0 ;0,1=45,2=0.000000
L 2.2598502 5.48213327 2.2598502 5.47786663 2 P 0 ;0,1=45,2=0.000000
L 2.2598502 5.47786663 2.25908366 5.4735999 2 P 0 ;0,1=45,2=0.000000
L 2.25908366 5.4735999 2.25755 5.46986634 2 P 0 ;0,1=45,2=0.000000
L 2.25755 5.46986634 2.2552498 5.46666604 2 P 0 ;0,1=45,2=0.000000
L 2.2552498 5.46666604 2.25256634 5.46453317 2 P 0 ;0,1=45,2=0.000000
L 2.25256634 5.46453317 2.24949961 5.464 2 P 0 ;0,1=45,2=0.000000
L 2.27283317 5.464 2.27283317 5.496 2 P 0 ;0,1=45,2=0.000000
L 2.27283317 5.496 2.28203327 5.496 2 P 0 ;0,1=45,2=0.000000
L 2.28203327 5.496 2.2851 5.49439931 2 P 0 ;0,1=45,2=0.000000
L 2.2851 5.49439931 2.2874002 5.49066673 2 P 0 ;0,1=45,2=0.000000
L 2.2874002 5.49066673 2.28816673 5.4864 2 P 0 ;0,1=45,2=0.000000
L 2.28816673 5.4864 2.2874002 5.48213327 2 P 0 ;0,1=45,2=0.000000
L 2.2874002 5.48213327 2.28548327 5.47893307 2 P 0 ;0,1=45,2=0.000000
L 2.28548327 5.47893307 2.28203327 5.47733238 2 P 0 ;0,1=45,2=0.000000
L 2.28203327 5.47733238 2.27283317 5.47733238 2 P 0 ;0,1=45,2=0.000000
L 1.45698297 4.8476 1.4636497 4.8726 1 P 0 ;0,1=40,2=0.000000
L 1.4636497 4.8726 1.47031693 4.8476 1 P 0 ;0,1=40,2=0.000000
L 1.46791644 4.85634961 1.45938297 4.85634961 1 P 0 ;0,1=40,2=0.000000
L 1.4856497 4.8476 1.4856497 4.8726 1 P 0 ;0,1=40,2=0.000000
L 1.4856497 4.8726 1.4824499 4.8676003 1 P 0 ;0,1=40,2=0.000000
L 1.4824499 4.8476 1.48884951 4.8476 1 P 0 ;0,1=40,2=0.000000
L 1.46444311 4.97658346 1.46551004 4.97783327 1 P 0 ;0,1=41,2=0.000000
L 1.46551004 4.97783327 1.46630984 4.97991614 1 P 0 ;0,1=41,2=0.000000
L 1.46630984 4.97991614 1.4668436 4.98283366 1 P 0 ;0,1=41,2=0.000000
L 1.4668436 4.98283366 1.46630984 4.98533317 1 P 0 ;0,1=41,2=0.000000
L 1.46630984 4.98533317 1.46524341 4.98699941 1 P 0 ;0,1=41,2=0.000000
L 1.46524341 4.98699941 1.46337667 4.98825 1 P 0 ;0,1=41,2=0.000000
L 1.46337667 4.98825 1.45617677 4.98825 1 P 0 ;0,1=41,2=0.000000
L 1.45617677 4.98825 1.45617677 4.96325 1 P 0 ;0,1=41,2=0.000000
L 1.45617677 4.96325 1.46497677 4.96325 1 P 0 ;0,1=41,2=0.000000
L 1.46497677 4.96325 1.4668436 4.96491624 1 P 0 ;0,1=41,2=0.000000
L 1.4668436 4.96491624 1.46791004 4.96741654 1 P 0 ;0,1=41,2=0.000000
L 1.46791004 4.96741654 1.46844321 4.97033327 1 P 0 ;0,1=41,2=0.000000
L 1.46844321 4.97033327 1.46791004 4.97324931 1 P 0 ;0,1=41,2=0.000000
L 1.46791004 4.97324931 1.46630984 4.97574961 1 P 0 ;0,1=41,2=0.000000
L 1.46630984 4.97574961 1.46444311 4.97658346 1 P 0 ;0,1=41,2=0.000000
L 1.46444311 4.97658346 1.45617677 4.97658346 1 P 0 ;0,1=41,2=0.000000
L 1.48430974 4.96325 1.48430974 4.98825 1 P 0 ;0,1=41,2=0.000000
L 1.48430974 4.98825 1.48110994 4.9832503 1 P 0 ;0,1=41,2=0.000000
L 1.48110994 4.96325 1.48750955 4.96325 1 P 0 ;0,1=41,2=0.000000
L 2.49228307 4.98187343 2.49335 4.98312323 1 P 0 ;0,1=42,2=0.000000
L 2.49335 4.98312323 2.4941498 4.9852061 1 P 0 ;0,1=42,2=0.000000
L 2.4941498 4.9852061 2.49468356 4.98812362 1 P 0 ;0,1=42,2=0.000000
L 2.49468356 4.98812362 2.4941498 4.99062313 1 P 0 ;0,1=42,2=0.000000
L 2.4941498 4.99062313 2.49308337 4.99228937 1 P 0 ;0,1=42,2=0.000000
L 2.49308337 4.99228937 2.49121663 4.99353996 1 P 0 ;0,1=42,2=0.000000
L 2.49121663 4.99353996 2.48401673 4.99353996 1 P 0 ;0,1=42,2=0.000000
L 2.48401673 4.99353996 2.48401673 4.96853996 1 P 0 ;0,1=42,2=0.000000
L 2.48401673 4.96853996 2.49281673 4.96853996 1 P 0 ;0,1=42,2=0.000000
L 2.49281673 4.96853996 2.49468356 4.9702062 1 P 0 ;0,1=42,2=0.000000
L 2.49468356 4.9702062 2.49575 4.9727065 1 P 0 ;0,1=42,2=0.000000
L 2.49575 4.9727065 2.49628317 4.97562323 1 P 0 ;0,1=42,2=0.000000
L 2.49628317 4.97562323 2.49575 4.97853927 1 P 0 ;0,1=42,2=0.000000
L 2.49575 4.97853927 2.4941498 4.98103957 1 P 0 ;0,1=42,2=0.000000
L 2.4941498 4.98103957 2.49228307 4.98187343 1 P 0 ;0,1=42,2=0.000000
L 2.49228307 4.98187343 2.48401673 4.98187343 1 P 0 ;0,1=42,2=0.000000
L 2.50628327 4.97353957 2.50788297 4.97062283 1 P 0 ;0,1=42,2=0.000000
L 2.50788297 4.97062283 2.51001634 4.9689565 1 P 0 ;0,1=42,2=0.000000
L 2.51001634 4.9689565 2.51241683 4.96853996 1 P 0 ;0,1=42,2=0.000000
L 2.51241683 4.96853996 2.5145502 4.9689565 1 P 0 ;0,1=42,2=0.000000
L 2.5145502 4.9689565 2.51668356 4.97103937 1 P 0 ;0,1=42,2=0.000000
L 2.51668356 4.97103937 2.51801663 4.97353957 1 P 0 ;0,1=42,2=0.000000
L 2.51801663 4.97353957 2.51828317 4.97603986 1 P 0 ;0,1=42,2=0.000000
L 2.51828317 4.97603986 2.51775 4.97895591 1 P 0 ;0,1=42,2=0.000000
L 2.51775 4.97895591 2.51588327 4.98103957 1 P 0 ;0,1=42,2=0.000000
L 2.51588327 4.98103957 2.51401644 4.98187343 1 P 0 ;0,1=42,2=0.000000
L 2.51401644 4.98187343 2.51161654 4.98187343 1 P 0 ;0,1=42,2=0.000000
L 2.51401644 4.98187343 2.51561663 4.98312323 1 P 0 ;0,1=42,2=0.000000
L 2.51561663 4.98312323 2.5169501 4.9852061 1 P 0 ;0,1=42,2=0.000000
L 2.5169501 4.9852061 2.51748337 4.9877063 1 P 0 ;0,1=42,2=0.000000
L 2.51748337 4.9877063 2.5169501 4.9902065 1 P 0 ;0,1=42,2=0.000000
L 2.5169501 4.9902065 2.51561663 4.99228937 1 P 0 ;0,1=42,2=0.000000
L 2.51561663 4.99228937 2.51321663 4.99353996 1 P 0 ;0,1=42,2=0.000000
L 2.51321663 4.99353996 2.51081663 4.99312333 1 P 0 ;0,1=42,2=0.000000
L 2.51081663 4.99312333 2.50841663 4.9914563 1 P 0 ;0,1=42,2=0.000000
L 2.53361654 4.96853996 2.5341497 4.9739562 1 P 0 ;0,1=42,2=0.000000
L 2.5341497 4.9739562 2.53495 4.97853927 1 P 0 ;0,1=42,2=0.000000
L 2.53495 4.97853927 2.53601644 4.98270659 1 P 0 ;0,1=42,2=0.000000
L 2.53601644 4.98270659 2.53735 4.98728976 1 P 0 ;0,1=42,2=0.000000
L 2.53735 4.98728976 2.53948337 4.99353996 1 P 0 ;0,1=42,2=0.000000
L 2.53948337 4.99353996 2.52881654 4.99353996 1 P 0 ;0,1=42,2=0.000000
L 2.48482293 4.84886004 2.49148967 4.87386004 1 P 0 ;0,1=43,2=0.000000
L 2.49148967 4.87386004 2.49815689 4.84886004 1 P 0 ;0,1=43,2=0.000000
L 2.4957564 4.85760965 2.48722293 4.85760965 1 P 0 ;0,1=43,2=0.000000
L 2.50762323 4.85385965 2.50922293 4.85094291 1 P 0 ;0,1=43,2=0.000000
L 2.50922293 4.85094291 2.5113563 4.84927657 1 P 0 ;0,1=43,2=0.000000
L 2.5113563 4.84927657 2.51375679 4.84886004 1 P 0 ;0,1=43,2=0.000000
L 2.51375679 4.84886004 2.51589016 4.84927657 1 P 0 ;0,1=43,2=0.000000
L 2.51589016 4.84927657 2.51802352 4.85135945 1 P 0 ;0,1=43,2=0.000000
L 2.51802352 4.85135945 2.51935659 4.85385965 1 P 0 ;0,1=43,2=0.000000
L 2.51935659 4.85385965 2.51962313 4.85635994 1 P 0 ;0,1=43,2=0.000000
L 2.51962313 4.85635994 2.51908996 4.85927598 1 P 0 ;0,1=43,2=0.000000
L 2.51908996 4.85927598 2.51722323 4.86135965 1 P 0 ;0,1=43,2=0.000000
L 2.51722323 4.86135965 2.5153564 4.8621935 1 P 0 ;0,1=43,2=0.000000
L 2.5153564 4.8621935 2.5129565 4.8621935 1 P 0 ;0,1=43,2=0.000000
L 2.5153564 4.8621935 2.51695659 4.86344331 1 P 0 ;0,1=43,2=0.000000
L 2.51695659 4.86344331 2.51829006 4.86552618 1 P 0 ;0,1=43,2=0.000000
L 2.51829006 4.86552618 2.51882333 4.86802638 1 P 0 ;0,1=43,2=0.000000
L 2.51882333 4.86802638 2.51829006 4.87052657 1 P 0 ;0,1=43,2=0.000000
L 2.51829006 4.87052657 2.51695659 4.87260945 1 P 0 ;0,1=43,2=0.000000
L 2.51695659 4.87260945 2.51455659 4.87386004 1 P 0 ;0,1=43,2=0.000000
L 2.51455659 4.87386004 2.51215659 4.87344341 1 P 0 ;0,1=43,2=0.000000
L 2.51215659 4.87344341 2.50975659 4.87177638 1 P 0 ;0,1=43,2=0.000000
L 2.5349565 4.84886004 2.53548967 4.85427628 1 P 0 ;0,1=43,2=0.000000
L 2.53548967 4.85427628 2.53628996 4.85885935 1 P 0 ;0,1=43,2=0.000000
L 2.53628996 4.85885935 2.5373564 4.86302667 1 P 0 ;0,1=43,2=0.000000
L 2.5373564 4.86302667 2.53868996 4.86760984 1 P 0 ;0,1=43,2=0.000000
L 2.53868996 4.86760984 2.54082333 4.87386004 1 P 0 ;0,1=43,2=0.000000
L 2.54082333 4.87386004 2.5301565 4.87386004 1 P 0 ;0,1=43,2=0.000000
L 7.615 4.77008002 7.64 4.77008002 3 P 0 
L 7.705 4.77008002 7.78 4.77008002 3 P 0 
L 7.845 4.77006004 7.87 4.77006004 3 P 0 
L 7.895 4.77006004 7.935 4.77005 3 P 0 
L 7.975 4.77005 8.01 4.77003996 3 P 0 
L 8.045 4.77003002 8.065 4.77003002 3 P 0 
L 8.13 4.77001998 8.21 4.77001004 3 P 0 
L 8.27 4.77 8.295 4.77 3 P 0 
L 8.365 4.77008002 8.32 4.77008002 3 P 0 
L 8.365 5.08111004 8.11 5.08111004 3 P 0 
L 8.08 5.08111004 8.05 5.08111004 3 P 0 
L 8.005 5.08111004 7.9 5.08111004 3 P 0 
L 7.87 5.08111004 7.615 5.08111004 3 P 0 
L 7.585 5.08111004 7.56728002 5.08111004 3 P 0 
L 7.50473002 4.90243996 7.50473002 4.81053996 3 P 0 
L 8.41851998 5.08111004 8.395 5.08111004 3 P 0 
L 8.47716998 4.89915 8.47716998 4.81071004 3 P 0 
L 8.47716998 5.04176004 8.47716998 4.87375 3 P 0 
L 8.4308 4.77008002 8.395 4.77008002 3 P 0 
L 7.55231998 4.77008002 7.585 4.77008002 3 P 0 
L 7.50473002 5.04351998 7.50473002 4.88888002 3 P 0 
L 7.71383317 5.49639961 7.7157501 5.49319931 2 P 0 ;0,1=46,2=0.000000
L 7.7157501 5.49319931 7.71804961 5.49106644 2 P 0 ;0,1=46,2=0.000000
L 7.71804961 5.49106644 7.72073307 5.49 2 P 0 ;0,1=46,2=0.000000
L 7.72073307 5.49 7.7237998 5.49106644 2 P 0 ;0,1=46,2=0.000000
L 7.7237998 5.49106644 7.7261 5.49319931 2 P 0 ;0,1=46,2=0.000000
L 7.7261 5.49319931 7.7284002 5.49639961 2 P 0 ;0,1=46,2=0.000000
L 7.7284002 5.49639961 7.72916673 5.50066634 2 P 0 ;0,1=46,2=0.000000
L 7.72916673 5.50066634 7.72916673 5.522 2 P 0 ;0,1=46,2=0.000000
L 7.741 5.47933366 7.764 5.47933366 2 P 0 ;0,1=46,2=0.000000
L 7.79193327 5.51933287 7.78963307 5.52093346 2 P 0 ;0,1=46,2=0.000000
L 7.78963307 5.52093346 7.7869503 5.522 2 P 0 ;0,1=46,2=0.000000
L 7.7869503 5.522 7.78388356 5.522 2 P 0 ;0,1=46,2=0.000000
L 7.78388356 5.522 7.78043287 5.52039931 2 P 0 ;0,1=46,2=0.000000
L 7.78043287 5.52039931 7.7777501 5.51773327 2 P 0 ;0,1=46,2=0.000000
L 7.7777501 5.51773327 7.77583317 5.51453297 2 P 0 ;0,1=46,2=0.000000
L 7.77583317 5.51453297 7.77429951 5.5091998 2 P 0 ;0,1=46,2=0.000000
L 7.77429951 5.5091998 7.77391624 5.5043998 2 P 0 ;0,1=46,2=0.000000
L 7.77391624 5.5043998 7.77468337 5.4995999 2 P 0 ;0,1=46,2=0.000000
L 7.77468337 5.4995999 7.77583317 5.49639961 2 P 0 ;0,1=46,2=0.000000
L 7.77583317 5.49639961 7.77813337 5.49319931 2 P 0 ;0,1=46,2=0.000000
L 7.77813337 5.49319931 7.78081683 5.49106644 2 P 0 ;0,1=46,2=0.000000
L 7.78081683 5.49106644 7.78349961 5.49 2 P 0 ;0,1=46,2=0.000000
L 7.78349961 5.49 7.78618307 5.49 2 P 0 ;0,1=46,2=0.000000
L 7.78618307 5.49 7.78886654 5.49106644 2 P 0 ;0,1=46,2=0.000000
L 7.78886654 5.49106644 7.79116673 5.49266604 2 P 0 ;0,1=46,2=0.000000
L 7.79116673 5.49266604 7.79308366 5.49479892 2 P 0 ;0,1=46,2=0.000000
L 7.80683317 5.49 7.80683317 5.522 2 P 0 ;0,1=46,2=0.000000
L 7.80683317 5.522 7.81603327 5.522 2 P 0 ;0,1=46,2=0.000000
L 7.81603327 5.522 7.8191 5.52039931 2 P 0 ;0,1=46,2=0.000000
L 7.8191 5.52039931 7.8214002 5.51666673 2 P 0 ;0,1=46,2=0.000000
L 7.8214002 5.51666673 7.82216673 5.5124 2 P 0 ;0,1=46,2=0.000000
L 7.82216673 5.5124 7.8214002 5.50813327 2 P 0 ;0,1=46,2=0.000000
L 7.8214002 5.50813327 7.81948327 5.50493307 2 P 0 ;0,1=46,2=0.000000
L 7.81948327 5.50493307 7.81603327 5.50333238 2 P 0 ;0,1=46,2=0.000000
L 7.81603327 5.50333238 7.80683317 5.50333238 2 P 0 ;0,1=46,2=0.000000
L 7.84549961 5.49 7.84549961 5.522 2 P 0 ;0,1=46,2=0.000000
L 7.84549961 5.522 7.8408999 5.5156003 2 P 0 ;0,1=46,2=0.000000
L 7.8408999 5.49 7.85009931 5.49 2 P 0 ;0,1=46,2=0.000000
L 7.865 5.47933366 7.888 5.47933366 2 P 0 ;0,1=46,2=0.000000
L 7.89868337 5.49 7.89868337 5.522 2 P 0 ;0,1=46,2=0.000000
L 7.89868337 5.522 7.91631654 5.49 2 P 0 ;0,1=46,2=0.000000
L 7.91631654 5.49 7.91631654 5.522 2 P 0 ;0,1=46,2=0.000000
L 7.92891624 5.522 7.93849961 5.49 2 P 0 ;0,1=46,2=0.000000
L 7.93849961 5.49 7.94808366 5.522 2 P 0 ;0,1=46,2=0.000000
L 7.96183317 5.522 7.96183317 5.49 2 P 0 ;0,1=46,2=0.000000
L 7.96183317 5.49 7.97716673 5.49 2 P 0 ;0,1=46,2=0.000000
L 7.9958999 5.522 8.00509931 5.522 2 P 0 ;0,1=46,2=0.000000
L 8.00049961 5.522 8.00049961 5.49 2 P 0 ;0,1=46,2=0.000000
L 7.9958999 5.49 8.00509931 5.49 2 P 0 ;0,1=46,2=0.000000
L 8.02268337 5.49 8.02268337 5.522 2 P 0 ;0,1=46,2=0.000000
L 8.02268337 5.522 8.04031654 5.49 2 P 0 ;0,1=46,2=0.000000
L 8.04031654 5.49 8.04031654 5.522 2 P 0 ;0,1=46,2=0.000000
L 8.05406663 5.49 8.05406663 5.522 2 P 0 ;0,1=46,2=0.000000
L 8.06863307 5.522 8.05406663 5.50226594 2 P 0 ;0,1=46,2=0.000000
L 8.07093327 5.49 8.06058337 5.51133268 2 P 0 ;0,1=46,2=0.000000
L 8.082 5.47933366 8.105 5.47933366 2 P 0 ;0,1=46,2=0.000000
L 8.12449961 5.522 8.12449961 5.49 2 P 0 ;0,1=46,2=0.000000
L 8.11568337 5.522 8.13331654 5.522 2 P 0 ;0,1=46,2=0.000000
L 8.15549961 5.49 8.15243287 5.49053317 2 P 0 ;0,1=46,2=0.000000
L 8.15243287 5.49053317 8.1497501 5.49266604 2 P 0 ;0,1=46,2=0.000000
L 8.1497501 5.49266604 8.1474499 5.49586634 2 P 0 ;0,1=46,2=0.000000
L 8.1474499 5.49586634 8.14591624 5.4995999 2 P 0 ;0,1=46,2=0.000000
L 8.14591624 5.4995999 8.1451497 5.50386663 2 P 0 ;0,1=46,2=0.000000
L 8.1451497 5.50386663 8.1451497 5.50813327 2 P 0 ;0,1=46,2=0.000000
L 8.1451497 5.50813327 8.14591624 5.5124 2 P 0 ;0,1=46,2=0.000000
L 8.14591624 5.5124 8.1474499 5.51613356 2 P 0 ;0,1=46,2=0.000000
L 8.1474499 5.51613356 8.1497501 5.51933287 2 P 0 ;0,1=46,2=0.000000
L 8.1497501 5.51933287 8.15243287 5.52146673 2 P 0 ;0,1=46,2=0.000000
L 8.15243287 5.52146673 8.15549961 5.522 2 P 0 ;0,1=46,2=0.000000
L 8.15549961 5.522 8.15856634 5.52146673 2 P 0 ;0,1=46,2=0.000000
L 8.15856634 5.52146673 8.1612498 5.51933287 2 P 0 ;0,1=46,2=0.000000
L 8.1612498 5.51933287 8.16355 5.51613356 2 P 0 ;0,1=46,2=0.000000
L 8.16355 5.51613356 8.16508366 5.5124 2 P 0 ;0,1=46,2=0.000000
L 8.16508366 5.5124 8.1658502 5.50813327 2 P 0 ;0,1=46,2=0.000000
L 8.1658502 5.50813327 8.1658502 5.50386663 2 P 0 ;0,1=46,2=0.000000
L 8.1658502 5.50386663 8.16508366 5.4995999 2 P 0 ;0,1=46,2=0.000000
L 8.16508366 5.4995999 8.16355 5.49586634 2 P 0 ;0,1=46,2=0.000000
L 8.16355 5.49586634 8.1612498 5.49266604 2 P 0 ;0,1=46,2=0.000000
L 8.1612498 5.49266604 8.15856634 5.49053317 2 P 0 ;0,1=46,2=0.000000
L 8.15856634 5.49053317 8.15549961 5.49 2 P 0 ;0,1=46,2=0.000000
L 8.17883317 5.49 8.17883317 5.522 2 P 0 ;0,1=46,2=0.000000
L 8.17883317 5.522 8.18803327 5.522 2 P 0 ;0,1=46,2=0.000000
L 8.18803327 5.522 8.1911 5.52039931 2 P 0 ;0,1=46,2=0.000000
L 8.1911 5.52039931 8.1934002 5.51666673 2 P 0 ;0,1=46,2=0.000000
L 8.1934002 5.51666673 8.19416673 5.5124 2 P 0 ;0,1=46,2=0.000000
L 8.19416673 5.5124 8.1934002 5.50813327 2 P 0 ;0,1=46,2=0.000000
L 8.1934002 5.50813327 8.19148327 5.50493307 2 P 0 ;0,1=46,2=0.000000
L 8.19148327 5.50493307 8.18803327 5.50333238 2 P 0 ;0,1=46,2=0.000000
L 8.18803327 5.50333238 8.17883317 5.50333238 2 P 0 ;0,1=46,2=0.000000
L 7.46052293 4.8476 7.46718967 4.8726 1 P 0 ;0,1=40,2=0.000000
L 7.46718967 4.8726 7.47385689 4.8476 1 P 0 ;0,1=40,2=0.000000
L 7.4714564 4.85634961 7.46292293 4.85634961 1 P 0 ;0,1=40,2=0.000000
L 7.48918967 4.8476 7.48918967 4.8726 1 P 0 ;0,1=40,2=0.000000
L 7.48918967 4.8726 7.48598986 4.8676003 1 P 0 ;0,1=40,2=0.000000
L 7.48598986 4.8476 7.49238947 4.8476 1 P 0 ;0,1=40,2=0.000000
L 7.46798307 4.97658346 7.46905 4.97783327 1 P 0 ;0,1=41,2=0.000000
L 7.46905 4.97783327 7.4698498 4.97991614 1 P 0 ;0,1=41,2=0.000000
L 7.4698498 4.97991614 7.47038356 4.98283366 1 P 0 ;0,1=41,2=0.000000
L 7.47038356 4.98283366 7.4698498 4.98533317 1 P 0 ;0,1=41,2=0.000000
L 7.4698498 4.98533317 7.46878337 4.98699941 1 P 0 ;0,1=41,2=0.000000
L 7.46878337 4.98699941 7.46691663 4.98825 1 P 0 ;0,1=41,2=0.000000
L 7.46691663 4.98825 7.45971673 4.98825 1 P 0 ;0,1=41,2=0.000000
L 7.45971673 4.98825 7.45971673 4.96325 1 P 0 ;0,1=41,2=0.000000
L 7.45971673 4.96325 7.46851673 4.96325 1 P 0 ;0,1=41,2=0.000000
L 7.46851673 4.96325 7.47038356 4.96491624 1 P 0 ;0,1=41,2=0.000000
L 7.47038356 4.96491624 7.47145 4.96741654 1 P 0 ;0,1=41,2=0.000000
L 7.47145 4.96741654 7.47198317 4.97033327 1 P 0 ;0,1=41,2=0.000000
L 7.47198317 4.97033327 7.47145 4.97324931 1 P 0 ;0,1=41,2=0.000000
L 7.47145 4.97324931 7.4698498 4.97574961 1 P 0 ;0,1=41,2=0.000000
L 7.4698498 4.97574961 7.46798307 4.97658346 1 P 0 ;0,1=41,2=0.000000
L 7.46798307 4.97658346 7.45971673 4.97658346 1 P 0 ;0,1=41,2=0.000000
L 7.4878497 4.96325 7.4878497 4.98825 1 P 0 ;0,1=41,2=0.000000
L 7.4878497 4.98825 7.4846499 4.9832503 1 P 0 ;0,1=41,2=0.000000
L 7.4846499 4.96325 7.49104951 4.96325 1 P 0 ;0,1=41,2=0.000000
L 8.49582303 4.98187343 8.49688996 4.98312323 1 P 0 ;0,1=42,2=0.000000
L 8.49688996 4.98312323 8.49768976 4.9852061 1 P 0 ;0,1=42,2=0.000000
L 8.49768976 4.9852061 8.49822352 4.98812362 1 P 0 ;0,1=42,2=0.000000
L 8.49822352 4.98812362 8.49768976 4.99062313 1 P 0 ;0,1=42,2=0.000000
L 8.49768976 4.99062313 8.49662333 4.99228937 1 P 0 ;0,1=42,2=0.000000
L 8.49662333 4.99228937 8.49475659 4.99353996 1 P 0 ;0,1=42,2=0.000000
L 8.49475659 4.99353996 8.48755669 4.99353996 1 P 0 ;0,1=42,2=0.000000
L 8.48755669 4.99353996 8.48755669 4.96853996 1 P 0 ;0,1=42,2=0.000000
L 8.48755669 4.96853996 8.49635669 4.96853996 1 P 0 ;0,1=42,2=0.000000
L 8.49635669 4.96853996 8.49822352 4.9702062 1 P 0 ;0,1=42,2=0.000000
L 8.49822352 4.9702062 8.49928996 4.9727065 1 P 0 ;0,1=42,2=0.000000
L 8.49928996 4.9727065 8.49982313 4.97562323 1 P 0 ;0,1=42,2=0.000000
L 8.49982313 4.97562323 8.49928996 4.97853927 1 P 0 ;0,1=42,2=0.000000
L 8.49928996 4.97853927 8.49768976 4.98103957 1 P 0 ;0,1=42,2=0.000000
L 8.49768976 4.98103957 8.49582303 4.98187343 1 P 0 ;0,1=42,2=0.000000
L 8.49582303 4.98187343 8.48755669 4.98187343 1 P 0 ;0,1=42,2=0.000000
L 8.50982323 4.97353957 8.51142293 4.97062283 1 P 0 ;0,1=42,2=0.000000
L 8.51142293 4.97062283 8.5135563 4.9689565 1 P 0 ;0,1=42,2=0.000000
L 8.5135563 4.9689565 8.51595679 4.96853996 1 P 0 ;0,1=42,2=0.000000
L 8.51595679 4.96853996 8.51809016 4.9689565 1 P 0 ;0,1=42,2=0.000000
L 8.51809016 4.9689565 8.52022352 4.97103937 1 P 0 ;0,1=42,2=0.000000
L 8.52022352 4.97103937 8.52155659 4.97353957 1 P 0 ;0,1=42,2=0.000000
L 8.52155659 4.97353957 8.52182313 4.97603986 1 P 0 ;0,1=42,2=0.000000
L 8.52182313 4.97603986 8.52128996 4.97895591 1 P 0 ;0,1=42,2=0.000000
L 8.52128996 4.97895591 8.51942323 4.98103957 1 P 0 ;0,1=42,2=0.000000
L 8.51942323 4.98103957 8.5175564 4.98187343 1 P 0 ;0,1=42,2=0.000000
L 8.5175564 4.98187343 8.5151565 4.98187343 1 P 0 ;0,1=42,2=0.000000
L 8.5175564 4.98187343 8.51915659 4.98312323 1 P 0 ;0,1=42,2=0.000000
L 8.51915659 4.98312323 8.52049006 4.9852061 1 P 0 ;0,1=42,2=0.000000
L 8.52049006 4.9852061 8.52102333 4.9877063 1 P 0 ;0,1=42,2=0.000000
L 8.52102333 4.9877063 8.52049006 4.9902065 1 P 0 ;0,1=42,2=0.000000
L 8.52049006 4.9902065 8.51915659 4.99228937 1 P 0 ;0,1=42,2=0.000000
L 8.51915659 4.99228937 8.51675659 4.99353996 1 P 0 ;0,1=42,2=0.000000
L 8.51675659 4.99353996 8.51435659 4.99312333 1 P 0 ;0,1=42,2=0.000000
L 8.51435659 4.99312333 8.51195659 4.9914563 1 P 0 ;0,1=42,2=0.000000
L 8.5371565 4.96853996 8.53768967 4.9739562 1 P 0 ;0,1=42,2=0.000000
L 8.53768967 4.9739562 8.53848996 4.97853927 1 P 0 ;0,1=42,2=0.000000
L 8.53848996 4.97853927 8.5395564 4.98270659 1 P 0 ;0,1=42,2=0.000000
L 8.5395564 4.98270659 8.54088996 4.98728976 1 P 0 ;0,1=42,2=0.000000
L 8.54088996 4.98728976 8.54302333 4.99353996 1 P 0 ;0,1=42,2=0.000000
L 8.54302333 4.99353996 8.5323565 4.99353996 1 P 0 ;0,1=42,2=0.000000
L 8.48836299 4.84886004 8.49502972 4.87386004 1 P 0 ;0,1=43,2=0.000000
L 8.49502972 4.87386004 8.50169695 4.84886004 1 P 0 ;0,1=43,2=0.000000
L 8.49929646 4.85760965 8.49076299 4.85760965 1 P 0 ;0,1=43,2=0.000000
L 8.51116329 4.85385965 8.51276299 4.85094291 1 P 0 ;0,1=43,2=0.000000
L 8.51276299 4.85094291 8.51489636 4.84927657 1 P 0 ;0,1=43,2=0.000000
L 8.51489636 4.84927657 8.51729685 4.84886004 1 P 0 ;0,1=43,2=0.000000
L 8.51729685 4.84886004 8.51943022 4.84927657 1 P 0 ;0,1=43,2=0.000000
L 8.51943022 4.84927657 8.52156358 4.85135945 1 P 0 ;0,1=43,2=0.000000
L 8.52156358 4.85135945 8.52289665 4.85385965 1 P 0 ;0,1=43,2=0.000000
L 8.52289665 4.85385965 8.52316319 4.85635994 1 P 0 ;0,1=43,2=0.000000
L 8.52316319 4.85635994 8.52263002 4.85927598 1 P 0 ;0,1=43,2=0.000000
L 8.52263002 4.85927598 8.52076329 4.86135965 1 P 0 ;0,1=43,2=0.000000
L 8.52076329 4.86135965 8.51889646 4.8621935 1 P 0 ;0,1=43,2=0.000000
L 8.51889646 4.8621935 8.51649656 4.8621935 1 P 0 ;0,1=43,2=0.000000
L 8.51889646 4.8621935 8.52049665 4.86344331 1 P 0 ;0,1=43,2=0.000000
L 8.52049665 4.86344331 8.52183012 4.86552618 1 P 0 ;0,1=43,2=0.000000
L 8.52183012 4.86552618 8.52236339 4.86802638 1 P 0 ;0,1=43,2=0.000000
L 8.52236339 4.86802638 8.52183012 4.87052657 1 P 0 ;0,1=43,2=0.000000
L 8.52183012 4.87052657 8.52049665 4.87260945 1 P 0 ;0,1=43,2=0.000000
L 8.52049665 4.87260945 8.51809665 4.87386004 1 P 0 ;0,1=43,2=0.000000
L 8.51809665 4.87386004 8.51569665 4.87344341 1 P 0 ;0,1=43,2=0.000000
L 8.51569665 4.87344341 8.51329665 4.87177638 1 P 0 ;0,1=43,2=0.000000
L 8.53849656 4.84886004 8.53902972 4.85427628 1 P 0 ;0,1=43,2=0.000000
L 8.53902972 4.85427628 8.53983002 4.85885935 1 P 0 ;0,1=43,2=0.000000
L 8.53983002 4.85885935 8.54089646 4.86302667 1 P 0 ;0,1=43,2=0.000000
L 8.54089646 4.86302667 8.54223002 4.86760984 1 P 0 ;0,1=43,2=0.000000
L 8.54223002 4.86760984 8.54436339 4.87386004 1 P 0 ;0,1=43,2=0.000000
L 8.54436339 4.87386004 8.53369656 4.87386004 1 P 0 ;0,1=43,2=0.000000
L 0.54323002 5.67156998 0.54323002 5.56843002 1 P 0 
L 0.54323002 5.56843002 0.49676998 5.56843002 1 P 0 
L 0.49676998 5.56843002 0.49676998 5.67156998 1 P 0 
L 0.49676998 5.67156998 0.54323002 5.67156998 1 P 0 
L 0.57141998 5.63826998 0.57771998 5.64456998 1 P 0 
L 0.57771998 5.64456998 0.58046998 5.64181004 1 P 0 
L 0.58046998 5.64181004 0.58046998 5.64693002 1 P 0 
L 0.58046998 5.64693002 0.57535 5.64693002 1 P 0 
L 0.57535 5.64693002 0.58046998 5.64181004 1 P 0 
L 0.57201004 5.62488002 0.57831004 5.63118002 1 P 0 
L 0.57831004 5.63118002 0.58106004 5.62843002 1 P 0 
L 0.58106004 5.62843002 0.58106004 5.63353996 1 P 0 
L 0.58106004 5.63353996 0.57593996 5.63353996 1 P 0 
L 0.57593996 5.63353996 0.58106004 5.62843002 1 P 0 
L 0.56461004 5.61668996 0.57798996 5.6037 1 P 0 
L 0.57798996 5.6037 0.56381998 5.6037 1 P 0 
L 0.56381998 5.6037 0.56381998 5.58243996 1 P 0 
L 0.56381998 5.58243996 0.56381998 5.6037 1 P 0 
L 0.56381998 5.6037 0.55121998 5.6037 1 P 0 
L 0.55121998 5.6037 0.56421004 5.61668996 1 P 0 
L 0.56421004 5.61668996 0.56421004 5.63676998 1 P 0 
L 0.56421004 5.63676998 0.56421004 5.61668996 1 P 0 
L 0.56421004 5.61668996 0.55121998 5.61668996 1 P 0 
L 0.55121998 5.61668996 0.57798996 5.61668996 1 P 0 
S P 0
OB 0.544130019685 5.67318996063 I
OS 0.495830019685 5.67318996063
OS 0.495830019685 5.67945
OS 0.544130019685 5.67945
OS 0.544130019685 5.67318996063
OE
SE
L 0.4 5.55266654 0.425 5.55266654 2 P 0 ;0,1=47,2=270.000000
L 0.425 5.55266654 0.425 5.56333337 2 P 0 ;0,1=47,2=270.000000
L 0.425 5.58733337 0.425 5.57666654 2 P 0 ;0,1=47,2=270.000000
L 0.425 5.57666654 0.4 5.57666654 2 P 0 ;0,1=47,2=270.000000
L 0.4 5.57666654 0.4 5.58733337 2 P 0 ;0,1=47,2=270.000000
L 0.41208307 5.58306663 0.41208307 5.57666654 2 P 0 ;0,1=47,2=270.000000
L 0.425 5.60013327 0.4 5.60013327 2 P 0 ;0,1=47,2=270.000000
L 0.4 5.60013327 0.4 5.60546654 2 P 0 ;0,1=47,2=270.000000
L 0.4 5.60546654 0.40125059 5.6075999 2 P 0 ;0,1=47,2=270.000000
L 0.40125059 5.6075999 0.40291683 5.6092 2 P 0 ;0,1=47,2=270.000000
L 0.40291683 5.6092 0.40541634 5.61053356 2 P 0 ;0,1=47,2=270.000000
L 0.40541634 5.61053356 0.40833386 5.6116 2 P 0 ;0,1=47,2=270.000000
L 0.40833386 5.6116 0.41250039 5.61186663 2 P 0 ;0,1=47,2=270.000000
L 0.41250039 5.61186663 0.41666693 5.6116 2 P 0 ;0,1=47,2=270.000000
L 0.41666693 5.6116 0.41958376 5.61053356 2 P 0 ;0,1=47,2=270.000000
L 0.41958376 5.61053356 0.42208396 5.6092 2 P 0 ;0,1=47,2=270.000000
L 0.42208396 5.6092 0.4237503 5.6075999 2 P 0 ;0,1=47,2=270.000000
L 0.4237503 5.6075999 0.425 5.60546654 2 P 0 ;0,1=47,2=270.000000
L 0.425 5.60546654 0.425 5.60013327 2 P 0 ;0,1=47,2=270.000000
L 0.43333307 5.622 0.43333307 5.638 2 P 0 ;0,1=47,2=270.000000
L 0.41250039 5.6555999 0.41250039 5.66093346 2 P 0 ;0,1=47,2=270.000000
L 0.41250039 5.66093346 0.42000039 5.66093346 2 P 0 ;0,1=47,2=270.000000
L 0.42000039 5.66093346 0.42250059 5.65933337 2 P 0 ;0,1=47,2=270.000000
L 0.42250059 5.65933337 0.42416693 5.65746663 2 P 0 ;0,1=47,2=270.000000
L 0.42416693 5.65746663 0.425 5.6548 2 P 0 ;0,1=47,2=270.000000
L 0.425 5.6548 0.42416693 5.65213346 2 P 0 ;0,1=47,2=270.000000
L 0.42416693 5.65213346 0.42250059 5.65026663 2 P 0 ;0,1=47,2=270.000000
L 0.42250059 5.65026663 0.42000039 5.64866654 2 P 0 ;0,1=47,2=270.000000
L 0.42000039 5.64866654 0.41708356 5.64759961 2 P 0 ;0,1=47,2=270.000000
L 0.41708356 5.64759961 0.4137502 5.64706644 2 P 0 ;0,1=47,2=270.000000
L 0.4137502 5.64706644 0.41083337 5.64706644 2 P 0 ;0,1=47,2=270.000000
L 0.41083337 5.64706644 0.40833386 5.64759961 2 P 0 ;0,1=47,2=270.000000
L 0.40833386 5.64759961 0.40541634 5.64866654 2 P 0 ;0,1=47,2=270.000000
L 0.40541634 5.64866654 0.40291683 5.65026663 2 P 0 ;0,1=47,2=270.000000
L 0.40291683 5.65026663 0.40125059 5.65186634 2 P 0 ;0,1=47,2=270.000000
L 0.40125059 5.65186634 0.4 5.6539997 2 P 0 ;0,1=47,2=270.000000
L 0.4 5.6539997 0.4 5.65586644 2 P 0 ;0,1=47,2=270.000000
L 0.4 5.65586644 0.40083317 5.6579998 2 P 0 ;0,1=47,2=270.000000
L 0.40083317 5.6579998 0.4025003 5.6596 2 P 0 ;0,1=47,2=270.000000
L 0.425 5.67266654 0.4 5.67266654 2 P 0 ;0,1=47,2=270.000000
L 0.4 5.67266654 0.4 5.67906663 2 P 0 ;0,1=47,2=270.000000
L 0.4 5.67906663 0.40125059 5.6812 2 P 0 ;0,1=47,2=270.000000
L 0.40125059 5.6812 0.40416663 5.6828001 2 P 0 ;0,1=47,2=270.000000
L 0.40416663 5.6828001 0.4075 5.68333337 2 P 0 ;0,1=47,2=270.000000
L 0.4075 5.68333337 0.41083337 5.6828001 2 P 0 ;0,1=47,2=270.000000
L 0.41083337 5.6828001 0.41333356 5.68146663 2 P 0 ;0,1=47,2=270.000000
L 0.41333356 5.68146663 0.41458406 5.67906663 2 P 0 ;0,1=47,2=270.000000
L 0.41458406 5.67906663 0.41458406 5.67266654 2 P 0 ;0,1=47,2=270.000000
L 0.4 5.69613327 0.41791673 5.69613327 2 P 0 ;0,1=47,2=270.000000
L 0.41791673 5.69613327 0.42166742 5.6971998 2 P 0 ;0,1=47,2=270.000000
L 0.42166742 5.6971998 0.42416693 5.69933317 2 P 0 ;0,1=47,2=270.000000
L 0.42416693 5.69933317 0.425 5.7019997 2 P 0 ;0,1=47,2=270.000000
L 0.425 5.7019997 0.42416693 5.70466673 2 P 0 ;0,1=47,2=270.000000
L 0.42416693 5.70466673 0.42166742 5.7068001 2 P 0 ;0,1=47,2=270.000000
L 0.42166742 5.7068001 0.41791673 5.70786663 2 P 0 ;0,1=47,2=270.000000
L 0.41791673 5.70786663 0.4 5.70786663 2 P 0 ;0,1=47,2=270.000000
L 0.43333307 5.718 0.43333307 5.734 2 P 0 ;0,1=47,2=270.000000
L 0.425 5.74466654 0.4 5.74466654 2 P 0 ;0,1=47,2=270.000000
L 0.4 5.74466654 0.4 5.75106663 2 P 0 ;0,1=47,2=270.000000
L 0.4 5.75106663 0.40125059 5.7532 2 P 0 ;0,1=47,2=270.000000
L 0.40125059 5.7532 0.40416663 5.7548001 2 P 0 ;0,1=47,2=270.000000
L 0.40416663 5.7548001 0.4075 5.75533337 2 P 0 ;0,1=47,2=270.000000
L 0.4075 5.75533337 0.41083337 5.7548001 2 P 0 ;0,1=47,2=270.000000
L 0.41083337 5.7548001 0.41333356 5.75346663 2 P 0 ;0,1=47,2=270.000000
L 0.41333356 5.75346663 0.41458406 5.75106663 2 P 0 ;0,1=47,2=270.000000
L 0.41458406 5.75106663 0.41458406 5.74466654 2 P 0 ;0,1=47,2=270.000000
L 0.4 5.766 0.425 5.76973297 2 P 0 ;0,1=47,2=270.000000
L 0.425 5.76973297 0.4 5.7739997 2 P 0 ;0,1=47,2=270.000000
L 0.4 5.7739997 0.425 5.77826644 2 P 0 ;0,1=47,2=270.000000
L 0.425 5.77826644 0.4 5.782 2 P 0 ;0,1=47,2=270.000000
L 0.425 5.79266654 0.4 5.79266654 2 P 0 ;0,1=47,2=270.000000
L 0.4 5.79266654 0.4 5.79933327 2 P 0 ;0,1=47,2=270.000000
L 0.4 5.79933327 0.40125059 5.80146663 2 P 0 ;0,1=47,2=270.000000
L 0.40125059 5.80146663 0.40291683 5.8028001 2 P 0 ;0,1=47,2=270.000000
L 0.40291683 5.8028001 0.4062502 5.80333337 2 P 0 ;0,1=47,2=270.000000
L 0.4062502 5.80333337 0.40958366 5.8028001 2 P 0 ;0,1=47,2=270.000000
L 0.40958366 5.8028001 0.41166654 5.8012 2 P 0 ;0,1=47,2=270.000000
L 0.41166654 5.8012 0.41291703 5.79933327 2 P 0 ;0,1=47,2=270.000000
L 0.41291703 5.79933327 0.41291703 5.79266654 2 P 0 ;0,1=47,2=270.000000
L 0.41291703 5.79933327 0.425 5.80333337 2 P 0 ;0,1=47,2=270.000000
L 0.43333307 5.814 0.43333307 5.83 2 P 0 ;0,1=47,2=270.000000
L 0.425 5.84066654 0.4 5.84066654 2 P 0 ;0,1=47,2=270.000000
L 0.4 5.84066654 0.4 5.84706663 2 P 0 ;0,1=47,2=270.000000
L 0.4 5.84706663 0.40125059 5.8492 2 P 0 ;0,1=47,2=270.000000
L 0.40125059 5.8492 0.40416663 5.8508001 2 P 0 ;0,1=47,2=270.000000
L 0.40416663 5.8508001 0.4075 5.85133337 2 P 0 ;0,1=47,2=270.000000
L 0.4075 5.85133337 0.41083337 5.8508001 2 P 0 ;0,1=47,2=270.000000
L 0.41083337 5.8508001 0.41333356 5.84946663 2 P 0 ;0,1=47,2=270.000000
L 0.41333356 5.84946663 0.41458406 5.84706663 2 P 0 ;0,1=47,2=270.000000
L 0.41458406 5.84706663 0.41458406 5.84066654 2 P 0 ;0,1=47,2=270.000000
L 0.41250039 5.8715999 0.41250039 5.87693346 2 P 0 ;0,1=47,2=270.000000
L 0.41250039 5.87693346 0.42000039 5.87693346 2 P 0 ;0,1=47,2=270.000000
L 0.42000039 5.87693346 0.42250059 5.87533337 2 P 0 ;0,1=47,2=270.000000
L 0.42250059 5.87533337 0.42416693 5.87346663 2 P 0 ;0,1=47,2=270.000000
L 0.42416693 5.87346663 0.425 5.8708 2 P 0 ;0,1=47,2=270.000000
L 0.425 5.8708 0.42416693 5.86813346 2 P 0 ;0,1=47,2=270.000000
L 0.42416693 5.86813346 0.42250059 5.86626663 2 P 0 ;0,1=47,2=270.000000
L 0.42250059 5.86626663 0.42000039 5.86466654 2 P 0 ;0,1=47,2=270.000000
L 0.42000039 5.86466654 0.41708356 5.86359961 2 P 0 ;0,1=47,2=270.000000
L 0.41708356 5.86359961 0.4137502 5.86306644 2 P 0 ;0,1=47,2=270.000000
L 0.4137502 5.86306644 0.41083337 5.86306644 2 P 0 ;0,1=47,2=270.000000
L 0.41083337 5.86306644 0.40833386 5.86359961 2 P 0 ;0,1=47,2=270.000000
L 0.40833386 5.86359961 0.40541634 5.86466654 2 P 0 ;0,1=47,2=270.000000
L 0.40541634 5.86466654 0.40291683 5.86626663 2 P 0 ;0,1=47,2=270.000000
L 0.40291683 5.86626663 0.40125059 5.86786634 2 P 0 ;0,1=47,2=270.000000
L 0.40125059 5.86786634 0.4 5.8699997 2 P 0 ;0,1=47,2=270.000000
L 0.4 5.8699997 0.4 5.87186644 2 P 0 ;0,1=47,2=270.000000
L 0.4 5.87186644 0.40083317 5.8739998 2 P 0 ;0,1=47,2=270.000000
L 0.40083317 5.8739998 0.4025003 5.8756 2 P 0 ;0,1=47,2=270.000000
L 0.55155 5.56942707 0.57655 5.56276033 2 P 0 ;0,1=48,2=90.000000
L 0.57655 5.56276033 0.55155 5.55609311 2 P 0 ;0,1=48,2=90.000000
L 0.56029961 5.5584936 0.56029961 5.56702707 2 P 0 ;0,1=48,2=90.000000
L 0.57446634 5.65925335 0.57571683 5.66085354 2 P 0 ;0,1=49,2=90.000000
L 0.57571683 5.66085354 0.57655 5.66271978 2 P 0 ;0,1=49,2=90.000000
L 0.57655 5.66271978 0.57655 5.66485315 2 P 0 ;0,1=49,2=90.000000
L 0.57655 5.66485315 0.57529941 5.66725364 2 P 0 ;0,1=49,2=90.000000
L 0.57529941 5.66725364 0.57321654 5.66911988 2 P 0 ;0,1=49,2=90.000000
L 0.57321654 5.66911988 0.57071634 5.67045344 2 P 0 ;0,1=49,2=90.000000
L 0.57071634 5.67045344 0.5665498 5.67152037 2 P 0 ;0,1=49,2=90.000000
L 0.5665498 5.67152037 0.5627998 5.67178701 2 P 0 ;0,1=49,2=90.000000
L 0.5627998 5.67178701 0.5590499 5.67125325 2 P 0 ;0,1=49,2=90.000000
L 0.5590499 5.67125325 0.55654961 5.67045344 2 P 0 ;0,1=49,2=90.000000
L 0.55654961 5.67045344 0.55404941 5.66885335 2 P 0 ;0,1=49,2=90.000000
L 0.55404941 5.66885335 0.55238307 5.66698652 2 P 0 ;0,1=49,2=90.000000
L 0.55238307 5.66698652 0.55155 5.66512028 2 P 0 ;0,1=49,2=90.000000
L 0.55155 5.66512028 0.55155 5.66325354 2 P 0 ;0,1=49,2=90.000000
L 0.55155 5.66325354 0.55238307 5.66138671 2 P 0 ;0,1=49,2=90.000000
L 0.55238307 5.66138671 0.55363287 5.65978661 2 P 0 ;0,1=49,2=90.000000
L 0.55363287 5.65978661 0.55529911 5.65845305 2 P 0 ;0,1=49,2=90.000000
L 4.81118002 5.54731998 4.82298996 5.54731998 3 P 0 
L 4.82298996 5.54731998 4.82298996 5.71268002 3 P 0 
L 4.82298996 5.71268002 4.81196998 5.71268002 3 P 0 
A 4.76786998 5.64968996 4.76786998 5.64968996 4.76 5.64968996 3 P 0 N
A 4.76786998 5.61031004 4.76786998 5.61031004 4.76 5.61031004 3 P 0 N
L 4.76771998 5.64965 4.78063002 5.6165 3 P 0 
L 4.70803002 5.71268002 4.69701004 5.71268002 3 P 0 
L 4.69701004 5.71268002 4.69701004 5.54731998 3 P 0 
L 4.69701004 5.54731998 4.70803002 5.54731998 3 P 0 
L 4.76 5.67646004 4.76 5.65756004 3 P 0 
L 4.76 5.60243996 4.76 5.58353996 3 P 0 
L 4.7234499 5.80926575 4.72651663 5.80659961 2 P 0 ;0,1=50,2=0.000000
L 4.72651663 5.80659961 4.72996663 5.805 2 P 0 ;0,1=50,2=0.000000
L 4.72996663 5.805 4.73303327 5.805 2 P 0 ;0,1=50,2=0.000000
L 4.73303327 5.805 4.7361 5.80659961 2 P 0 ;0,1=50,2=0.000000
L 4.7361 5.80659961 4.7384002 5.80926575 2 P 0 ;0,1=50,2=0.000000
L 4.7384002 5.80926575 4.73955 5.8130002 2 P 0 ;0,1=50,2=0.000000
L 4.73955 5.8130002 4.73878346 5.81673278 2 P 0 ;0,1=50,2=0.000000
L 4.73878346 5.81673278 4.73686654 5.81993307 2 P 0 ;0,1=50,2=0.000000
L 4.73686654 5.81993307 4.73341654 5.82206683 2 P 0 ;0,1=50,2=0.000000
L 4.73341654 5.82206683 4.72881683 5.82313327 2 P 0 ;0,1=50,2=0.000000
L 4.72881683 5.82313327 4.72613337 5.82526624 2 P 0 ;0,1=50,2=0.000000
L 4.72613337 5.82526624 4.72498287 5.8289997 2 P 0 ;0,1=50,2=0.000000
L 4.72498287 5.8289997 4.7257501 5.83273327 2 P 0 ;0,1=50,2=0.000000
L 4.7257501 5.83273327 4.72766634 5.83539931 2 P 0 ;0,1=50,2=0.000000
L 4.72766634 5.83539931 4.7303498 5.837 2 P 0 ;0,1=50,2=0.000000
L 4.7303498 5.837 4.73303327 5.837 2 P 0 ;0,1=50,2=0.000000
L 4.73303327 5.837 4.73571673 5.83593346 2 P 0 ;0,1=50,2=0.000000
L 4.73571673 5.83593346 4.73801703 5.83326644 2 P 0 ;0,1=50,2=0.000000
L 4.751 5.837 4.75636614 5.805 2 P 0 ;0,1=50,2=0.000000
L 4.75636614 5.805 4.76249961 5.837 2 P 0 ;0,1=50,2=0.000000
L 4.76249961 5.837 4.76863307 5.805 2 P 0 ;0,1=50,2=0.000000
L 4.76863307 5.805 4.774 5.837 2 P 0 ;0,1=50,2=0.000000
L 4.79349961 5.805 4.79349961 5.837 2 P 0 ;0,1=50,2=0.000000
L 4.79349961 5.837 4.7888999 5.8306003 2 P 0 ;0,1=50,2=0.000000
L 4.7888999 5.805 4.79809931 5.805 2 P 0 ;0,1=50,2=0.000000
L 4.63421004 5.7235 4.63421004 5.5365 3 P 0 
L 4.63421004 5.5365 4.48578996 5.5365 3 P 0 
L 4.48578996 5.5365 4.48578996 5.7235 3 P 0 
L 4.48578996 5.7235 4.63421004 5.7235 3 P 0 
L 4.56906004 5.5926 4.60055 5.5926 3 P 0 
L 4.60055 5.5926 4.60055 5.6674 3 P 0 
L 4.60055 5.6674 4.56906004 5.6674 3 P 0 
L 4.56906004 5.6674 4.56906004 5.5926 3 P 0 
L 4.56906004 5.5926 4.60055 5.5926 3 P 0 
L 4.60055 5.5926 4.60055 5.62016004 3 P 0 
L 4.60055 5.62016004 4.56906004 5.62016004 3 P 0 
L 4.51906004 5.5926 4.55055 5.5926 3 P 0 
L 4.55055 5.5926 4.55055 5.6674 3 P 0 
L 4.55055 5.6674 4.51906004 5.6674 3 P 0 
L 4.51906004 5.6674 4.51906004 5.5926 3 P 0 
L 4.51906004 5.5926 4.55055 5.5926 3 P 0 
L 4.55055 5.5926 4.55055 5.62016004 3 P 0 
L 4.55055 5.62016004 4.51906004 5.62016004 3 P 0 
L 4.59268002 5.72338002 4.59268002 5.74306004 3 P 0 
L 4.59268002 5.74306004 4.57693002 5.74306004 3 P 0 
L 4.57693002 5.74306004 4.57693002 5.72338002 3 P 0 
L 4.57693002 5.72338002 4.59268002 5.72338002 3 P 0 
L 4.54268002 5.72338002 4.54268002 5.74306004 3 P 0 
L 4.54268002 5.74306004 4.52693002 5.74306004 3 P 0 
L 4.52693002 5.74306004 4.52693002 5.72338002 3 P 0 
L 4.52693002 5.72338002 4.54268002 5.72338002 3 P 0 
L 4.59268002 5.51693996 4.59268002 5.53661998 3 P 0 
L 4.59268002 5.53661998 4.57693002 5.53661998 3 P 0 
L 4.57693002 5.53661998 4.57693002 5.51693996 3 P 0 
L 4.57693002 5.51693996 4.59268002 5.51693996 3 P 0 
L 4.54268002 5.51693996 4.54268002 5.53661998 3 P 0 
L 4.54268002 5.53661998 4.52693002 5.53661998 3 P 0 
L 4.52693002 5.53661998 4.52693002 5.51693996 3 P 0 
L 4.52693002 5.51693996 4.54268002 5.51693996 3 P 0 
L 4.5234499 5.87926575 4.52651663 5.87659961 2 P 0 ;0,1=51,2=0.000000
L 4.52651663 5.87659961 4.52996663 5.875 2 P 0 ;0,1=51,2=0.000000
L 4.52996663 5.875 4.53303327 5.875 2 P 0 ;0,1=51,2=0.000000
L 4.53303327 5.875 4.5361 5.87659961 2 P 0 ;0,1=51,2=0.000000
L 4.5361 5.87659961 4.5384002 5.87926575 2 P 0 ;0,1=51,2=0.000000
L 4.5384002 5.87926575 4.53955 5.8830002 2 P 0 ;0,1=51,2=0.000000
L 4.53955 5.8830002 4.53878346 5.88673278 2 P 0 ;0,1=51,2=0.000000
L 4.53878346 5.88673278 4.53686654 5.88993307 2 P 0 ;0,1=51,2=0.000000
L 4.53686654 5.88993307 4.53341654 5.89206683 2 P 0 ;0,1=51,2=0.000000
L 4.53341654 5.89206683 4.52881683 5.89313327 2 P 0 ;0,1=51,2=0.000000
L 4.52881683 5.89313327 4.52613337 5.89526624 2 P 0 ;0,1=51,2=0.000000
L 4.52613337 5.89526624 4.52498287 5.8989997 2 P 0 ;0,1=51,2=0.000000
L 4.52498287 5.8989997 4.5257501 5.90273327 2 P 0 ;0,1=51,2=0.000000
L 4.5257501 5.90273327 4.52766634 5.90539931 2 P 0 ;0,1=51,2=0.000000
L 4.52766634 5.90539931 4.5303498 5.907 2 P 0 ;0,1=51,2=0.000000
L 4.5303498 5.907 4.53303327 5.907 2 P 0 ;0,1=51,2=0.000000
L 4.53303327 5.907 4.53571673 5.90593346 2 P 0 ;0,1=51,2=0.000000
L 4.53571673 5.90593346 4.53801703 5.90326644 2 P 0 ;0,1=51,2=0.000000
L 4.551 5.907 4.55636614 5.875 2 P 0 ;0,1=51,2=0.000000
L 4.55636614 5.875 4.56249961 5.907 2 P 0 ;0,1=51,2=0.000000
L 4.56249961 5.907 4.56863307 5.875 2 P 0 ;0,1=51,2=0.000000
L 4.56863307 5.875 4.574 5.907 2 P 0 ;0,1=51,2=0.000000
L 4.58506663 5.88139961 4.58736614 5.87766604 2 P 0 ;0,1=51,2=0.000000
L 4.58736614 5.87766604 4.59043287 5.87553317 2 P 0 ;0,1=51,2=0.000000
L 4.59043287 5.87553317 4.59388356 5.875 2 P 0 ;0,1=51,2=0.000000
L 4.59388356 5.875 4.5969503 5.87553317 2 P 0 ;0,1=51,2=0.000000
L 4.5969503 5.87553317 4.60001703 5.87819931 2 P 0 ;0,1=51,2=0.000000
L 4.60001703 5.87819931 4.60193327 5.88139961 2 P 0 ;0,1=51,2=0.000000
L 4.60193327 5.88139961 4.60231654 5.8845999 2 P 0 ;0,1=51,2=0.000000
L 4.60231654 5.8845999 4.60155 5.88833238 2 P 0 ;0,1=51,2=0.000000
L 4.60155 5.88833238 4.59886654 5.89099951 2 P 0 ;0,1=51,2=0.000000
L 4.59886654 5.89099951 4.59618307 5.89206683 2 P 0 ;0,1=51,2=0.000000
L 4.59618307 5.89206683 4.59273307 5.89206683 2 P 0 ;0,1=51,2=0.000000
L 4.59618307 5.89206683 4.59848327 5.89366654 2 P 0 ;0,1=51,2=0.000000
L 4.59848327 5.89366654 4.6004002 5.89633268 2 P 0 ;0,1=51,2=0.000000
L 4.6004002 5.89633268 4.60116673 5.89953297 2 P 0 ;0,1=51,2=0.000000
L 4.60116673 5.89953297 4.6004002 5.90273327 2 P 0 ;0,1=51,2=0.000000
L 4.6004002 5.90273327 4.59848327 5.90539931 2 P 0 ;0,1=51,2=0.000000
L 4.59848327 5.90539931 4.59503327 5.907 2 P 0 ;0,1=51,2=0.000000
L 4.59503327 5.907 4.59158337 5.90646673 2 P 0 ;0,1=51,2=0.000000
L 4.59158337 5.90646673 4.58813337 5.90433287 2 P 0 ;0,1=51,2=0.000000
L 4.58461969 5.82306004 4.58461969 5.84806004 2 P 0 ;0,1=52,2=0.000000
L 4.58461969 5.84806004 4.58141988 5.84306033 2 P 0 ;0,1=52,2=0.000000
L 4.58141988 5.82306004 4.58781949 5.82306004 2 P 0 ;0,1=52,2=0.000000
L 4.52837313 5.84389341 4.52997323 5.84639291 2 P 0 ;0,1=53,2=0.000000
L 4.52997323 5.84639291 4.53183996 5.84764341 2 P 0 ;0,1=53,2=0.000000
L 4.53183996 5.84764341 4.53397333 5.84806004 2 P 0 ;0,1=53,2=0.000000
L 4.53397333 5.84806004 4.53663996 5.84722687 2 P 0 ;0,1=53,2=0.000000
L 4.53663996 5.84722687 4.53850669 5.84514321 2 P 0 ;0,1=53,2=0.000000
L 4.53850669 5.84514321 4.53903996 5.8426437 2 P 0 ;0,1=53,2=0.000000
L 4.53903996 5.8426437 4.53877333 5.84014272 2 P 0 ;0,1=53,2=0.000000
L 4.53877333 5.84014272 4.5377064 5.83805984 2 P 0 ;0,1=53,2=0.000000
L 4.5377064 5.83805984 4.53237323 5.83389331 2 P 0 ;0,1=53,2=0.000000
L 4.53237323 5.83389331 4.52997323 5.83097648 2 P 0 ;0,1=53,2=0.000000
L 4.52997323 5.83097648 4.52837313 5.82680915 2 P 0 ;0,1=53,2=0.000000
L 4.52837313 5.82680915 4.52783986 5.82306004 2 P 0 ;0,1=53,2=0.000000
L 4.52783986 5.82306004 4.53903996 5.82306004 2 P 0 ;0,1=53,2=0.000000
L 4.5779997 5.555 4.57586634 5.55541654 2 P 0 ;0,1=54,2=0.000000
L 4.57586634 5.55541654 4.5740001 5.55708287 2 P 0 ;0,1=54,2=0.000000
L 4.5740001 5.55708287 4.5723999 5.55958307 2 P 0 ;0,1=54,2=0.000000
L 4.5723999 5.55958307 4.57133297 5.5624999 2 P 0 ;0,1=54,2=0.000000
L 4.57133297 5.5624999 4.5707998 5.56583327 2 P 0 ;0,1=54,2=0.000000
L 4.5707998 5.56583327 4.5707998 5.56916663 2 P 0 ;0,1=54,2=0.000000
L 4.5707998 5.56916663 4.57133297 5.5725 2 P 0 ;0,1=54,2=0.000000
L 4.57133297 5.5725 4.5723999 5.57541683 2 P 0 ;0,1=54,2=0.000000
L 4.5723999 5.57541683 4.5740001 5.57791634 2 P 0 ;0,1=54,2=0.000000
L 4.5740001 5.57791634 4.57586634 5.57958337 2 P 0 ;0,1=54,2=0.000000
L 4.57586634 5.57958337 4.5779997 5.58 2 P 0 ;0,1=54,2=0.000000
L 4.5779997 5.58 4.58013307 5.57958337 2 P 0 ;0,1=54,2=0.000000
L 4.58013307 5.57958337 4.5819998 5.57791634 2 P 0 ;0,1=54,2=0.000000
L 4.5819998 5.57791634 4.5836 5.57541683 2 P 0 ;0,1=54,2=0.000000
L 4.5836 5.57541683 4.58466693 5.5725 2 P 0 ;0,1=54,2=0.000000
L 4.58466693 5.5725 4.5852001 5.56916663 2 P 0 ;0,1=54,2=0.000000
L 4.5852001 5.56916663 4.5852001 5.56583327 2 P 0 ;0,1=54,2=0.000000
L 4.5852001 5.56583327 4.58466693 5.5624999 2 P 0 ;0,1=54,2=0.000000
L 4.58466693 5.5624999 4.5836 5.55958307 2 P 0 ;0,1=54,2=0.000000
L 4.5836 5.55958307 4.5819998 5.55708287 2 P 0 ;0,1=54,2=0.000000
L 4.5819998 5.55708287 4.58013307 5.55541654 2 P 0 ;0,1=54,2=0.000000
L 4.58013307 5.55541654 4.5779997 5.555 2 P 0 ;0,1=54,2=0.000000
L 4.59586673 5.555 4.59586673 5.58 2 P 0 ;0,1=54,2=0.000000
L 4.59586673 5.58 4.60813317 5.555 2 P 0 ;0,1=54,2=0.000000
L 4.60813317 5.555 4.60813317 5.58 2 P 0 ;0,1=54,2=0.000000
L 4.6229997 5.5 4.62086634 5.50041654 2 P 0 ;0,1=54,2=0.000000
L 4.62086634 5.50041654 4.6190001 5.50208287 2 P 0 ;0,1=54,2=0.000000
L 4.6190001 5.50208287 4.6173999 5.50458307 2 P 0 ;0,1=54,2=0.000000
L 4.6173999 5.50458307 4.61633297 5.5074999 2 P 0 ;0,1=54,2=0.000000
L 4.61633297 5.5074999 4.6157998 5.51083327 2 P 0 ;0,1=54,2=0.000000
L 4.6157998 5.51083327 4.6157998 5.51416663 2 P 0 ;0,1=54,2=0.000000
L 4.6157998 5.51416663 4.61633297 5.5175 2 P 0 ;0,1=54,2=0.000000
L 4.61633297 5.5175 4.6173999 5.52041683 2 P 0 ;0,1=54,2=0.000000
L 4.6173999 5.52041683 4.6190001 5.52291634 2 P 0 ;0,1=54,2=0.000000
L 4.6190001 5.52291634 4.62086634 5.52458337 2 P 0 ;0,1=54,2=0.000000
L 4.62086634 5.52458337 4.6229997 5.525 2 P 0 ;0,1=54,2=0.000000
L 4.6229997 5.525 4.62513307 5.52458337 2 P 0 ;0,1=54,2=0.000000
L 4.62513307 5.52458337 4.6269998 5.52291634 2 P 0 ;0,1=54,2=0.000000
L 4.6269998 5.52291634 4.6286 5.52041683 2 P 0 ;0,1=54,2=0.000000
L 4.6286 5.52041683 4.62966693 5.5175 2 P 0 ;0,1=54,2=0.000000
L 4.62966693 5.5175 4.6302001 5.51416663 2 P 0 ;0,1=54,2=0.000000
L 4.6302001 5.51416663 4.6302001 5.51083327 2 P 0 ;0,1=54,2=0.000000
L 4.6302001 5.51083327 4.62966693 5.5074999 2 P 0 ;0,1=54,2=0.000000
L 4.62966693 5.5074999 4.6286 5.50458307 2 P 0 ;0,1=54,2=0.000000
L 4.6286 5.50458307 4.6269998 5.50208287 2 P 0 ;0,1=54,2=0.000000
L 4.6269998 5.50208287 4.62513307 5.50041654 2 P 0 ;0,1=54,2=0.000000
L 4.62513307 5.50041654 4.6229997 5.5 2 P 0 ;0,1=54,2=0.000000
L 4.64086673 5.5 4.64086673 5.525 2 P 0 ;0,1=54,2=0.000000
L 4.64086673 5.525 4.65313317 5.5 2 P 0 ;0,1=54,2=0.000000
L 4.65313317 5.5 4.65313317 5.525 2 P 0 ;0,1=54,2=0.000000
L 4.58691969 5.68503996 4.58691969 5.71003996 2 P 0 ;0,1=52,2=0.000000
L 4.58691969 5.71003996 4.58371988 5.70504026 2 P 0 ;0,1=52,2=0.000000
L 4.58371988 5.68503996 4.59011949 5.68503996 2 P 0 ;0,1=52,2=0.000000
L 4.52935315 5.70587333 4.53095325 5.70837283 2 P 0 ;0,1=53,2=0.000000
L 4.53095325 5.70837283 4.53281998 5.70962333 2 P 0 ;0,1=53,2=0.000000
L 4.53281998 5.70962333 4.53495335 5.71003996 2 P 0 ;0,1=53,2=0.000000
L 4.53495335 5.71003996 4.53761998 5.70920679 2 P 0 ;0,1=53,2=0.000000
L 4.53761998 5.70920679 4.53948671 5.70712313 2 P 0 ;0,1=53,2=0.000000
L 4.53948671 5.70712313 4.54001998 5.70462362 2 P 0 ;0,1=53,2=0.000000
L 4.54001998 5.70462362 4.53975335 5.70212264 2 P 0 ;0,1=53,2=0.000000
L 4.53975335 5.70212264 4.53868642 5.70003976 2 P 0 ;0,1=53,2=0.000000
L 4.53868642 5.70003976 4.53335325 5.69587323 2 P 0 ;0,1=53,2=0.000000
L 4.53335325 5.69587323 4.53095325 5.6929564 2 P 0 ;0,1=53,2=0.000000
L 4.53095325 5.6929564 4.52935315 5.68878907 2 P 0 ;0,1=53,2=0.000000
L 4.52935315 5.68878907 4.52881988 5.68503996 2 P 0 ;0,1=53,2=0.000000
L 4.52881988 5.68503996 4.54001998 5.68503996 2 P 0 ;0,1=53,2=0.000000
L 4.98496004 5.61968996 4.85503996 5.61968996 3 P 0 
L 4.85503996 5.61968996 4.85503996 5.58031004 3 P 0 
L 4.85503996 5.58031004 4.98496004 5.58031004 3 P 0 
L 4.98496004 5.58031004 4.98496004 5.58818996 3 P 0 
L 4.98496004 5.58818996 4.97315 5.6 3 P 0 
L 4.97315 5.6 4.98496004 5.61181004 3 P 0 
L 4.98496004 5.61181004 4.98496004 5.61968996 3 P 0 
A 4.99581004 5.65276004 4.99581004 5.65276004 4.98946004 5.65276004 6 P 0 N
L 4.89213327 5.825 4.89213327 5.80708327 2 P 0 ;0,1=55,2=0.000000
L 4.89213327 5.80708327 4.8931998 5.80333258 2 P 0 ;0,1=55,2=0.000000
L 4.8931998 5.80333258 4.89533317 5.80083307 2 P 0 ;0,1=55,2=0.000000
L 4.89533317 5.80083307 4.8979997 5.8 2 P 0 ;0,1=55,2=0.000000
L 4.8979997 5.8 4.90066673 5.80083307 2 P 0 ;0,1=55,2=0.000000
L 4.90066673 5.80083307 4.9028001 5.80333258 2 P 0 ;0,1=55,2=0.000000
L 4.9028001 5.80333258 4.90386663 5.80708327 2 P 0 ;0,1=55,2=0.000000
L 4.90386663 5.80708327 4.90386663 5.825 2 P 0 ;0,1=55,2=0.000000
L 4.9252 5.8 4.9252 5.825 2 P 0 ;0,1=55,2=0.000000
L 4.9252 5.825 4.91533297 5.80708327 2 P 0 ;0,1=55,2=0.000000
L 4.91533297 5.80708327 4.92866693 5.80708327 2 P 0 ;0,1=55,2=0.000000
L 4.94013327 5.80374911 4.94173297 5.80166624 2 P 0 ;0,1=55,2=0.000000
L 4.94173297 5.80166624 4.9435997 5.80041654 2 P 0 ;0,1=55,2=0.000000
L 4.9435997 5.80041654 4.9459997 5.8 2 P 0 ;0,1=55,2=0.000000
L 4.9459997 5.8 4.9484002 5.80083307 2 P 0 ;0,1=55,2=0.000000
L 4.9484002 5.80083307 4.95026644 5.80249941 2 P 0 ;0,1=55,2=0.000000
L 4.95026644 5.80249941 4.9516 5.80541624 2 P 0 ;0,1=55,2=0.000000
L 4.9516 5.80541624 4.95186663 5.80874961 2 P 0 ;0,1=55,2=0.000000
L 4.95186663 5.80874961 4.95133337 5.81208297 2 P 0 ;0,1=55,2=0.000000
L 4.95133337 5.81208297 4.9499998 5.81416663 2 P 0 ;0,1=55,2=0.000000
L 4.9499998 5.81416663 4.94813307 5.81583297 2 P 0 ;0,1=55,2=0.000000
L 4.94813307 5.81583297 4.94626683 5.81624951 2 P 0 ;0,1=55,2=0.000000
L 4.94626683 5.81624951 4.9444 5.81583297 2 P 0 ;0,1=55,2=0.000000
L 4.9444 5.81583297 4.9420001 5.81416663 2 P 0 ;0,1=55,2=0.000000
L 4.9420001 5.81416663 4.9427999 5.825 2 P 0 ;0,1=55,2=0.000000
L 4.9427999 5.825 4.9499998 5.825 2 P 0 ;0,1=55,2=0.000000
L 4.10798002 5.83196998 4.26808002 5.83196998 3 P 0 
L 4.26808002 5.83196998 4.26808002 5.42803002 3 P 0 
L 4.26808002 5.42803002 4.10798002 5.42803002 3 P 0 
L 4.10798002 5.42803002 4.10798002 5.83196998 3 P 0 
L 4.10791004 5.81346004 4.08843002 5.81346004 3 P 0 
L 4.08843002 5.81346004 4.08843002 5.74653996 3 P 0 
L 4.08843002 5.74653996 4.10791004 5.74653996 3 P 0 
L 4.10791004 5.74653996 4.10791004 5.81346004 3 P 0 
L 4.31126004 5.78786998 4.29156998 5.78786998 3 P 0 
L 4.29156998 5.78786998 4.29156998 5.77213002 3 P 0 
L 4.29156998 5.77213002 4.31126004 5.77213002 3 P 0 
L 4.31126004 5.77213002 4.31126004 5.78786998 3 P 0 
L 4.22346004 5.76406004 4.22346004 5.79555 3 P 0 
L 4.22346004 5.79555 4.16046998 5.79555 3 P 0 
L 4.16046998 5.79555 4.16046998 5.76406004 3 P 0 
L 4.16046998 5.76406004 4.22346004 5.76406004 3 P 0 
L 4.22346004 5.76406004 4.22346004 5.79555 3 P 0 
L 4.22346004 5.79555 4.19983996 5.79555 3 P 0 
L 4.19983996 5.79555 4.19983996 5.76406004 3 P 0 
L 4.08843002 5.68786998 4.06873996 5.68786998 3 P 0 
L 4.06873996 5.68786998 4.06873996 5.67213002 3 P 0 
L 4.06873996 5.67213002 4.08843002 5.67213002 3 P 0 
L 4.08843002 5.67213002 4.08843002 5.68786998 3 P 0 
L 4.08843002 5.58786998 4.06873996 5.58786998 3 P 0 
L 4.06873996 5.58786998 4.06873996 5.57213002 3 P 0 
L 4.06873996 5.57213002 4.08843002 5.57213002 3 P 0 
L 4.08843002 5.57213002 4.08843002 5.58786998 3 P 0 
L 4.08843002 5.48786998 4.06873996 5.48786998 3 P 0 
L 4.06873996 5.48786998 4.06873996 5.47213002 3 P 0 
L 4.06873996 5.47213002 4.08843002 5.47213002 3 P 0 
L 4.08843002 5.47213002 4.08843002 5.48786998 3 P 0 
L 4.31126004 5.68786998 4.29156998 5.68786998 3 P 0 
L 4.29156998 5.68786998 4.29156998 5.67213002 3 P 0 
L 4.29156998 5.67213002 4.31126004 5.67213002 3 P 0 
L 4.31126004 5.67213002 4.31126004 5.68786998 3 P 0 
L 4.31126004 5.58786998 4.29156998 5.58786998 3 P 0 
L 4.29156998 5.58786998 4.29156998 5.57213002 3 P 0 
L 4.29156998 5.57213002 4.31126004 5.57213002 3 P 0 
L 4.31126004 5.57213002 4.31126004 5.58786998 3 P 0 
L 4.31126004 5.48786998 4.29156998 5.48786998 3 P 0 
L 4.29156998 5.48786998 4.29156998 5.47213002 3 P 0 
L 4.29156998 5.47213002 4.31126004 5.47213002 3 P 0 
L 4.31126004 5.47213002 4.31126004 5.48786998 3 P 0 
L 4.22346004 5.66406004 4.22346004 5.69555 3 P 0 
L 4.22346004 5.69555 4.16046998 5.69555 3 P 0 
L 4.16046998 5.69555 4.16046998 5.66406004 3 P 0 
L 4.16046998 5.66406004 4.22346004 5.66406004 3 P 0 
L 4.22346004 5.66406004 4.22346004 5.69555 3 P 0 
L 4.22346004 5.69555 4.19983996 5.69555 3 P 0 
L 4.19983996 5.69555 4.19983996 5.66406004 3 P 0 
L 4.22346004 5.56406004 4.22346004 5.59555 3 P 0 
L 4.22346004 5.59555 4.16046998 5.59555 3 P 0 
L 4.16046998 5.59555 4.16046998 5.56406004 3 P 0 
L 4.16046998 5.56406004 4.22346004 5.56406004 3 P 0 
L 4.22346004 5.56406004 4.22346004 5.59555 3 P 0 
L 4.22346004 5.59555 4.19983996 5.59555 3 P 0 
L 4.19983996 5.59555 4.19983996 5.56406004 3 P 0 
L 4.22346004 5.46406004 4.22346004 5.49555 3 P 0 
L 4.22346004 5.49555 4.16046998 5.49555 3 P 0 
L 4.16046998 5.49555 4.16046998 5.46406004 3 P 0 
L 4.16046998 5.46406004 4.22346004 5.46406004 3 P 0 
L 4.22346004 5.46406004 4.22346004 5.49555 3 P 0 
L 4.22346004 5.49555 4.19983996 5.49555 3 P 0 
L 4.19983996 5.49555 4.19983996 5.46406004 3 P 0 
L 4.08843002 5.78786998 4.06873996 5.78786998 3 P 0 
L 4.06873996 5.78786998 4.06873996 5.77213002 3 P 0 
L 4.06873996 5.77213002 4.08843002 5.77213002 3 P 0 
L 4.08843002 5.77213002 4.08843002 5.78786998 3 P 0 
L 4.08843002 5.68786998 4.06873996 5.68786998 3 P 0 
L 4.06873996 5.68786998 4.06873996 5.67213002 3 P 0 
L 4.06873996 5.67213002 4.08843002 5.67213002 3 P 0 
L 4.08843002 5.67213002 4.08843002 5.68786998 3 P 0 
L 4.08843002 5.58786998 4.06873996 5.58786998 2 P 0 
L 4.06873996 5.58786998 4.06873996 5.57213002 2 P 0 
L 4.06873996 5.57213002 4.08843002 5.57213002 2 P 0 
L 4.08843002 5.57213002 4.08843002 5.58786998 2 P 0 
L 4.10791004 5.71346004 4.08843002 5.71346004 3 P 0 
L 4.08843002 5.71346004 4.08843002 5.64653996 3 P 0 
L 4.08843002 5.64653996 4.10791004 5.64653996 3 P 0 
L 4.10791004 5.64653996 4.10791004 5.71346004 3 P 0 
L 4.10791004 5.61346004 4.08843002 5.61346004 3 P 0 
L 4.08843002 5.61346004 4.08843002 5.54653996 3 P 0 
L 4.08843002 5.54653996 4.10791004 5.54653996 3 P 0 
L 4.10791004 5.54653996 4.10791004 5.61346004 3 P 0 
L 4.10791004 5.51346004 4.08843002 5.51346004 3 P 0 
L 4.08843002 5.51346004 4.08843002 5.44653996 3 P 0 
L 4.08843002 5.44653996 4.10791004 5.44653996 3 P 0 
L 4.10791004 5.44653996 4.10791004 5.51346004 3 P 0 
L 4.28763996 5.81346004 4.26815 5.81346004 3 P 0 
L 4.26815 5.81346004 4.26815 5.74653996 3 P 0 
L 4.26815 5.74653996 4.28763996 5.74653996 3 P 0 
L 4.28763996 5.74653996 4.28763996 5.81346004 3 P 0 
L 4.28763996 5.71346004 4.26815 5.71346004 3 P 0 
L 4.26815 5.71346004 4.26815 5.64653996 3 P 0 
L 4.26815 5.64653996 4.28763996 5.64653996 3 P 0 
L 4.28763996 5.64653996 4.28763996 5.71346004 3 P 0 
L 4.28763996 5.61346004 4.26815 5.61346004 3 P 0 
L 4.26815 5.61346004 4.26815 5.54653996 3 P 0 
L 4.26815 5.54653996 4.28763996 5.54653996 3 P 0 
L 4.28763996 5.54653996 4.28763996 5.61346004 3 P 0 
L 4.28763996 5.51346004 4.26815 5.51346004 3 P 0 
L 4.26815 5.51346004 4.26815 5.44653996 3 P 0 
L 4.26815 5.44653996 4.28763996 5.44653996 3 P 0 
L 4.28763996 5.44653996 4.28763996 5.51346004 3 P 0 
L 4.1434499 5.86426575 4.14651663 5.86159961 2 P 0 ;0,1=56,2=0.000000
L 4.14651663 5.86159961 4.14996663 5.86 2 P 0 ;0,1=56,2=0.000000
L 4.14996663 5.86 4.15303327 5.86 2 P 0 ;0,1=56,2=0.000000
L 4.15303327 5.86 4.1561 5.86159961 2 P 0 ;0,1=56,2=0.000000
L 4.1561 5.86159961 4.1584002 5.86426575 2 P 0 ;0,1=56,2=0.000000
L 4.1584002 5.86426575 4.15955 5.8680002 2 P 0 ;0,1=56,2=0.000000
L 4.15955 5.8680002 4.15878346 5.87173278 2 P 0 ;0,1=56,2=0.000000
L 4.15878346 5.87173278 4.15686654 5.87493307 2 P 0 ;0,1=56,2=0.000000
L 4.15686654 5.87493307 4.15341654 5.87706683 2 P 0 ;0,1=56,2=0.000000
L 4.15341654 5.87706683 4.14881683 5.87813327 2 P 0 ;0,1=56,2=0.000000
L 4.14881683 5.87813327 4.14613337 5.88026624 2 P 0 ;0,1=56,2=0.000000
L 4.14613337 5.88026624 4.14498287 5.8839997 2 P 0 ;0,1=56,2=0.000000
L 4.14498287 5.8839997 4.1457501 5.88773327 2 P 0 ;0,1=56,2=0.000000
L 4.1457501 5.88773327 4.14766634 5.89039931 2 P 0 ;0,1=56,2=0.000000
L 4.14766634 5.89039931 4.1503498 5.892 2 P 0 ;0,1=56,2=0.000000
L 4.1503498 5.892 4.15303327 5.892 2 P 0 ;0,1=56,2=0.000000
L 4.15303327 5.892 4.15571673 5.89093346 2 P 0 ;0,1=56,2=0.000000
L 4.15571673 5.89093346 4.15801703 5.88826644 2 P 0 ;0,1=56,2=0.000000
L 4.171 5.892 4.17636614 5.86 2 P 0 ;0,1=56,2=0.000000
L 4.17636614 5.86 4.18249961 5.892 2 P 0 ;0,1=56,2=0.000000
L 4.18249961 5.892 4.18863307 5.86 2 P 0 ;0,1=56,2=0.000000
L 4.18863307 5.86 4.194 5.892 2 P 0 ;0,1=56,2=0.000000
L 4.20621644 5.88666673 4.20851663 5.88986614 2 P 0 ;0,1=56,2=0.000000
L 4.20851663 5.88986614 4.2112001 5.89146673 2 P 0 ;0,1=56,2=0.000000
L 4.2112001 5.89146673 4.21426683 5.892 2 P 0 ;0,1=56,2=0.000000
L 4.21426683 5.892 4.2181 5.89093346 2 P 0 ;0,1=56,2=0.000000
L 4.2181 5.89093346 4.22078346 5.88826644 2 P 0 ;0,1=56,2=0.000000
L 4.22078346 5.88826644 4.22155 5.88506713 2 P 0 ;0,1=56,2=0.000000
L 4.22155 5.88506713 4.22116673 5.88186585 2 P 0 ;0,1=56,2=0.000000
L 4.22116673 5.88186585 4.21963307 5.8791998 2 P 0 ;0,1=56,2=0.000000
L 4.21963307 5.8791998 4.21196663 5.87386663 2 P 0 ;0,1=56,2=0.000000
L 4.21196663 5.87386663 4.20851663 5.87013307 2 P 0 ;0,1=56,2=0.000000
L 4.20851663 5.87013307 4.20621644 5.86479892 2 P 0 ;0,1=56,2=0.000000
L 4.20621644 5.86479892 4.2054499 5.86 2 P 0 ;0,1=56,2=0.000000
L 4.2054499 5.86 4.22155 5.86 2 P 0 ;0,1=56,2=0.000000
L 4.26 5.7729997 4.25958346 5.77086634 2 P 0 ;0,1=54,2=270.000000
L 4.25958346 5.77086634 4.25791713 5.7690001 2 P 0 ;0,1=54,2=270.000000
L 4.25791713 5.7690001 4.25541693 5.7673999 2 P 0 ;0,1=54,2=270.000000
L 4.25541693 5.7673999 4.2525001 5.76633297 2 P 0 ;0,1=54,2=270.000000
L 4.2525001 5.76633297 4.24916673 5.7657998 2 P 0 ;0,1=54,2=270.000000
L 4.24916673 5.7657998 4.24583337 5.7657998 2 P 0 ;0,1=54,2=270.000000
L 4.24583337 5.7657998 4.2425 5.76633297 2 P 0 ;0,1=54,2=270.000000
L 4.2425 5.76633297 4.23958317 5.7673999 2 P 0 ;0,1=54,2=270.000000
L 4.23958317 5.7673999 4.23708366 5.7690001 2 P 0 ;0,1=54,2=270.000000
L 4.23708366 5.7690001 4.23541663 5.77086634 2 P 0 ;0,1=54,2=270.000000
L 4.23541663 5.77086634 4.235 5.7729997 2 P 0 ;0,1=54,2=270.000000
L 4.235 5.7729997 4.23541663 5.77513307 2 P 0 ;0,1=54,2=270.000000
L 4.23541663 5.77513307 4.23708366 5.7769998 2 P 0 ;0,1=54,2=270.000000
L 4.23708366 5.7769998 4.23958317 5.7786 2 P 0 ;0,1=54,2=270.000000
L 4.23958317 5.7786 4.2425 5.77966693 2 P 0 ;0,1=54,2=270.000000
L 4.2425 5.77966693 4.24583337 5.7802001 2 P 0 ;0,1=54,2=270.000000
L 4.24583337 5.7802001 4.24916673 5.7802001 2 P 0 ;0,1=54,2=270.000000
L 4.24916673 5.7802001 4.2525001 5.77966693 2 P 0 ;0,1=54,2=270.000000
L 4.2525001 5.77966693 4.25541693 5.7786 2 P 0 ;0,1=54,2=270.000000
L 4.25541693 5.7786 4.25791713 5.7769998 2 P 0 ;0,1=54,2=270.000000
L 4.25791713 5.7769998 4.25958346 5.77513307 2 P 0 ;0,1=54,2=270.000000
L 4.25958346 5.77513307 4.26 5.7729997 2 P 0 ;0,1=54,2=270.000000
L 4.26 5.79086673 4.235 5.79086673 2 P 0 ;0,1=54,2=270.000000
L 4.235 5.79086673 4.26 5.80313317 2 P 0 ;0,1=54,2=270.000000
L 4.26 5.80313317 4.235 5.80313317 2 P 0 ;0,1=54,2=270.000000
L 4.3279997 5.825 4.32586634 5.82541654 2 P 0 ;0,1=54,2=0.000000
L 4.32586634 5.82541654 4.3240001 5.82708287 2 P 0 ;0,1=54,2=0.000000
L 4.3240001 5.82708287 4.3223999 5.82958307 2 P 0 ;0,1=54,2=0.000000
L 4.3223999 5.82958307 4.32133297 5.8324999 2 P 0 ;0,1=54,2=0.000000
L 4.32133297 5.8324999 4.3207998 5.83583327 2 P 0 ;0,1=54,2=0.000000
L 4.3207998 5.83583327 4.3207998 5.83916663 2 P 0 ;0,1=54,2=0.000000
L 4.3207998 5.83916663 4.32133297 5.8425 2 P 0 ;0,1=54,2=0.000000
L 4.32133297 5.8425 4.3223999 5.84541683 2 P 0 ;0,1=54,2=0.000000
L 4.3223999 5.84541683 4.3240001 5.84791634 2 P 0 ;0,1=54,2=0.000000
L 4.3240001 5.84791634 4.32586634 5.84958337 2 P 0 ;0,1=54,2=0.000000
L 4.32586634 5.84958337 4.3279997 5.85 2 P 0 ;0,1=54,2=0.000000
L 4.3279997 5.85 4.33013307 5.84958337 2 P 0 ;0,1=54,2=0.000000
L 4.33013307 5.84958337 4.3319998 5.84791634 2 P 0 ;0,1=54,2=0.000000
L 4.3319998 5.84791634 4.3336 5.84541683 2 P 0 ;0,1=54,2=0.000000
L 4.3336 5.84541683 4.33466693 5.8425 2 P 0 ;0,1=54,2=0.000000
L 4.33466693 5.8425 4.3352001 5.83916663 2 P 0 ;0,1=54,2=0.000000
L 4.3352001 5.83916663 4.3352001 5.83583327 2 P 0 ;0,1=54,2=0.000000
L 4.3352001 5.83583327 4.33466693 5.8324999 2 P 0 ;0,1=54,2=0.000000
L 4.33466693 5.8324999 4.3336 5.82958307 2 P 0 ;0,1=54,2=0.000000
L 4.3336 5.82958307 4.3319998 5.82708287 2 P 0 ;0,1=54,2=0.000000
L 4.3319998 5.82708287 4.33013307 5.82541654 2 P 0 ;0,1=54,2=0.000000
L 4.33013307 5.82541654 4.3279997 5.825 2 P 0 ;0,1=54,2=0.000000
L 4.34586673 5.825 4.34586673 5.85 2 P 0 ;0,1=54,2=0.000000
L 4.34586673 5.85 4.35813317 5.825 2 P 0 ;0,1=54,2=0.000000
L 4.35813317 5.825 4.35813317 5.85 2 P 0 ;0,1=54,2=0.000000
L 4.12474331 5.57779961 4.12634301 5.57488287 2 P 0 ;0,1=57,2=0.000000
L 4.12634301 5.57488287 4.12847638 5.57321654 2 P 0 ;0,1=57,2=0.000000
L 4.12847638 5.57321654 4.13087687 5.5728 2 P 0 ;0,1=57,2=0.000000
L 4.13087687 5.5728 4.13301024 5.57321654 2 P 0 ;0,1=57,2=0.000000
L 4.13301024 5.57321654 4.1351436 5.57529941 2 P 0 ;0,1=57,2=0.000000
L 4.1351436 5.57529941 4.13647667 5.57779961 2 P 0 ;0,1=57,2=0.000000
L 4.13647667 5.57779961 4.13674321 5.5802999 2 P 0 ;0,1=57,2=0.000000
L 4.13674321 5.5802999 4.13621004 5.58321594 2 P 0 ;0,1=57,2=0.000000
L 4.13621004 5.58321594 4.13434331 5.58529961 2 P 0 ;0,1=57,2=0.000000
L 4.13434331 5.58529961 4.13247648 5.58613346 2 P 0 ;0,1=57,2=0.000000
L 4.13247648 5.58613346 4.13007657 5.58613346 2 P 0 ;0,1=57,2=0.000000
L 4.13247648 5.58613346 4.13407667 5.58738327 2 P 0 ;0,1=57,2=0.000000
L 4.13407667 5.58738327 4.13541014 5.58946614 2 P 0 ;0,1=57,2=0.000000
L 4.13541014 5.58946614 4.13594341 5.59196634 2 P 0 ;0,1=57,2=0.000000
L 4.13594341 5.59196634 4.13541014 5.59446654 2 P 0 ;0,1=57,2=0.000000
L 4.13541014 5.59446654 4.13407667 5.59654941 2 P 0 ;0,1=57,2=0.000000
L 4.13407667 5.59654941 4.13167667 5.5978 2 P 0 ;0,1=57,2=0.000000
L 4.13167667 5.5978 4.12927667 5.59738337 2 P 0 ;0,1=57,2=0.000000
L 4.12927667 5.59738337 4.12687667 5.59571634 2 P 0 ;0,1=57,2=0.000000
L 4.13381004 5.47161998 4.13381004 5.49661998 2 P 0 ;0,1=58,2=0.000000
L 4.13381004 5.49661998 4.12394301 5.47870325 2 P 0 ;0,1=58,2=0.000000
L 4.12394301 5.47870325 4.13727697 5.47870325 2 P 0 ;0,1=58,2=0.000000
L 4.12554321 5.69363337 4.12714331 5.69613287 2 P 0 ;0,1=53,2=0.000000
L 4.12714331 5.69613287 4.12901004 5.69738337 2 P 0 ;0,1=53,2=0.000000
L 4.12901004 5.69738337 4.13114341 5.6978 2 P 0 ;0,1=53,2=0.000000
L 4.13114341 5.6978 4.13381004 5.69696683 2 P 0 ;0,1=53,2=0.000000
L 4.13381004 5.69696683 4.13567677 5.69488317 2 P 0 ;0,1=53,2=0.000000
L 4.13567677 5.69488317 4.13621004 5.69238366 2 P 0 ;0,1=53,2=0.000000
L 4.13621004 5.69238366 4.13594341 5.68988268 2 P 0 ;0,1=53,2=0.000000
L 4.13594341 5.68988268 4.13487648 5.6877998 2 P 0 ;0,1=53,2=0.000000
L 4.13487648 5.6877998 4.12954331 5.68363327 2 P 0 ;0,1=53,2=0.000000
L 4.12954331 5.68363327 4.12714331 5.68071644 2 P 0 ;0,1=53,2=0.000000
L 4.12714331 5.68071644 4.12554321 5.67654911 2 P 0 ;0,1=53,2=0.000000
L 4.12554321 5.67654911 4.12500994 5.6728 2 P 0 ;0,1=53,2=0.000000
L 4.12500994 5.6728 4.13621004 5.6728 2 P 0 ;0,1=53,2=0.000000
L 4.13060974 5.7728 4.13060974 5.7978 2 P 0 ;0,1=52,2=0.000000
L 4.13060974 5.7978 4.12740994 5.7928003 2 P 0 ;0,1=52,2=0.000000
L 4.12740994 5.7728 4.13380955 5.7728 2 P 0 ;0,1=52,2=0.000000
L 3.94550315 5.69001339 3.94710325 5.69251289 2 P 0 ;0,1=53,2=0.000000
L 3.94710325 5.69251289 3.94896998 5.69376339 2 P 0 ;0,1=53,2=0.000000
L 3.94896998 5.69376339 3.95110335 5.69418002 2 P 0 ;0,1=53,2=0.000000
L 3.95110335 5.69418002 3.95376998 5.69334685 2 P 0 ;0,1=53,2=0.000000
L 3.95376998 5.69334685 3.95563671 5.69126319 2 P 0 ;0,1=53,2=0.000000
L 3.95563671 5.69126319 3.95616998 5.68876368 2 P 0 ;0,1=53,2=0.000000
L 3.95616998 5.68876368 3.95590335 5.6862627 2 P 0 ;0,1=53,2=0.000000
L 3.95590335 5.6862627 3.95483642 5.68417982 2 P 0 ;0,1=53,2=0.000000
L 3.95483642 5.68417982 3.94950325 5.68001329 2 P 0 ;0,1=53,2=0.000000
L 3.94950325 5.68001329 3.94710325 5.67709646 2 P 0 ;0,1=53,2=0.000000
L 3.94710325 5.67709646 3.94550315 5.67292913 2 P 0 ;0,1=53,2=0.000000
L 3.94550315 5.67292913 3.94496988 5.66918002 2 P 0 ;0,1=53,2=0.000000
L 3.94496988 5.66918002 3.95616998 5.66918002 2 P 0 ;0,1=53,2=0.000000
L 3.94470325 5.57181959 3.94630295 5.56890285 2 P 0 ;0,1=57,2=0.000000
L 3.94630295 5.56890285 3.94843632 5.56723652 2 P 0 ;0,1=57,2=0.000000
L 3.94843632 5.56723652 3.95083681 5.56681998 2 P 0 ;0,1=57,2=0.000000
L 3.95083681 5.56681998 3.95297018 5.56723652 2 P 0 ;0,1=57,2=0.000000
L 3.95297018 5.56723652 3.95510354 5.56931939 2 P 0 ;0,1=57,2=0.000000
L 3.95510354 5.56931939 3.95643661 5.57181959 2 P 0 ;0,1=57,2=0.000000
L 3.95643661 5.57181959 3.95670315 5.57431988 2 P 0 ;0,1=57,2=0.000000
L 3.95670315 5.57431988 3.95616998 5.57723593 2 P 0 ;0,1=57,2=0.000000
L 3.95616998 5.57723593 3.95430325 5.57931959 2 P 0 ;0,1=57,2=0.000000
L 3.95430325 5.57931959 3.95243642 5.58015344 2 P 0 ;0,1=57,2=0.000000
L 3.95243642 5.58015344 3.95003652 5.58015344 2 P 0 ;0,1=57,2=0.000000
L 3.95243642 5.58015344 3.95403661 5.58140325 2 P 0 ;0,1=57,2=0.000000
L 3.95403661 5.58140325 3.95537008 5.58348612 2 P 0 ;0,1=57,2=0.000000
L 3.95537008 5.58348612 3.95590335 5.58598632 2 P 0 ;0,1=57,2=0.000000
L 3.95590335 5.58598632 3.95537008 5.58848652 2 P 0 ;0,1=57,2=0.000000
L 3.95537008 5.58848652 3.95403661 5.59056939 2 P 0 ;0,1=57,2=0.000000
L 3.95403661 5.59056939 3.95163661 5.59181998 2 P 0 ;0,1=57,2=0.000000
L 3.95163661 5.59181998 3.94923661 5.59140335 2 P 0 ;0,1=57,2=0.000000
L 3.94923661 5.59140335 3.94683661 5.58973632 2 P 0 ;0,1=57,2=0.000000
L 3.95376998 5.46838996 3.95376998 5.49338996 2 P 0 ;0,1=58,2=0.000000
L 3.95376998 5.49338996 3.94390295 5.47547323 2 P 0 ;0,1=58,2=0.000000
L 3.94390295 5.47547323 3.95723691 5.47547323 2 P 0 ;0,1=58,2=0.000000
L 3.9579997 5.77 3.9579997 5.795 2 P 0 ;0,1=52,2=0.000000
L 3.9579997 5.795 3.9547999 5.7900003 2 P 0 ;0,1=52,2=0.000000
L 3.9547999 5.77 3.96119951 5.77 2 P 0 ;0,1=52,2=0.000000
A 6.26951998 4.77205 6.27295856 4.76205817 6.28575 4.77204783 2 P 0 N
A 6.27295856 4.76205817 6.28181998 4.7563 6.28575276 4.77205 2 P 0 N
A 6.28181998 4.7563 6.30013445 4.76411083 6.28582333 4.77228996 2 P 0 N
A 6.30013445 4.76411083 6.29756998 4.78386004 6.28581998 4.77229321 2 P 0 N
A 6.29756998 4.78386004 6.2935437 4.76780728 6.30945 4.77234902 2 P 0 N
A 6.2935437 4.76780728 6.30543996 4.7563 6.30945148 4.77235 2 P 0 N
L 6.27001004 4.77205 6.26016998 4.77205 2 P 0 
A 6.30543996 4.7563 6.32375443 4.76411083 6.30944331 4.77228996 2 P 0 N
A 6.32375443 4.76411083 6.32118996 4.78386004 6.30943996 4.77229321 2 P 0 N
A 6.32118996 4.78386004 6.3171687 4.76780719 6.33308002 4.77235148 2 P 0 N
A 6.3171687 4.76780719 6.32906004 4.7563 6.33307815 4.77235 2 P 0 N
A 6.32906004 4.7563 6.34738169 4.76411083 6.333069 4.77228996 2 P 0 N
A 6.34738169 4.76411083 6.34481004 4.78386004 6.33306998 4.77228927 2 P 0 N
A 6.34481004 4.78386004 6.34079124 4.76780295 6.3567 4.77235276 2 P 0 N
A 6.34079124 4.76780295 6.35268996 4.7563 6.35669656 4.77235 2 P 0 N
A 6.35268996 4.7563 6.36643022 4.75930463 6.35652539 4.77168002 2 P 0 N
A 6.36643022 4.75930463 6.37236998 4.77205 6.35653002 4.7716752 2 P 0 N
L 6.38221004 4.77205 6.37236998 4.77205 2 P 0 
L 6.4708 4.85315 6.4708 4.90985 3 P 0 
L 6.4708 4.90985 6.17158002 4.90985 3 P 0 
L 6.17158002 4.90985 6.17158002 4.85315 3 P 0 
L 6.4708 4.69095 6.4708 4.63425 3 P 0 
L 6.4708 4.63425 6.17158002 4.63425 3 P 0 
L 6.17158002 4.63425 6.17158002 4.69095 3 P 0 
L 6.2787565 4.5727 6.2787565 4.5977 2 P 0 ;0,1=59,2=0.000000
L 6.2787565 4.5977 6.28515659 4.5977 2 P 0 ;0,1=59,2=0.000000
L 6.28515659 4.5977 6.28728996 4.59644941 2 P 0 ;0,1=59,2=0.000000
L 6.28728996 4.59644941 6.28889006 4.59353337 2 P 0 ;0,1=59,2=0.000000
L 6.28889006 4.59353337 6.28942333 4.5902 2 P 0 ;0,1=59,2=0.000000
L 6.28942333 4.5902 6.28889006 4.58686663 2 P 0 ;0,1=59,2=0.000000
L 6.28889006 4.58686663 6.28755659 4.58436644 2 P 0 ;0,1=59,2=0.000000
L 6.28755659 4.58436644 6.28515659 4.58311594 2 P 0 ;0,1=59,2=0.000000
L 6.28515659 4.58311594 6.2787565 4.58311594 2 P 0 ;0,1=59,2=0.000000
L 6.30248986 4.57603258 6.30462323 4.5739497 2 P 0 ;0,1=59,2=0.000000
L 6.30462323 4.5739497 6.30702323 4.5727 2 P 0 ;0,1=59,2=0.000000
L 6.30702323 4.5727 6.30915659 4.5727 2 P 0 ;0,1=59,2=0.000000
L 6.30915659 4.5727 6.31128996 4.5739497 2 P 0 ;0,1=59,2=0.000000
L 6.31128996 4.5739497 6.31289006 4.57603258 2 P 0 ;0,1=59,2=0.000000
L 6.31289006 4.57603258 6.31368996 4.5789501 2 P 0 ;0,1=59,2=0.000000
L 6.31368996 4.5789501 6.31315669 4.58186614 2 P 0 ;0,1=59,2=0.000000
L 6.31315669 4.58186614 6.31182323 4.58436644 2 P 0 ;0,1=59,2=0.000000
L 6.31182323 4.58436644 6.30942323 4.58603346 2 P 0 ;0,1=59,2=0.000000
L 6.30942323 4.58603346 6.30622343 4.58686663 2 P 0 ;0,1=59,2=0.000000
L 6.30622343 4.58686663 6.30435659 4.58853297 2 P 0 ;0,1=59,2=0.000000
L 6.30435659 4.58853297 6.3035563 4.5914498 2 P 0 ;0,1=59,2=0.000000
L 6.3035563 4.5914498 6.30409006 4.59436654 2 P 0 ;0,1=59,2=0.000000
L 6.30409006 4.59436654 6.30542313 4.59644941 2 P 0 ;0,1=59,2=0.000000
L 6.30542313 4.59644941 6.30728986 4.5977 2 P 0 ;0,1=59,2=0.000000
L 6.30728986 4.5977 6.30915659 4.5977 2 P 0 ;0,1=59,2=0.000000
L 6.30915659 4.5977 6.31102333 4.59686683 2 P 0 ;0,1=59,2=0.000000
L 6.31102333 4.59686683 6.31262352 4.59478317 2 P 0 ;0,1=59,2=0.000000
L 6.33208967 4.5977 6.33208967 4.5727 2 P 0 ;0,1=59,2=0.000000
L 6.32595669 4.5977 6.33822313 4.5977 2 P 0 ;0,1=59,2=0.000000
L 6.3507565 4.5977 6.3507565 4.5727 2 P 0 ;0,1=59,2=0.000000
L 6.3507565 4.5727 6.36142333 4.5727 2 P 0 ;0,1=59,2=0.000000
L 6.37502313 4.59353337 6.37662323 4.59603287 2 P 0 ;0,1=59,2=0.000000
L 6.37662323 4.59603287 6.37848996 4.59728337 2 P 0 ;0,1=59,2=0.000000
L 6.37848996 4.59728337 6.38062333 4.5977 2 P 0 ;0,1=59,2=0.000000
L 6.38062333 4.5977 6.38328996 4.59686683 2 P 0 ;0,1=59,2=0.000000
L 6.38328996 4.59686683 6.38515669 4.59478317 2 P 0 ;0,1=59,2=0.000000
L 6.38515669 4.59478317 6.38568996 4.59228366 2 P 0 ;0,1=59,2=0.000000
L 6.38568996 4.59228366 6.38542333 4.58978268 2 P 0 ;0,1=59,2=0.000000
L 6.38542333 4.58978268 6.3843564 4.5876998 2 P 0 ;0,1=59,2=0.000000
L 6.3843564 4.5876998 6.37902323 4.58353327 2 P 0 ;0,1=59,2=0.000000
L 6.37902323 4.58353327 6.37662323 4.58061644 2 P 0 ;0,1=59,2=0.000000
L 6.37662323 4.58061644 6.37502313 4.57644911 2 P 0 ;0,1=59,2=0.000000
L 6.37502313 4.57644911 6.37448986 4.5727 2 P 0 ;0,1=59,2=0.000000
L 6.37448986 4.5727 6.38568996 4.5727 2 P 0 ;0,1=59,2=0.000000
L 6.54618996 4.67788002 6.54618996 4.65621998 7 P 0 
L 6.47966654 4.395 6.47966654 4.42 2 P 0 ;0,1=60,2=0.000000
L 6.47966654 4.42 6.48606663 4.42 2 P 0 ;0,1=60,2=0.000000
L 6.48606663 4.42 6.4882 4.41874941 2 P 0 ;0,1=60,2=0.000000
L 6.4882 4.41874941 6.4898001 4.41583337 2 P 0 ;0,1=60,2=0.000000
L 6.4898001 4.41583337 6.49033337 4.4125 2 P 0 ;0,1=60,2=0.000000
L 6.49033337 4.4125 6.4898001 4.40916663 2 P 0 ;0,1=60,2=0.000000
L 6.4898001 4.40916663 6.48846663 4.40666644 2 P 0 ;0,1=60,2=0.000000
L 6.48846663 4.40666644 6.48606663 4.40541594 2 P 0 ;0,1=60,2=0.000000
L 6.48606663 4.40541594 6.47966654 4.40541594 2 P 0 ;0,1=60,2=0.000000
L 6.5033999 4.39833258 6.50553327 4.3962497 2 P 0 ;0,1=60,2=0.000000
L 6.50553327 4.3962497 6.50793327 4.395 2 P 0 ;0,1=60,2=0.000000
L 6.50793327 4.395 6.51006663 4.395 2 P 0 ;0,1=60,2=0.000000
L 6.51006663 4.395 6.5122 4.3962497 2 P 0 ;0,1=60,2=0.000000
L 6.5122 4.3962497 6.5138001 4.39833258 2 P 0 ;0,1=60,2=0.000000
L 6.5138001 4.39833258 6.5146 4.4012501 2 P 0 ;0,1=60,2=0.000000
L 6.5146 4.4012501 6.51406673 4.40416614 2 P 0 ;0,1=60,2=0.000000
L 6.51406673 4.40416614 6.51273327 4.40666644 2 P 0 ;0,1=60,2=0.000000
L 6.51273327 4.40666644 6.51033327 4.40833346 2 P 0 ;0,1=60,2=0.000000
L 6.51033327 4.40833346 6.50713346 4.40916663 2 P 0 ;0,1=60,2=0.000000
L 6.50713346 4.40916663 6.50526663 4.41083297 2 P 0 ;0,1=60,2=0.000000
L 6.50526663 4.41083297 6.50446634 4.4137498 2 P 0 ;0,1=60,2=0.000000
L 6.50446634 4.4137498 6.5050001 4.41666654 2 P 0 ;0,1=60,2=0.000000
L 6.5050001 4.41666654 6.50633317 4.41874941 2 P 0 ;0,1=60,2=0.000000
L 6.50633317 4.41874941 6.5081999 4.42 2 P 0 ;0,1=60,2=0.000000
L 6.5081999 4.42 6.51006663 4.42 2 P 0 ;0,1=60,2=0.000000
L 6.51006663 4.42 6.51193337 4.41916683 2 P 0 ;0,1=60,2=0.000000
L 6.51193337 4.41916683 6.51353356 4.41708317 2 P 0 ;0,1=60,2=0.000000
L 6.5329997 4.42 6.5329997 4.395 2 P 0 ;0,1=60,2=0.000000
L 6.52686673 4.42 6.53913317 4.42 2 P 0 ;0,1=60,2=0.000000
L 6.55166654 4.395 6.55166654 4.42 2 P 0 ;0,1=60,2=0.000000
L 6.55166654 4.42 6.55833327 4.42 2 P 0 ;0,1=60,2=0.000000
L 6.55833327 4.42 6.56046663 4.41874941 2 P 0 ;0,1=60,2=0.000000
L 6.56046663 4.41874941 6.5618001 4.41708317 2 P 0 ;0,1=60,2=0.000000
L 6.5618001 4.41708317 6.56233337 4.4137498 2 P 0 ;0,1=60,2=0.000000
L 6.56233337 4.4137498 6.5618001 4.41041634 2 P 0 ;0,1=60,2=0.000000
L 6.5618001 4.41041634 6.5602 4.40833346 2 P 0 ;0,1=60,2=0.000000
L 6.5602 4.40833346 6.55833327 4.40708297 2 P 0 ;0,1=60,2=0.000000
L 6.55833327 4.40708297 6.55166654 4.40708297 2 P 0 ;0,1=60,2=0.000000
L 6.55833327 4.40708297 6.56233337 4.395 2 P 0 ;0,1=60,2=0.000000
L 6.5809997 4.395 6.5809997 4.42 2 P 0 ;0,1=60,2=0.000000
L 6.5809997 4.42 6.5777999 4.4150003 2 P 0 ;0,1=60,2=0.000000
L 6.5777999 4.395 6.58419951 4.395 2 P 0 ;0,1=60,2=0.000000
L 6.59913327 4.39874911 6.60073297 4.39666624 2 P 0 ;0,1=60,2=0.000000
L 6.60073297 4.39666624 6.6025997 4.39541654 2 P 0 ;0,1=60,2=0.000000
L 6.6025997 4.39541654 6.6049997 4.395 2 P 0 ;0,1=60,2=0.000000
L 6.6049997 4.395 6.6074002 4.39583307 2 P 0 ;0,1=60,2=0.000000
L 6.6074002 4.39583307 6.60926644 4.39749941 2 P 0 ;0,1=60,2=0.000000
L 6.60926644 4.39749941 6.6106 4.40041624 2 P 0 ;0,1=60,2=0.000000
L 6.6106 4.40041624 6.61086663 4.40374961 2 P 0 ;0,1=60,2=0.000000
L 6.61086663 4.40374961 6.61033337 4.40708297 2 P 0 ;0,1=60,2=0.000000
L 6.61033337 4.40708297 6.6089998 4.40916663 2 P 0 ;0,1=60,2=0.000000
L 6.6089998 4.40916663 6.60713307 4.41083297 2 P 0 ;0,1=60,2=0.000000
L 6.60713307 4.41083297 6.60526683 4.41124951 2 P 0 ;0,1=60,2=0.000000
L 6.60526683 4.41124951 6.6034 4.41083297 2 P 0 ;0,1=60,2=0.000000
L 6.6034 4.41083297 6.6010001 4.40916663 2 P 0 ;0,1=60,2=0.000000
L 6.6010001 4.40916663 6.6017999 4.42 2 P 0 ;0,1=60,2=0.000000
L 6.6017999 4.42 6.6089998 4.42 2 P 0 ;0,1=60,2=0.000000
L 6.52701998 4.75205 6.50536004 4.75205 7 P 0 
L 6.52618996 4.44671654 6.50118996 4.44671654 2 P 0 ;0,1=61,2=270.000000
L 6.50118996 4.44671654 6.50118996 4.45311663 2 P 0 ;0,1=61,2=270.000000
L 6.50118996 4.45311663 6.50244055 4.45525 2 P 0 ;0,1=61,2=270.000000
L 6.50244055 4.45525 6.50535659 4.4568501 2 P 0 ;0,1=61,2=270.000000
L 6.50535659 4.4568501 6.50868996 4.45738337 2 P 0 ;0,1=61,2=270.000000
L 6.50868996 4.45738337 6.51202333 4.4568501 2 P 0 ;0,1=61,2=270.000000
L 6.51202333 4.4568501 6.51452352 4.45551663 2 P 0 ;0,1=61,2=270.000000
L 6.51452352 4.45551663 6.51577402 4.45311663 2 P 0 ;0,1=61,2=270.000000
L 6.51577402 4.45311663 6.51577402 4.44671654 2 P 0 ;0,1=61,2=270.000000
L 6.52285738 4.4704499 6.52494026 4.47258327 2 P 0 ;0,1=61,2=270.000000
L 6.52494026 4.47258327 6.52618996 4.47498327 2 P 0 ;0,1=61,2=270.000000
L 6.52618996 4.47498327 6.52618996 4.47711663 2 P 0 ;0,1=61,2=270.000000
L 6.52618996 4.47711663 6.52494026 4.47925 2 P 0 ;0,1=61,2=270.000000
L 6.52494026 4.47925 6.52285738 4.4808501 2 P 0 ;0,1=61,2=270.000000
L 6.52285738 4.4808501 6.51993986 4.48165 2 P 0 ;0,1=61,2=270.000000
L 6.51993986 4.48165 6.51702382 4.48111673 2 P 0 ;0,1=61,2=270.000000
L 6.51702382 4.48111673 6.51452352 4.47978327 2 P 0 ;0,1=61,2=270.000000
L 6.51452352 4.47978327 6.5128565 4.47738327 2 P 0 ;0,1=61,2=270.000000
L 6.5128565 4.47738327 6.51202333 4.47418346 2 P 0 ;0,1=61,2=270.000000
L 6.51202333 4.47418346 6.51035699 4.47231663 2 P 0 ;0,1=61,2=270.000000
L 6.51035699 4.47231663 6.50744016 4.47151634 2 P 0 ;0,1=61,2=270.000000
L 6.50744016 4.47151634 6.50452343 4.4720501 2 P 0 ;0,1=61,2=270.000000
L 6.50452343 4.4720501 6.50244055 4.47338317 2 P 0 ;0,1=61,2=270.000000
L 6.50244055 4.47338317 6.50118996 4.4752499 2 P 0 ;0,1=61,2=270.000000
L 6.50118996 4.4752499 6.50118996 4.47711663 2 P 0 ;0,1=61,2=270.000000
L 6.50118996 4.47711663 6.50202313 4.47898337 2 P 0 ;0,1=61,2=270.000000
L 6.50202313 4.47898337 6.50410679 4.48058356 2 P 0 ;0,1=61,2=270.000000
L 6.50118996 4.5000497 6.52618996 4.5000497 2 P 0 ;0,1=61,2=270.000000
L 6.50118996 4.49391673 6.50118996 4.50618317 2 P 0 ;0,1=61,2=270.000000
L 6.52618996 4.51871654 6.50118996 4.51871654 2 P 0 ;0,1=61,2=270.000000
L 6.50118996 4.51871654 6.50118996 4.52538327 2 P 0 ;0,1=61,2=270.000000
L 6.50118996 4.52538327 6.50244055 4.52751663 2 P 0 ;0,1=61,2=270.000000
L 6.50244055 4.52751663 6.50410679 4.5288501 2 P 0 ;0,1=61,2=270.000000
L 6.50410679 4.5288501 6.50744016 4.52938337 2 P 0 ;0,1=61,2=270.000000
L 6.50744016 4.52938337 6.51077362 4.5288501 2 P 0 ;0,1=61,2=270.000000
L 6.51077362 4.5288501 6.5128565 4.52725 2 P 0 ;0,1=61,2=270.000000
L 6.5128565 4.52725 6.51410699 4.52538327 2 P 0 ;0,1=61,2=270.000000
L 6.51410699 4.52538327 6.51410699 4.51871654 2 P 0 ;0,1=61,2=270.000000
L 6.51410699 4.52538327 6.52618996 4.52938337 2 P 0 ;0,1=61,2=270.000000
L 6.52618996 4.5480497 6.50118996 4.5480497 2 P 0 ;0,1=61,2=270.000000
L 6.50118996 4.5480497 6.50618967 4.5448499 2 P 0 ;0,1=61,2=270.000000
L 6.52618996 4.5448499 6.52618996 4.55124951 2 P 0 ;0,1=61,2=270.000000
L 6.50118996 4.5720497 6.50202313 4.56991634 2 P 0 ;0,1=61,2=270.000000
L 6.50202313 4.56991634 6.50410679 4.56831663 2 P 0 ;0,1=61,2=270.000000
L 6.50410679 4.56831663 6.5066063 4.5672498 2 P 0 ;0,1=61,2=270.000000
L 6.5066063 4.5672498 6.50994045 4.5664499 2 P 0 ;0,1=61,2=270.000000
L 6.50994045 4.5664499 6.51369035 4.56618327 2 P 0 ;0,1=61,2=270.000000
L 6.51369035 4.56618327 6.51744035 4.5664499 2 P 0 ;0,1=61,2=270.000000
L 6.51744035 4.5664499 6.52077372 4.5672498 2 P 0 ;0,1=61,2=270.000000
L 6.52077372 4.5672498 6.52327392 4.56831663 2 P 0 ;0,1=61,2=270.000000
L 6.52327392 4.56831663 6.52535689 4.56991634 2 P 0 ;0,1=61,2=270.000000
L 6.52535689 4.56991634 6.52618996 4.5720497 2 P 0 ;0,1=61,2=270.000000
L 6.52618996 4.5720497 6.52535689 4.57418307 2 P 0 ;0,1=61,2=270.000000
L 6.52535689 4.57418307 6.52327392 4.57578327 2 P 0 ;0,1=61,2=270.000000
L 6.52327392 4.57578327 6.52077372 4.5768501 2 P 0 ;0,1=61,2=270.000000
L 6.52077372 4.5768501 6.51744035 4.57765 2 P 0 ;0,1=61,2=270.000000
L 6.51744035 4.57765 6.51369035 4.57791663 2 P 0 ;0,1=61,2=270.000000
L 6.51369035 4.57791663 6.50994045 4.57765 2 P 0 ;0,1=61,2=270.000000
L 6.50994045 4.57765 6.5066063 4.5768501 2 P 0 ;0,1=61,2=270.000000
L 6.5066063 4.5768501 6.50410679 4.57578327 2 P 0 ;0,1=61,2=270.000000
L 6.50410679 4.57578327 6.50202313 4.57418307 2 P 0 ;0,1=61,2=270.000000
L 6.50202313 4.57418307 6.50118996 4.5720497 2 P 0 ;0,1=61,2=270.000000
L 6.52395 5.03398002 6.71843002 5.03398002 3 P 0 
L 6.71843002 5.03398002 6.71843002 4.80011998 3 P 0 
L 6.71843002 4.80011998 6.52395 4.80011998 3 P 0 
L 6.52395 4.80011998 6.52395 5.03398002 3 P 0 
L 6.49273002 4.98291998 6.49273002 4.96716998 3 P 0 
L 6.49273002 4.96716998 6.51241004 4.97503996 3 P 0 
L 6.51241004 4.97503996 6.49273002 4.98291998 3 P 0 
L 6.49273002 4.98291998 6.49858996 4.97523996 3 P 0 
L 6.73811998 4.85406004 6.71843002 4.85406004 3 P 0 
L 6.63693996 5.03398002 6.63693996 5.05366004 3 P 0 
L 6.71843002 4.9328 6.74993002 4.9328 3 P 0 
L 6.58968996 4.80011998 6.58968996 4.79 3 P 0 
L 6.52395 4.91705 6.50426004 4.91705 3 P 0 
S P 0
OB 6.52395 5.033980019685 I
OS 6.57118996063 5.033980019685
OS 6.52395 4.98673996063
OS 6.52395 5.033980019685
OE
SE
L 6.55166654 5.13 6.55166654 5.155 2 P 0 ;0,1=62,2=0.000000
L 6.55166654 5.155 6.55806663 5.155 2 P 0 ;0,1=62,2=0.000000
L 6.55806663 5.155 6.5602 5.15374941 2 P 0 ;0,1=62,2=0.000000
L 6.5602 5.15374941 6.5618001 5.15083337 2 P 0 ;0,1=62,2=0.000000
L 6.5618001 5.15083337 6.56233337 5.1475 2 P 0 ;0,1=62,2=0.000000
L 6.56233337 5.1475 6.5618001 5.14416663 2 P 0 ;0,1=62,2=0.000000
L 6.5618001 5.14416663 6.56046663 5.14166644 2 P 0 ;0,1=62,2=0.000000
L 6.56046663 5.14166644 6.55806663 5.14041594 2 P 0 ;0,1=62,2=0.000000
L 6.55806663 5.14041594 6.55166654 5.14041594 2 P 0 ;0,1=62,2=0.000000
L 6.5753999 5.13333258 6.57753327 5.1312497 2 P 0 ;0,1=62,2=0.000000
L 6.57753327 5.1312497 6.57993327 5.13 2 P 0 ;0,1=62,2=0.000000
L 6.57993327 5.13 6.58206663 5.13 2 P 0 ;0,1=62,2=0.000000
L 6.58206663 5.13 6.5842 5.1312497 2 P 0 ;0,1=62,2=0.000000
L 6.5842 5.1312497 6.5858001 5.13333258 2 P 0 ;0,1=62,2=0.000000
L 6.5858001 5.13333258 6.5866 5.1362501 2 P 0 ;0,1=62,2=0.000000
L 6.5866 5.1362501 6.58606673 5.13916614 2 P 0 ;0,1=62,2=0.000000
L 6.58606673 5.13916614 6.58473327 5.14166644 2 P 0 ;0,1=62,2=0.000000
L 6.58473327 5.14166644 6.58233327 5.14333346 2 P 0 ;0,1=62,2=0.000000
L 6.58233327 5.14333346 6.57913346 5.14416663 2 P 0 ;0,1=62,2=0.000000
L 6.57913346 5.14416663 6.57726663 5.14583297 2 P 0 ;0,1=62,2=0.000000
L 6.57726663 5.14583297 6.57646634 5.1487498 2 P 0 ;0,1=62,2=0.000000
L 6.57646634 5.1487498 6.5770001 5.15166654 2 P 0 ;0,1=62,2=0.000000
L 6.5770001 5.15166654 6.57833317 5.15374941 2 P 0 ;0,1=62,2=0.000000
L 6.57833317 5.15374941 6.5801999 5.155 2 P 0 ;0,1=62,2=0.000000
L 6.5801999 5.155 6.58206663 5.155 2 P 0 ;0,1=62,2=0.000000
L 6.58206663 5.155 6.58393337 5.15416683 2 P 0 ;0,1=62,2=0.000000
L 6.58393337 5.15416683 6.58553356 5.15208317 2 P 0 ;0,1=62,2=0.000000
L 6.6049997 5.155 6.6049997 5.13 2 P 0 ;0,1=62,2=0.000000
L 6.59886673 5.155 6.61113317 5.155 2 P 0 ;0,1=62,2=0.000000
L 6.62313327 5.155 6.62313327 5.13708327 2 P 0 ;0,1=62,2=0.000000
L 6.62313327 5.13708327 6.6241998 5.13333258 2 P 0 ;0,1=62,2=0.000000
L 6.6241998 5.13333258 6.62633317 5.13083307 2 P 0 ;0,1=62,2=0.000000
L 6.62633317 5.13083307 6.6289997 5.13 2 P 0 ;0,1=62,2=0.000000
L 6.6289997 5.13 6.63166673 5.13083307 2 P 0 ;0,1=62,2=0.000000
L 6.63166673 5.13083307 6.6338001 5.13333258 2 P 0 ;0,1=62,2=0.000000
L 6.6338001 5.13333258 6.63486663 5.13708327 2 P 0 ;0,1=62,2=0.000000
L 6.63486663 5.13708327 6.63486663 5.155 2 P 0 ;0,1=62,2=0.000000
L 6.6529997 5.13 6.6529997 5.155 2 P 0 ;0,1=62,2=0.000000
L 6.6529997 5.155 6.6497999 5.1500003 2 P 0 ;0,1=62,2=0.000000
L 6.6497999 5.13 6.65619951 5.13 2 P 0 ;0,1=62,2=0.000000
L 6.50118632 4.83387608 6.50305315 4.83179311 2 P 0 ;0,1=28,2=0.000000
L 6.50305315 4.83179311 6.50518652 4.83096004 2 P 0 ;0,1=28,2=0.000000
L 6.50518652 4.83096004 6.50731988 4.83179311 2 P 0 ;0,1=28,2=0.000000
L 6.50731988 4.83179311 6.50918661 4.83429262 2 P 0 ;0,1=28,2=0.000000
L 6.50918661 4.83429262 6.51052008 4.83804331 2 P 0 ;0,1=28,2=0.000000
L 6.51052008 4.83804331 6.51105335 4.84179331 2 P 0 ;0,1=28,2=0.000000
L 6.51105335 4.84179331 6.51105335 4.84637638 2 P 0 ;0,1=28,2=0.000000
L 6.51105335 4.84637638 6.51052008 4.85012638 2 P 0 ;0,1=28,2=0.000000
L 6.51052008 4.85012638 6.50918661 4.85345974 2 P 0 ;0,1=28,2=0.000000
L 6.50918661 4.85345974 6.50758642 4.85512687 2 P 0 ;0,1=28,2=0.000000
L 6.50758642 4.85512687 6.50571969 4.85596004 2 P 0 ;0,1=28,2=0.000000
L 6.50571969 4.85596004 6.50358632 4.85512687 2 P 0 ;0,1=28,2=0.000000
L 6.50358632 4.85512687 6.50198661 4.85345974 2 P 0 ;0,1=28,2=0.000000
L 6.50198661 4.85345974 6.50091978 4.85096033 2 P 0 ;0,1=28,2=0.000000
L 6.50091978 4.85096033 6.50038652 4.84762618 2 P 0 ;0,1=28,2=0.000000
L 6.50038652 4.84762618 6.50091978 4.84471014 2 P 0 ;0,1=28,2=0.000000
L 6.50091978 4.84471014 6.50225325 4.84179331 2 P 0 ;0,1=28,2=0.000000
L 6.50225325 4.84179331 6.50385344 4.84012618 2 P 0 ;0,1=28,2=0.000000
L 6.50385344 4.84012618 6.50571969 4.83970965 2 P 0 ;0,1=28,2=0.000000
L 6.50571969 4.83970965 6.50785305 4.84054282 2 P 0 ;0,1=28,2=0.000000
L 6.50785305 4.84054282 6.50945325 4.84262648 2 P 0 ;0,1=28,2=0.000000
L 6.50945325 4.84262648 6.51105335 4.84637638 2 P 0 ;0,1=28,2=0.000000
L 6.64 4.7559997 6.615 4.7559997 2 P 0 ;0,1=63,2=270.000000
L 6.615 4.7559997 6.6199997 4.7527999 2 P 0 ;0,1=63,2=270.000000
L 6.64 4.7527999 6.64 4.75919951 2 P 0 ;0,1=63,2=270.000000
L 6.64 4.7832 6.615 4.7832 2 P 0 ;0,1=63,2=270.000000
L 6.615 4.7832 6.63291673 4.77333297 2 P 0 ;0,1=63,2=270.000000
L 6.63291673 4.77333297 6.63291673 4.78666693 2 P 0 ;0,1=63,2=270.000000
L 6.73293317 5.02583337 6.73453327 5.02833287 2 P 0 ;0,1=64,2=0.000000
L 6.73453327 5.02833287 6.7364 5.02958337 2 P 0 ;0,1=64,2=0.000000
L 6.7364 5.02958337 6.73853337 5.03 2 P 0 ;0,1=64,2=0.000000
L 6.73853337 5.03 6.7412 5.02916683 2 P 0 ;0,1=64,2=0.000000
L 6.7412 5.02916683 6.74306673 5.02708317 2 P 0 ;0,1=64,2=0.000000
L 6.74306673 5.02708317 6.7436 5.02458366 2 P 0 ;0,1=64,2=0.000000
L 6.7436 5.02458366 6.74333337 5.02208268 2 P 0 ;0,1=64,2=0.000000
L 6.74333337 5.02208268 6.74226644 5.0199998 2 P 0 ;0,1=64,2=0.000000
L 6.74226644 5.0199998 6.73693327 5.01583327 2 P 0 ;0,1=64,2=0.000000
L 6.73693327 5.01583327 6.73453327 5.01291644 2 P 0 ;0,1=64,2=0.000000
L 6.73453327 5.01291644 6.73293317 5.00874911 2 P 0 ;0,1=64,2=0.000000
L 6.73293317 5.00874911 6.7323999 5.005 2 P 0 ;0,1=64,2=0.000000
L 6.7323999 5.005 6.7436 5.005 2 P 0 ;0,1=64,2=0.000000
L 6.75613327 5.00999961 6.75773297 5.00708287 2 P 0 ;0,1=64,2=0.000000
L 6.75773297 5.00708287 6.75986634 5.00541654 2 P 0 ;0,1=64,2=0.000000
L 6.75986634 5.00541654 6.76226683 5.005 2 P 0 ;0,1=64,2=0.000000
L 6.76226683 5.005 6.7644002 5.00541654 2 P 0 ;0,1=64,2=0.000000
L 6.7644002 5.00541654 6.76653356 5.00749941 2 P 0 ;0,1=64,2=0.000000
L 6.76653356 5.00749941 6.76786663 5.00999961 2 P 0 ;0,1=64,2=0.000000
L 6.76786663 5.00999961 6.76813317 5.0124999 2 P 0 ;0,1=64,2=0.000000
L 6.76813317 5.0124999 6.7676 5.01541594 2 P 0 ;0,1=64,2=0.000000
L 6.7676 5.01541594 6.76573327 5.01749961 2 P 0 ;0,1=64,2=0.000000
L 6.76573327 5.01749961 6.76386644 5.01833346 2 P 0 ;0,1=64,2=0.000000
L 6.76386644 5.01833346 6.76146654 5.01833346 2 P 0 ;0,1=64,2=0.000000
L 6.76386644 5.01833346 6.76546663 5.01958327 2 P 0 ;0,1=64,2=0.000000
L 6.76546663 5.01958327 6.7668001 5.02166614 2 P 0 ;0,1=64,2=0.000000
L 6.7668001 5.02166614 6.76733337 5.02416634 2 P 0 ;0,1=64,2=0.000000
L 6.76733337 5.02416634 6.7668001 5.02666654 2 P 0 ;0,1=64,2=0.000000
L 6.7668001 5.02666654 6.76546663 5.02874941 2 P 0 ;0,1=64,2=0.000000
L 6.76546663 5.02874941 6.76306663 5.03 2 P 0 ;0,1=64,2=0.000000
L 6.76306663 5.03 6.76066663 5.02958337 2 P 0 ;0,1=64,2=0.000000
L 6.76066663 5.02958337 6.75826663 5.02791634 2 P 0 ;0,1=64,2=0.000000
L 6.66916663 5.04293317 6.66666713 5.04453327 2 P 0 ;0,1=65,2=270.000000
L 6.66666713 5.04453327 6.66541663 5.0464 2 P 0 ;0,1=65,2=270.000000
L 6.66541663 5.0464 6.665 5.04853337 2 P 0 ;0,1=65,2=270.000000
L 6.665 5.04853337 6.66583317 5.0512 2 P 0 ;0,1=65,2=270.000000
L 6.66583317 5.0512 6.66791683 5.05306673 2 P 0 ;0,1=65,2=270.000000
L 6.66791683 5.05306673 6.67041634 5.0536 2 P 0 ;0,1=65,2=270.000000
L 6.67041634 5.0536 6.67291732 5.05333337 2 P 0 ;0,1=65,2=270.000000
L 6.67291732 5.05333337 6.6750002 5.05226644 2 P 0 ;0,1=65,2=270.000000
L 6.6750002 5.05226644 6.67916673 5.04693327 2 P 0 ;0,1=65,2=270.000000
L 6.67916673 5.04693327 6.68208356 5.04453327 2 P 0 ;0,1=65,2=270.000000
L 6.68208356 5.04453327 6.68625089 5.04293317 2 P 0 ;0,1=65,2=270.000000
L 6.68625089 5.04293317 6.69 5.0423999 2 P 0 ;0,1=65,2=270.000000
L 6.69 5.0423999 6.69 5.0536 2 P 0 ;0,1=65,2=270.000000
L 6.69 5.0752 6.665 5.0752 2 P 0 ;0,1=65,2=270.000000
L 6.665 5.0752 6.68291673 5.06533297 2 P 0 ;0,1=65,2=270.000000
L 6.68291673 5.06533297 6.68291673 5.07866693 2 P 0 ;0,1=65,2=270.000000
L 6.50916663 5.04293317 6.50666713 5.04453327 2 P 0 ;0,1=66,2=270.000000
L 6.50666713 5.04453327 6.50541663 5.0464 2 P 0 ;0,1=66,2=270.000000
L 6.50541663 5.0464 6.505 5.04853337 2 P 0 ;0,1=66,2=270.000000
L 6.505 5.04853337 6.50583317 5.0512 2 P 0 ;0,1=66,2=270.000000
L 6.50583317 5.0512 6.50791683 5.05306673 2 P 0 ;0,1=66,2=270.000000
L 6.50791683 5.05306673 6.51041634 5.0536 2 P 0 ;0,1=66,2=270.000000
L 6.51041634 5.0536 6.51291732 5.05333337 2 P 0 ;0,1=66,2=270.000000
L 6.51291732 5.05333337 6.5150002 5.05226644 2 P 0 ;0,1=66,2=270.000000
L 6.5150002 5.05226644 6.51916673 5.04693327 2 P 0 ;0,1=66,2=270.000000
L 6.51916673 5.04693327 6.52208356 5.04453327 2 P 0 ;0,1=66,2=270.000000
L 6.52208356 5.04453327 6.52625089 5.04293317 2 P 0 ;0,1=66,2=270.000000
L 6.52625089 5.04293317 6.53 5.0423999 2 P 0 ;0,1=66,2=270.000000
L 6.53 5.0423999 6.53 5.0536 2 P 0 ;0,1=66,2=270.000000
L 6.53 5.0719997 6.52958346 5.07386644 2 P 0 ;0,1=66,2=270.000000
L 6.52958346 5.07386644 6.52833376 5.0759998 2 P 0 ;0,1=66,2=270.000000
L 6.52833376 5.0759998 6.52625089 5.07733337 2 P 0 ;0,1=66,2=270.000000
L 6.52625089 5.07733337 6.52333327 5.07786663 2 P 0 ;0,1=66,2=270.000000
L 6.52333327 5.07786663 6.52041722 5.07733337 2 P 0 ;0,1=66,2=270.000000
L 6.52041722 5.07733337 6.51791703 5.07573327 2 P 0 ;0,1=66,2=270.000000
L 6.51791703 5.07573327 6.51666654 5.07333327 2 P 0 ;0,1=66,2=270.000000
L 6.51666654 5.07333327 6.51666654 5.07066663 2 P 0 ;0,1=66,2=270.000000
L 6.51666654 5.07066663 6.51583337 5.06906654 2 P 0 ;0,1=66,2=270.000000
L 6.51583337 5.06906654 6.51375049 5.06773297 2 P 0 ;0,1=66,2=270.000000
L 6.51375049 5.06773297 6.51083366 5.0671998 2 P 0 ;0,1=66,2=270.000000
L 6.51083366 5.0671998 6.50791683 5.0680001 2 P 0 ;0,1=66,2=270.000000
L 6.50791683 5.0680001 6.50583317 5.06986634 2 P 0 ;0,1=66,2=270.000000
L 6.50583317 5.06986634 6.505 5.0719997 2 P 0 ;0,1=66,2=270.000000
L 6.505 5.0719997 6.50583317 5.07413307 2 P 0 ;0,1=66,2=270.000000
L 6.50583317 5.07413307 6.50791683 5.0759998 2 P 0 ;0,1=66,2=270.000000
L 6.50791683 5.0759998 6.51083366 5.0768001 2 P 0 ;0,1=66,2=270.000000
L 6.51083366 5.0768001 6.51375049 5.07626644 2 P 0 ;0,1=66,2=270.000000
L 6.51375049 5.07626644 6.51583337 5.07493337 2 P 0 ;0,1=66,2=270.000000
L 6.51583337 5.07493337 6.51666654 5.07333327 2 P 0 ;0,1=66,2=270.000000
L 6.51666654 5.07333327 6.51666654 5.07066663 2 P 0 ;0,1=66,2=270.000000
L 6.51666654 5.07066663 6.51791703 5.06826663 2 P 0 ;0,1=66,2=270.000000
L 6.51791703 5.06826663 6.52041722 5.06666654 2 P 0 ;0,1=66,2=270.000000
L 6.52041722 5.06666654 6.52333327 5.06613327 2 P 0 ;0,1=66,2=270.000000
L 6.52333327 5.06613327 6.52625089 5.06666654 2 P 0 ;0,1=66,2=270.000000
L 6.52625089 5.06666654 6.52833376 5.0680001 2 P 0 ;0,1=66,2=270.000000
L 6.52833376 5.0680001 6.52958346 5.07013346 2 P 0 ;0,1=66,2=270.000000
L 6.52958346 5.07013346 6.53 5.0719997 2 P 0 ;0,1=66,2=270.000000
A 6.84513002 4.88705 6.84513002 4.88705 6.84118996 4.88705 2 P 0 N
L 6.92666654 4.88 6.92666654 4.905 2 P 0 ;0,1=67,2=0.000000
L 6.92666654 4.905 6.93306663 4.905 2 P 0 ;0,1=67,2=0.000000
L 6.93306663 4.905 6.9352 4.90374941 2 P 0 ;0,1=67,2=0.000000
L 6.9352 4.90374941 6.9368001 4.90083337 2 P 0 ;0,1=67,2=0.000000
L 6.9368001 4.90083337 6.93733337 4.8975 2 P 0 ;0,1=67,2=0.000000
L 6.93733337 4.8975 6.9368001 4.89416663 2 P 0 ;0,1=67,2=0.000000
L 6.9368001 4.89416663 6.93546663 4.89166644 2 P 0 ;0,1=67,2=0.000000
L 6.93546663 4.89166644 6.93306663 4.89041594 2 P 0 ;0,1=67,2=0.000000
L 6.93306663 4.89041594 6.92666654 4.89041594 2 P 0 ;0,1=67,2=0.000000
L 6.9503999 4.88333258 6.95253327 4.8812497 2 P 0 ;0,1=67,2=0.000000
L 6.95253327 4.8812497 6.95493327 4.88 2 P 0 ;0,1=67,2=0.000000
L 6.95493327 4.88 6.95706663 4.88 2 P 0 ;0,1=67,2=0.000000
L 6.95706663 4.88 6.9592 4.8812497 2 P 0 ;0,1=67,2=0.000000
L 6.9592 4.8812497 6.9608001 4.88333258 2 P 0 ;0,1=67,2=0.000000
L 6.9608001 4.88333258 6.9616 4.8862501 2 P 0 ;0,1=67,2=0.000000
L 6.9616 4.8862501 6.96106673 4.88916614 2 P 0 ;0,1=67,2=0.000000
L 6.96106673 4.88916614 6.95973327 4.89166644 2 P 0 ;0,1=67,2=0.000000
L 6.95973327 4.89166644 6.95733327 4.89333346 2 P 0 ;0,1=67,2=0.000000
L 6.95733327 4.89333346 6.95413346 4.89416663 2 P 0 ;0,1=67,2=0.000000
L 6.95413346 4.89416663 6.95226663 4.89583297 2 P 0 ;0,1=67,2=0.000000
L 6.95226663 4.89583297 6.95146634 4.8987498 2 P 0 ;0,1=67,2=0.000000
L 6.95146634 4.8987498 6.9520001 4.90166654 2 P 0 ;0,1=67,2=0.000000
L 6.9520001 4.90166654 6.95333317 4.90374941 2 P 0 ;0,1=67,2=0.000000
L 6.95333317 4.90374941 6.9551999 4.905 2 P 0 ;0,1=67,2=0.000000
L 6.9551999 4.905 6.95706663 4.905 2 P 0 ;0,1=67,2=0.000000
L 6.95706663 4.905 6.95893337 4.90416683 2 P 0 ;0,1=67,2=0.000000
L 6.95893337 4.90416683 6.96053356 4.90208317 2 P 0 ;0,1=67,2=0.000000
L 6.9799997 4.905 6.9799997 4.88 2 P 0 ;0,1=67,2=0.000000
L 6.97386673 4.905 6.98613317 4.905 2 P 0 ;0,1=67,2=0.000000
L 7.00986663 4.90291634 7.00826644 4.90416683 2 P 0 ;0,1=67,2=0.000000
L 7.00826644 4.90416683 7.0064002 4.905 2 P 0 ;0,1=67,2=0.000000
L 7.0064002 4.905 7.00426683 4.905 2 P 0 ;0,1=67,2=0.000000
L 7.00426683 4.905 7.00186634 4.90374941 2 P 0 ;0,1=67,2=0.000000
L 7.00186634 4.90374941 7.0000001 4.90166654 2 P 0 ;0,1=67,2=0.000000
L 7.0000001 4.90166654 6.99866654 4.89916634 2 P 0 ;0,1=67,2=0.000000
L 6.99866654 4.89916634 6.99759961 4.8949998 2 P 0 ;0,1=67,2=0.000000
L 6.99759961 4.8949998 6.99733297 4.8912498 2 P 0 ;0,1=67,2=0.000000
L 6.99733297 4.8912498 6.99786673 4.8874999 2 P 0 ;0,1=67,2=0.000000
L 6.99786673 4.8874999 6.99866654 4.88499961 2 P 0 ;0,1=67,2=0.000000
L 6.99866654 4.88499961 7.00026663 4.88249941 2 P 0 ;0,1=67,2=0.000000
L 7.00026663 4.88249941 7.00213346 4.88083307 2 P 0 ;0,1=67,2=0.000000
L 7.00213346 4.88083307 7.0039997 4.88 2 P 0 ;0,1=67,2=0.000000
L 7.0039997 4.88 7.00586644 4.88 2 P 0 ;0,1=67,2=0.000000
L 7.00586644 4.88 7.00773327 4.88083307 2 P 0 ;0,1=67,2=0.000000
L 7.00773327 4.88083307 7.00933337 4.88208287 2 P 0 ;0,1=67,2=0.000000
L 7.00933337 4.88208287 7.01066693 4.88374911 2 P 0 ;0,1=67,2=0.000000
L 7.02213327 4.88499961 7.02373297 4.88208287 2 P 0 ;0,1=67,2=0.000000
L 7.02373297 4.88208287 7.02586634 4.88041654 2 P 0 ;0,1=67,2=0.000000
L 7.02586634 4.88041654 7.02826683 4.88 2 P 0 ;0,1=67,2=0.000000
L 7.02826683 4.88 7.0304002 4.88041654 2 P 0 ;0,1=67,2=0.000000
L 7.0304002 4.88041654 7.03253356 4.88249941 2 P 0 ;0,1=67,2=0.000000
L 7.03253356 4.88249941 7.03386663 4.88499961 2 P 0 ;0,1=67,2=0.000000
L 7.03386663 4.88499961 7.03413317 4.8874999 2 P 0 ;0,1=67,2=0.000000
L 7.03413317 4.8874999 7.0336 4.89041594 2 P 0 ;0,1=67,2=0.000000
L 7.0336 4.89041594 7.03173327 4.89249961 2 P 0 ;0,1=67,2=0.000000
L 7.03173327 4.89249961 7.02986644 4.89333346 2 P 0 ;0,1=67,2=0.000000
L 7.02986644 4.89333346 7.02746654 4.89333346 2 P 0 ;0,1=67,2=0.000000
L 7.02986644 4.89333346 7.03146663 4.89458327 2 P 0 ;0,1=67,2=0.000000
L 7.03146663 4.89458327 7.0328001 4.89666614 2 P 0 ;0,1=67,2=0.000000
L 7.0328001 4.89666614 7.03333337 4.89916634 2 P 0 ;0,1=67,2=0.000000
L 7.03333337 4.89916634 7.0328001 4.90166654 2 P 0 ;0,1=67,2=0.000000
L 7.0328001 4.90166654 7.03146663 4.90374941 2 P 0 ;0,1=67,2=0.000000
L 7.03146663 4.90374941 7.02906663 4.905 2 P 0 ;0,1=67,2=0.000000
L 7.02906663 4.905 7.02666663 4.90458337 2 P 0 ;0,1=67,2=0.000000
L 7.02666663 4.90458337 7.02426663 4.90291634 2 P 0 ;0,1=67,2=0.000000
A 6.84513002 4.94705 6.84513002 4.94705 6.84118996 4.94705 2 P 0 N
L 6.92466654 4.935 6.92466654 4.96 2 P 0 ;0,1=68,2=0.000000
L 6.92466654 4.96 6.93106663 4.96 2 P 0 ;0,1=68,2=0.000000
L 6.93106663 4.96 6.9332 4.95874941 2 P 0 ;0,1=68,2=0.000000
L 6.9332 4.95874941 6.9348001 4.95583337 2 P 0 ;0,1=68,2=0.000000
L 6.9348001 4.95583337 6.93533337 4.9525 2 P 0 ;0,1=68,2=0.000000
L 6.93533337 4.9525 6.9348001 4.94916663 2 P 0 ;0,1=68,2=0.000000
L 6.9348001 4.94916663 6.93346663 4.94666644 2 P 0 ;0,1=68,2=0.000000
L 6.93346663 4.94666644 6.93106663 4.94541594 2 P 0 ;0,1=68,2=0.000000
L 6.93106663 4.94541594 6.92466654 4.94541594 2 P 0 ;0,1=68,2=0.000000
L 6.9483999 4.93833258 6.95053327 4.9362497 2 P 0 ;0,1=68,2=0.000000
L 6.95053327 4.9362497 6.95293327 4.935 2 P 0 ;0,1=68,2=0.000000
L 6.95293327 4.935 6.95506663 4.935 2 P 0 ;0,1=68,2=0.000000
L 6.95506663 4.935 6.9572 4.9362497 2 P 0 ;0,1=68,2=0.000000
L 6.9572 4.9362497 6.9588001 4.93833258 2 P 0 ;0,1=68,2=0.000000
L 6.9588001 4.93833258 6.9596 4.9412501 2 P 0 ;0,1=68,2=0.000000
L 6.9596 4.9412501 6.95906673 4.94416614 2 P 0 ;0,1=68,2=0.000000
L 6.95906673 4.94416614 6.95773327 4.94666644 2 P 0 ;0,1=68,2=0.000000
L 6.95773327 4.94666644 6.95533327 4.94833346 2 P 0 ;0,1=68,2=0.000000
L 6.95533327 4.94833346 6.95213346 4.94916663 2 P 0 ;0,1=68,2=0.000000
L 6.95213346 4.94916663 6.95026663 4.95083297 2 P 0 ;0,1=68,2=0.000000
L 6.95026663 4.95083297 6.94946634 4.9537498 2 P 0 ;0,1=68,2=0.000000
L 6.94946634 4.9537498 6.9500001 4.95666654 2 P 0 ;0,1=68,2=0.000000
L 6.9500001 4.95666654 6.95133317 4.95874941 2 P 0 ;0,1=68,2=0.000000
L 6.95133317 4.95874941 6.9531999 4.96 2 P 0 ;0,1=68,2=0.000000
L 6.9531999 4.96 6.95506663 4.96 2 P 0 ;0,1=68,2=0.000000
L 6.95506663 4.96 6.95693337 4.95916683 2 P 0 ;0,1=68,2=0.000000
L 6.95693337 4.95916683 6.95853356 4.95708317 2 P 0 ;0,1=68,2=0.000000
L 6.9779997 4.96 6.9779997 4.935 2 P 0 ;0,1=68,2=0.000000
L 6.97186673 4.96 6.98413317 4.96 2 P 0 ;0,1=68,2=0.000000
L 7.00786663 4.95791634 7.00626644 4.95916683 2 P 0 ;0,1=68,2=0.000000
L 7.00626644 4.95916683 7.0044002 4.96 2 P 0 ;0,1=68,2=0.000000
L 7.0044002 4.96 7.00226683 4.96 2 P 0 ;0,1=68,2=0.000000
L 7.00226683 4.96 6.99986634 4.95874941 2 P 0 ;0,1=68,2=0.000000
L 6.99986634 4.95874941 6.9980001 4.95666654 2 P 0 ;0,1=68,2=0.000000
L 6.9980001 4.95666654 6.99666654 4.95416634 2 P 0 ;0,1=68,2=0.000000
L 6.99666654 4.95416634 6.99559961 4.9499998 2 P 0 ;0,1=68,2=0.000000
L 6.99559961 4.9499998 6.99533297 4.9462498 2 P 0 ;0,1=68,2=0.000000
L 6.99533297 4.9462498 6.99586673 4.9424999 2 P 0 ;0,1=68,2=0.000000
L 6.99586673 4.9424999 6.99666654 4.93999961 2 P 0 ;0,1=68,2=0.000000
L 6.99666654 4.93999961 6.99826663 4.93749941 2 P 0 ;0,1=68,2=0.000000
L 6.99826663 4.93749941 7.00013346 4.93583307 2 P 0 ;0,1=68,2=0.000000
L 7.00013346 4.93583307 7.0019997 4.935 2 P 0 ;0,1=68,2=0.000000
L 7.0019997 4.935 7.00386644 4.935 2 P 0 ;0,1=68,2=0.000000
L 7.00386644 4.935 7.00573327 4.93583307 2 P 0 ;0,1=68,2=0.000000
L 7.00573327 4.93583307 7.00733337 4.93708287 2 P 0 ;0,1=68,2=0.000000
L 7.00733337 4.93708287 7.00866693 4.93874911 2 P 0 ;0,1=68,2=0.000000
L 7.02093317 4.95583337 7.02253327 4.95833287 2 P 0 ;0,1=68,2=0.000000
L 7.02253327 4.95833287 7.0244 4.95958337 2 P 0 ;0,1=68,2=0.000000
L 7.0244 4.95958337 7.02653337 4.96 2 P 0 ;0,1=68,2=0.000000
L 7.02653337 4.96 7.0292 4.95916683 2 P 0 ;0,1=68,2=0.000000
L 7.0292 4.95916683 7.03106673 4.95708317 2 P 0 ;0,1=68,2=0.000000
L 7.03106673 4.95708317 7.0316 4.95458366 2 P 0 ;0,1=68,2=0.000000
L 7.0316 4.95458366 7.03133337 4.95208268 2 P 0 ;0,1=68,2=0.000000
L 7.03133337 4.95208268 7.03026644 4.9499998 2 P 0 ;0,1=68,2=0.000000
L 7.03026644 4.9499998 7.02493327 4.94583327 2 P 0 ;0,1=68,2=0.000000
L 7.02493327 4.94583327 7.02253327 4.94291644 2 P 0 ;0,1=68,2=0.000000
L 7.02253327 4.94291644 7.02093317 4.93874911 2 P 0 ;0,1=68,2=0.000000
L 7.02093317 4.93874911 7.0203999 4.935 2 P 0 ;0,1=68,2=0.000000
L 7.0203999 4.935 7.0316 4.935 2 P 0 ;0,1=68,2=0.000000
L 7.0499997 4.96 7.04786634 4.95916683 2 P 0 ;0,1=68,2=0.000000
L 7.04786634 4.95916683 7.04626663 4.95708317 2 P 0 ;0,1=68,2=0.000000
L 7.04626663 4.95708317 7.0451998 4.95458366 2 P 0 ;0,1=68,2=0.000000
L 7.0451998 4.95458366 7.0443999 4.95124951 2 P 0 ;0,1=68,2=0.000000
L 7.0443999 4.95124951 7.04413327 4.94749961 2 P 0 ;0,1=68,2=0.000000
L 7.04413327 4.94749961 7.0443999 4.94374961 2 P 0 ;0,1=68,2=0.000000
L 7.0443999 4.94374961 7.0451998 4.94041624 2 P 0 ;0,1=68,2=0.000000
L 7.0451998 4.94041624 7.04626663 4.93791604 2 P 0 ;0,1=68,2=0.000000
L 7.04626663 4.93791604 7.04786634 4.93583307 2 P 0 ;0,1=68,2=0.000000
L 7.04786634 4.93583307 7.0499997 4.935 2 P 0 ;0,1=68,2=0.000000
L 7.0499997 4.935 7.05213307 4.93583307 2 P 0 ;0,1=68,2=0.000000
L 7.05213307 4.93583307 7.05373327 4.93791604 2 P 0 ;0,1=68,2=0.000000
L 7.05373327 4.93791604 7.0548001 4.94041624 2 P 0 ;0,1=68,2=0.000000
L 7.0548001 4.94041624 7.0556 4.94374961 2 P 0 ;0,1=68,2=0.000000
L 7.0556 4.94374961 7.05586663 4.94749961 2 P 0 ;0,1=68,2=0.000000
L 7.05586663 4.94749961 7.0556 4.95124951 2 P 0 ;0,1=68,2=0.000000
L 7.0556 4.95124951 7.0548001 4.95458366 2 P 0 ;0,1=68,2=0.000000
L 7.0548001 4.95458366 7.05373327 4.95708317 2 P 0 ;0,1=68,2=0.000000
L 7.05373327 4.95708317 7.05213307 4.95916683 2 P 0 ;0,1=68,2=0.000000
L 7.05213307 4.95916683 7.0499997 4.96 2 P 0 ;0,1=68,2=0.000000
L 6.82618996 4.74973002 6.79351004 4.74973002 3 P 0 
L 6.79351004 4.74973002 6.79351004 4.58436998 3 P 0 
L 6.79351004 4.58436998 6.82618996 4.58436998 3 P 0 
L 6.92618996 4.74973002 6.95886998 4.74973002 3 P 0 
L 6.95886998 4.74973002 6.95886998 4.58436998 3 P 0 
L 6.95886998 4.58436998 6.92618996 4.58436998 3 P 0 
L 7.01 4.61166654 6.985 4.61166654 2 P 0 ;0,1=69,2=270.000000
L 6.985 4.61166654 6.985 4.61806663 2 P 0 ;0,1=69,2=270.000000
L 6.985 4.61806663 6.98625059 4.6202 2 P 0 ;0,1=69,2=270.000000
L 6.98625059 4.6202 6.98916663 4.6218001 2 P 0 ;0,1=69,2=270.000000
L 6.98916663 4.6218001 6.9925 4.62233337 2 P 0 ;0,1=69,2=270.000000
L 6.9925 4.62233337 6.99583337 4.6218001 2 P 0 ;0,1=69,2=270.000000
L 6.99583337 4.6218001 6.99833356 4.62046663 2 P 0 ;0,1=69,2=270.000000
L 6.99833356 4.62046663 6.99958406 4.61806663 2 P 0 ;0,1=69,2=270.000000
L 6.99958406 4.61806663 6.99958406 4.61166654 2 P 0 ;0,1=69,2=270.000000
L 7.00666742 4.6353999 7.0087503 4.63753327 2 P 0 ;0,1=69,2=270.000000
L 7.0087503 4.63753327 7.01 4.63993327 2 P 0 ;0,1=69,2=270.000000
L 7.01 4.63993327 7.01 4.64206663 2 P 0 ;0,1=69,2=270.000000
L 7.01 4.64206663 7.0087503 4.6442 2 P 0 ;0,1=69,2=270.000000
L 7.0087503 4.6442 7.00666742 4.6458001 2 P 0 ;0,1=69,2=270.000000
L 7.00666742 4.6458001 7.0037499 4.6466 2 P 0 ;0,1=69,2=270.000000
L 7.0037499 4.6466 7.00083386 4.64606673 2 P 0 ;0,1=69,2=270.000000
L 7.00083386 4.64606673 6.99833356 4.64473327 2 P 0 ;0,1=69,2=270.000000
L 6.99833356 4.64473327 6.99666654 4.64233327 2 P 0 ;0,1=69,2=270.000000
L 6.99666654 4.64233327 6.99583337 4.63913346 2 P 0 ;0,1=69,2=270.000000
L 6.99583337 4.63913346 6.99416703 4.63726663 2 P 0 ;0,1=69,2=270.000000
L 6.99416703 4.63726663 6.9912502 4.63646634 2 P 0 ;0,1=69,2=270.000000
L 6.9912502 4.63646634 6.98833346 4.6370001 2 P 0 ;0,1=69,2=270.000000
L 6.98833346 4.6370001 6.98625059 4.63833317 2 P 0 ;0,1=69,2=270.000000
L 6.98625059 4.63833317 6.985 4.6401999 2 P 0 ;0,1=69,2=270.000000
L 6.985 4.6401999 6.985 4.64206663 2 P 0 ;0,1=69,2=270.000000
L 6.985 4.64206663 6.98583317 4.64393337 2 P 0 ;0,1=69,2=270.000000
L 6.98583317 4.64393337 6.98791683 4.64553356 2 P 0 ;0,1=69,2=270.000000
L 6.985 4.6649997 7.01 4.6649997 2 P 0 ;0,1=69,2=270.000000
L 6.985 4.65886673 6.985 4.67113317 2 P 0 ;0,1=69,2=270.000000
L 6.985 4.68366654 7.01 4.68366654 2 P 0 ;0,1=69,2=270.000000
L 7.01 4.68366654 7.01 4.69433337 2 P 0 ;0,1=69,2=270.000000
L 7.01 4.7129997 6.985 4.7129997 2 P 0 ;0,1=69,2=270.000000
L 6.985 4.7129997 6.9899997 4.7097999 2 P 0 ;0,1=69,2=270.000000
L 7.01 4.7097999 7.01 4.71619951 2 P 0 ;0,1=69,2=270.000000
L 4.04061004 5.07198996 4.06423002 5.09561004 3 P 0 
L 4.06423002 5.09561004 4.06423002 5.13753996 3 P 0 
L 4.06423002 5.13753996 3.85556998 5.13753996 3 P 0 
L 3.85556998 5.13753996 3.85556998 5.00643996 3 P 0 
L 3.85556998 5.00643996 4.06423002 5.00643996 3 P 0 
L 4.06423002 5.00643996 4.06423002 5.04836998 3 P 0 
L 4.06423002 5.04836998 4.04061004 5.07198996 3 P 0 
A 4.07216998 5.18223002 4.07216998 5.18223002 4.06545 5.18223002 6 P 0 N
L 4.09713327 5.195 4.09713327 5.17708327 2 P 0 ;0,1=70,2=0.000000
L 4.09713327 5.17708327 4.0981998 5.17333258 2 P 0 ;0,1=70,2=0.000000
L 4.0981998 5.17333258 4.10033317 5.17083307 2 P 0 ;0,1=70,2=0.000000
L 4.10033317 5.17083307 4.1029997 5.17 2 P 0 ;0,1=70,2=0.000000
L 4.1029997 5.17 4.10566673 5.17083307 2 P 0 ;0,1=70,2=0.000000
L 4.10566673 5.17083307 4.1078001 5.17333258 2 P 0 ;0,1=70,2=0.000000
L 4.1078001 5.17333258 4.10886663 5.17708327 2 P 0 ;0,1=70,2=0.000000
L 4.10886663 5.17708327 4.10886663 5.195 2 P 0 ;0,1=70,2=0.000000
L 4.1269997 5.17 4.1269997 5.195 2 P 0 ;0,1=70,2=0.000000
L 4.1269997 5.195 4.1237999 5.1900003 2 P 0 ;0,1=70,2=0.000000
L 4.1237999 5.17 4.13019951 5.17 2 P 0 ;0,1=70,2=0.000000
L 4.1509997 5.195 4.14886634 5.19416683 2 P 0 ;0,1=70,2=0.000000
L 4.14886634 5.19416683 4.14726663 5.19208317 2 P 0 ;0,1=70,2=0.000000
L 4.14726663 5.19208317 4.1461998 5.18958366 2 P 0 ;0,1=70,2=0.000000
L 4.1461998 5.18958366 4.1453999 5.18624951 2 P 0 ;0,1=70,2=0.000000
L 4.1453999 5.18624951 4.14513327 5.18249961 2 P 0 ;0,1=70,2=0.000000
L 4.14513327 5.18249961 4.1453999 5.17874961 2 P 0 ;0,1=70,2=0.000000
L 4.1453999 5.17874961 4.1461998 5.17541624 2 P 0 ;0,1=70,2=0.000000
L 4.1461998 5.17541624 4.14726663 5.17291604 2 P 0 ;0,1=70,2=0.000000
L 4.14726663 5.17291604 4.14886634 5.17083307 2 P 0 ;0,1=70,2=0.000000
L 4.14886634 5.17083307 4.1509997 5.17 2 P 0 ;0,1=70,2=0.000000
L 4.1509997 5.17 4.15313307 5.17083307 2 P 0 ;0,1=70,2=0.000000
L 4.15313307 5.17083307 4.15473327 5.17291604 2 P 0 ;0,1=70,2=0.000000
L 4.15473327 5.17291604 4.1558001 5.17541624 2 P 0 ;0,1=70,2=0.000000
L 4.1558001 5.17541624 4.1566 5.17874961 2 P 0 ;0,1=70,2=0.000000
L 4.1566 5.17874961 4.15686663 5.18249961 2 P 0 ;0,1=70,2=0.000000
L 4.15686663 5.18249961 4.1566 5.18624951 2 P 0 ;0,1=70,2=0.000000
L 4.1566 5.18624951 4.1558001 5.18958366 2 P 0 ;0,1=70,2=0.000000
L 4.1558001 5.18958366 4.15473327 5.19208317 2 P 0 ;0,1=70,2=0.000000
L 4.15473327 5.19208317 4.15313307 5.19416683 2 P 0 ;0,1=70,2=0.000000
L 4.15313307 5.19416683 4.1509997 5.195 2 P 0 ;0,1=70,2=0.000000
L 4.1749997 5.17 4.1749997 5.195 2 P 0 ;0,1=70,2=0.000000
L 4.1749997 5.195 4.1717999 5.1900003 2 P 0 ;0,1=70,2=0.000000
L 4.1717999 5.17 4.17819951 5.17 2 P 0 ;0,1=70,2=0.000000
L 0.06496004 1.21851004 0.06496004 4.73425 3 P 0 
L 0.06496004 4.73425 0.37991998 4.73425 3 P 0 
L 0.37991998 4.73425 0.37991998 1.21851004 3 P 0 
L 0.37991998 1.21851004 0.06496004 1.21851004 3 P 0 
L 0.37598002 1.21851004 0.43503996 1.21851004 3 P 0 
L 0.43503996 1.21851004 0.43503996 4.73425 3 P 0 
L 0.43503996 4.73425 0.37598002 4.73425 3 P 0 
L 0.12383317 1.11639961 0.1257501 1.11319931 2 P 0 ;0,1=71,2=0.000000
L 0.1257501 1.11319931 0.12804961 1.11106644 2 P 0 ;0,1=71,2=0.000000
L 0.12804961 1.11106644 0.13073307 1.11 2 P 0 ;0,1=71,2=0.000000
L 0.13073307 1.11 0.1337998 1.11106644 2 P 0 ;0,1=71,2=0.000000
L 0.1337998 1.11106644 0.1361 1.11319931 2 P 0 ;0,1=71,2=0.000000
L 0.1361 1.11319931 0.1384002 1.11639961 2 P 0 ;0,1=71,2=0.000000
L 0.1384002 1.11639961 0.13916673 1.12066634 2 P 0 ;0,1=71,2=0.000000
L 0.13916673 1.12066634 0.13916673 1.142 2 P 0 ;0,1=71,2=0.000000
L 0.151 1.09933366 0.174 1.09933366 2 P 0 ;0,1=71,2=0.000000
L 0.18583317 1.11 0.18583317 1.142 2 P 0 ;0,1=71,2=0.000000
L 0.18583317 1.142 0.19503327 1.142 2 P 0 ;0,1=71,2=0.000000
L 0.19503327 1.142 0.1981 1.14039931 2 P 0 ;0,1=71,2=0.000000
L 0.1981 1.14039931 0.2004002 1.13666673 2 P 0 ;0,1=71,2=0.000000
L 0.2004002 1.13666673 0.20116673 1.1324 2 P 0 ;0,1=71,2=0.000000
L 0.20116673 1.1324 0.2004002 1.12813327 2 P 0 ;0,1=71,2=0.000000
L 0.2004002 1.12813327 0.19848327 1.12493307 2 P 0 ;0,1=71,2=0.000000
L 0.19848327 1.12493307 0.19503327 1.12333238 2 P 0 ;0,1=71,2=0.000000
L 0.19503327 1.12333238 0.18583317 1.12333238 2 P 0 ;0,1=71,2=0.000000
L 0.23293327 1.13933287 0.23063307 1.14093346 2 P 0 ;0,1=71,2=0.000000
L 0.23063307 1.14093346 0.2279503 1.142 2 P 0 ;0,1=71,2=0.000000
L 0.2279503 1.142 0.22488356 1.142 2 P 0 ;0,1=71,2=0.000000
L 0.22488356 1.142 0.22143287 1.14039931 2 P 0 ;0,1=71,2=0.000000
L 0.22143287 1.14039931 0.2187501 1.13773327 2 P 0 ;0,1=71,2=0.000000
L 0.2187501 1.13773327 0.21683317 1.13453297 2 P 0 ;0,1=71,2=0.000000
L 0.21683317 1.13453297 0.21529951 1.1291998 2 P 0 ;0,1=71,2=0.000000
L 0.21529951 1.1291998 0.21491624 1.1243998 2 P 0 ;0,1=71,2=0.000000
L 0.21491624 1.1243998 0.21568337 1.1195999 2 P 0 ;0,1=71,2=0.000000
L 0.21568337 1.1195999 0.21683317 1.11639961 2 P 0 ;0,1=71,2=0.000000
L 0.21683317 1.11639961 0.21913337 1.11319931 2 P 0 ;0,1=71,2=0.000000
L 0.21913337 1.11319931 0.22181683 1.11106644 2 P 0 ;0,1=71,2=0.000000
L 0.22181683 1.11106644 0.22449961 1.11 2 P 0 ;0,1=71,2=0.000000
L 0.22449961 1.11 0.22718307 1.11 2 P 0 ;0,1=71,2=0.000000
L 0.22718307 1.11 0.22986654 1.11106644 2 P 0 ;0,1=71,2=0.000000
L 0.22986654 1.11106644 0.23216673 1.11266604 2 P 0 ;0,1=71,2=0.000000
L 0.23216673 1.11266604 0.23408366 1.11479892 2 P 0 ;0,1=71,2=0.000000
L 0.2508999 1.142 0.26009931 1.142 2 P 0 ;0,1=71,2=0.000000
L 0.25549961 1.142 0.25549961 1.11 2 P 0 ;0,1=71,2=0.000000
L 0.2508999 1.11 0.26009931 1.11 2 P 0 ;0,1=71,2=0.000000
L 0.29416673 1.11 0.27883317 1.11 2 P 0 ;0,1=71,2=0.000000
L 0.27883317 1.11 0.27883317 1.142 2 P 0 ;0,1=71,2=0.000000
L 0.27883317 1.142 0.29416673 1.142 2 P 0 ;0,1=71,2=0.000000
L 0.28803327 1.12653366 0.27883317 1.12653366 2 P 0 ;0,1=71,2=0.000000
L 0.30906663 1.11639961 0.31136614 1.11266604 2 P 0 ;0,1=71,2=0.000000
L 0.31136614 1.11266604 0.31443287 1.11053317 2 P 0 ;0,1=71,2=0.000000
L 0.31443287 1.11053317 0.31788356 1.11 2 P 0 ;0,1=71,2=0.000000
L 0.31788356 1.11 0.3209503 1.11053317 2 P 0 ;0,1=71,2=0.000000
L 0.3209503 1.11053317 0.32401703 1.11319931 2 P 0 ;0,1=71,2=0.000000
L 0.32401703 1.11319931 0.32593327 1.11639961 2 P 0 ;0,1=71,2=0.000000
L 0.32593327 1.11639961 0.32631654 1.1195999 2 P 0 ;0,1=71,2=0.000000
L 0.32631654 1.1195999 0.32555 1.12333238 2 P 0 ;0,1=71,2=0.000000
L 0.32555 1.12333238 0.32286654 1.12599951 2 P 0 ;0,1=71,2=0.000000
L 0.32286654 1.12599951 0.32018307 1.12706683 2 P 0 ;0,1=71,2=0.000000
L 0.32018307 1.12706683 0.31673307 1.12706683 2 P 0 ;0,1=71,2=0.000000
L 0.32018307 1.12706683 0.32248327 1.12866654 2 P 0 ;0,1=71,2=0.000000
L 0.32248327 1.12866654 0.3244002 1.13133268 2 P 0 ;0,1=71,2=0.000000
L 0.3244002 1.13133268 0.32516673 1.13453297 2 P 0 ;0,1=71,2=0.000000
L 0.32516673 1.13453297 0.3244002 1.13773327 2 P 0 ;0,1=71,2=0.000000
L 0.3244002 1.13773327 0.32248327 1.14039931 2 P 0 ;0,1=71,2=0.000000
L 0.32248327 1.14039931 0.31903327 1.142 2 P 0 ;0,1=71,2=0.000000
L 0.31903327 1.142 0.31558337 1.14146673 2 P 0 ;0,1=71,2=0.000000
L 0.31558337 1.14146673 0.31213337 1.13933287 2 P 0 ;0,1=71,2=0.000000
L 0.10826998 1.74921299 0.08326998 1.75587972 2 P 0 ;0,1=72,2=270.000000
L 0.08326998 1.75587972 0.10826998 1.76254695 2 P 0 ;0,1=72,2=270.000000
L 0.09952037 1.76014646 0.09952037 1.75161299 2 P 0 ;0,1=72,2=270.000000
L 0.10826998 1.77987972 0.08326998 1.77987972 2 P 0 ;0,1=72,2=270.000000
L 0.08326998 1.77987972 0.08826969 1.77667992 2 P 0 ;0,1=72,2=270.000000
L 0.10826998 1.77667992 0.10826998 1.78307953 2 P 0 ;0,1=72,2=270.000000
L 0.08743661 1.79881319 0.08493711 1.80041329 2 P 0 ;0,1=72,2=270.000000
L 0.08493711 1.80041329 0.08368661 1.80228002 2 P 0 ;0,1=72,2=270.000000
L 0.08368661 1.80228002 0.08326998 1.80441339 2 P 0 ;0,1=72,2=270.000000
L 0.08326998 1.80441339 0.08410315 1.80708002 2 P 0 ;0,1=72,2=270.000000
L 0.08410315 1.80708002 0.08618681 1.80894675 2 P 0 ;0,1=72,2=270.000000
L 0.08618681 1.80894675 0.08868632 1.80948002 2 P 0 ;0,1=72,2=270.000000
L 0.08868632 1.80948002 0.0911873 1.80921339 2 P 0 ;0,1=72,2=270.000000
L 0.0911873 1.80921339 0.09327018 1.80814646 2 P 0 ;0,1=72,2=270.000000
L 0.09327018 1.80814646 0.09743671 1.80281329 2 P 0 ;0,1=72,2=270.000000
L 0.09743671 1.80281329 0.10035354 1.80041329 2 P 0 ;0,1=72,2=270.000000
L 0.10035354 1.80041329 0.10452087 1.79881319 2 P 0 ;0,1=72,2=270.000000
L 0.10452087 1.79881319 0.10826998 1.79827992 2 P 0 ;0,1=72,2=270.000000
L 0.10826998 1.79827992 0.10826998 1.80948002 2 P 0 ;0,1=72,2=270.000000
L 0.35083652 1.17746309 0.34958671 1.17853002 2 P 0 ;0,1=73,2=270.000000
L 0.34958671 1.17853002 0.34750384 1.17932982 2 P 0 ;0,1=73,2=270.000000
L 0.34750384 1.17932982 0.34458632 1.17986358 2 P 0 ;0,1=73,2=270.000000
L 0.34458632 1.17986358 0.34208681 1.17932982 2 P 0 ;0,1=73,2=270.000000
L 0.34208681 1.17932982 0.34042057 1.17826339 2 P 0 ;0,1=73,2=270.000000
L 0.34042057 1.17826339 0.33916998 1.17639665 2 P 0 ;0,1=73,2=270.000000
L 0.33916998 1.17639665 0.33916998 1.16919675 2 P 0 ;0,1=73,2=270.000000
L 0.33916998 1.16919675 0.36416998 1.16919675 2 P 0 ;0,1=73,2=270.000000
L 0.36416998 1.16919675 0.36416998 1.17799675 2 P 0 ;0,1=73,2=270.000000
L 0.36416998 1.17799675 0.36250374 1.17986358 2 P 0 ;0,1=73,2=270.000000
L 0.36250374 1.17986358 0.36000344 1.18093002 2 P 0 ;0,1=73,2=270.000000
L 0.36000344 1.18093002 0.35708671 1.18146319 2 P 0 ;0,1=73,2=270.000000
L 0.35708671 1.18146319 0.35417067 1.18093002 2 P 0 ;0,1=73,2=270.000000
L 0.35417067 1.18093002 0.35167037 1.17932982 2 P 0 ;0,1=73,2=270.000000
L 0.35167037 1.17932982 0.35083652 1.17746309 2 P 0 ;0,1=73,2=270.000000
L 0.35083652 1.17746309 0.35083652 1.16919675 2 P 0 ;0,1=73,2=270.000000
L 0.34333661 1.19426319 0.34083711 1.19586329 2 P 0 ;0,1=73,2=270.000000
L 0.34083711 1.19586329 0.33958661 1.19773002 2 P 0 ;0,1=73,2=270.000000
L 0.33958661 1.19773002 0.33916998 1.19986339 2 P 0 ;0,1=73,2=270.000000
L 0.33916998 1.19986339 0.34000315 1.20253002 2 P 0 ;0,1=73,2=270.000000
L 0.34000315 1.20253002 0.34208681 1.20439675 2 P 0 ;0,1=73,2=270.000000
L 0.34208681 1.20439675 0.34458632 1.20493002 2 P 0 ;0,1=73,2=270.000000
L 0.34458632 1.20493002 0.3470873 1.20466339 2 P 0 ;0,1=73,2=270.000000
L 0.3470873 1.20466339 0.34917018 1.20359646 2 P 0 ;0,1=73,2=270.000000
L 0.34917018 1.20359646 0.35333671 1.19826329 2 P 0 ;0,1=73,2=270.000000
L 0.35333671 1.19826329 0.35625354 1.19586329 2 P 0 ;0,1=73,2=270.000000
L 0.35625354 1.19586329 0.36042087 1.19426319 2 P 0 ;0,1=73,2=270.000000
L 0.36042087 1.19426319 0.36416998 1.19372992 2 P 0 ;0,1=73,2=270.000000
L 0.36416998 1.19372992 0.36416998 1.20493002 2 P 0 ;0,1=73,2=270.000000
L 0.10826998 1.16866299 0.08326998 1.17532972 2 P 0 ;0,1=74,2=270.000000
L 0.08326998 1.17532972 0.10826998 1.18199695 2 P 0 ;0,1=74,2=270.000000
L 0.09952037 1.17959646 0.09952037 1.17106299 2 P 0 ;0,1=74,2=270.000000
L 0.08743661 1.19426319 0.08493711 1.19586329 2 P 0 ;0,1=74,2=270.000000
L 0.08493711 1.19586329 0.08368661 1.19773002 2 P 0 ;0,1=74,2=270.000000
L 0.08368661 1.19773002 0.08326998 1.19986339 2 P 0 ;0,1=74,2=270.000000
L 0.08326998 1.19986339 0.08410315 1.20253002 2 P 0 ;0,1=74,2=270.000000
L 0.08410315 1.20253002 0.08618681 1.20439675 2 P 0 ;0,1=74,2=270.000000
L 0.08618681 1.20439675 0.08868632 1.20493002 2 P 0 ;0,1=74,2=270.000000
L 0.08868632 1.20493002 0.0911873 1.20466339 2 P 0 ;0,1=74,2=270.000000
L 0.0911873 1.20466339 0.09327018 1.20359646 2 P 0 ;0,1=74,2=270.000000
L 0.09327018 1.20359646 0.09743671 1.19826329 2 P 0 ;0,1=74,2=270.000000
L 0.09743671 1.19826329 0.10035354 1.19586329 2 P 0 ;0,1=74,2=270.000000
L 0.10035354 1.19586329 0.10452087 1.19426319 2 P 0 ;0,1=74,2=270.000000
L 0.10452087 1.19426319 0.10826998 1.19372992 2 P 0 ;0,1=74,2=270.000000
L 0.10826998 1.19372992 0.10826998 1.20493002 2 P 0 ;0,1=74,2=270.000000
L 0.27209656 1.17746309 0.27084675 1.17853002 2 P 0 ;0,1=41,2=270.000000
L 0.27084675 1.17853002 0.26876388 1.17932982 2 P 0 ;0,1=41,2=270.000000
L 0.26876388 1.17932982 0.26584636 1.17986358 2 P 0 ;0,1=41,2=270.000000
L 0.26584636 1.17986358 0.26334685 1.17932982 2 P 0 ;0,1=41,2=270.000000
L 0.26334685 1.17932982 0.26168061 1.17826339 2 P 0 ;0,1=41,2=270.000000
L 0.26168061 1.17826339 0.26043002 1.17639665 2 P 0 ;0,1=41,2=270.000000
L 0.26043002 1.17639665 0.26043002 1.16919675 2 P 0 ;0,1=41,2=270.000000
L 0.26043002 1.16919675 0.28543002 1.16919675 2 P 0 ;0,1=41,2=270.000000
L 0.28543002 1.16919675 0.28543002 1.17799675 2 P 0 ;0,1=41,2=270.000000
L 0.28543002 1.17799675 0.28376378 1.17986358 2 P 0 ;0,1=41,2=270.000000
L 0.28376378 1.17986358 0.28126348 1.18093002 2 P 0 ;0,1=41,2=270.000000
L 0.28126348 1.18093002 0.27834675 1.18146319 2 P 0 ;0,1=41,2=270.000000
L 0.27834675 1.18146319 0.27543071 1.18093002 2 P 0 ;0,1=41,2=270.000000
L 0.27543071 1.18093002 0.27293041 1.17932982 2 P 0 ;0,1=41,2=270.000000
L 0.27293041 1.17932982 0.27209656 1.17746309 2 P 0 ;0,1=41,2=270.000000
L 0.27209656 1.17746309 0.27209656 1.16919675 2 P 0 ;0,1=41,2=270.000000
L 0.28543002 1.19932972 0.26043002 1.19932972 2 P 0 ;0,1=41,2=270.000000
L 0.26043002 1.19932972 0.26542972 1.19612992 2 P 0 ;0,1=41,2=270.000000
L 0.28543002 1.19612992 0.28543002 1.20252953 2 P 0 ;0,1=41,2=270.000000
L 0.35166654 4.76513307 0.35041673 4.7662 2 P 0 ;0,1=75,2=270.000000
L 0.35041673 4.7662 0.34833386 4.7669998 2 P 0 ;0,1=75,2=270.000000
L 0.34833386 4.7669998 0.34541634 4.76753356 2 P 0 ;0,1=75,2=270.000000
L 0.34541634 4.76753356 0.34291683 4.7669998 2 P 0 ;0,1=75,2=270.000000
L 0.34291683 4.7669998 0.34125059 4.76593337 2 P 0 ;0,1=75,2=270.000000
L 0.34125059 4.76593337 0.34 4.76406663 2 P 0 ;0,1=75,2=270.000000
L 0.34 4.76406663 0.34 4.75686673 2 P 0 ;0,1=75,2=270.000000
L 0.34 4.75686673 0.365 4.75686673 2 P 0 ;0,1=75,2=270.000000
L 0.365 4.75686673 0.365 4.76566673 2 P 0 ;0,1=75,2=270.000000
L 0.365 4.76566673 0.36333376 4.76753356 2 P 0 ;0,1=75,2=270.000000
L 0.36333376 4.76753356 0.36083346 4.7686 2 P 0 ;0,1=75,2=270.000000
L 0.36083346 4.7686 0.35791673 4.76913317 2 P 0 ;0,1=75,2=270.000000
L 0.35791673 4.76913317 0.35500069 4.7686 2 P 0 ;0,1=75,2=270.000000
L 0.35500069 4.7686 0.35250039 4.7669998 2 P 0 ;0,1=75,2=270.000000
L 0.35250039 4.7669998 0.35166654 4.76513307 2 P 0 ;0,1=75,2=270.000000
L 0.35166654 4.76513307 0.35166654 4.75686673 2 P 0 ;0,1=75,2=270.000000
L 0.365 4.7869997 0.36458346 4.78886644 2 P 0 ;0,1=75,2=270.000000
L 0.36458346 4.78886644 0.36333376 4.7909998 2 P 0 ;0,1=75,2=270.000000
L 0.36333376 4.7909998 0.36125089 4.79233337 2 P 0 ;0,1=75,2=270.000000
L 0.36125089 4.79233337 0.35833327 4.79286663 2 P 0 ;0,1=75,2=270.000000
L 0.35833327 4.79286663 0.35541722 4.79233337 2 P 0 ;0,1=75,2=270.000000
L 0.35541722 4.79233337 0.35291703 4.79073327 2 P 0 ;0,1=75,2=270.000000
L 0.35291703 4.79073327 0.35166654 4.78833327 2 P 0 ;0,1=75,2=270.000000
L 0.35166654 4.78833327 0.35166654 4.78566663 2 P 0 ;0,1=75,2=270.000000
L 0.35166654 4.78566663 0.35083337 4.78406654 2 P 0 ;0,1=75,2=270.000000
L 0.35083337 4.78406654 0.34875049 4.78273297 2 P 0 ;0,1=75,2=270.000000
L 0.34875049 4.78273297 0.34583366 4.7821998 2 P 0 ;0,1=75,2=270.000000
L 0.34583366 4.7821998 0.34291683 4.7830001 2 P 0 ;0,1=75,2=270.000000
L 0.34291683 4.7830001 0.34083317 4.78486634 2 P 0 ;0,1=75,2=270.000000
L 0.34083317 4.78486634 0.34 4.7869997 2 P 0 ;0,1=75,2=270.000000
L 0.34 4.7869997 0.34083317 4.78913307 2 P 0 ;0,1=75,2=270.000000
L 0.34083317 4.78913307 0.34291683 4.7909998 2 P 0 ;0,1=75,2=270.000000
L 0.34291683 4.7909998 0.34583366 4.7918001 2 P 0 ;0,1=75,2=270.000000
L 0.34583366 4.7918001 0.34875049 4.79126644 2 P 0 ;0,1=75,2=270.000000
L 0.34875049 4.79126644 0.35083337 4.78993337 2 P 0 ;0,1=75,2=270.000000
L 0.35083337 4.78993337 0.35166654 4.78833327 2 P 0 ;0,1=75,2=270.000000
L 0.35166654 4.78833327 0.35166654 4.78566663 2 P 0 ;0,1=75,2=270.000000
L 0.35166654 4.78566663 0.35291703 4.78326663 2 P 0 ;0,1=75,2=270.000000
L 0.35291703 4.78326663 0.35541722 4.78166654 2 P 0 ;0,1=75,2=270.000000
L 0.35541722 4.78166654 0.35833327 4.78113327 2 P 0 ;0,1=75,2=270.000000
L 0.35833327 4.78113327 0.36125089 4.78166654 2 P 0 ;0,1=75,2=270.000000
L 0.36125089 4.78166654 0.36333376 4.7830001 2 P 0 ;0,1=75,2=270.000000
L 0.36333376 4.7830001 0.36458346 4.78513346 2 P 0 ;0,1=75,2=270.000000
L 0.36458346 4.78513346 0.365 4.7869997 2 P 0 ;0,1=75,2=270.000000
L 0.34416663 4.80593317 0.34166713 4.80753327 2 P 0 ;0,1=75,2=270.000000
L 0.34166713 4.80753327 0.34041663 4.8094 2 P 0 ;0,1=75,2=270.000000
L 0.34041663 4.8094 0.34 4.81153337 2 P 0 ;0,1=75,2=270.000000
L 0.34 4.81153337 0.34083317 4.8142 2 P 0 ;0,1=75,2=270.000000
L 0.34083317 4.8142 0.34291683 4.81606673 2 P 0 ;0,1=75,2=270.000000
L 0.34291683 4.81606673 0.34541634 4.8166 2 P 0 ;0,1=75,2=270.000000
L 0.34541634 4.8166 0.34791732 4.81633337 2 P 0 ;0,1=75,2=270.000000
L 0.34791732 4.81633337 0.3500002 4.81526644 2 P 0 ;0,1=75,2=270.000000
L 0.3500002 4.81526644 0.35416673 4.80993327 2 P 0 ;0,1=75,2=270.000000
L 0.35416673 4.80993327 0.35708356 4.80753327 2 P 0 ;0,1=75,2=270.000000
L 0.35708356 4.80753327 0.36125089 4.80593317 2 P 0 ;0,1=75,2=270.000000
L 0.36125089 4.80593317 0.365 4.8053999 2 P 0 ;0,1=75,2=270.000000
L 0.365 4.8053999 0.365 4.8166 2 P 0 ;0,1=75,2=270.000000
L 0.175 4.75633297 0.15 4.7629997 2 P 0 ;0,1=76,2=270.000000
L 0.15 4.7629997 0.175 4.76966693 2 P 0 ;0,1=76,2=270.000000
L 0.16625039 4.76726644 0.16625039 4.75873297 2 P 0 ;0,1=76,2=270.000000
L 0.175 4.7869997 0.17458346 4.78886644 2 P 0 ;0,1=76,2=270.000000
L 0.17458346 4.78886644 0.17333376 4.7909998 2 P 0 ;0,1=76,2=270.000000
L 0.17333376 4.7909998 0.17125089 4.79233337 2 P 0 ;0,1=76,2=270.000000
L 0.17125089 4.79233337 0.16833327 4.79286663 2 P 0 ;0,1=76,2=270.000000
L 0.16833327 4.79286663 0.16541722 4.79233337 2 P 0 ;0,1=76,2=270.000000
L 0.16541722 4.79233337 0.16291703 4.79073327 2 P 0 ;0,1=76,2=270.000000
L 0.16291703 4.79073327 0.16166654 4.78833327 2 P 0 ;0,1=76,2=270.000000
L 0.16166654 4.78833327 0.16166654 4.78566663 2 P 0 ;0,1=76,2=270.000000
L 0.16166654 4.78566663 0.16083337 4.78406654 2 P 0 ;0,1=76,2=270.000000
L 0.16083337 4.78406654 0.15875049 4.78273297 2 P 0 ;0,1=76,2=270.000000
L 0.15875049 4.78273297 0.15583366 4.7821998 2 P 0 ;0,1=76,2=270.000000
L 0.15583366 4.7821998 0.15291683 4.7830001 2 P 0 ;0,1=76,2=270.000000
L 0.15291683 4.7830001 0.15083317 4.78486634 2 P 0 ;0,1=76,2=270.000000
L 0.15083317 4.78486634 0.15 4.7869997 2 P 0 ;0,1=76,2=270.000000
L 0.15 4.7869997 0.15083317 4.78913307 2 P 0 ;0,1=76,2=270.000000
L 0.15083317 4.78913307 0.15291683 4.7909998 2 P 0 ;0,1=76,2=270.000000
L 0.15291683 4.7909998 0.15583366 4.7918001 2 P 0 ;0,1=76,2=270.000000
L 0.15583366 4.7918001 0.15875049 4.79126644 2 P 0 ;0,1=76,2=270.000000
L 0.15875049 4.79126644 0.16083337 4.78993337 2 P 0 ;0,1=76,2=270.000000
L 0.16083337 4.78993337 0.16166654 4.78833327 2 P 0 ;0,1=76,2=270.000000
L 0.16166654 4.78833327 0.16166654 4.78566663 2 P 0 ;0,1=76,2=270.000000
L 0.16166654 4.78566663 0.16291703 4.78326663 2 P 0 ;0,1=76,2=270.000000
L 0.16291703 4.78326663 0.16541722 4.78166654 2 P 0 ;0,1=76,2=270.000000
L 0.16541722 4.78166654 0.16833327 4.78113327 2 P 0 ;0,1=76,2=270.000000
L 0.16833327 4.78113327 0.17125089 4.78166654 2 P 0 ;0,1=76,2=270.000000
L 0.17125089 4.78166654 0.17333376 4.7830001 2 P 0 ;0,1=76,2=270.000000
L 0.17333376 4.7830001 0.17458346 4.78513346 2 P 0 ;0,1=76,2=270.000000
L 0.17458346 4.78513346 0.175 4.7869997 2 P 0 ;0,1=76,2=270.000000
L 0.175 4.8109997 0.15 4.8109997 2 P 0 ;0,1=76,2=270.000000
L 0.15 4.8109997 0.1549997 4.8077999 2 P 0 ;0,1=76,2=270.000000
L 0.175 4.8077999 0.175 4.81419951 2 P 0 ;0,1=76,2=270.000000
L 0.18701004 1.16866299 0.16201004 1.17532972 2 P 0 ;0,1=40,2=270.000000
L 0.16201004 1.17532972 0.18701004 1.18199695 2 P 0 ;0,1=40,2=270.000000
L 0.17826043 1.17959646 0.17826043 1.17106299 2 P 0 ;0,1=40,2=270.000000
L 0.18701004 1.19932972 0.16201004 1.19932972 2 P 0 ;0,1=40,2=270.000000
L 0.16201004 1.19932972 0.16700974 1.19612992 2 P 0 ;0,1=40,2=270.000000
L 0.18701004 1.19612992 0.18701004 1.20252953 2 P 0 ;0,1=40,2=270.000000
L 0.105 4.75633297 0.08 4.7629997 2 P 0 ;0,1=77,2=270.000000
L 0.08 4.7629997 0.105 4.76966693 2 P 0 ;0,1=77,2=270.000000
L 0.09625039 4.76726644 0.09625039 4.75873297 2 P 0 ;0,1=77,2=270.000000
L 0.105 4.7869997 0.10458346 4.78886644 2 P 0 ;0,1=77,2=270.000000
L 0.10458346 4.78886644 0.10333376 4.7909998 2 P 0 ;0,1=77,2=270.000000
L 0.10333376 4.7909998 0.10125089 4.79233337 2 P 0 ;0,1=77,2=270.000000
L 0.10125089 4.79233337 0.09833327 4.79286663 2 P 0 ;0,1=77,2=270.000000
L 0.09833327 4.79286663 0.09541722 4.79233337 2 P 0 ;0,1=77,2=270.000000
L 0.09541722 4.79233337 0.09291703 4.79073327 2 P 0 ;0,1=77,2=270.000000
L 0.09291703 4.79073327 0.09166654 4.78833327 2 P 0 ;0,1=77,2=270.000000
L 0.09166654 4.78833327 0.09166654 4.78566663 2 P 0 ;0,1=77,2=270.000000
L 0.09166654 4.78566663 0.09083337 4.78406654 2 P 0 ;0,1=77,2=270.000000
L 0.09083337 4.78406654 0.08875049 4.78273297 2 P 0 ;0,1=77,2=270.000000
L 0.08875049 4.78273297 0.08583366 4.7821998 2 P 0 ;0,1=77,2=270.000000
L 0.08583366 4.7821998 0.08291683 4.7830001 2 P 0 ;0,1=77,2=270.000000
L 0.08291683 4.7830001 0.08083317 4.78486634 2 P 0 ;0,1=77,2=270.000000
L 0.08083317 4.78486634 0.08 4.7869997 2 P 0 ;0,1=77,2=270.000000
L 0.08 4.7869997 0.08083317 4.78913307 2 P 0 ;0,1=77,2=270.000000
L 0.08083317 4.78913307 0.08291683 4.7909998 2 P 0 ;0,1=77,2=270.000000
L 0.08291683 4.7909998 0.08583366 4.7918001 2 P 0 ;0,1=77,2=270.000000
L 0.08583366 4.7918001 0.08875049 4.79126644 2 P 0 ;0,1=77,2=270.000000
L 0.08875049 4.79126644 0.09083337 4.78993337 2 P 0 ;0,1=77,2=270.000000
L 0.09083337 4.78993337 0.09166654 4.78833327 2 P 0 ;0,1=77,2=270.000000
L 0.09166654 4.78833327 0.09166654 4.78566663 2 P 0 ;0,1=77,2=270.000000
L 0.09166654 4.78566663 0.09291703 4.78326663 2 P 0 ;0,1=77,2=270.000000
L 0.09291703 4.78326663 0.09541722 4.78166654 2 P 0 ;0,1=77,2=270.000000
L 0.09541722 4.78166654 0.09833327 4.78113327 2 P 0 ;0,1=77,2=270.000000
L 0.09833327 4.78113327 0.10125089 4.78166654 2 P 0 ;0,1=77,2=270.000000
L 0.10125089 4.78166654 0.10333376 4.7830001 2 P 0 ;0,1=77,2=270.000000
L 0.10333376 4.7830001 0.10458346 4.78513346 2 P 0 ;0,1=77,2=270.000000
L 0.10458346 4.78513346 0.105 4.7869997 2 P 0 ;0,1=77,2=270.000000
L 0.08416663 4.80593317 0.08166713 4.80753327 2 P 0 ;0,1=77,2=270.000000
L 0.08166713 4.80753327 0.08041663 4.8094 2 P 0 ;0,1=77,2=270.000000
L 0.08041663 4.8094 0.08 4.81153337 2 P 0 ;0,1=77,2=270.000000
L 0.08 4.81153337 0.08083317 4.8142 2 P 0 ;0,1=77,2=270.000000
L 0.08083317 4.8142 0.08291683 4.81606673 2 P 0 ;0,1=77,2=270.000000
L 0.08291683 4.81606673 0.08541634 4.8166 2 P 0 ;0,1=77,2=270.000000
L 0.08541634 4.8166 0.08791732 4.81633337 2 P 0 ;0,1=77,2=270.000000
L 0.08791732 4.81633337 0.0900002 4.81526644 2 P 0 ;0,1=77,2=270.000000
L 0.0900002 4.81526644 0.09416673 4.80993327 2 P 0 ;0,1=77,2=270.000000
L 0.09416673 4.80993327 0.09708356 4.80753327 2 P 0 ;0,1=77,2=270.000000
L 0.09708356 4.80753327 0.10125089 4.80593317 2 P 0 ;0,1=77,2=270.000000
L 0.10125089 4.80593317 0.105 4.8053999 2 P 0 ;0,1=77,2=270.000000
L 0.105 4.8053999 0.105 4.8166 2 P 0 ;0,1=77,2=270.000000
L 0.155 1.79133297 0.13 1.7979997 2 P 0 ;0,1=78,2=270.000000
L 0.13 1.7979997 0.155 1.80466693 2 P 0 ;0,1=78,2=270.000000
L 0.14625039 1.80226644 0.14625039 1.79373297 2 P 0 ;0,1=78,2=270.000000
L 0.155 1.8219997 0.13 1.8219997 2 P 0 ;0,1=78,2=270.000000
L 0.13 1.8219997 0.1349997 1.8187999 2 P 0 ;0,1=78,2=270.000000
L 0.155 1.8187999 0.155 1.82519951 2 P 0 ;0,1=78,2=270.000000
L 0.15000039 1.84013327 0.15291713 1.84173297 2 P 0 ;0,1=78,2=270.000000
L 0.15291713 1.84173297 0.15458346 1.84386634 2 P 0 ;0,1=78,2=270.000000
L 0.15458346 1.84386634 0.155 1.84626683 2 P 0 ;0,1=78,2=270.000000
L 0.155 1.84626683 0.15458346 1.8484002 2 P 0 ;0,1=78,2=270.000000
L 0.15458346 1.8484002 0.15250059 1.85053356 2 P 0 ;0,1=78,2=270.000000
L 0.15250059 1.85053356 0.15000039 1.85186663 2 P 0 ;0,1=78,2=270.000000
L 0.15000039 1.85186663 0.1475001 1.85213317 2 P 0 ;0,1=78,2=270.000000
L 0.1475001 1.85213317 0.14458406 1.8516 2 P 0 ;0,1=78,2=270.000000
L 0.14458406 1.8516 0.14250039 1.84973327 2 P 0 ;0,1=78,2=270.000000
L 0.14250039 1.84973327 0.14166654 1.84786644 2 P 0 ;0,1=78,2=270.000000
L 0.14166654 1.84786644 0.14166654 1.84546654 2 P 0 ;0,1=78,2=270.000000
L 0.14166654 1.84786644 0.14041673 1.84946663 2 P 0 ;0,1=78,2=270.000000
L 0.14041673 1.84946663 0.13833386 1.8508001 2 P 0 ;0,1=78,2=270.000000
L 0.13833386 1.8508001 0.13583366 1.85133337 2 P 0 ;0,1=78,2=270.000000
L 0.13583366 1.85133337 0.13333346 1.8508001 2 P 0 ;0,1=78,2=270.000000
L 0.13333346 1.8508001 0.13125059 1.84946663 2 P 0 ;0,1=78,2=270.000000
L 0.13125059 1.84946663 0.13 1.84706663 2 P 0 ;0,1=78,2=270.000000
L 0.13 1.84706663 0.13041663 1.84466663 2 P 0 ;0,1=78,2=270.000000
L 0.13041663 1.84466663 0.13208366 1.84226663 2 P 0 ;0,1=78,2=270.000000
L 0.34666654 1.76013307 0.34541673 1.7612 2 P 0 ;0,1=79,2=270.000000
L 0.34541673 1.7612 0.34333386 1.7619998 2 P 0 ;0,1=79,2=270.000000
L 0.34333386 1.7619998 0.34041634 1.76253356 2 P 0 ;0,1=79,2=270.000000
L 0.34041634 1.76253356 0.33791683 1.7619998 2 P 0 ;0,1=79,2=270.000000
L 0.33791683 1.7619998 0.33625059 1.76093337 2 P 0 ;0,1=79,2=270.000000
L 0.33625059 1.76093337 0.335 1.75906663 2 P 0 ;0,1=79,2=270.000000
L 0.335 1.75906663 0.335 1.75186673 2 P 0 ;0,1=79,2=270.000000
L 0.335 1.75186673 0.36 1.75186673 2 P 0 ;0,1=79,2=270.000000
L 0.36 1.75186673 0.36 1.76066673 2 P 0 ;0,1=79,2=270.000000
L 0.36 1.76066673 0.35833376 1.76253356 2 P 0 ;0,1=79,2=270.000000
L 0.35833376 1.76253356 0.35583346 1.7636 2 P 0 ;0,1=79,2=270.000000
L 0.35583346 1.7636 0.35291673 1.76413317 2 P 0 ;0,1=79,2=270.000000
L 0.35291673 1.76413317 0.35000069 1.7636 2 P 0 ;0,1=79,2=270.000000
L 0.35000069 1.7636 0.34750039 1.7619998 2 P 0 ;0,1=79,2=270.000000
L 0.34750039 1.7619998 0.34666654 1.76013307 2 P 0 ;0,1=79,2=270.000000
L 0.34666654 1.76013307 0.34666654 1.75186673 2 P 0 ;0,1=79,2=270.000000
L 0.36 1.7819997 0.335 1.7819997 2 P 0 ;0,1=79,2=270.000000
L 0.335 1.7819997 0.3399997 1.7787999 2 P 0 ;0,1=79,2=270.000000
L 0.36 1.7787999 0.36 1.78519951 2 P 0 ;0,1=79,2=270.000000
L 0.33916663 1.80093317 0.33666713 1.80253327 2 P 0 ;0,1=79,2=270.000000
L 0.33666713 1.80253327 0.33541663 1.8044 2 P 0 ;0,1=79,2=270.000000
L 0.33541663 1.8044 0.335 1.80653337 2 P 0 ;0,1=79,2=270.000000
L 0.335 1.80653337 0.33583317 1.8092 2 P 0 ;0,1=79,2=270.000000
L 0.33583317 1.8092 0.33791683 1.81106673 2 P 0 ;0,1=79,2=270.000000
L 0.33791683 1.81106673 0.34041634 1.8116 2 P 0 ;0,1=79,2=270.000000
L 0.34041634 1.8116 0.34291732 1.81133337 2 P 0 ;0,1=79,2=270.000000
L 0.34291732 1.81133337 0.3450002 1.81026644 2 P 0 ;0,1=79,2=270.000000
L 0.3450002 1.81026644 0.34916673 1.80493327 2 P 0 ;0,1=79,2=270.000000
L 0.34916673 1.80493327 0.35208356 1.80253327 2 P 0 ;0,1=79,2=270.000000
L 0.35208356 1.80253327 0.35625089 1.80093317 2 P 0 ;0,1=79,2=270.000000
L 0.35625089 1.80093317 0.36 1.8003999 2 P 0 ;0,1=79,2=270.000000
L 0.36 1.8003999 0.36 1.8116 2 P 0 ;0,1=79,2=270.000000
L 0.30166654 1.80013307 0.30041673 1.8012 2 P 0 ;0,1=80,2=270.000000
L 0.30041673 1.8012 0.29833386 1.8019998 2 P 0 ;0,1=80,2=270.000000
L 0.29833386 1.8019998 0.29541634 1.80253356 2 P 0 ;0,1=80,2=270.000000
L 0.29541634 1.80253356 0.29291683 1.8019998 2 P 0 ;0,1=80,2=270.000000
L 0.29291683 1.8019998 0.29125059 1.80093337 2 P 0 ;0,1=80,2=270.000000
L 0.29125059 1.80093337 0.29 1.79906663 2 P 0 ;0,1=80,2=270.000000
L 0.29 1.79906663 0.29 1.79186673 2 P 0 ;0,1=80,2=270.000000
L 0.29 1.79186673 0.315 1.79186673 2 P 0 ;0,1=80,2=270.000000
L 0.315 1.79186673 0.315 1.80066673 2 P 0 ;0,1=80,2=270.000000
L 0.315 1.80066673 0.31333376 1.80253356 2 P 0 ;0,1=80,2=270.000000
L 0.31333376 1.80253356 0.31083346 1.8036 2 P 0 ;0,1=80,2=270.000000
L 0.31083346 1.8036 0.30791673 1.80413317 2 P 0 ;0,1=80,2=270.000000
L 0.30791673 1.80413317 0.30500069 1.8036 2 P 0 ;0,1=80,2=270.000000
L 0.30500069 1.8036 0.30250039 1.8019998 2 P 0 ;0,1=80,2=270.000000
L 0.30250039 1.8019998 0.30166654 1.80013307 2 P 0 ;0,1=80,2=270.000000
L 0.30166654 1.80013307 0.30166654 1.79186673 2 P 0 ;0,1=80,2=270.000000
L 0.315 1.8219997 0.29 1.8219997 2 P 0 ;0,1=80,2=270.000000
L 0.29 1.8219997 0.2949997 1.8187999 2 P 0 ;0,1=80,2=270.000000
L 0.315 1.8187999 0.315 1.82519951 2 P 0 ;0,1=80,2=270.000000
L 0.31000039 1.84013327 0.31291713 1.84173297 2 P 0 ;0,1=80,2=270.000000
L 0.31291713 1.84173297 0.31458346 1.84386634 2 P 0 ;0,1=80,2=270.000000
L 0.31458346 1.84386634 0.315 1.84626683 2 P 0 ;0,1=80,2=270.000000
L 0.315 1.84626683 0.31458346 1.8484002 2 P 0 ;0,1=80,2=270.000000
L 0.31458346 1.8484002 0.31250059 1.85053356 2 P 0 ;0,1=80,2=270.000000
L 0.31250059 1.85053356 0.31000039 1.85186663 2 P 0 ;0,1=80,2=270.000000
L 0.31000039 1.85186663 0.3075001 1.85213317 2 P 0 ;0,1=80,2=270.000000
L 0.3075001 1.85213317 0.30458406 1.8516 2 P 0 ;0,1=80,2=270.000000
L 0.30458406 1.8516 0.30250039 1.84973327 2 P 0 ;0,1=80,2=270.000000
L 0.30250039 1.84973327 0.30166654 1.84786644 2 P 0 ;0,1=80,2=270.000000
L 0.30166654 1.84786644 0.30166654 1.84546654 2 P 0 ;0,1=80,2=270.000000
L 0.30166654 1.84786644 0.30041673 1.84946663 2 P 0 ;0,1=80,2=270.000000
L 0.30041673 1.84946663 0.29833386 1.8508001 2 P 0 ;0,1=80,2=270.000000
L 0.29833386 1.8508001 0.29583366 1.85133337 2 P 0 ;0,1=80,2=270.000000
L 0.29583366 1.85133337 0.29333346 1.8508001 2 P 0 ;0,1=80,2=270.000000
L 0.29333346 1.8508001 0.29125059 1.84946663 2 P 0 ;0,1=80,2=270.000000
L 0.29125059 1.84946663 0.29 1.84706663 2 P 0 ;0,1=80,2=270.000000
L 0.29 1.84706663 0.29041663 1.84466663 2 P 0 ;0,1=80,2=270.000000
L 0.29041663 1.84466663 0.29208366 1.84226663 2 P 0 ;0,1=80,2=270.000000
L 0.27666654 4.76513307 0.27541673 4.7662 2 P 0 ;0,1=81,2=270.000000
L 0.27541673 4.7662 0.27333386 4.7669998 2 P 0 ;0,1=81,2=270.000000
L 0.27333386 4.7669998 0.27041634 4.76753356 2 P 0 ;0,1=81,2=270.000000
L 0.27041634 4.76753356 0.26791683 4.7669998 2 P 0 ;0,1=81,2=270.000000
L 0.26791683 4.7669998 0.26625059 4.76593337 2 P 0 ;0,1=81,2=270.000000
L 0.26625059 4.76593337 0.265 4.76406663 2 P 0 ;0,1=81,2=270.000000
L 0.265 4.76406663 0.265 4.75686673 2 P 0 ;0,1=81,2=270.000000
L 0.265 4.75686673 0.29 4.75686673 2 P 0 ;0,1=81,2=270.000000
L 0.29 4.75686673 0.29 4.76566673 2 P 0 ;0,1=81,2=270.000000
L 0.29 4.76566673 0.28833376 4.76753356 2 P 0 ;0,1=81,2=270.000000
L 0.28833376 4.76753356 0.28583346 4.7686 2 P 0 ;0,1=81,2=270.000000
L 0.28583346 4.7686 0.28291673 4.76913317 2 P 0 ;0,1=81,2=270.000000
L 0.28291673 4.76913317 0.28000069 4.7686 2 P 0 ;0,1=81,2=270.000000
L 0.28000069 4.7686 0.27750039 4.7669998 2 P 0 ;0,1=81,2=270.000000
L 0.27750039 4.7669998 0.27666654 4.76513307 2 P 0 ;0,1=81,2=270.000000
L 0.27666654 4.76513307 0.27666654 4.75686673 2 P 0 ;0,1=81,2=270.000000
L 0.29 4.7869997 0.28958346 4.78886644 2 P 0 ;0,1=81,2=270.000000
L 0.28958346 4.78886644 0.28833376 4.7909998 2 P 0 ;0,1=81,2=270.000000
L 0.28833376 4.7909998 0.28625089 4.79233337 2 P 0 ;0,1=81,2=270.000000
L 0.28625089 4.79233337 0.28333327 4.79286663 2 P 0 ;0,1=81,2=270.000000
L 0.28333327 4.79286663 0.28041722 4.79233337 2 P 0 ;0,1=81,2=270.000000
L 0.28041722 4.79233337 0.27791703 4.79073327 2 P 0 ;0,1=81,2=270.000000
L 0.27791703 4.79073327 0.27666654 4.78833327 2 P 0 ;0,1=81,2=270.000000
L 0.27666654 4.78833327 0.27666654 4.78566663 2 P 0 ;0,1=81,2=270.000000
L 0.27666654 4.78566663 0.27583337 4.78406654 2 P 0 ;0,1=81,2=270.000000
L 0.27583337 4.78406654 0.27375049 4.78273297 2 P 0 ;0,1=81,2=270.000000
L 0.27375049 4.78273297 0.27083366 4.7821998 2 P 0 ;0,1=81,2=270.000000
L 0.27083366 4.7821998 0.26791683 4.7830001 2 P 0 ;0,1=81,2=270.000000
L 0.26791683 4.7830001 0.26583317 4.78486634 2 P 0 ;0,1=81,2=270.000000
L 0.26583317 4.78486634 0.265 4.7869997 2 P 0 ;0,1=81,2=270.000000
L 0.265 4.7869997 0.26583317 4.78913307 2 P 0 ;0,1=81,2=270.000000
L 0.26583317 4.78913307 0.26791683 4.7909998 2 P 0 ;0,1=81,2=270.000000
L 0.26791683 4.7909998 0.27083366 4.7918001 2 P 0 ;0,1=81,2=270.000000
L 0.27083366 4.7918001 0.27375049 4.79126644 2 P 0 ;0,1=81,2=270.000000
L 0.27375049 4.79126644 0.27583337 4.78993337 2 P 0 ;0,1=81,2=270.000000
L 0.27583337 4.78993337 0.27666654 4.78833327 2 P 0 ;0,1=81,2=270.000000
L 0.27666654 4.78833327 0.27666654 4.78566663 2 P 0 ;0,1=81,2=270.000000
L 0.27666654 4.78566663 0.27791703 4.78326663 2 P 0 ;0,1=81,2=270.000000
L 0.27791703 4.78326663 0.28041722 4.78166654 2 P 0 ;0,1=81,2=270.000000
L 0.28041722 4.78166654 0.28333327 4.78113327 2 P 0 ;0,1=81,2=270.000000
L 0.28333327 4.78113327 0.28625089 4.78166654 2 P 0 ;0,1=81,2=270.000000
L 0.28625089 4.78166654 0.28833376 4.7830001 2 P 0 ;0,1=81,2=270.000000
L 0.28833376 4.7830001 0.28958346 4.78513346 2 P 0 ;0,1=81,2=270.000000
L 0.28958346 4.78513346 0.29 4.7869997 2 P 0 ;0,1=81,2=270.000000
L 0.29 4.8109997 0.265 4.8109997 2 P 0 ;0,1=81,2=270.000000
L 0.265 4.8109997 0.2699997 4.8077999 2 P 0 ;0,1=81,2=270.000000
L 0.29 4.8077999 0.29 4.81419951 2 P 0 ;0,1=81,2=270.000000
L 12.52951998 1.25788002 12.52951998 4.77361998 3 P 0 
L 12.52951998 4.77361998 12.84448002 4.77361998 3 P 0 
L 12.84448002 4.77361998 12.84448002 1.25788002 3 P 0 
L 12.84448002 1.25788002 12.52951998 1.25788002 3 P 0 
L 12.84053996 1.25788002 12.8996 1.25788002 3 P 0 
L 12.8996 1.25788002 12.8996 4.77361998 3 P 0 
L 12.8996 4.77361998 12.84053996 4.77361998 3 P 0 
L 12.58383317 1.15639961 12.5857501 1.15319931 2 P 0 ;0,1=82,2=0.000000
L 12.5857501 1.15319931 12.58804961 1.15106644 2 P 0 ;0,1=82,2=0.000000
L 12.58804961 1.15106644 12.59073307 1.15 2 P 0 ;0,1=82,2=0.000000
L 12.59073307 1.15 12.5937998 1.15106644 2 P 0 ;0,1=82,2=0.000000
L 12.5937998 1.15106644 12.5961 1.15319931 2 P 0 ;0,1=82,2=0.000000
L 12.5961 1.15319931 12.5984002 1.15639961 2 P 0 ;0,1=82,2=0.000000
L 12.5984002 1.15639961 12.59916673 1.16066634 2 P 0 ;0,1=82,2=0.000000
L 12.59916673 1.16066634 12.59916673 1.182 2 P 0 ;0,1=82,2=0.000000
L 12.611 1.13933366 12.634 1.13933366 2 P 0 ;0,1=82,2=0.000000
L 12.64583317 1.15 12.64583317 1.182 2 P 0 ;0,1=82,2=0.000000
L 12.64583317 1.182 12.65503327 1.182 2 P 0 ;0,1=82,2=0.000000
L 12.65503327 1.182 12.6581 1.18039931 2 P 0 ;0,1=82,2=0.000000
L 12.6581 1.18039931 12.6604002 1.17666673 2 P 0 ;0,1=82,2=0.000000
L 12.6604002 1.17666673 12.66116673 1.1724 2 P 0 ;0,1=82,2=0.000000
L 12.66116673 1.1724 12.6604002 1.16813327 2 P 0 ;0,1=82,2=0.000000
L 12.6604002 1.16813327 12.65848327 1.16493307 2 P 0 ;0,1=82,2=0.000000
L 12.65848327 1.16493307 12.65503327 1.16333238 2 P 0 ;0,1=82,2=0.000000
L 12.65503327 1.16333238 12.64583317 1.16333238 2 P 0 ;0,1=82,2=0.000000
L 12.69293327 1.17933287 12.69063307 1.18093346 2 P 0 ;0,1=82,2=0.000000
L 12.69063307 1.18093346 12.6879503 1.182 2 P 0 ;0,1=82,2=0.000000
L 12.6879503 1.182 12.68488356 1.182 2 P 0 ;0,1=82,2=0.000000
L 12.68488356 1.182 12.68143287 1.18039931 2 P 0 ;0,1=82,2=0.000000
L 12.68143287 1.18039931 12.6787501 1.17773327 2 P 0 ;0,1=82,2=0.000000
L 12.6787501 1.17773327 12.67683317 1.17453297 2 P 0 ;0,1=82,2=0.000000
L 12.67683317 1.17453297 12.67529951 1.1691998 2 P 0 ;0,1=82,2=0.000000
L 12.67529951 1.1691998 12.67491624 1.1643998 2 P 0 ;0,1=82,2=0.000000
L 12.67491624 1.1643998 12.67568337 1.1595999 2 P 0 ;0,1=82,2=0.000000
L 12.67568337 1.1595999 12.67683317 1.15639961 2 P 0 ;0,1=82,2=0.000000
L 12.67683317 1.15639961 12.67913337 1.15319931 2 P 0 ;0,1=82,2=0.000000
L 12.67913337 1.15319931 12.68181683 1.15106644 2 P 0 ;0,1=82,2=0.000000
L 12.68181683 1.15106644 12.68449961 1.15 2 P 0 ;0,1=82,2=0.000000
L 12.68449961 1.15 12.68718307 1.15 2 P 0 ;0,1=82,2=0.000000
L 12.68718307 1.15 12.68986654 1.15106644 2 P 0 ;0,1=82,2=0.000000
L 12.68986654 1.15106644 12.69216673 1.15266604 2 P 0 ;0,1=82,2=0.000000
L 12.69216673 1.15266604 12.69408366 1.15479892 2 P 0 ;0,1=82,2=0.000000
L 12.7108999 1.182 12.72009931 1.182 2 P 0 ;0,1=82,2=0.000000
L 12.71549961 1.182 12.71549961 1.15 2 P 0 ;0,1=82,2=0.000000
L 12.7108999 1.15 12.72009931 1.15 2 P 0 ;0,1=82,2=0.000000
L 12.75416673 1.15 12.73883317 1.15 2 P 0 ;0,1=82,2=0.000000
L 12.73883317 1.15 12.73883317 1.182 2 P 0 ;0,1=82,2=0.000000
L 12.73883317 1.182 12.75416673 1.182 2 P 0 ;0,1=82,2=0.000000
L 12.74803327 1.16653366 12.73883317 1.16653366 2 P 0 ;0,1=82,2=0.000000
L 12.7821 1.15 12.7821 1.182 2 P 0 ;0,1=82,2=0.000000
L 12.7821 1.182 12.76791624 1.15906663 2 P 0 ;0,1=82,2=0.000000
L 12.76791624 1.15906663 12.78708366 1.15906663 2 P 0 ;0,1=82,2=0.000000
L 12.575 1.79133297 12.55 1.7979997 2 P 0 ;0,1=72,2=270.000000
L 12.55 1.7979997 12.575 1.80466693 2 P 0 ;0,1=72,2=270.000000
L 12.56625039 1.80226644 12.56625039 1.79373297 2 P 0 ;0,1=72,2=270.000000
L 12.575 1.8219997 12.55 1.8219997 2 P 0 ;0,1=72,2=270.000000
L 12.55 1.8219997 12.5549997 1.8187999 2 P 0 ;0,1=72,2=270.000000
L 12.575 1.8187999 12.575 1.82519951 2 P 0 ;0,1=72,2=270.000000
L 12.55416663 1.84093317 12.55166713 1.84253327 2 P 0 ;0,1=72,2=270.000000
L 12.55166713 1.84253327 12.55041663 1.8444 2 P 0 ;0,1=72,2=270.000000
L 12.55041663 1.8444 12.55 1.84653337 2 P 0 ;0,1=72,2=270.000000
L 12.55 1.84653337 12.55083317 1.8492 2 P 0 ;0,1=72,2=270.000000
L 12.55083317 1.8492 12.55291683 1.85106673 2 P 0 ;0,1=72,2=270.000000
L 12.55291683 1.85106673 12.55541634 1.8516 2 P 0 ;0,1=72,2=270.000000
L 12.55541634 1.8516 12.55791732 1.85133337 2 P 0 ;0,1=72,2=270.000000
L 12.55791732 1.85133337 12.5600002 1.85026644 2 P 0 ;0,1=72,2=270.000000
L 12.5600002 1.85026644 12.56416673 1.84493327 2 P 0 ;0,1=72,2=270.000000
L 12.56416673 1.84493327 12.56708356 1.84253327 2 P 0 ;0,1=72,2=270.000000
L 12.56708356 1.84253327 12.57125089 1.84093317 2 P 0 ;0,1=72,2=270.000000
L 12.57125089 1.84093317 12.575 1.8403999 2 P 0 ;0,1=72,2=270.000000
L 12.575 1.8403999 12.575 1.8516 2 P 0 ;0,1=72,2=270.000000
L 12.81539656 1.21683307 12.81414675 1.2179 2 P 0 ;0,1=73,2=270.000000
L 12.81414675 1.2179 12.81206388 1.2186998 2 P 0 ;0,1=73,2=270.000000
L 12.81206388 1.2186998 12.80914636 1.21923356 2 P 0 ;0,1=73,2=270.000000
L 12.80914636 1.21923356 12.80664685 1.2186998 2 P 0 ;0,1=73,2=270.000000
L 12.80664685 1.2186998 12.80498061 1.21763337 2 P 0 ;0,1=73,2=270.000000
L 12.80498061 1.21763337 12.80373002 1.21576663 2 P 0 ;0,1=73,2=270.000000
L 12.80373002 1.21576663 12.80373002 1.20856673 2 P 0 ;0,1=73,2=270.000000
L 12.80373002 1.20856673 12.82873002 1.20856673 2 P 0 ;0,1=73,2=270.000000
L 12.82873002 1.20856673 12.82873002 1.21736673 2 P 0 ;0,1=73,2=270.000000
L 12.82873002 1.21736673 12.82706378 1.21923356 2 P 0 ;0,1=73,2=270.000000
L 12.82706378 1.21923356 12.82456348 1.2203 2 P 0 ;0,1=73,2=270.000000
L 12.82456348 1.2203 12.82164675 1.22083317 2 P 0 ;0,1=73,2=270.000000
L 12.82164675 1.22083317 12.81873071 1.2203 2 P 0 ;0,1=73,2=270.000000
L 12.81873071 1.2203 12.81623041 1.2186998 2 P 0 ;0,1=73,2=270.000000
L 12.81623041 1.2186998 12.81539656 1.21683307 2 P 0 ;0,1=73,2=270.000000
L 12.81539656 1.21683307 12.81539656 1.20856673 2 P 0 ;0,1=73,2=270.000000
L 12.80789665 1.23363317 12.80539715 1.23523327 2 P 0 ;0,1=73,2=270.000000
L 12.80539715 1.23523327 12.80414665 1.2371 2 P 0 ;0,1=73,2=270.000000
L 12.80414665 1.2371 12.80373002 1.23923337 2 P 0 ;0,1=73,2=270.000000
L 12.80373002 1.23923337 12.80456319 1.2419 2 P 0 ;0,1=73,2=270.000000
L 12.80456319 1.2419 12.80664685 1.24376673 2 P 0 ;0,1=73,2=270.000000
L 12.80664685 1.24376673 12.80914636 1.2443 2 P 0 ;0,1=73,2=270.000000
L 12.80914636 1.2443 12.81164734 1.24403337 2 P 0 ;0,1=73,2=270.000000
L 12.81164734 1.24403337 12.81373022 1.24296644 2 P 0 ;0,1=73,2=270.000000
L 12.81373022 1.24296644 12.81789675 1.23763327 2 P 0 ;0,1=73,2=270.000000
L 12.81789675 1.23763327 12.82081358 1.23523327 2 P 0 ;0,1=73,2=270.000000
L 12.82081358 1.23523327 12.82498091 1.23363317 2 P 0 ;0,1=73,2=270.000000
L 12.82498091 1.23363317 12.82873002 1.2330999 2 P 0 ;0,1=73,2=270.000000
L 12.82873002 1.2330999 12.82873002 1.2443 2 P 0 ;0,1=73,2=270.000000
L 12.57283002 1.20803297 12.54783002 1.2146997 2 P 0 ;0,1=74,2=270.000000
L 12.54783002 1.2146997 12.57283002 1.22136693 2 P 0 ;0,1=74,2=270.000000
L 12.56408041 1.21896644 12.56408041 1.21043297 2 P 0 ;0,1=74,2=270.000000
L 12.55199665 1.23363317 12.54949715 1.23523327 2 P 0 ;0,1=74,2=270.000000
L 12.54949715 1.23523327 12.54824665 1.2371 2 P 0 ;0,1=74,2=270.000000
L 12.54824665 1.2371 12.54783002 1.23923337 2 P 0 ;0,1=74,2=270.000000
L 12.54783002 1.23923337 12.54866319 1.2419 2 P 0 ;0,1=74,2=270.000000
L 12.54866319 1.2419 12.55074685 1.24376673 2 P 0 ;0,1=74,2=270.000000
L 12.55074685 1.24376673 12.55324636 1.2443 2 P 0 ;0,1=74,2=270.000000
L 12.55324636 1.2443 12.55574734 1.24403337 2 P 0 ;0,1=74,2=270.000000
L 12.55574734 1.24403337 12.55783022 1.24296644 2 P 0 ;0,1=74,2=270.000000
L 12.55783022 1.24296644 12.56199675 1.23763327 2 P 0 ;0,1=74,2=270.000000
L 12.56199675 1.23763327 12.56491358 1.23523327 2 P 0 ;0,1=74,2=270.000000
L 12.56491358 1.23523327 12.56908091 1.23363317 2 P 0 ;0,1=74,2=270.000000
L 12.56908091 1.23363317 12.57283002 1.2330999 2 P 0 ;0,1=74,2=270.000000
L 12.57283002 1.2330999 12.57283002 1.2443 2 P 0 ;0,1=74,2=270.000000
L 12.7366565 1.21683307 12.73540669 1.2179 2 P 0 ;0,1=41,2=270.000000
L 12.73540669 1.2179 12.73332382 1.2186998 2 P 0 ;0,1=41,2=270.000000
L 12.73332382 1.2186998 12.7304063 1.21923356 2 P 0 ;0,1=41,2=270.000000
L 12.7304063 1.21923356 12.72790679 1.2186998 2 P 0 ;0,1=41,2=270.000000
L 12.72790679 1.2186998 12.72624055 1.21763337 2 P 0 ;0,1=41,2=270.000000
L 12.72624055 1.21763337 12.72498996 1.21576663 2 P 0 ;0,1=41,2=270.000000
L 12.72498996 1.21576663 12.72498996 1.20856673 2 P 0 ;0,1=41,2=270.000000
L 12.72498996 1.20856673 12.74998996 1.20856673 2 P 0 ;0,1=41,2=270.000000
L 12.74998996 1.20856673 12.74998996 1.21736673 2 P 0 ;0,1=41,2=270.000000
L 12.74998996 1.21736673 12.74832372 1.21923356 2 P 0 ;0,1=41,2=270.000000
L 12.74832372 1.21923356 12.74582343 1.2203 2 P 0 ;0,1=41,2=270.000000
L 12.74582343 1.2203 12.74290669 1.22083317 2 P 0 ;0,1=41,2=270.000000
L 12.74290669 1.22083317 12.73999065 1.2203 2 P 0 ;0,1=41,2=270.000000
L 12.73999065 1.2203 12.73749035 1.2186998 2 P 0 ;0,1=41,2=270.000000
L 12.73749035 1.2186998 12.7366565 1.21683307 2 P 0 ;0,1=41,2=270.000000
L 12.7366565 1.21683307 12.7366565 1.20856673 2 P 0 ;0,1=41,2=270.000000
L 12.74998996 1.2386997 12.72498996 1.2386997 2 P 0 ;0,1=41,2=270.000000
L 12.72498996 1.2386997 12.72998967 1.2354999 2 P 0 ;0,1=41,2=270.000000
L 12.74998996 1.2354999 12.74998996 1.24189951 2 P 0 ;0,1=41,2=270.000000
L 12.81666654 4.80013307 12.81541673 4.8012 2 P 0 ;0,1=75,2=270.000000
L 12.81541673 4.8012 12.81333386 4.8019998 2 P 0 ;0,1=75,2=270.000000
L 12.81333386 4.8019998 12.81041634 4.80253356 2 P 0 ;0,1=75,2=270.000000
L 12.81041634 4.80253356 12.80791683 4.8019998 2 P 0 ;0,1=75,2=270.000000
L 12.80791683 4.8019998 12.80625059 4.80093337 2 P 0 ;0,1=75,2=270.000000
L 12.80625059 4.80093337 12.805 4.79906663 2 P 0 ;0,1=75,2=270.000000
L 12.805 4.79906663 12.805 4.79186673 2 P 0 ;0,1=75,2=270.000000
L 12.805 4.79186673 12.83 4.79186673 2 P 0 ;0,1=75,2=270.000000
L 12.83 4.79186673 12.83 4.80066673 2 P 0 ;0,1=75,2=270.000000
L 12.83 4.80066673 12.82833376 4.80253356 2 P 0 ;0,1=75,2=270.000000
L 12.82833376 4.80253356 12.82583346 4.8036 2 P 0 ;0,1=75,2=270.000000
L 12.82583346 4.8036 12.82291673 4.80413317 2 P 0 ;0,1=75,2=270.000000
L 12.82291673 4.80413317 12.82000069 4.8036 2 P 0 ;0,1=75,2=270.000000
L 12.82000069 4.8036 12.81750039 4.8019998 2 P 0 ;0,1=75,2=270.000000
L 12.81750039 4.8019998 12.81666654 4.80013307 2 P 0 ;0,1=75,2=270.000000
L 12.81666654 4.80013307 12.81666654 4.79186673 2 P 0 ;0,1=75,2=270.000000
L 12.83 4.8219997 12.82958346 4.82386644 2 P 0 ;0,1=75,2=270.000000
L 12.82958346 4.82386644 12.82833376 4.8259998 2 P 0 ;0,1=75,2=270.000000
L 12.82833376 4.8259998 12.82625089 4.82733337 2 P 0 ;0,1=75,2=270.000000
L 12.82625089 4.82733337 12.82333327 4.82786663 2 P 0 ;0,1=75,2=270.000000
L 12.82333327 4.82786663 12.82041722 4.82733337 2 P 0 ;0,1=75,2=270.000000
L 12.82041722 4.82733337 12.81791703 4.82573327 2 P 0 ;0,1=75,2=270.000000
L 12.81791703 4.82573327 12.81666654 4.82333327 2 P 0 ;0,1=75,2=270.000000
L 12.81666654 4.82333327 12.81666654 4.82066663 2 P 0 ;0,1=75,2=270.000000
L 12.81666654 4.82066663 12.81583337 4.81906654 2 P 0 ;0,1=75,2=270.000000
L 12.81583337 4.81906654 12.81375049 4.81773297 2 P 0 ;0,1=75,2=270.000000
L 12.81375049 4.81773297 12.81083366 4.8171998 2 P 0 ;0,1=75,2=270.000000
L 12.81083366 4.8171998 12.80791683 4.8180001 2 P 0 ;0,1=75,2=270.000000
L 12.80791683 4.8180001 12.80583317 4.81986634 2 P 0 ;0,1=75,2=270.000000
L 12.80583317 4.81986634 12.805 4.8219997 2 P 0 ;0,1=75,2=270.000000
L 12.805 4.8219997 12.80583317 4.82413307 2 P 0 ;0,1=75,2=270.000000
L 12.80583317 4.82413307 12.80791683 4.8259998 2 P 0 ;0,1=75,2=270.000000
L 12.80791683 4.8259998 12.81083366 4.8268001 2 P 0 ;0,1=75,2=270.000000
L 12.81083366 4.8268001 12.81375049 4.82626644 2 P 0 ;0,1=75,2=270.000000
L 12.81375049 4.82626644 12.81583337 4.82493337 2 P 0 ;0,1=75,2=270.000000
L 12.81583337 4.82493337 12.81666654 4.82333327 2 P 0 ;0,1=75,2=270.000000
L 12.81666654 4.82333327 12.81666654 4.82066663 2 P 0 ;0,1=75,2=270.000000
L 12.81666654 4.82066663 12.81791703 4.81826663 2 P 0 ;0,1=75,2=270.000000
L 12.81791703 4.81826663 12.82041722 4.81666654 2 P 0 ;0,1=75,2=270.000000
L 12.82041722 4.81666654 12.82333327 4.81613327 2 P 0 ;0,1=75,2=270.000000
L 12.82333327 4.81613327 12.82625089 4.81666654 2 P 0 ;0,1=75,2=270.000000
L 12.82625089 4.81666654 12.82833376 4.8180001 2 P 0 ;0,1=75,2=270.000000
L 12.82833376 4.8180001 12.82958346 4.82013346 2 P 0 ;0,1=75,2=270.000000
L 12.82958346 4.82013346 12.83 4.8219997 2 P 0 ;0,1=75,2=270.000000
L 12.80916663 4.84093317 12.80666713 4.84253327 2 P 0 ;0,1=75,2=270.000000
L 12.80666713 4.84253327 12.80541663 4.8444 2 P 0 ;0,1=75,2=270.000000
L 12.80541663 4.8444 12.805 4.84653337 2 P 0 ;0,1=75,2=270.000000
L 12.805 4.84653337 12.80583317 4.8492 2 P 0 ;0,1=75,2=270.000000
L 12.80583317 4.8492 12.80791683 4.85106673 2 P 0 ;0,1=75,2=270.000000
L 12.80791683 4.85106673 12.81041634 4.8516 2 P 0 ;0,1=75,2=270.000000
L 12.81041634 4.8516 12.81291732 4.85133337 2 P 0 ;0,1=75,2=270.000000
L 12.81291732 4.85133337 12.8150002 4.85026644 2 P 0 ;0,1=75,2=270.000000
L 12.8150002 4.85026644 12.81916673 4.84493327 2 P 0 ;0,1=75,2=270.000000
L 12.81916673 4.84493327 12.82208356 4.84253327 2 P 0 ;0,1=75,2=270.000000
L 12.82208356 4.84253327 12.82625089 4.84093317 2 P 0 ;0,1=75,2=270.000000
L 12.82625089 4.84093317 12.83 4.8403999 2 P 0 ;0,1=75,2=270.000000
L 12.83 4.8403999 12.83 4.8516 2 P 0 ;0,1=75,2=270.000000
L 12.635 4.79133297 12.61 4.7979997 2 P 0 ;0,1=76,2=270.000000
L 12.61 4.7979997 12.635 4.80466693 2 P 0 ;0,1=76,2=270.000000
L 12.62625039 4.80226644 12.62625039 4.79373297 2 P 0 ;0,1=76,2=270.000000
L 12.635 4.8219997 12.63458346 4.82386644 2 P 0 ;0,1=76,2=270.000000
L 12.63458346 4.82386644 12.63333376 4.8259998 2 P 0 ;0,1=76,2=270.000000
L 12.63333376 4.8259998 12.63125089 4.82733337 2 P 0 ;0,1=76,2=270.000000
L 12.63125089 4.82733337 12.62833327 4.82786663 2 P 0 ;0,1=76,2=270.000000
L 12.62833327 4.82786663 12.62541722 4.82733337 2 P 0 ;0,1=76,2=270.000000
L 12.62541722 4.82733337 12.62291703 4.82573327 2 P 0 ;0,1=76,2=270.000000
L 12.62291703 4.82573327 12.62166654 4.82333327 2 P 0 ;0,1=76,2=270.000000
L 12.62166654 4.82333327 12.62166654 4.82066663 2 P 0 ;0,1=76,2=270.000000
L 12.62166654 4.82066663 12.62083337 4.81906654 2 P 0 ;0,1=76,2=270.000000
L 12.62083337 4.81906654 12.61875049 4.81773297 2 P 0 ;0,1=76,2=270.000000
L 12.61875049 4.81773297 12.61583366 4.8171998 2 P 0 ;0,1=76,2=270.000000
L 12.61583366 4.8171998 12.61291683 4.8180001 2 P 0 ;0,1=76,2=270.000000
L 12.61291683 4.8180001 12.61083317 4.81986634 2 P 0 ;0,1=76,2=270.000000
L 12.61083317 4.81986634 12.61 4.8219997 2 P 0 ;0,1=76,2=270.000000
L 12.61 4.8219997 12.61083317 4.82413307 2 P 0 ;0,1=76,2=270.000000
L 12.61083317 4.82413307 12.61291683 4.8259998 2 P 0 ;0,1=76,2=270.000000
L 12.61291683 4.8259998 12.61583366 4.8268001 2 P 0 ;0,1=76,2=270.000000
L 12.61583366 4.8268001 12.61875049 4.82626644 2 P 0 ;0,1=76,2=270.000000
L 12.61875049 4.82626644 12.62083337 4.82493337 2 P 0 ;0,1=76,2=270.000000
L 12.62083337 4.82493337 12.62166654 4.82333327 2 P 0 ;0,1=76,2=270.000000
L 12.62166654 4.82333327 12.62166654 4.82066663 2 P 0 ;0,1=76,2=270.000000
L 12.62166654 4.82066663 12.62291703 4.81826663 2 P 0 ;0,1=76,2=270.000000
L 12.62291703 4.81826663 12.62541722 4.81666654 2 P 0 ;0,1=76,2=270.000000
L 12.62541722 4.81666654 12.62833327 4.81613327 2 P 0 ;0,1=76,2=270.000000
L 12.62833327 4.81613327 12.63125089 4.81666654 2 P 0 ;0,1=76,2=270.000000
L 12.63125089 4.81666654 12.63333376 4.8180001 2 P 0 ;0,1=76,2=270.000000
L 12.63333376 4.8180001 12.63458346 4.82013346 2 P 0 ;0,1=76,2=270.000000
L 12.63458346 4.82013346 12.635 4.8219997 2 P 0 ;0,1=76,2=270.000000
L 12.635 4.8459997 12.61 4.8459997 2 P 0 ;0,1=76,2=270.000000
L 12.61 4.8459997 12.6149997 4.8427999 2 P 0 ;0,1=76,2=270.000000
L 12.635 4.8427999 12.635 4.84919951 2 P 0 ;0,1=76,2=270.000000
L 12.65156998 1.20803297 12.62656998 1.2146997 2 P 0 ;0,1=40,2=270.000000
L 12.62656998 1.2146997 12.65156998 1.22136693 2 P 0 ;0,1=40,2=270.000000
L 12.64282037 1.21896644 12.64282037 1.21043297 2 P 0 ;0,1=40,2=270.000000
L 12.65156998 1.2386997 12.62656998 1.2386997 2 P 0 ;0,1=40,2=270.000000
L 12.62656998 1.2386997 12.63156969 1.2354999 2 P 0 ;0,1=40,2=270.000000
L 12.65156998 1.2354999 12.65156998 1.24189951 2 P 0 ;0,1=40,2=270.000000
L 12.575 4.79133297 12.55 4.7979997 2 P 0 ;0,1=77,2=270.000000
L 12.55 4.7979997 12.575 4.80466693 2 P 0 ;0,1=77,2=270.000000
L 12.56625039 4.80226644 12.56625039 4.79373297 2 P 0 ;0,1=77,2=270.000000
L 12.575 4.8219997 12.57458346 4.82386644 2 P 0 ;0,1=77,2=270.000000
L 12.57458346 4.82386644 12.57333376 4.8259998 2 P 0 ;0,1=77,2=270.000000
L 12.57333376 4.8259998 12.57125089 4.82733337 2 P 0 ;0,1=77,2=270.000000
L 12.57125089 4.82733337 12.56833327 4.82786663 2 P 0 ;0,1=77,2=270.000000
L 12.56833327 4.82786663 12.56541722 4.82733337 2 P 0 ;0,1=77,2=270.000000
L 12.56541722 4.82733337 12.56291703 4.82573327 2 P 0 ;0,1=77,2=270.000000
L 12.56291703 4.82573327 12.56166654 4.82333327 2 P 0 ;0,1=77,2=270.000000
L 12.56166654 4.82333327 12.56166654 4.82066663 2 P 0 ;0,1=77,2=270.000000
L 12.56166654 4.82066663 12.56083337 4.81906654 2 P 0 ;0,1=77,2=270.000000
L 12.56083337 4.81906654 12.55875049 4.81773297 2 P 0 ;0,1=77,2=270.000000
L 12.55875049 4.81773297 12.55583366 4.8171998 2 P 0 ;0,1=77,2=270.000000
L 12.55583366 4.8171998 12.55291683 4.8180001 2 P 0 ;0,1=77,2=270.000000
L 12.55291683 4.8180001 12.55083317 4.81986634 2 P 0 ;0,1=77,2=270.000000
L 12.55083317 4.81986634 12.55 4.8219997 2 P 0 ;0,1=77,2=270.000000
L 12.55 4.8219997 12.55083317 4.82413307 2 P 0 ;0,1=77,2=270.000000
L 12.55083317 4.82413307 12.55291683 4.8259998 2 P 0 ;0,1=77,2=270.000000
L 12.55291683 4.8259998 12.55583366 4.8268001 2 P 0 ;0,1=77,2=270.000000
L 12.55583366 4.8268001 12.55875049 4.82626644 2 P 0 ;0,1=77,2=270.000000
L 12.55875049 4.82626644 12.56083337 4.82493337 2 P 0 ;0,1=77,2=270.000000
L 12.56083337 4.82493337 12.56166654 4.82333327 2 P 0 ;0,1=77,2=270.000000
L 12.56166654 4.82333327 12.56166654 4.82066663 2 P 0 ;0,1=77,2=270.000000
L 12.56166654 4.82066663 12.56291703 4.81826663 2 P 0 ;0,1=77,2=270.000000
L 12.56291703 4.81826663 12.56541722 4.81666654 2 P 0 ;0,1=77,2=270.000000
L 12.56541722 4.81666654 12.56833327 4.81613327 2 P 0 ;0,1=77,2=270.000000
L 12.56833327 4.81613327 12.57125089 4.81666654 2 P 0 ;0,1=77,2=270.000000
L 12.57125089 4.81666654 12.57333376 4.8180001 2 P 0 ;0,1=77,2=270.000000
L 12.57333376 4.8180001 12.57458346 4.82013346 2 P 0 ;0,1=77,2=270.000000
L 12.57458346 4.82013346 12.575 4.8219997 2 P 0 ;0,1=77,2=270.000000
L 12.55416663 4.84093317 12.55166713 4.84253327 2 P 0 ;0,1=77,2=270.000000
L 12.55166713 4.84253327 12.55041663 4.8444 2 P 0 ;0,1=77,2=270.000000
L 12.55041663 4.8444 12.55 4.84653337 2 P 0 ;0,1=77,2=270.000000
L 12.55 4.84653337 12.55083317 4.8492 2 P 0 ;0,1=77,2=270.000000
L 12.55083317 4.8492 12.55291683 4.85106673 2 P 0 ;0,1=77,2=270.000000
L 12.55291683 4.85106673 12.55541634 4.8516 2 P 0 ;0,1=77,2=270.000000
L 12.55541634 4.8516 12.55791732 4.85133337 2 P 0 ;0,1=77,2=270.000000
L 12.55791732 4.85133337 12.5600002 4.85026644 2 P 0 ;0,1=77,2=270.000000
L 12.5600002 4.85026644 12.56416673 4.84493327 2 P 0 ;0,1=77,2=270.000000
L 12.56416673 4.84493327 12.56708356 4.84253327 2 P 0 ;0,1=77,2=270.000000
L 12.56708356 4.84253327 12.57125089 4.84093317 2 P 0 ;0,1=77,2=270.000000
L 12.57125089 4.84093317 12.575 4.8403999 2 P 0 ;0,1=77,2=270.000000
L 12.575 4.8403999 12.575 4.8516 2 P 0 ;0,1=77,2=270.000000
L 12.625 1.81633297 12.6 1.8229997 2 P 0 ;0,1=78,2=270.000000
L 12.6 1.8229997 12.625 1.82966693 2 P 0 ;0,1=78,2=270.000000
L 12.61625039 1.82726644 12.61625039 1.81873297 2 P 0 ;0,1=78,2=270.000000
L 12.625 1.8469997 12.6 1.8469997 2 P 0 ;0,1=78,2=270.000000
L 12.6 1.8469997 12.6049997 1.8437999 2 P 0 ;0,1=78,2=270.000000
L 12.625 1.8437999 12.625 1.85019951 2 P 0 ;0,1=78,2=270.000000
L 12.62000039 1.86513327 12.62291713 1.86673297 2 P 0 ;0,1=78,2=270.000000
L 12.62291713 1.86673297 12.62458346 1.86886634 2 P 0 ;0,1=78,2=270.000000
L 12.62458346 1.86886634 12.625 1.87126683 2 P 0 ;0,1=78,2=270.000000
L 12.625 1.87126683 12.62458346 1.8734002 2 P 0 ;0,1=78,2=270.000000
L 12.62458346 1.8734002 12.62250059 1.87553356 2 P 0 ;0,1=78,2=270.000000
L 12.62250059 1.87553356 12.62000039 1.87686663 2 P 0 ;0,1=78,2=270.000000
L 12.62000039 1.87686663 12.6175001 1.87713317 2 P 0 ;0,1=78,2=270.000000
L 12.6175001 1.87713317 12.61458406 1.8766 2 P 0 ;0,1=78,2=270.000000
L 12.61458406 1.8766 12.61250039 1.87473327 2 P 0 ;0,1=78,2=270.000000
L 12.61250039 1.87473327 12.61166654 1.87286644 2 P 0 ;0,1=78,2=270.000000
L 12.61166654 1.87286644 12.61166654 1.87046654 2 P 0 ;0,1=78,2=270.000000
L 12.61166654 1.87286644 12.61041673 1.87446663 2 P 0 ;0,1=78,2=270.000000
L 12.61041673 1.87446663 12.60833386 1.8758001 2 P 0 ;0,1=78,2=270.000000
L 12.60833386 1.8758001 12.60583366 1.87633337 2 P 0 ;0,1=78,2=270.000000
L 12.60583366 1.87633337 12.60333346 1.8758001 2 P 0 ;0,1=78,2=270.000000
L 12.60333346 1.8758001 12.60125059 1.87446663 2 P 0 ;0,1=78,2=270.000000
L 12.60125059 1.87446663 12.6 1.87206663 2 P 0 ;0,1=78,2=270.000000
L 12.6 1.87206663 12.60041663 1.86966663 2 P 0 ;0,1=78,2=270.000000
L 12.60041663 1.86966663 12.60208366 1.86726663 2 P 0 ;0,1=78,2=270.000000
L 12.81539656 1.79238307 12.81414675 1.79345 2 P 0 ;0,1=79,2=270.000000
L 12.81414675 1.79345 12.81206388 1.7942498 2 P 0 ;0,1=79,2=270.000000
L 12.81206388 1.7942498 12.80914636 1.79478356 2 P 0 ;0,1=79,2=270.000000
L 12.80914636 1.79478356 12.80664685 1.7942498 2 P 0 ;0,1=79,2=270.000000
L 12.80664685 1.7942498 12.80498061 1.79318337 2 P 0 ;0,1=79,2=270.000000
L 12.80498061 1.79318337 12.80373002 1.79131663 2 P 0 ;0,1=79,2=270.000000
L 12.80373002 1.79131663 12.80373002 1.78411673 2 P 0 ;0,1=79,2=270.000000
L 12.80373002 1.78411673 12.82873002 1.78411673 2 P 0 ;0,1=79,2=270.000000
L 12.82873002 1.78411673 12.82873002 1.79291673 2 P 0 ;0,1=79,2=270.000000
L 12.82873002 1.79291673 12.82706378 1.79478356 2 P 0 ;0,1=79,2=270.000000
L 12.82706378 1.79478356 12.82456348 1.79585 2 P 0 ;0,1=79,2=270.000000
L 12.82456348 1.79585 12.82164675 1.79638317 2 P 0 ;0,1=79,2=270.000000
L 12.82164675 1.79638317 12.81873071 1.79585 2 P 0 ;0,1=79,2=270.000000
L 12.81873071 1.79585 12.81623041 1.7942498 2 P 0 ;0,1=79,2=270.000000
L 12.81623041 1.7942498 12.81539656 1.79238307 2 P 0 ;0,1=79,2=270.000000
L 12.81539656 1.79238307 12.81539656 1.78411673 2 P 0 ;0,1=79,2=270.000000
L 12.82873002 1.8142497 12.80373002 1.8142497 2 P 0 ;0,1=79,2=270.000000
L 12.80373002 1.8142497 12.80872972 1.8110499 2 P 0 ;0,1=79,2=270.000000
L 12.82873002 1.8110499 12.82873002 1.81744951 2 P 0 ;0,1=79,2=270.000000
L 12.80789665 1.83318317 12.80539715 1.83478327 2 P 0 ;0,1=79,2=270.000000
L 12.80539715 1.83478327 12.80414665 1.83665 2 P 0 ;0,1=79,2=270.000000
L 12.80414665 1.83665 12.80373002 1.83878337 2 P 0 ;0,1=79,2=270.000000
L 12.80373002 1.83878337 12.80456319 1.84145 2 P 0 ;0,1=79,2=270.000000
L 12.80456319 1.84145 12.80664685 1.84331673 2 P 0 ;0,1=79,2=270.000000
L 12.80664685 1.84331673 12.80914636 1.84385 2 P 0 ;0,1=79,2=270.000000
L 12.80914636 1.84385 12.81164734 1.84358337 2 P 0 ;0,1=79,2=270.000000
L 12.81164734 1.84358337 12.81373022 1.84251644 2 P 0 ;0,1=79,2=270.000000
L 12.81373022 1.84251644 12.81789675 1.83718327 2 P 0 ;0,1=79,2=270.000000
L 12.81789675 1.83718327 12.82081358 1.83478327 2 P 0 ;0,1=79,2=270.000000
L 12.82081358 1.83478327 12.82498091 1.83318317 2 P 0 ;0,1=79,2=270.000000
L 12.82498091 1.83318317 12.82873002 1.8326499 2 P 0 ;0,1=79,2=270.000000
L 12.82873002 1.8326499 12.82873002 1.84385 2 P 0 ;0,1=79,2=270.000000
L 12.76166654 1.82513307 12.76041673 1.8262 2 P 0 ;0,1=80,2=270.000000
L 12.76041673 1.8262 12.75833386 1.8269998 2 P 0 ;0,1=80,2=270.000000
L 12.75833386 1.8269998 12.75541634 1.82753356 2 P 0 ;0,1=80,2=270.000000
L 12.75541634 1.82753356 12.75291683 1.8269998 2 P 0 ;0,1=80,2=270.000000
L 12.75291683 1.8269998 12.75125059 1.82593337 2 P 0 ;0,1=80,2=270.000000
L 12.75125059 1.82593337 12.75 1.82406663 2 P 0 ;0,1=80,2=270.000000
L 12.75 1.82406663 12.75 1.81686673 2 P 0 ;0,1=80,2=270.000000
L 12.75 1.81686673 12.775 1.81686673 2 P 0 ;0,1=80,2=270.000000
L 12.775 1.81686673 12.775 1.82566673 2 P 0 ;0,1=80,2=270.000000
L 12.775 1.82566673 12.77333376 1.82753356 2 P 0 ;0,1=80,2=270.000000
L 12.77333376 1.82753356 12.77083346 1.8286 2 P 0 ;0,1=80,2=270.000000
L 12.77083346 1.8286 12.76791673 1.82913317 2 P 0 ;0,1=80,2=270.000000
L 12.76791673 1.82913317 12.76500069 1.8286 2 P 0 ;0,1=80,2=270.000000
L 12.76500069 1.8286 12.76250039 1.8269998 2 P 0 ;0,1=80,2=270.000000
L 12.76250039 1.8269998 12.76166654 1.82513307 2 P 0 ;0,1=80,2=270.000000
L 12.76166654 1.82513307 12.76166654 1.81686673 2 P 0 ;0,1=80,2=270.000000
L 12.775 1.8469997 12.75 1.8469997 2 P 0 ;0,1=80,2=270.000000
L 12.75 1.8469997 12.7549997 1.8437999 2 P 0 ;0,1=80,2=270.000000
L 12.775 1.8437999 12.775 1.85019951 2 P 0 ;0,1=80,2=270.000000
L 12.77000039 1.86513327 12.77291713 1.86673297 2 P 0 ;0,1=80,2=270.000000
L 12.77291713 1.86673297 12.77458346 1.86886634 2 P 0 ;0,1=80,2=270.000000
L 12.77458346 1.86886634 12.775 1.87126683 2 P 0 ;0,1=80,2=270.000000
L 12.775 1.87126683 12.77458346 1.8734002 2 P 0 ;0,1=80,2=270.000000
L 12.77458346 1.8734002 12.77250059 1.87553356 2 P 0 ;0,1=80,2=270.000000
L 12.77250059 1.87553356 12.77000039 1.87686663 2 P 0 ;0,1=80,2=270.000000
L 12.77000039 1.87686663 12.7675001 1.87713317 2 P 0 ;0,1=80,2=270.000000
L 12.7675001 1.87713317 12.76458406 1.8766 2 P 0 ;0,1=80,2=270.000000
L 12.76458406 1.8766 12.76250039 1.87473327 2 P 0 ;0,1=80,2=270.000000
L 12.76250039 1.87473327 12.76166654 1.87286644 2 P 0 ;0,1=80,2=270.000000
L 12.76166654 1.87286644 12.76166654 1.87046654 2 P 0 ;0,1=80,2=270.000000
L 12.76166654 1.87286644 12.76041673 1.87446663 2 P 0 ;0,1=80,2=270.000000
L 12.76041673 1.87446663 12.75833386 1.8758001 2 P 0 ;0,1=80,2=270.000000
L 12.75833386 1.8758001 12.75583366 1.87633337 2 P 0 ;0,1=80,2=270.000000
L 12.75583366 1.87633337 12.75333346 1.8758001 2 P 0 ;0,1=80,2=270.000000
L 12.75333346 1.8758001 12.75125059 1.87446663 2 P 0 ;0,1=80,2=270.000000
L 12.75125059 1.87446663 12.75 1.87206663 2 P 0 ;0,1=80,2=270.000000
L 12.75 1.87206663 12.75041663 1.86966663 2 P 0 ;0,1=80,2=270.000000
L 12.75041663 1.86966663 12.75208366 1.86726663 2 P 0 ;0,1=80,2=270.000000
L 12.74166654 4.80013307 12.74041673 4.8012 2 P 0 ;0,1=81,2=270.000000
L 12.74041673 4.8012 12.73833386 4.8019998 2 P 0 ;0,1=81,2=270.000000
L 12.73833386 4.8019998 12.73541634 4.80253356 2 P 0 ;0,1=81,2=270.000000
L 12.73541634 4.80253356 12.73291683 4.8019998 2 P 0 ;0,1=81,2=270.000000
L 12.73291683 4.8019998 12.73125059 4.80093337 2 P 0 ;0,1=81,2=270.000000
L 12.73125059 4.80093337 12.73 4.79906663 2 P 0 ;0,1=81,2=270.000000
L 12.73 4.79906663 12.73 4.79186673 2 P 0 ;0,1=81,2=270.000000
L 12.73 4.79186673 12.755 4.79186673 2 P 0 ;0,1=81,2=270.000000
L 12.755 4.79186673 12.755 4.80066673 2 P 0 ;0,1=81,2=270.000000
L 12.755 4.80066673 12.75333376 4.80253356 2 P 0 ;0,1=81,2=270.000000
L 12.75333376 4.80253356 12.75083346 4.8036 2 P 0 ;0,1=81,2=270.000000
L 12.75083346 4.8036 12.74791673 4.80413317 2 P 0 ;0,1=81,2=270.000000
L 12.74791673 4.80413317 12.74500069 4.8036 2 P 0 ;0,1=81,2=270.000000
L 12.74500069 4.8036 12.74250039 4.8019998 2 P 0 ;0,1=81,2=270.000000
L 12.74250039 4.8019998 12.74166654 4.80013307 2 P 0 ;0,1=81,2=270.000000
L 12.74166654 4.80013307 12.74166654 4.79186673 2 P 0 ;0,1=81,2=270.000000
L 12.755 4.8219997 12.75458346 4.82386644 2 P 0 ;0,1=81,2=270.000000
L 12.75458346 4.82386644 12.75333376 4.8259998 2 P 0 ;0,1=81,2=270.000000
L 12.75333376 4.8259998 12.75125089 4.82733337 2 P 0 ;0,1=81,2=270.000000
L 12.75125089 4.82733337 12.74833327 4.82786663 2 P 0 ;0,1=81,2=270.000000
L 12.74833327 4.82786663 12.74541722 4.82733337 2 P 0 ;0,1=81,2=270.000000
L 12.74541722 4.82733337 12.74291703 4.82573327 2 P 0 ;0,1=81,2=270.000000
L 12.74291703 4.82573327 12.74166654 4.82333327 2 P 0 ;0,1=81,2=270.000000
L 12.74166654 4.82333327 12.74166654 4.82066663 2 P 0 ;0,1=81,2=270.000000
L 12.74166654 4.82066663 12.74083337 4.81906654 2 P 0 ;0,1=81,2=270.000000
L 12.74083337 4.81906654 12.73875049 4.81773297 2 P 0 ;0,1=81,2=270.000000
L 12.73875049 4.81773297 12.73583366 4.8171998 2 P 0 ;0,1=81,2=270.000000
L 12.73583366 4.8171998 12.73291683 4.8180001 2 P 0 ;0,1=81,2=270.000000
L 12.73291683 4.8180001 12.73083317 4.81986634 2 P 0 ;0,1=81,2=270.000000
L 12.73083317 4.81986634 12.73 4.8219997 2 P 0 ;0,1=81,2=270.000000
L 12.73 4.8219997 12.73083317 4.82413307 2 P 0 ;0,1=81,2=270.000000
L 12.73083317 4.82413307 12.73291683 4.8259998 2 P 0 ;0,1=81,2=270.000000
L 12.73291683 4.8259998 12.73583366 4.8268001 2 P 0 ;0,1=81,2=270.000000
L 12.73583366 4.8268001 12.73875049 4.82626644 2 P 0 ;0,1=81,2=270.000000
L 12.73875049 4.82626644 12.74083337 4.82493337 2 P 0 ;0,1=81,2=270.000000
L 12.74083337 4.82493337 12.74166654 4.82333327 2 P 0 ;0,1=81,2=270.000000
L 12.74166654 4.82333327 12.74166654 4.82066663 2 P 0 ;0,1=81,2=270.000000
L 12.74166654 4.82066663 12.74291703 4.81826663 2 P 0 ;0,1=81,2=270.000000
L 12.74291703 4.81826663 12.74541722 4.81666654 2 P 0 ;0,1=81,2=270.000000
L 12.74541722 4.81666654 12.74833327 4.81613327 2 P 0 ;0,1=81,2=270.000000
L 12.74833327 4.81613327 12.75125089 4.81666654 2 P 0 ;0,1=81,2=270.000000
L 12.75125089 4.81666654 12.75333376 4.8180001 2 P 0 ;0,1=81,2=270.000000
L 12.75333376 4.8180001 12.75458346 4.82013346 2 P 0 ;0,1=81,2=270.000000
L 12.75458346 4.82013346 12.755 4.8219997 2 P 0 ;0,1=81,2=270.000000
L 12.755 4.8459997 12.73 4.8459997 2 P 0 ;0,1=81,2=270.000000
L 12.73 4.8459997 12.7349997 4.8427999 2 P 0 ;0,1=81,2=270.000000
L 12.755 4.8427999 12.755 4.84919951 2 P 0 ;0,1=81,2=270.000000
L 0.675 -0.4 0.675 -0.2 3 P 0 
L 0.675 -0.2 0.775 -0.2 3 P 0 
L 0.775 -0.2 0.775 -0.4 3 P 0 
L 0.775 -0.4 0.675 -0.4 3 P 0 
L 1.395 -0.41206683 1.395 -0.40193327 2 P 0 ;0,1=83,2=270.000000
L 1.395 -0.40193327 1.42 -0.41206683 2 P 0 ;0,1=83,2=270.000000
L 1.42 -0.41206683 1.42 -0.40193327 2 P 0 ;0,1=83,2=270.000000
L 1.42 -0.3798 1.395 -0.3798 2 P 0 ;0,1=83,2=270.000000
L 1.395 -0.3798 1.41291673 -0.38966703 2 P 0 ;0,1=83,2=270.000000
L 1.41291673 -0.38966703 1.41291673 -0.37633307 2 P 0 ;0,1=83,2=270.000000
L 1.41625089 -0.36486673 1.41833376 -0.36326703 2 P 0 ;0,1=83,2=270.000000
L 1.41833376 -0.36326703 1.41958346 -0.3614003 2 P 0 ;0,1=83,2=270.000000
L 1.41958346 -0.3614003 1.42 -0.3590003 2 P 0 ;0,1=83,2=270.000000
L 1.42 -0.3590003 1.41916693 -0.3565998 2 P 0 ;0,1=83,2=270.000000
L 1.41916693 -0.3565998 1.41750059 -0.35473356 2 P 0 ;0,1=83,2=270.000000
L 1.41750059 -0.35473356 1.41458376 -0.3534 2 P 0 ;0,1=83,2=270.000000
L 1.41458376 -0.3534 1.41125039 -0.35313337 2 P 0 ;0,1=83,2=270.000000
L 1.41125039 -0.35313337 1.40791703 -0.35366663 2 P 0 ;0,1=83,2=270.000000
L 1.40791703 -0.35366663 1.40583337 -0.3550002 2 P 0 ;0,1=83,2=270.000000
L 1.40583337 -0.3550002 1.40416703 -0.35686693 2 P 0 ;0,1=83,2=270.000000
L 1.40416703 -0.35686693 1.40375049 -0.35873317 2 P 0 ;0,1=83,2=270.000000
L 1.40375049 -0.35873317 1.40416703 -0.3606 2 P 0 ;0,1=83,2=270.000000
L 1.40416703 -0.3606 1.40583337 -0.3629999 2 P 0 ;0,1=83,2=270.000000
L 1.40583337 -0.3629999 1.395 -0.3622001 2 P 0 ;0,1=83,2=270.000000
L 1.395 -0.3622001 1.395 -0.3550002 2 P 0 ;0,1=83,2=270.000000
L 1.41666742 -0.3406001 1.4187503 -0.33846673 2 P 0 ;0,1=83,2=270.000000
L 1.4187503 -0.33846673 1.42 -0.33606673 2 P 0 ;0,1=83,2=270.000000
L 1.42 -0.33606673 1.42 -0.33393337 2 P 0 ;0,1=83,2=270.000000
L 1.42 -0.33393337 1.4187503 -0.3318 2 P 0 ;0,1=83,2=270.000000
L 1.4187503 -0.3318 1.41666742 -0.3301999 2 P 0 ;0,1=83,2=270.000000
L 1.41666742 -0.3301999 1.4137499 -0.3294 2 P 0 ;0,1=83,2=270.000000
L 1.4137499 -0.3294 1.41083386 -0.32993327 2 P 0 ;0,1=83,2=270.000000
L 1.41083386 -0.32993327 1.40833356 -0.33126673 2 P 0 ;0,1=83,2=270.000000
L 1.40833356 -0.33126673 1.40666654 -0.33366673 2 P 0 ;0,1=83,2=270.000000
L 1.40666654 -0.33366673 1.40583337 -0.33686654 2 P 0 ;0,1=83,2=270.000000
L 1.40583337 -0.33686654 1.40416703 -0.33873337 2 P 0 ;0,1=83,2=270.000000
L 1.40416703 -0.33873337 1.4012502 -0.33953366 2 P 0 ;0,1=83,2=270.000000
L 1.4012502 -0.33953366 1.39833346 -0.3389999 2 P 0 ;0,1=83,2=270.000000
L 1.39833346 -0.3389999 1.39625059 -0.33766683 2 P 0 ;0,1=83,2=270.000000
L 1.39625059 -0.33766683 1.395 -0.3358001 2 P 0 ;0,1=83,2=270.000000
L 1.395 -0.3358001 1.395 -0.33393337 2 P 0 ;0,1=83,2=270.000000
L 1.395 -0.33393337 1.39583317 -0.33206663 2 P 0 ;0,1=83,2=270.000000
L 1.39583317 -0.33206663 1.39791683 -0.33046644 2 P 0 ;0,1=83,2=270.000000
L 1.42833307 -0.319 1.42833307 -0.303 2 P 0 ;0,1=83,2=270.000000
L 1.395 -0.2902001 1.395 -0.28380049 2 P 0 ;0,1=83,2=270.000000
L 1.395 -0.2870003 1.42 -0.2870003 2 P 0 ;0,1=83,2=270.000000
L 1.42 -0.2902001 1.42 -0.28380049 2 P 0 ;0,1=83,2=270.000000
L 1.42 -0.26913327 1.395 -0.26913327 2 P 0 ;0,1=83,2=270.000000
L 1.395 -0.26913327 1.42 -0.25686683 2 P 0 ;0,1=83,2=270.000000
L 1.42 -0.25686683 1.395 -0.25686683 2 P 0 ;0,1=83,2=270.000000
L 1.42833307 -0.247 1.42833307 -0.231 2 P 0 ;0,1=83,2=270.000000
L 1.395 -0.22033346 1.42 -0.22033346 2 P 0 ;0,1=83,2=270.000000
L 1.42 -0.22033346 1.42 -0.20966663 2 P 0 ;0,1=83,2=270.000000
L 1.42 -0.1910003 1.395 -0.1910003 2 P 0 ;0,1=83,2=270.000000
L 1.395 -0.1910003 1.3999997 -0.1942001 2 P 0 ;0,1=83,2=270.000000
L 1.42 -0.1942001 1.42 -0.18780049 2 P 0 ;0,1=83,2=270.000000
L 1.39916663 -0.17206683 1.39666713 -0.17046673 2 P 0 ;0,1=83,2=270.000000
L 1.39666713 -0.17046673 1.39541663 -0.1686 2 P 0 ;0,1=83,2=270.000000
L 1.39541663 -0.1686 1.395 -0.16646663 2 P 0 ;0,1=83,2=270.000000
L 1.395 -0.16646663 1.39583317 -0.1638 2 P 0 ;0,1=83,2=270.000000
L 1.39583317 -0.1638 1.39791683 -0.16193327 2 P 0 ;0,1=83,2=270.000000
L 1.39791683 -0.16193327 1.40041634 -0.1614 2 P 0 ;0,1=83,2=270.000000
L 1.40041634 -0.1614 1.40291732 -0.16166663 2 P 0 ;0,1=83,2=270.000000
L 1.40291732 -0.16166663 1.4050002 -0.16273356 2 P 0 ;0,1=83,2=270.000000
L 1.4050002 -0.16273356 1.40916673 -0.16806673 2 P 0 ;0,1=83,2=270.000000
L 1.40916673 -0.16806673 1.41208356 -0.17046673 2 P 0 ;0,1=83,2=270.000000
L 1.41208356 -0.17046673 1.41625089 -0.17206683 2 P 0 ;0,1=83,2=270.000000
L 1.41625089 -0.17206683 1.42 -0.1726001 2 P 0 ;0,1=83,2=270.000000
L 1.42 -0.1726001 1.42 -0.1614 2 P 0 ;0,1=83,2=270.000000
L 0.825 -0.4 0.825 -0.2 3 P 0 
L 0.825 -0.2 0.925 -0.2 3 P 0 
L 0.925 -0.2 0.925 -0.4 3 P 0 
L 0.925 -0.4 0.825 -0.4 3 P 0 
L 1.445 -0.41206683 1.445 -0.40193327 2 P 0 ;0,1=84,2=270.000000
L 1.445 -0.40193327 1.47 -0.41206683 2 P 0 ;0,1=84,2=270.000000
L 1.47 -0.41206683 1.47 -0.40193327 2 P 0 ;0,1=84,2=270.000000
L 1.47 -0.3798 1.445 -0.3798 2 P 0 ;0,1=84,2=270.000000
L 1.445 -0.3798 1.46291673 -0.38966703 2 P 0 ;0,1=84,2=270.000000
L 1.46291673 -0.38966703 1.46291673 -0.37633307 2 P 0 ;0,1=84,2=270.000000
L 1.46625089 -0.36486673 1.46833376 -0.36326703 2 P 0 ;0,1=84,2=270.000000
L 1.46833376 -0.36326703 1.46958346 -0.3614003 2 P 0 ;0,1=84,2=270.000000
L 1.46958346 -0.3614003 1.47 -0.3590003 2 P 0 ;0,1=84,2=270.000000
L 1.47 -0.3590003 1.46916693 -0.3565998 2 P 0 ;0,1=84,2=270.000000
L 1.46916693 -0.3565998 1.46750059 -0.35473356 2 P 0 ;0,1=84,2=270.000000
L 1.46750059 -0.35473356 1.46458376 -0.3534 2 P 0 ;0,1=84,2=270.000000
L 1.46458376 -0.3534 1.46125039 -0.35313337 2 P 0 ;0,1=84,2=270.000000
L 1.46125039 -0.35313337 1.45791703 -0.35366663 2 P 0 ;0,1=84,2=270.000000
L 1.45791703 -0.35366663 1.45583337 -0.3550002 2 P 0 ;0,1=84,2=270.000000
L 1.45583337 -0.3550002 1.45416703 -0.35686693 2 P 0 ;0,1=84,2=270.000000
L 1.45416703 -0.35686693 1.45375049 -0.35873317 2 P 0 ;0,1=84,2=270.000000
L 1.45375049 -0.35873317 1.45416703 -0.3606 2 P 0 ;0,1=84,2=270.000000
L 1.45416703 -0.3606 1.45583337 -0.3629999 2 P 0 ;0,1=84,2=270.000000
L 1.45583337 -0.3629999 1.445 -0.3622001 2 P 0 ;0,1=84,2=270.000000
L 1.445 -0.3622001 1.445 -0.3550002 2 P 0 ;0,1=84,2=270.000000
L 1.46666742 -0.3406001 1.4687503 -0.33846673 2 P 0 ;0,1=84,2=270.000000
L 1.4687503 -0.33846673 1.47 -0.33606673 2 P 0 ;0,1=84,2=270.000000
L 1.47 -0.33606673 1.47 -0.33393337 2 P 0 ;0,1=84,2=270.000000
L 1.47 -0.33393337 1.4687503 -0.3318 2 P 0 ;0,1=84,2=270.000000
L 1.4687503 -0.3318 1.46666742 -0.3301999 2 P 0 ;0,1=84,2=270.000000
L 1.46666742 -0.3301999 1.4637499 -0.3294 2 P 0 ;0,1=84,2=270.000000
L 1.4637499 -0.3294 1.46083386 -0.32993327 2 P 0 ;0,1=84,2=270.000000
L 1.46083386 -0.32993327 1.45833356 -0.33126673 2 P 0 ;0,1=84,2=270.000000
L 1.45833356 -0.33126673 1.45666654 -0.33366673 2 P 0 ;0,1=84,2=270.000000
L 1.45666654 -0.33366673 1.45583337 -0.33686654 2 P 0 ;0,1=84,2=270.000000
L 1.45583337 -0.33686654 1.45416703 -0.33873337 2 P 0 ;0,1=84,2=270.000000
L 1.45416703 -0.33873337 1.4512502 -0.33953366 2 P 0 ;0,1=84,2=270.000000
L 1.4512502 -0.33953366 1.44833346 -0.3389999 2 P 0 ;0,1=84,2=270.000000
L 1.44833346 -0.3389999 1.44625059 -0.33766683 2 P 0 ;0,1=84,2=270.000000
L 1.44625059 -0.33766683 1.445 -0.3358001 2 P 0 ;0,1=84,2=270.000000
L 1.445 -0.3358001 1.445 -0.33393337 2 P 0 ;0,1=84,2=270.000000
L 1.445 -0.33393337 1.44583317 -0.33206663 2 P 0 ;0,1=84,2=270.000000
L 1.44583317 -0.33206663 1.44791683 -0.33046644 2 P 0 ;0,1=84,2=270.000000
L 1.47833307 -0.319 1.47833307 -0.303 2 P 0 ;0,1=84,2=270.000000
L 1.445 -0.2902001 1.445 -0.28380049 2 P 0 ;0,1=84,2=270.000000
L 1.445 -0.2870003 1.47 -0.2870003 2 P 0 ;0,1=84,2=270.000000
L 1.47 -0.2902001 1.47 -0.28380049 2 P 0 ;0,1=84,2=270.000000
L 1.47 -0.26913327 1.445 -0.26913327 2 P 0 ;0,1=84,2=270.000000
L 1.445 -0.26913327 1.47 -0.25686683 2 P 0 ;0,1=84,2=270.000000
L 1.47 -0.25686683 1.445 -0.25686683 2 P 0 ;0,1=84,2=270.000000
L 1.47833307 -0.247 1.47833307 -0.231 2 P 0 ;0,1=84,2=270.000000
L 1.445 -0.22033346 1.47 -0.22033346 2 P 0 ;0,1=84,2=270.000000
L 1.47 -0.22033346 1.47 -0.20966663 2 P 0 ;0,1=84,2=270.000000
L 1.47 -0.1910003 1.445 -0.1910003 2 P 0 ;0,1=84,2=270.000000
L 1.445 -0.1910003 1.4499997 -0.1942001 2 P 0 ;0,1=84,2=270.000000
L 1.47 -0.1942001 1.47 -0.18780049 2 P 0 ;0,1=84,2=270.000000
L 1.445 -0.1670003 1.44583317 -0.16913366 2 P 0 ;0,1=84,2=270.000000
L 1.44583317 -0.16913366 1.44791683 -0.17073337 2 P 0 ;0,1=84,2=270.000000
L 1.44791683 -0.17073337 1.45041634 -0.1718002 2 P 0 ;0,1=84,2=270.000000
L 1.45041634 -0.1718002 1.45375049 -0.1726001 2 P 0 ;0,1=84,2=270.000000
L 1.45375049 -0.1726001 1.45750039 -0.17286673 2 P 0 ;0,1=84,2=270.000000
L 1.45750039 -0.17286673 1.46125039 -0.1726001 2 P 0 ;0,1=84,2=270.000000
L 1.46125039 -0.1726001 1.46458376 -0.1718002 2 P 0 ;0,1=84,2=270.000000
L 1.46458376 -0.1718002 1.46708396 -0.17073337 2 P 0 ;0,1=84,2=270.000000
L 1.46708396 -0.17073337 1.46916693 -0.16913366 2 P 0 ;0,1=84,2=270.000000
L 1.46916693 -0.16913366 1.47 -0.1670003 2 P 0 ;0,1=84,2=270.000000
L 1.47 -0.1670003 1.46916693 -0.16486693 2 P 0 ;0,1=84,2=270.000000
L 1.46916693 -0.16486693 1.46708396 -0.16326673 2 P 0 ;0,1=84,2=270.000000
L 1.46708396 -0.16326673 1.46458376 -0.1621999 2 P 0 ;0,1=84,2=270.000000
L 1.46458376 -0.1621999 1.46125039 -0.1614 2 P 0 ;0,1=84,2=270.000000
L 1.46125039 -0.1614 1.45750039 -0.16113337 2 P 0 ;0,1=84,2=270.000000
L 1.45750039 -0.16113337 1.45375049 -0.1614 2 P 0 ;0,1=84,2=270.000000
L 1.45375049 -0.1614 1.45041634 -0.1621999 2 P 0 ;0,1=84,2=270.000000
L 1.45041634 -0.1621999 1.44791683 -0.16326673 2 P 0 ;0,1=84,2=270.000000
L 1.44791683 -0.16326673 1.44583317 -0.16486693 2 P 0 ;0,1=84,2=270.000000
L 1.44583317 -0.16486693 1.445 -0.1670003 2 P 0 ;0,1=84,2=270.000000
L 0.975 -0.4 0.975 -0.2 3 P 0 
L 0.975 -0.2 1.075 -0.2 3 P 0 
L 1.075 -0.2 1.075 -0.4 3 P 0 
L 1.075 -0.4 0.975 -0.4 3 P 0 
L 1.495 -0.41206683 1.495 -0.40193327 2 P 0 ;0,1=85,2=270.000000
L 1.495 -0.40193327 1.52 -0.41206683 2 P 0 ;0,1=85,2=270.000000
L 1.52 -0.41206683 1.52 -0.40193327 2 P 0 ;0,1=85,2=270.000000
L 1.52 -0.3798 1.495 -0.3798 2 P 0 ;0,1=85,2=270.000000
L 1.495 -0.3798 1.51291673 -0.38966703 2 P 0 ;0,1=85,2=270.000000
L 1.51291673 -0.38966703 1.51291673 -0.37633307 2 P 0 ;0,1=85,2=270.000000
L 1.51625089 -0.36486673 1.51833376 -0.36326703 2 P 0 ;0,1=85,2=270.000000
L 1.51833376 -0.36326703 1.51958346 -0.3614003 2 P 0 ;0,1=85,2=270.000000
L 1.51958346 -0.3614003 1.52 -0.3590003 2 P 0 ;0,1=85,2=270.000000
L 1.52 -0.3590003 1.51916693 -0.3565998 2 P 0 ;0,1=85,2=270.000000
L 1.51916693 -0.3565998 1.51750059 -0.35473356 2 P 0 ;0,1=85,2=270.000000
L 1.51750059 -0.35473356 1.51458376 -0.3534 2 P 0 ;0,1=85,2=270.000000
L 1.51458376 -0.3534 1.51125039 -0.35313337 2 P 0 ;0,1=85,2=270.000000
L 1.51125039 -0.35313337 1.50791703 -0.35366663 2 P 0 ;0,1=85,2=270.000000
L 1.50791703 -0.35366663 1.50583337 -0.3550002 2 P 0 ;0,1=85,2=270.000000
L 1.50583337 -0.3550002 1.50416703 -0.35686693 2 P 0 ;0,1=85,2=270.000000
L 1.50416703 -0.35686693 1.50375049 -0.35873317 2 P 0 ;0,1=85,2=270.000000
L 1.50375049 -0.35873317 1.50416703 -0.3606 2 P 0 ;0,1=85,2=270.000000
L 1.50416703 -0.3606 1.50583337 -0.3629999 2 P 0 ;0,1=85,2=270.000000
L 1.50583337 -0.3629999 1.495 -0.3622001 2 P 0 ;0,1=85,2=270.000000
L 1.495 -0.3622001 1.495 -0.3550002 2 P 0 ;0,1=85,2=270.000000
L 1.51666742 -0.3406001 1.5187503 -0.33846673 2 P 0 ;0,1=85,2=270.000000
L 1.5187503 -0.33846673 1.52 -0.33606673 2 P 0 ;0,1=85,2=270.000000
L 1.52 -0.33606673 1.52 -0.33393337 2 P 0 ;0,1=85,2=270.000000
L 1.52 -0.33393337 1.5187503 -0.3318 2 P 0 ;0,1=85,2=270.000000
L 1.5187503 -0.3318 1.51666742 -0.3301999 2 P 0 ;0,1=85,2=270.000000
L 1.51666742 -0.3301999 1.5137499 -0.3294 2 P 0 ;0,1=85,2=270.000000
L 1.5137499 -0.3294 1.51083386 -0.32993327 2 P 0 ;0,1=85,2=270.000000
L 1.51083386 -0.32993327 1.50833356 -0.33126673 2 P 0 ;0,1=85,2=270.000000
L 1.50833356 -0.33126673 1.50666654 -0.33366673 2 P 0 ;0,1=85,2=270.000000
L 1.50666654 -0.33366673 1.50583337 -0.33686654 2 P 0 ;0,1=85,2=270.000000
L 1.50583337 -0.33686654 1.50416703 -0.33873337 2 P 0 ;0,1=85,2=270.000000
L 1.50416703 -0.33873337 1.5012502 -0.33953366 2 P 0 ;0,1=85,2=270.000000
L 1.5012502 -0.33953366 1.49833346 -0.3389999 2 P 0 ;0,1=85,2=270.000000
L 1.49833346 -0.3389999 1.49625059 -0.33766683 2 P 0 ;0,1=85,2=270.000000
L 1.49625059 -0.33766683 1.495 -0.3358001 2 P 0 ;0,1=85,2=270.000000
L 1.495 -0.3358001 1.495 -0.33393337 2 P 0 ;0,1=85,2=270.000000
L 1.495 -0.33393337 1.49583317 -0.33206663 2 P 0 ;0,1=85,2=270.000000
L 1.49583317 -0.33206663 1.49791683 -0.33046644 2 P 0 ;0,1=85,2=270.000000
L 1.52833307 -0.319 1.52833307 -0.303 2 P 0 ;0,1=85,2=270.000000
L 1.495 -0.2902001 1.495 -0.28380049 2 P 0 ;0,1=85,2=270.000000
L 1.495 -0.2870003 1.52 -0.2870003 2 P 0 ;0,1=85,2=270.000000
L 1.52 -0.2902001 1.52 -0.28380049 2 P 0 ;0,1=85,2=270.000000
L 1.52 -0.26913327 1.495 -0.26913327 2 P 0 ;0,1=85,2=270.000000
L 1.495 -0.26913327 1.52 -0.25686683 2 P 0 ;0,1=85,2=270.000000
L 1.52 -0.25686683 1.495 -0.25686683 2 P 0 ;0,1=85,2=270.000000
L 1.52833307 -0.247 1.52833307 -0.231 2 P 0 ;0,1=85,2=270.000000
L 1.495 -0.22033346 1.52 -0.22033346 2 P 0 ;0,1=85,2=270.000000
L 1.52 -0.22033346 1.52 -0.20966663 2 P 0 ;0,1=85,2=270.000000
L 1.51625089 -0.19686673 1.51833376 -0.19526703 2 P 0 ;0,1=85,2=270.000000
L 1.51833376 -0.19526703 1.51958346 -0.1934003 2 P 0 ;0,1=85,2=270.000000
L 1.51958346 -0.1934003 1.52 -0.1910003 2 P 0 ;0,1=85,2=270.000000
L 1.52 -0.1910003 1.51916693 -0.1885998 2 P 0 ;0,1=85,2=270.000000
L 1.51916693 -0.1885998 1.51750059 -0.18673356 2 P 0 ;0,1=85,2=270.000000
L 1.51750059 -0.18673356 1.51458376 -0.1854 2 P 0 ;0,1=85,2=270.000000
L 1.51458376 -0.1854 1.51125039 -0.18513337 2 P 0 ;0,1=85,2=270.000000
L 1.51125039 -0.18513337 1.50791703 -0.18566663 2 P 0 ;0,1=85,2=270.000000
L 1.50791703 -0.18566663 1.50583337 -0.1870002 2 P 0 ;0,1=85,2=270.000000
L 1.50583337 -0.1870002 1.50416703 -0.18886693 2 P 0 ;0,1=85,2=270.000000
L 1.50416703 -0.18886693 1.50375049 -0.19073317 2 P 0 ;0,1=85,2=270.000000
L 1.50375049 -0.19073317 1.50416703 -0.1926 2 P 0 ;0,1=85,2=270.000000
L 1.50416703 -0.1926 1.50583337 -0.1949999 2 P 0 ;0,1=85,2=270.000000
L 1.50583337 -0.1949999 1.495 -0.1942001 2 P 0 ;0,1=85,2=270.000000
L 1.495 -0.1942001 1.495 -0.1870002 2 P 0 ;0,1=85,2=270.000000
L 1.125 -0.4 1.125 -0.2 3 P 0 
L 1.125 -0.2 1.225 -0.2 3 P 0 
L 1.225 -0.2 1.225 -0.4 3 P 0 
L 1.225 -0.4 1.125 -0.4 3 P 0 
L 1.545 -0.41206683 1.545 -0.40193327 2 P 0 ;0,1=86,2=270.000000
L 1.545 -0.40193327 1.57 -0.41206683 2 P 0 ;0,1=86,2=270.000000
L 1.57 -0.41206683 1.57 -0.40193327 2 P 0 ;0,1=86,2=270.000000
L 1.57 -0.3798 1.545 -0.3798 2 P 0 ;0,1=86,2=270.000000
L 1.545 -0.3798 1.56291673 -0.38966703 2 P 0 ;0,1=86,2=270.000000
L 1.56291673 -0.38966703 1.56291673 -0.37633307 2 P 0 ;0,1=86,2=270.000000
L 1.56625089 -0.36486673 1.56833376 -0.36326703 2 P 0 ;0,1=86,2=270.000000
L 1.56833376 -0.36326703 1.56958346 -0.3614003 2 P 0 ;0,1=86,2=270.000000
L 1.56958346 -0.3614003 1.57 -0.3590003 2 P 0 ;0,1=86,2=270.000000
L 1.57 -0.3590003 1.56916693 -0.3565998 2 P 0 ;0,1=86,2=270.000000
L 1.56916693 -0.3565998 1.56750059 -0.35473356 2 P 0 ;0,1=86,2=270.000000
L 1.56750059 -0.35473356 1.56458376 -0.3534 2 P 0 ;0,1=86,2=270.000000
L 1.56458376 -0.3534 1.56125039 -0.35313337 2 P 0 ;0,1=86,2=270.000000
L 1.56125039 -0.35313337 1.55791703 -0.35366663 2 P 0 ;0,1=86,2=270.000000
L 1.55791703 -0.35366663 1.55583337 -0.3550002 2 P 0 ;0,1=86,2=270.000000
L 1.55583337 -0.3550002 1.55416703 -0.35686693 2 P 0 ;0,1=86,2=270.000000
L 1.55416703 -0.35686693 1.55375049 -0.35873317 2 P 0 ;0,1=86,2=270.000000
L 1.55375049 -0.35873317 1.55416703 -0.3606 2 P 0 ;0,1=86,2=270.000000
L 1.55416703 -0.3606 1.55583337 -0.3629999 2 P 0 ;0,1=86,2=270.000000
L 1.55583337 -0.3629999 1.545 -0.3622001 2 P 0 ;0,1=86,2=270.000000
L 1.545 -0.3622001 1.545 -0.3550002 2 P 0 ;0,1=86,2=270.000000
L 1.56666742 -0.3406001 1.5687503 -0.33846673 2 P 0 ;0,1=86,2=270.000000
L 1.5687503 -0.33846673 1.57 -0.33606673 2 P 0 ;0,1=86,2=270.000000
L 1.57 -0.33606673 1.57 -0.33393337 2 P 0 ;0,1=86,2=270.000000
L 1.57 -0.33393337 1.5687503 -0.3318 2 P 0 ;0,1=86,2=270.000000
L 1.5687503 -0.3318 1.56666742 -0.3301999 2 P 0 ;0,1=86,2=270.000000
L 1.56666742 -0.3301999 1.5637499 -0.3294 2 P 0 ;0,1=86,2=270.000000
L 1.5637499 -0.3294 1.56083386 -0.32993327 2 P 0 ;0,1=86,2=270.000000
L 1.56083386 -0.32993327 1.55833356 -0.33126673 2 P 0 ;0,1=86,2=270.000000
L 1.55833356 -0.33126673 1.55666654 -0.33366673 2 P 0 ;0,1=86,2=270.000000
L 1.55666654 -0.33366673 1.55583337 -0.33686654 2 P 0 ;0,1=86,2=270.000000
L 1.55583337 -0.33686654 1.55416703 -0.33873337 2 P 0 ;0,1=86,2=270.000000
L 1.55416703 -0.33873337 1.5512502 -0.33953366 2 P 0 ;0,1=86,2=270.000000
L 1.5512502 -0.33953366 1.54833346 -0.3389999 2 P 0 ;0,1=86,2=270.000000
L 1.54833346 -0.3389999 1.54625059 -0.33766683 2 P 0 ;0,1=86,2=270.000000
L 1.54625059 -0.33766683 1.545 -0.3358001 2 P 0 ;0,1=86,2=270.000000
L 1.545 -0.3358001 1.545 -0.33393337 2 P 0 ;0,1=86,2=270.000000
L 1.545 -0.33393337 1.54583317 -0.33206663 2 P 0 ;0,1=86,2=270.000000
L 1.54583317 -0.33206663 1.54791683 -0.33046644 2 P 0 ;0,1=86,2=270.000000
L 1.57833307 -0.319 1.57833307 -0.303 2 P 0 ;0,1=86,2=270.000000
L 1.545 -0.2902001 1.545 -0.28380049 2 P 0 ;0,1=86,2=270.000000
L 1.545 -0.2870003 1.57 -0.2870003 2 P 0 ;0,1=86,2=270.000000
L 1.57 -0.2902001 1.57 -0.28380049 2 P 0 ;0,1=86,2=270.000000
L 1.57 -0.26913327 1.545 -0.26913327 2 P 0 ;0,1=86,2=270.000000
L 1.545 -0.26913327 1.57 -0.25686683 2 P 0 ;0,1=86,2=270.000000
L 1.57 -0.25686683 1.545 -0.25686683 2 P 0 ;0,1=86,2=270.000000
L 1.57833307 -0.247 1.57833307 -0.231 2 P 0 ;0,1=86,2=270.000000
L 1.545 -0.22033346 1.57 -0.22033346 2 P 0 ;0,1=86,2=270.000000
L 1.57 -0.22033346 1.57 -0.20966663 2 P 0 ;0,1=86,2=270.000000
L 1.56500039 -0.19686673 1.56791713 -0.19526703 2 P 0 ;0,1=86,2=270.000000
L 1.56791713 -0.19526703 1.56958346 -0.19313366 2 P 0 ;0,1=86,2=270.000000
L 1.56958346 -0.19313366 1.57 -0.19073317 2 P 0 ;0,1=86,2=270.000000
L 1.57 -0.19073317 1.56958346 -0.1885998 2 P 0 ;0,1=86,2=270.000000
L 1.56958346 -0.1885998 1.56750059 -0.18646644 2 P 0 ;0,1=86,2=270.000000
L 1.56750059 -0.18646644 1.56500039 -0.18513337 2 P 0 ;0,1=86,2=270.000000
L 1.56500039 -0.18513337 1.5625001 -0.18486683 2 P 0 ;0,1=86,2=270.000000
L 1.5625001 -0.18486683 1.55958406 -0.1854 2 P 0 ;0,1=86,2=270.000000
L 1.55958406 -0.1854 1.55750039 -0.18726673 2 P 0 ;0,1=86,2=270.000000
L 1.55750039 -0.18726673 1.55666654 -0.18913356 2 P 0 ;0,1=86,2=270.000000
L 1.55666654 -0.18913356 1.55666654 -0.19153346 2 P 0 ;0,1=86,2=270.000000
L 1.55666654 -0.18913356 1.55541673 -0.18753337 2 P 0 ;0,1=86,2=270.000000
L 1.55541673 -0.18753337 1.55333386 -0.1861999 2 P 0 ;0,1=86,2=270.000000
L 1.55333386 -0.1861999 1.55083366 -0.18566663 2 P 0 ;0,1=86,2=270.000000
L 1.55083366 -0.18566663 1.54833346 -0.1861999 2 P 0 ;0,1=86,2=270.000000
L 1.54833346 -0.1861999 1.54625059 -0.18753337 2 P 0 ;0,1=86,2=270.000000
L 1.54625059 -0.18753337 1.545 -0.18993337 2 P 0 ;0,1=86,2=270.000000
L 1.545 -0.18993337 1.54541663 -0.19233337 2 P 0 ;0,1=86,2=270.000000
L 1.54541663 -0.19233337 1.54708366 -0.19473337 2 P 0 ;0,1=86,2=270.000000
L 1.275 -0.4 1.275 -0.2 3 P 0 
L 1.275 -0.2 1.375 -0.2 3 P 0 
L 1.375 -0.2 1.375 -0.4 3 P 0 
L 1.375 -0.4 1.275 -0.4 3 P 0 
L 1.595 -0.41206683 1.595 -0.40193327 2 P 0 ;0,1=87,2=270.000000
L 1.595 -0.40193327 1.62 -0.41206683 2 P 0 ;0,1=87,2=270.000000
L 1.62 -0.41206683 1.62 -0.40193327 2 P 0 ;0,1=87,2=270.000000
L 1.62 -0.3798 1.595 -0.3798 2 P 0 ;0,1=87,2=270.000000
L 1.595 -0.3798 1.61291673 -0.38966703 2 P 0 ;0,1=87,2=270.000000
L 1.61291673 -0.38966703 1.61291673 -0.37633307 2 P 0 ;0,1=87,2=270.000000
L 1.61625089 -0.36486673 1.61833376 -0.36326703 2 P 0 ;0,1=87,2=270.000000
L 1.61833376 -0.36326703 1.61958346 -0.3614003 2 P 0 ;0,1=87,2=270.000000
L 1.61958346 -0.3614003 1.62 -0.3590003 2 P 0 ;0,1=87,2=270.000000
L 1.62 -0.3590003 1.61916693 -0.3565998 2 P 0 ;0,1=87,2=270.000000
L 1.61916693 -0.3565998 1.61750059 -0.35473356 2 P 0 ;0,1=87,2=270.000000
L 1.61750059 -0.35473356 1.61458376 -0.3534 2 P 0 ;0,1=87,2=270.000000
L 1.61458376 -0.3534 1.61125039 -0.35313337 2 P 0 ;0,1=87,2=270.000000
L 1.61125039 -0.35313337 1.60791703 -0.35366663 2 P 0 ;0,1=87,2=270.000000
L 1.60791703 -0.35366663 1.60583337 -0.3550002 2 P 0 ;0,1=87,2=270.000000
L 1.60583337 -0.3550002 1.60416703 -0.35686693 2 P 0 ;0,1=87,2=270.000000
L 1.60416703 -0.35686693 1.60375049 -0.35873317 2 P 0 ;0,1=87,2=270.000000
L 1.60375049 -0.35873317 1.60416703 -0.3606 2 P 0 ;0,1=87,2=270.000000
L 1.60416703 -0.3606 1.60583337 -0.3629999 2 P 0 ;0,1=87,2=270.000000
L 1.60583337 -0.3629999 1.595 -0.3622001 2 P 0 ;0,1=87,2=270.000000
L 1.595 -0.3622001 1.595 -0.3550002 2 P 0 ;0,1=87,2=270.000000
L 1.61666742 -0.3406001 1.6187503 -0.33846673 2 P 0 ;0,1=87,2=270.000000
L 1.6187503 -0.33846673 1.62 -0.33606673 2 P 0 ;0,1=87,2=270.000000
L 1.62 -0.33606673 1.62 -0.33393337 2 P 0 ;0,1=87,2=270.000000
L 1.62 -0.33393337 1.6187503 -0.3318 2 P 0 ;0,1=87,2=270.000000
L 1.6187503 -0.3318 1.61666742 -0.3301999 2 P 0 ;0,1=87,2=270.000000
L 1.61666742 -0.3301999 1.6137499 -0.3294 2 P 0 ;0,1=87,2=270.000000
L 1.6137499 -0.3294 1.61083386 -0.32993327 2 P 0 ;0,1=87,2=270.000000
L 1.61083386 -0.32993327 1.60833356 -0.33126673 2 P 0 ;0,1=87,2=270.000000
L 1.60833356 -0.33126673 1.60666654 -0.33366673 2 P 0 ;0,1=87,2=270.000000
L 1.60666654 -0.33366673 1.60583337 -0.33686654 2 P 0 ;0,1=87,2=270.000000
L 1.60583337 -0.33686654 1.60416703 -0.33873337 2 P 0 ;0,1=87,2=270.000000
L 1.60416703 -0.33873337 1.6012502 -0.33953366 2 P 0 ;0,1=87,2=270.000000
L 1.6012502 -0.33953366 1.59833346 -0.3389999 2 P 0 ;0,1=87,2=270.000000
L 1.59833346 -0.3389999 1.59625059 -0.33766683 2 P 0 ;0,1=87,2=270.000000
L 1.59625059 -0.33766683 1.595 -0.3358001 2 P 0 ;0,1=87,2=270.000000
L 1.595 -0.3358001 1.595 -0.33393337 2 P 0 ;0,1=87,2=270.000000
L 1.595 -0.33393337 1.59583317 -0.33206663 2 P 0 ;0,1=87,2=270.000000
L 1.59583317 -0.33206663 1.59791683 -0.33046644 2 P 0 ;0,1=87,2=270.000000
L 1.62833307 -0.319 1.62833307 -0.303 2 P 0 ;0,1=87,2=270.000000
L 1.595 -0.2902001 1.595 -0.28380049 2 P 0 ;0,1=87,2=270.000000
L 1.595 -0.2870003 1.62 -0.2870003 2 P 0 ;0,1=87,2=270.000000
L 1.62 -0.2902001 1.62 -0.28380049 2 P 0 ;0,1=87,2=270.000000
L 1.62 -0.26913327 1.595 -0.26913327 2 P 0 ;0,1=87,2=270.000000
L 1.595 -0.26913327 1.62 -0.25686683 2 P 0 ;0,1=87,2=270.000000
L 1.62 -0.25686683 1.595 -0.25686683 2 P 0 ;0,1=87,2=270.000000
L 1.62833307 -0.247 1.62833307 -0.231 2 P 0 ;0,1=87,2=270.000000
L 1.595 -0.22033346 1.62 -0.22033346 2 P 0 ;0,1=87,2=270.000000
L 1.62 -0.22033346 1.62 -0.20966663 2 P 0 ;0,1=87,2=270.000000
L 1.62 -0.1910003 1.595 -0.1910003 2 P 0 ;0,1=87,2=270.000000
L 1.595 -0.1910003 1.5999997 -0.1942001 2 P 0 ;0,1=87,2=270.000000
L 1.62 -0.1942001 1.62 -0.18780049 2 P 0 ;0,1=87,2=270.000000
L 0.69 6.21 0.69 6.41 3 P 0 
L 0.69 6.41 0.89 6.41 3 P 0 
L 0.89 6.41 0.89 6.21 3 P 0 
L 0.89 6.21 0.69 6.21 3 P 0 
L 0.66293317 6.175 0.67306673 6.175 2 P 0 ;0,1=88,2=0.000000
L 0.67306673 6.175 0.66293317 6.15 2 P 0 ;0,1=88,2=0.000000
L 0.66293317 6.15 0.67306673 6.15 2 P 0 ;0,1=88,2=0.000000
L 0.6919997 6.15 0.69386644 6.15041654 2 P 0 ;0,1=88,2=0.000000
L 0.69386644 6.15041654 0.6959998 6.15166624 2 P 0 ;0,1=88,2=0.000000
L 0.6959998 6.15166624 0.69733337 6.15374911 2 P 0 ;0,1=88,2=0.000000
L 0.69733337 6.15374911 0.69786663 6.15666673 2 P 0 ;0,1=88,2=0.000000
L 0.69786663 6.15666673 0.69733337 6.15958278 2 P 0 ;0,1=88,2=0.000000
L 0.69733337 6.15958278 0.69573327 6.16208297 2 P 0 ;0,1=88,2=0.000000
L 0.69573327 6.16208297 0.69333327 6.16333346 2 P 0 ;0,1=88,2=0.000000
L 0.69333327 6.16333346 0.69066663 6.16333346 2 P 0 ;0,1=88,2=0.000000
L 0.69066663 6.16333346 0.68906654 6.16416663 2 P 0 ;0,1=88,2=0.000000
L 0.68906654 6.16416663 0.68773297 6.16624951 2 P 0 ;0,1=88,2=0.000000
L 0.68773297 6.16624951 0.6871998 6.16916634 2 P 0 ;0,1=88,2=0.000000
L 0.6871998 6.16916634 0.6880001 6.17208317 2 P 0 ;0,1=88,2=0.000000
L 0.6880001 6.17208317 0.68986634 6.17416683 2 P 0 ;0,1=88,2=0.000000
L 0.68986634 6.17416683 0.6919997 6.175 2 P 0 ;0,1=88,2=0.000000
L 0.6919997 6.175 0.69413307 6.17416683 2 P 0 ;0,1=88,2=0.000000
L 0.69413307 6.17416683 0.6959998 6.17208317 2 P 0 ;0,1=88,2=0.000000
L 0.6959998 6.17208317 0.6968001 6.16916634 2 P 0 ;0,1=88,2=0.000000
L 0.6968001 6.16916634 0.69626644 6.16624951 2 P 0 ;0,1=88,2=0.000000
L 0.69626644 6.16624951 0.69493337 6.16416663 2 P 0 ;0,1=88,2=0.000000
L 0.69493337 6.16416663 0.69333327 6.16333346 2 P 0 ;0,1=88,2=0.000000
L 0.69333327 6.16333346 0.69066663 6.16333346 2 P 0 ;0,1=88,2=0.000000
L 0.69066663 6.16333346 0.68826663 6.16208297 2 P 0 ;0,1=88,2=0.000000
L 0.68826663 6.16208297 0.68666654 6.15958278 2 P 0 ;0,1=88,2=0.000000
L 0.68666654 6.15958278 0.68613327 6.15666673 2 P 0 ;0,1=88,2=0.000000
L 0.68613327 6.15666673 0.68666654 6.15374911 2 P 0 ;0,1=88,2=0.000000
L 0.68666654 6.15374911 0.6880001 6.15166624 2 P 0 ;0,1=88,2=0.000000
L 0.6880001 6.15166624 0.69013346 6.15041654 2 P 0 ;0,1=88,2=0.000000
L 0.69013346 6.15041654 0.6919997 6.15 2 P 0 ;0,1=88,2=0.000000
L 0.71013327 6.15374911 0.71173297 6.15166624 2 P 0 ;0,1=88,2=0.000000
L 0.71173297 6.15166624 0.7135997 6.15041654 2 P 0 ;0,1=88,2=0.000000
L 0.7135997 6.15041654 0.7159997 6.15 2 P 0 ;0,1=88,2=0.000000
L 0.7159997 6.15 0.7184002 6.15083307 2 P 0 ;0,1=88,2=0.000000
L 0.7184002 6.15083307 0.72026644 6.15249941 2 P 0 ;0,1=88,2=0.000000
L 0.72026644 6.15249941 0.7216 6.15541624 2 P 0 ;0,1=88,2=0.000000
L 0.7216 6.15541624 0.72186663 6.15874961 2 P 0 ;0,1=88,2=0.000000
L 0.72186663 6.15874961 0.72133337 6.16208297 2 P 0 ;0,1=88,2=0.000000
L 0.72133337 6.16208297 0.7199998 6.16416663 2 P 0 ;0,1=88,2=0.000000
L 0.7199998 6.16416663 0.71813307 6.16583297 2 P 0 ;0,1=88,2=0.000000
L 0.71813307 6.16583297 0.71626683 6.16624951 2 P 0 ;0,1=88,2=0.000000
L 0.71626683 6.16624951 0.7144 6.16583297 2 P 0 ;0,1=88,2=0.000000
L 0.7144 6.16583297 0.7120001 6.16416663 2 P 0 ;0,1=88,2=0.000000
L 0.7120001 6.16416663 0.7127999 6.175 2 P 0 ;0,1=88,2=0.000000
L 0.7127999 6.175 0.7199998 6.175 2 P 0 ;0,1=88,2=0.000000
L 0.73413327 6.15 0.73413327 6.175 2 P 0 ;0,1=88,2=0.000000
L 0.73413327 6.175 0.73946654 6.175 2 P 0 ;0,1=88,2=0.000000
L 0.73946654 6.175 0.7415999 6.17374941 2 P 0 ;0,1=88,2=0.000000
L 0.7415999 6.17374941 0.7432 6.17208317 2 P 0 ;0,1=88,2=0.000000
L 0.7432 6.17208317 0.74453356 6.16958366 2 P 0 ;0,1=88,2=0.000000
L 0.74453356 6.16958366 0.7456 6.16666614 2 P 0 ;0,1=88,2=0.000000
L 0.7456 6.16666614 0.74586663 6.16249961 2 P 0 ;0,1=88,2=0.000000
L 0.74586663 6.16249961 0.7456 6.15833307 2 P 0 ;0,1=88,2=0.000000
L 0.7456 6.15833307 0.74453356 6.15541624 2 P 0 ;0,1=88,2=0.000000
L 0.74453356 6.15541624 0.7432 6.15291604 2 P 0 ;0,1=88,2=0.000000
L 0.7432 6.15291604 0.7415999 6.1512497 2 P 0 ;0,1=88,2=0.000000
L 0.7415999 6.1512497 0.73946654 6.15 2 P 0 ;0,1=88,2=0.000000
L 0.73946654 6.15 0.73413327 6.15 2 P 0 ;0,1=88,2=0.000000
L 0.756 6.14166693 0.772 6.14166693 2 P 0 ;0,1=88,2=0.000000
L 0.7847999 6.175 0.79119951 6.175 2 P 0 ;0,1=88,2=0.000000
L 0.7879997 6.175 0.7879997 6.15 2 P 0 ;0,1=88,2=0.000000
L 0.7847999 6.15 0.79119951 6.15 2 P 0 ;0,1=88,2=0.000000
L 0.80586673 6.15 0.80586673 6.175 2 P 0 ;0,1=88,2=0.000000
L 0.80586673 6.175 0.81813317 6.15 2 P 0 ;0,1=88,2=0.000000
L 0.81813317 6.15 0.81813317 6.175 2 P 0 ;0,1=88,2=0.000000
L 0.828 6.14166693 0.844 6.14166693 2 P 0 ;0,1=88,2=0.000000
L 0.85466654 6.175 0.85466654 6.15 2 P 0 ;0,1=88,2=0.000000
L 0.85466654 6.15 0.86533337 6.15 2 P 0 ;0,1=88,2=0.000000
L 0.8839997 6.15 0.8839997 6.175 2 P 0 ;0,1=88,2=0.000000
L 0.8839997 6.175 0.8807999 6.1700003 2 P 0 ;0,1=88,2=0.000000
L 0.8807999 6.15 0.88719951 6.15 2 P 0 ;0,1=88,2=0.000000
L 0.90293317 6.17083337 0.90453327 6.17333287 2 P 0 ;0,1=88,2=0.000000
L 0.90453327 6.17333287 0.9064 6.17458337 2 P 0 ;0,1=88,2=0.000000
L 0.9064 6.17458337 0.90853337 6.175 2 P 0 ;0,1=88,2=0.000000
L 0.90853337 6.175 0.9112 6.17416683 2 P 0 ;0,1=88,2=0.000000
L 0.9112 6.17416683 0.91306673 6.17208317 2 P 0 ;0,1=88,2=0.000000
L 0.91306673 6.17208317 0.9136 6.16958366 2 P 0 ;0,1=88,2=0.000000
L 0.9136 6.16958366 0.91333337 6.16708268 2 P 0 ;0,1=88,2=0.000000
L 0.91333337 6.16708268 0.91226644 6.1649998 2 P 0 ;0,1=88,2=0.000000
L 0.91226644 6.1649998 0.90693327 6.16083327 2 P 0 ;0,1=88,2=0.000000
L 0.90693327 6.16083327 0.90453327 6.15791644 2 P 0 ;0,1=88,2=0.000000
L 0.90453327 6.15791644 0.90293317 6.15374911 2 P 0 ;0,1=88,2=0.000000
L 0.90293317 6.15374911 0.9023999 6.15 2 P 0 ;0,1=88,2=0.000000
L 0.9023999 6.15 0.9136 6.15 2 P 0 ;0,1=88,2=0.000000
L 0.915 6.21 0.915 6.41 3 P 0 
L 0.915 6.41 1.115 6.41 3 P 0 
L 1.115 6.41 1.115 6.21 3 P 0 
L 1.115 6.21 0.915 6.21 3 P 0 
L 0.88793317 6.5 0.89806673 6.5 2 P 0 ;0,1=89,2=0.000000
L 0.89806673 6.5 0.88793317 6.475 2 P 0 ;0,1=89,2=0.000000
L 0.88793317 6.475 0.89806673 6.475 2 P 0 ;0,1=89,2=0.000000
L 0.9169997 6.475 0.91886644 6.47541654 2 P 0 ;0,1=89,2=0.000000
L 0.91886644 6.47541654 0.9209998 6.47666624 2 P 0 ;0,1=89,2=0.000000
L 0.9209998 6.47666624 0.92233337 6.47874911 2 P 0 ;0,1=89,2=0.000000
L 0.92233337 6.47874911 0.92286663 6.48166673 2 P 0 ;0,1=89,2=0.000000
L 0.92286663 6.48166673 0.92233337 6.48458278 2 P 0 ;0,1=89,2=0.000000
L 0.92233337 6.48458278 0.92073327 6.48708297 2 P 0 ;0,1=89,2=0.000000
L 0.92073327 6.48708297 0.91833327 6.48833346 2 P 0 ;0,1=89,2=0.000000
L 0.91833327 6.48833346 0.91566663 6.48833346 2 P 0 ;0,1=89,2=0.000000
L 0.91566663 6.48833346 0.91406654 6.48916663 2 P 0 ;0,1=89,2=0.000000
L 0.91406654 6.48916663 0.91273297 6.49124951 2 P 0 ;0,1=89,2=0.000000
L 0.91273297 6.49124951 0.9121998 6.49416634 2 P 0 ;0,1=89,2=0.000000
L 0.9121998 6.49416634 0.9130001 6.49708317 2 P 0 ;0,1=89,2=0.000000
L 0.9130001 6.49708317 0.91486634 6.49916683 2 P 0 ;0,1=89,2=0.000000
L 0.91486634 6.49916683 0.9169997 6.5 2 P 0 ;0,1=89,2=0.000000
L 0.9169997 6.5 0.91913307 6.49916683 2 P 0 ;0,1=89,2=0.000000
L 0.91913307 6.49916683 0.9209998 6.49708317 2 P 0 ;0,1=89,2=0.000000
L 0.9209998 6.49708317 0.9218001 6.49416634 2 P 0 ;0,1=89,2=0.000000
L 0.9218001 6.49416634 0.92126644 6.49124951 2 P 0 ;0,1=89,2=0.000000
L 0.92126644 6.49124951 0.91993337 6.48916663 2 P 0 ;0,1=89,2=0.000000
L 0.91993337 6.48916663 0.91833327 6.48833346 2 P 0 ;0,1=89,2=0.000000
L 0.91833327 6.48833346 0.91566663 6.48833346 2 P 0 ;0,1=89,2=0.000000
L 0.91566663 6.48833346 0.91326663 6.48708297 2 P 0 ;0,1=89,2=0.000000
L 0.91326663 6.48708297 0.91166654 6.48458278 2 P 0 ;0,1=89,2=0.000000
L 0.91166654 6.48458278 0.91113327 6.48166673 2 P 0 ;0,1=89,2=0.000000
L 0.91113327 6.48166673 0.91166654 6.47874911 2 P 0 ;0,1=89,2=0.000000
L 0.91166654 6.47874911 0.9130001 6.47666624 2 P 0 ;0,1=89,2=0.000000
L 0.9130001 6.47666624 0.91513346 6.47541654 2 P 0 ;0,1=89,2=0.000000
L 0.91513346 6.47541654 0.9169997 6.475 2 P 0 ;0,1=89,2=0.000000
L 0.93513327 6.47874911 0.93673297 6.47666624 2 P 0 ;0,1=89,2=0.000000
L 0.93673297 6.47666624 0.9385997 6.47541654 2 P 0 ;0,1=89,2=0.000000
L 0.9385997 6.47541654 0.9409997 6.475 2 P 0 ;0,1=89,2=0.000000
L 0.9409997 6.475 0.9434002 6.47583307 2 P 0 ;0,1=89,2=0.000000
L 0.9434002 6.47583307 0.94526644 6.47749941 2 P 0 ;0,1=89,2=0.000000
L 0.94526644 6.47749941 0.9466 6.48041624 2 P 0 ;0,1=89,2=0.000000
L 0.9466 6.48041624 0.94686663 6.48374961 2 P 0 ;0,1=89,2=0.000000
L 0.94686663 6.48374961 0.94633337 6.48708297 2 P 0 ;0,1=89,2=0.000000
L 0.94633337 6.48708297 0.9449998 6.48916663 2 P 0 ;0,1=89,2=0.000000
L 0.9449998 6.48916663 0.94313307 6.49083297 2 P 0 ;0,1=89,2=0.000000
L 0.94313307 6.49083297 0.94126683 6.49124951 2 P 0 ;0,1=89,2=0.000000
L 0.94126683 6.49124951 0.9394 6.49083297 2 P 0 ;0,1=89,2=0.000000
L 0.9394 6.49083297 0.9370001 6.48916663 2 P 0 ;0,1=89,2=0.000000
L 0.9370001 6.48916663 0.9377999 6.5 2 P 0 ;0,1=89,2=0.000000
L 0.9377999 6.5 0.9449998 6.5 2 P 0 ;0,1=89,2=0.000000
L 0.95913327 6.475 0.95913327 6.5 2 P 0 ;0,1=89,2=0.000000
L 0.95913327 6.5 0.96446654 6.5 2 P 0 ;0,1=89,2=0.000000
L 0.96446654 6.5 0.9665999 6.49874941 2 P 0 ;0,1=89,2=0.000000
L 0.9665999 6.49874941 0.9682 6.49708317 2 P 0 ;0,1=89,2=0.000000
L 0.9682 6.49708317 0.96953356 6.49458366 2 P 0 ;0,1=89,2=0.000000
L 0.96953356 6.49458366 0.9706 6.49166614 2 P 0 ;0,1=89,2=0.000000
L 0.9706 6.49166614 0.97086663 6.48749961 2 P 0 ;0,1=89,2=0.000000
L 0.97086663 6.48749961 0.9706 6.48333307 2 P 0 ;0,1=89,2=0.000000
L 0.9706 6.48333307 0.96953356 6.48041624 2 P 0 ;0,1=89,2=0.000000
L 0.96953356 6.48041624 0.9682 6.47791604 2 P 0 ;0,1=89,2=0.000000
L 0.9682 6.47791604 0.9665999 6.4762497 2 P 0 ;0,1=89,2=0.000000
L 0.9665999 6.4762497 0.96446654 6.475 2 P 0 ;0,1=89,2=0.000000
L 0.96446654 6.475 0.95913327 6.475 2 P 0 ;0,1=89,2=0.000000
L 0.981 6.46666693 0.997 6.46666693 2 P 0 ;0,1=89,2=0.000000
L 1.0097999 6.5 1.01619951 6.5 2 P 0 ;0,1=89,2=0.000000
L 1.0129997 6.5 1.0129997 6.475 2 P 0 ;0,1=89,2=0.000000
L 1.0097999 6.475 1.01619951 6.475 2 P 0 ;0,1=89,2=0.000000
L 1.03086673 6.475 1.03086673 6.5 2 P 0 ;0,1=89,2=0.000000
L 1.03086673 6.5 1.04313317 6.475 2 P 0 ;0,1=89,2=0.000000
L 1.04313317 6.475 1.04313317 6.5 2 P 0 ;0,1=89,2=0.000000
L 1.053 6.46666693 1.069 6.46666693 2 P 0 ;0,1=89,2=0.000000
L 1.07966654 6.5 1.07966654 6.475 2 P 0 ;0,1=89,2=0.000000
L 1.07966654 6.475 1.09033337 6.475 2 P 0 ;0,1=89,2=0.000000
L 1.1089997 6.475 1.1089997 6.5 2 P 0 ;0,1=89,2=0.000000
L 1.1089997 6.5 1.1057999 6.4950003 2 P 0 ;0,1=89,2=0.000000
L 1.1057999 6.475 1.11219951 6.475 2 P 0 ;0,1=89,2=0.000000
L 1.1329997 6.5 1.13086634 6.49916683 2 P 0 ;0,1=89,2=0.000000
L 1.13086634 6.49916683 1.12926663 6.49708317 2 P 0 ;0,1=89,2=0.000000
L 1.12926663 6.49708317 1.1281998 6.49458366 2 P 0 ;0,1=89,2=0.000000
L 1.1281998 6.49458366 1.1273999 6.49124951 2 P 0 ;0,1=89,2=0.000000
L 1.1273999 6.49124951 1.12713327 6.48749961 2 P 0 ;0,1=89,2=0.000000
L 1.12713327 6.48749961 1.1273999 6.48374961 2 P 0 ;0,1=89,2=0.000000
L 1.1273999 6.48374961 1.1281998 6.48041624 2 P 0 ;0,1=89,2=0.000000
L 1.1281998 6.48041624 1.12926663 6.47791604 2 P 0 ;0,1=89,2=0.000000
L 1.12926663 6.47791604 1.13086634 6.47583307 2 P 0 ;0,1=89,2=0.000000
L 1.13086634 6.47583307 1.1329997 6.475 2 P 0 ;0,1=89,2=0.000000
L 1.1329997 6.475 1.13513307 6.47583307 2 P 0 ;0,1=89,2=0.000000
L 1.13513307 6.47583307 1.13673327 6.47791604 2 P 0 ;0,1=89,2=0.000000
L 1.13673327 6.47791604 1.1378001 6.48041624 2 P 0 ;0,1=89,2=0.000000
L 1.1378001 6.48041624 1.1386 6.48374961 2 P 0 ;0,1=89,2=0.000000
L 1.1386 6.48374961 1.13886663 6.48749961 2 P 0 ;0,1=89,2=0.000000
L 1.13886663 6.48749961 1.1386 6.49124951 2 P 0 ;0,1=89,2=0.000000
L 1.1386 6.49124951 1.1378001 6.49458366 2 P 0 ;0,1=89,2=0.000000
L 1.1378001 6.49458366 1.13673327 6.49708317 2 P 0 ;0,1=89,2=0.000000
L 1.13673327 6.49708317 1.13513307 6.49916683 2 P 0 ;0,1=89,2=0.000000
L 1.13513307 6.49916683 1.1329997 6.5 2 P 0 ;0,1=89,2=0.000000
L 1.59 6.21 1.59 6.41 3 P 0 
L 1.59 6.41 1.79 6.41 3 P 0 
L 1.79 6.41 1.79 6.21 3 P 0 
L 1.79 6.21 1.59 6.21 3 P 0 
L 1.57293317 6.175 1.58306673 6.175 2 P 0 ;0,1=90,2=0.000000
L 1.58306673 6.175 1.57293317 6.15 2 P 0 ;0,1=90,2=0.000000
L 1.57293317 6.15 1.58306673 6.15 2 P 0 ;0,1=90,2=0.000000
L 1.6019997 6.15 1.60386644 6.15041654 2 P 0 ;0,1=90,2=0.000000
L 1.60386644 6.15041654 1.6059998 6.15166624 2 P 0 ;0,1=90,2=0.000000
L 1.6059998 6.15166624 1.60733337 6.15374911 2 P 0 ;0,1=90,2=0.000000
L 1.60733337 6.15374911 1.60786663 6.15666673 2 P 0 ;0,1=90,2=0.000000
L 1.60786663 6.15666673 1.60733337 6.15958278 2 P 0 ;0,1=90,2=0.000000
L 1.60733337 6.15958278 1.60573327 6.16208297 2 P 0 ;0,1=90,2=0.000000
L 1.60573327 6.16208297 1.60333327 6.16333346 2 P 0 ;0,1=90,2=0.000000
L 1.60333327 6.16333346 1.60066663 6.16333346 2 P 0 ;0,1=90,2=0.000000
L 1.60066663 6.16333346 1.59906654 6.16416663 2 P 0 ;0,1=90,2=0.000000
L 1.59906654 6.16416663 1.59773297 6.16624951 2 P 0 ;0,1=90,2=0.000000
L 1.59773297 6.16624951 1.5971998 6.16916634 2 P 0 ;0,1=90,2=0.000000
L 1.5971998 6.16916634 1.5980001 6.17208317 2 P 0 ;0,1=90,2=0.000000
L 1.5980001 6.17208317 1.59986634 6.17416683 2 P 0 ;0,1=90,2=0.000000
L 1.59986634 6.17416683 1.6019997 6.175 2 P 0 ;0,1=90,2=0.000000
L 1.6019997 6.175 1.60413307 6.17416683 2 P 0 ;0,1=90,2=0.000000
L 1.60413307 6.17416683 1.6059998 6.17208317 2 P 0 ;0,1=90,2=0.000000
L 1.6059998 6.17208317 1.6068001 6.16916634 2 P 0 ;0,1=90,2=0.000000
L 1.6068001 6.16916634 1.60626644 6.16624951 2 P 0 ;0,1=90,2=0.000000
L 1.60626644 6.16624951 1.60493337 6.16416663 2 P 0 ;0,1=90,2=0.000000
L 1.60493337 6.16416663 1.60333327 6.16333346 2 P 0 ;0,1=90,2=0.000000
L 1.60333327 6.16333346 1.60066663 6.16333346 2 P 0 ;0,1=90,2=0.000000
L 1.60066663 6.16333346 1.59826663 6.16208297 2 P 0 ;0,1=90,2=0.000000
L 1.59826663 6.16208297 1.59666654 6.15958278 2 P 0 ;0,1=90,2=0.000000
L 1.59666654 6.15958278 1.59613327 6.15666673 2 P 0 ;0,1=90,2=0.000000
L 1.59613327 6.15666673 1.59666654 6.15374911 2 P 0 ;0,1=90,2=0.000000
L 1.59666654 6.15374911 1.5980001 6.15166624 2 P 0 ;0,1=90,2=0.000000
L 1.5980001 6.15166624 1.60013346 6.15041654 2 P 0 ;0,1=90,2=0.000000
L 1.60013346 6.15041654 1.6019997 6.15 2 P 0 ;0,1=90,2=0.000000
L 1.62013327 6.15374911 1.62173297 6.15166624 2 P 0 ;0,1=90,2=0.000000
L 1.62173297 6.15166624 1.6235997 6.15041654 2 P 0 ;0,1=90,2=0.000000
L 1.6235997 6.15041654 1.6259997 6.15 2 P 0 ;0,1=90,2=0.000000
L 1.6259997 6.15 1.6284002 6.15083307 2 P 0 ;0,1=90,2=0.000000
L 1.6284002 6.15083307 1.63026644 6.15249941 2 P 0 ;0,1=90,2=0.000000
L 1.63026644 6.15249941 1.6316 6.15541624 2 P 0 ;0,1=90,2=0.000000
L 1.6316 6.15541624 1.63186663 6.15874961 2 P 0 ;0,1=90,2=0.000000
L 1.63186663 6.15874961 1.63133337 6.16208297 2 P 0 ;0,1=90,2=0.000000
L 1.63133337 6.16208297 1.6299998 6.16416663 2 P 0 ;0,1=90,2=0.000000
L 1.6299998 6.16416663 1.62813307 6.16583297 2 P 0 ;0,1=90,2=0.000000
L 1.62813307 6.16583297 1.62626683 6.16624951 2 P 0 ;0,1=90,2=0.000000
L 1.62626683 6.16624951 1.6244 6.16583297 2 P 0 ;0,1=90,2=0.000000
L 1.6244 6.16583297 1.6220001 6.16416663 2 P 0 ;0,1=90,2=0.000000
L 1.6220001 6.16416663 1.6227999 6.175 2 P 0 ;0,1=90,2=0.000000
L 1.6227999 6.175 1.6299998 6.175 2 P 0 ;0,1=90,2=0.000000
L 1.64413327 6.15 1.64413327 6.175 2 P 0 ;0,1=90,2=0.000000
L 1.64413327 6.175 1.64946654 6.175 2 P 0 ;0,1=90,2=0.000000
L 1.64946654 6.175 1.6515999 6.17374941 2 P 0 ;0,1=90,2=0.000000
L 1.6515999 6.17374941 1.6532 6.17208317 2 P 0 ;0,1=90,2=0.000000
L 1.6532 6.17208317 1.65453356 6.16958366 2 P 0 ;0,1=90,2=0.000000
L 1.65453356 6.16958366 1.6556 6.16666614 2 P 0 ;0,1=90,2=0.000000
L 1.6556 6.16666614 1.65586663 6.16249961 2 P 0 ;0,1=90,2=0.000000
L 1.65586663 6.16249961 1.6556 6.15833307 2 P 0 ;0,1=90,2=0.000000
L 1.6556 6.15833307 1.65453356 6.15541624 2 P 0 ;0,1=90,2=0.000000
L 1.65453356 6.15541624 1.6532 6.15291604 2 P 0 ;0,1=90,2=0.000000
L 1.6532 6.15291604 1.6515999 6.1512497 2 P 0 ;0,1=90,2=0.000000
L 1.6515999 6.1512497 1.64946654 6.15 2 P 0 ;0,1=90,2=0.000000
L 1.64946654 6.15 1.64413327 6.15 2 P 0 ;0,1=90,2=0.000000
L 1.666 6.14166693 1.682 6.14166693 2 P 0 ;0,1=90,2=0.000000
L 1.6947999 6.175 1.70119951 6.175 2 P 0 ;0,1=90,2=0.000000
L 1.6979997 6.175 1.6979997 6.15 2 P 0 ;0,1=90,2=0.000000
L 1.6947999 6.15 1.70119951 6.15 2 P 0 ;0,1=90,2=0.000000
L 1.71586673 6.15 1.71586673 6.175 2 P 0 ;0,1=90,2=0.000000
L 1.71586673 6.175 1.72813317 6.15 2 P 0 ;0,1=90,2=0.000000
L 1.72813317 6.15 1.72813317 6.175 2 P 0 ;0,1=90,2=0.000000
L 1.738 6.14166693 1.754 6.14166693 2 P 0 ;0,1=90,2=0.000000
L 1.76466654 6.175 1.76466654 6.15 2 P 0 ;0,1=90,2=0.000000
L 1.76466654 6.15 1.77533337 6.15 2 P 0 ;0,1=90,2=0.000000
L 1.7939997 6.15 1.7939997 6.175 2 P 0 ;0,1=90,2=0.000000
L 1.7939997 6.175 1.7907999 6.1700003 2 P 0 ;0,1=90,2=0.000000
L 1.7907999 6.15 1.79719951 6.15 2 P 0 ;0,1=90,2=0.000000
L 1.365 6.21 1.365 6.41 3 P 0 
L 1.365 6.41 1.565 6.41 3 P 0 
L 1.565 6.41 1.565 6.21 3 P 0 
L 1.565 6.21 1.365 6.21 3 P 0 
L 1.35293317 6.5 1.36306673 6.5 2 P 0 ;0,1=91,2=0.000000
L 1.36306673 6.5 1.35293317 6.475 2 P 0 ;0,1=91,2=0.000000
L 1.35293317 6.475 1.36306673 6.475 2 P 0 ;0,1=91,2=0.000000
L 1.3819997 6.475 1.38386644 6.47541654 2 P 0 ;0,1=91,2=0.000000
L 1.38386644 6.47541654 1.3859998 6.47666624 2 P 0 ;0,1=91,2=0.000000
L 1.3859998 6.47666624 1.38733337 6.47874911 2 P 0 ;0,1=91,2=0.000000
L 1.38733337 6.47874911 1.38786663 6.48166673 2 P 0 ;0,1=91,2=0.000000
L 1.38786663 6.48166673 1.38733337 6.48458278 2 P 0 ;0,1=91,2=0.000000
L 1.38733337 6.48458278 1.38573327 6.48708297 2 P 0 ;0,1=91,2=0.000000
L 1.38573327 6.48708297 1.38333327 6.48833346 2 P 0 ;0,1=91,2=0.000000
L 1.38333327 6.48833346 1.38066663 6.48833346 2 P 0 ;0,1=91,2=0.000000
L 1.38066663 6.48833346 1.37906654 6.48916663 2 P 0 ;0,1=91,2=0.000000
L 1.37906654 6.48916663 1.37773297 6.49124951 2 P 0 ;0,1=91,2=0.000000
L 1.37773297 6.49124951 1.3771998 6.49416634 2 P 0 ;0,1=91,2=0.000000
L 1.3771998 6.49416634 1.3780001 6.49708317 2 P 0 ;0,1=91,2=0.000000
L 1.3780001 6.49708317 1.37986634 6.49916683 2 P 0 ;0,1=91,2=0.000000
L 1.37986634 6.49916683 1.3819997 6.5 2 P 0 ;0,1=91,2=0.000000
L 1.3819997 6.5 1.38413307 6.49916683 2 P 0 ;0,1=91,2=0.000000
L 1.38413307 6.49916683 1.3859998 6.49708317 2 P 0 ;0,1=91,2=0.000000
L 1.3859998 6.49708317 1.3868001 6.49416634 2 P 0 ;0,1=91,2=0.000000
L 1.3868001 6.49416634 1.38626644 6.49124951 2 P 0 ;0,1=91,2=0.000000
L 1.38626644 6.49124951 1.38493337 6.48916663 2 P 0 ;0,1=91,2=0.000000
L 1.38493337 6.48916663 1.38333327 6.48833346 2 P 0 ;0,1=91,2=0.000000
L 1.38333327 6.48833346 1.38066663 6.48833346 2 P 0 ;0,1=91,2=0.000000
L 1.38066663 6.48833346 1.37826663 6.48708297 2 P 0 ;0,1=91,2=0.000000
L 1.37826663 6.48708297 1.37666654 6.48458278 2 P 0 ;0,1=91,2=0.000000
L 1.37666654 6.48458278 1.37613327 6.48166673 2 P 0 ;0,1=91,2=0.000000
L 1.37613327 6.48166673 1.37666654 6.47874911 2 P 0 ;0,1=91,2=0.000000
L 1.37666654 6.47874911 1.3780001 6.47666624 2 P 0 ;0,1=91,2=0.000000
L 1.3780001 6.47666624 1.38013346 6.47541654 2 P 0 ;0,1=91,2=0.000000
L 1.38013346 6.47541654 1.3819997 6.475 2 P 0 ;0,1=91,2=0.000000
L 1.40013327 6.47874911 1.40173297 6.47666624 2 P 0 ;0,1=91,2=0.000000
L 1.40173297 6.47666624 1.4035997 6.47541654 2 P 0 ;0,1=91,2=0.000000
L 1.4035997 6.47541654 1.4059997 6.475 2 P 0 ;0,1=91,2=0.000000
L 1.4059997 6.475 1.4084002 6.47583307 2 P 0 ;0,1=91,2=0.000000
L 1.4084002 6.47583307 1.41026644 6.47749941 2 P 0 ;0,1=91,2=0.000000
L 1.41026644 6.47749941 1.4116 6.48041624 2 P 0 ;0,1=91,2=0.000000
L 1.4116 6.48041624 1.41186663 6.48374961 2 P 0 ;0,1=91,2=0.000000
L 1.41186663 6.48374961 1.41133337 6.48708297 2 P 0 ;0,1=91,2=0.000000
L 1.41133337 6.48708297 1.4099998 6.48916663 2 P 0 ;0,1=91,2=0.000000
L 1.4099998 6.48916663 1.40813307 6.49083297 2 P 0 ;0,1=91,2=0.000000
L 1.40813307 6.49083297 1.40626683 6.49124951 2 P 0 ;0,1=91,2=0.000000
L 1.40626683 6.49124951 1.4044 6.49083297 2 P 0 ;0,1=91,2=0.000000
L 1.4044 6.49083297 1.4020001 6.48916663 2 P 0 ;0,1=91,2=0.000000
L 1.4020001 6.48916663 1.4027999 6.5 2 P 0 ;0,1=91,2=0.000000
L 1.4027999 6.5 1.4099998 6.5 2 P 0 ;0,1=91,2=0.000000
L 1.42413327 6.475 1.42413327 6.5 2 P 0 ;0,1=91,2=0.000000
L 1.42413327 6.5 1.42946654 6.5 2 P 0 ;0,1=91,2=0.000000
L 1.42946654 6.5 1.4315999 6.49874941 2 P 0 ;0,1=91,2=0.000000
L 1.4315999 6.49874941 1.4332 6.49708317 2 P 0 ;0,1=91,2=0.000000
L 1.4332 6.49708317 1.43453356 6.49458366 2 P 0 ;0,1=91,2=0.000000
L 1.43453356 6.49458366 1.4356 6.49166614 2 P 0 ;0,1=91,2=0.000000
L 1.4356 6.49166614 1.43586663 6.48749961 2 P 0 ;0,1=91,2=0.000000
L 1.43586663 6.48749961 1.4356 6.48333307 2 P 0 ;0,1=91,2=0.000000
L 1.4356 6.48333307 1.43453356 6.48041624 2 P 0 ;0,1=91,2=0.000000
L 1.43453356 6.48041624 1.4332 6.47791604 2 P 0 ;0,1=91,2=0.000000
L 1.4332 6.47791604 1.4315999 6.4762497 2 P 0 ;0,1=91,2=0.000000
L 1.4315999 6.4762497 1.42946654 6.475 2 P 0 ;0,1=91,2=0.000000
L 1.42946654 6.475 1.42413327 6.475 2 P 0 ;0,1=91,2=0.000000
L 1.446 6.46666693 1.462 6.46666693 2 P 0 ;0,1=91,2=0.000000
L 1.4747999 6.5 1.48119951 6.5 2 P 0 ;0,1=91,2=0.000000
L 1.4779997 6.5 1.4779997 6.475 2 P 0 ;0,1=91,2=0.000000
L 1.4747999 6.475 1.48119951 6.475 2 P 0 ;0,1=91,2=0.000000
L 1.49586673 6.475 1.49586673 6.5 2 P 0 ;0,1=91,2=0.000000
L 1.49586673 6.5 1.50813317 6.475 2 P 0 ;0,1=91,2=0.000000
L 1.50813317 6.475 1.50813317 6.5 2 P 0 ;0,1=91,2=0.000000
L 1.518 6.46666693 1.534 6.46666693 2 P 0 ;0,1=91,2=0.000000
L 1.54466654 6.5 1.54466654 6.475 2 P 0 ;0,1=91,2=0.000000
L 1.54466654 6.475 1.55533337 6.475 2 P 0 ;0,1=91,2=0.000000
L 1.56813327 6.47999961 1.56973297 6.47708287 2 P 0 ;0,1=91,2=0.000000
L 1.56973297 6.47708287 1.57186634 6.47541654 2 P 0 ;0,1=91,2=0.000000
L 1.57186634 6.47541654 1.57426683 6.475 2 P 0 ;0,1=91,2=0.000000
L 1.57426683 6.475 1.5764002 6.47541654 2 P 0 ;0,1=91,2=0.000000
L 1.5764002 6.47541654 1.57853356 6.47749941 2 P 0 ;0,1=91,2=0.000000
L 1.57853356 6.47749941 1.57986663 6.47999961 2 P 0 ;0,1=91,2=0.000000
L 1.57986663 6.47999961 1.58013317 6.4824999 2 P 0 ;0,1=91,2=0.000000
L 1.58013317 6.4824999 1.5796 6.48541594 2 P 0 ;0,1=91,2=0.000000
L 1.5796 6.48541594 1.57773327 6.48749961 2 P 0 ;0,1=91,2=0.000000
L 1.57773327 6.48749961 1.57586644 6.48833346 2 P 0 ;0,1=91,2=0.000000
L 1.57586644 6.48833346 1.57346654 6.48833346 2 P 0 ;0,1=91,2=0.000000
L 1.57586644 6.48833346 1.57746663 6.48958327 2 P 0 ;0,1=91,2=0.000000
L 1.57746663 6.48958327 1.5788001 6.49166614 2 P 0 ;0,1=91,2=0.000000
L 1.5788001 6.49166614 1.57933337 6.49416634 2 P 0 ;0,1=91,2=0.000000
L 1.57933337 6.49416634 1.5788001 6.49666654 2 P 0 ;0,1=91,2=0.000000
L 1.5788001 6.49666654 1.57746663 6.49874941 2 P 0 ;0,1=91,2=0.000000
L 1.57746663 6.49874941 1.57506663 6.5 2 P 0 ;0,1=91,2=0.000000
L 1.57506663 6.5 1.57266663 6.49958337 2 P 0 ;0,1=91,2=0.000000
L 1.57266663 6.49958337 1.57026663 6.49791634 2 P 0 ;0,1=91,2=0.000000
L 1.14 6.21 1.14 6.41 3 P 0 
L 1.14 6.41 1.34 6.41 3 P 0 
L 1.34 6.41 1.34 6.21 3 P 0 
L 1.34 6.21 1.14 6.21 3 P 0 
L 1.11793317 6.175 1.12806673 6.175 2 P 0 ;0,1=92,2=0.000000
L 1.12806673 6.175 1.11793317 6.15 2 P 0 ;0,1=92,2=0.000000
L 1.11793317 6.15 1.12806673 6.15 2 P 0 ;0,1=92,2=0.000000
L 1.1469997 6.15 1.14886644 6.15041654 2 P 0 ;0,1=92,2=0.000000
L 1.14886644 6.15041654 1.1509998 6.15166624 2 P 0 ;0,1=92,2=0.000000
L 1.1509998 6.15166624 1.15233337 6.15374911 2 P 0 ;0,1=92,2=0.000000
L 1.15233337 6.15374911 1.15286663 6.15666673 2 P 0 ;0,1=92,2=0.000000
L 1.15286663 6.15666673 1.15233337 6.15958278 2 P 0 ;0,1=92,2=0.000000
L 1.15233337 6.15958278 1.15073327 6.16208297 2 P 0 ;0,1=92,2=0.000000
L 1.15073327 6.16208297 1.14833327 6.16333346 2 P 0 ;0,1=92,2=0.000000
L 1.14833327 6.16333346 1.14566663 6.16333346 2 P 0 ;0,1=92,2=0.000000
L 1.14566663 6.16333346 1.14406654 6.16416663 2 P 0 ;0,1=92,2=0.000000
L 1.14406654 6.16416663 1.14273297 6.16624951 2 P 0 ;0,1=92,2=0.000000
L 1.14273297 6.16624951 1.1421998 6.16916634 2 P 0 ;0,1=92,2=0.000000
L 1.1421998 6.16916634 1.1430001 6.17208317 2 P 0 ;0,1=92,2=0.000000
L 1.1430001 6.17208317 1.14486634 6.17416683 2 P 0 ;0,1=92,2=0.000000
L 1.14486634 6.17416683 1.1469997 6.175 2 P 0 ;0,1=92,2=0.000000
L 1.1469997 6.175 1.14913307 6.17416683 2 P 0 ;0,1=92,2=0.000000
L 1.14913307 6.17416683 1.1509998 6.17208317 2 P 0 ;0,1=92,2=0.000000
L 1.1509998 6.17208317 1.1518001 6.16916634 2 P 0 ;0,1=92,2=0.000000
L 1.1518001 6.16916634 1.15126644 6.16624951 2 P 0 ;0,1=92,2=0.000000
L 1.15126644 6.16624951 1.14993337 6.16416663 2 P 0 ;0,1=92,2=0.000000
L 1.14993337 6.16416663 1.14833327 6.16333346 2 P 0 ;0,1=92,2=0.000000
L 1.14833327 6.16333346 1.14566663 6.16333346 2 P 0 ;0,1=92,2=0.000000
L 1.14566663 6.16333346 1.14326663 6.16208297 2 P 0 ;0,1=92,2=0.000000
L 1.14326663 6.16208297 1.14166654 6.15958278 2 P 0 ;0,1=92,2=0.000000
L 1.14166654 6.15958278 1.14113327 6.15666673 2 P 0 ;0,1=92,2=0.000000
L 1.14113327 6.15666673 1.14166654 6.15374911 2 P 0 ;0,1=92,2=0.000000
L 1.14166654 6.15374911 1.1430001 6.15166624 2 P 0 ;0,1=92,2=0.000000
L 1.1430001 6.15166624 1.14513346 6.15041654 2 P 0 ;0,1=92,2=0.000000
L 1.14513346 6.15041654 1.1469997 6.15 2 P 0 ;0,1=92,2=0.000000
L 1.16513327 6.15374911 1.16673297 6.15166624 2 P 0 ;0,1=92,2=0.000000
L 1.16673297 6.15166624 1.1685997 6.15041654 2 P 0 ;0,1=92,2=0.000000
L 1.1685997 6.15041654 1.1709997 6.15 2 P 0 ;0,1=92,2=0.000000
L 1.1709997 6.15 1.1734002 6.15083307 2 P 0 ;0,1=92,2=0.000000
L 1.1734002 6.15083307 1.17526644 6.15249941 2 P 0 ;0,1=92,2=0.000000
L 1.17526644 6.15249941 1.1766 6.15541624 2 P 0 ;0,1=92,2=0.000000
L 1.1766 6.15541624 1.17686663 6.15874961 2 P 0 ;0,1=92,2=0.000000
L 1.17686663 6.15874961 1.17633337 6.16208297 2 P 0 ;0,1=92,2=0.000000
L 1.17633337 6.16208297 1.1749998 6.16416663 2 P 0 ;0,1=92,2=0.000000
L 1.1749998 6.16416663 1.17313307 6.16583297 2 P 0 ;0,1=92,2=0.000000
L 1.17313307 6.16583297 1.17126683 6.16624951 2 P 0 ;0,1=92,2=0.000000
L 1.17126683 6.16624951 1.1694 6.16583297 2 P 0 ;0,1=92,2=0.000000
L 1.1694 6.16583297 1.1670001 6.16416663 2 P 0 ;0,1=92,2=0.000000
L 1.1670001 6.16416663 1.1677999 6.175 2 P 0 ;0,1=92,2=0.000000
L 1.1677999 6.175 1.1749998 6.175 2 P 0 ;0,1=92,2=0.000000
L 1.18913327 6.15 1.18913327 6.175 2 P 0 ;0,1=92,2=0.000000
L 1.18913327 6.175 1.19446654 6.175 2 P 0 ;0,1=92,2=0.000000
L 1.19446654 6.175 1.1965999 6.17374941 2 P 0 ;0,1=92,2=0.000000
L 1.1965999 6.17374941 1.1982 6.17208317 2 P 0 ;0,1=92,2=0.000000
L 1.1982 6.17208317 1.19953356 6.16958366 2 P 0 ;0,1=92,2=0.000000
L 1.19953356 6.16958366 1.2006 6.16666614 2 P 0 ;0,1=92,2=0.000000
L 1.2006 6.16666614 1.20086663 6.16249961 2 P 0 ;0,1=92,2=0.000000
L 1.20086663 6.16249961 1.2006 6.15833307 2 P 0 ;0,1=92,2=0.000000
L 1.2006 6.15833307 1.19953356 6.15541624 2 P 0 ;0,1=92,2=0.000000
L 1.19953356 6.15541624 1.1982 6.15291604 2 P 0 ;0,1=92,2=0.000000
L 1.1982 6.15291604 1.1965999 6.1512497 2 P 0 ;0,1=92,2=0.000000
L 1.1965999 6.1512497 1.19446654 6.15 2 P 0 ;0,1=92,2=0.000000
L 1.19446654 6.15 1.18913327 6.15 2 P 0 ;0,1=92,2=0.000000
L 1.211 6.14166693 1.227 6.14166693 2 P 0 ;0,1=92,2=0.000000
L 1.2397999 6.175 1.24619951 6.175 2 P 0 ;0,1=92,2=0.000000
L 1.2429997 6.175 1.2429997 6.15 2 P 0 ;0,1=92,2=0.000000
L 1.2397999 6.15 1.24619951 6.15 2 P 0 ;0,1=92,2=0.000000
L 1.26086673 6.15 1.26086673 6.175 2 P 0 ;0,1=92,2=0.000000
L 1.26086673 6.175 1.27313317 6.15 2 P 0 ;0,1=92,2=0.000000
L 1.27313317 6.15 1.27313317 6.175 2 P 0 ;0,1=92,2=0.000000
L 1.283 6.14166693 1.299 6.14166693 2 P 0 ;0,1=92,2=0.000000
L 1.30966654 6.175 1.30966654 6.15 2 P 0 ;0,1=92,2=0.000000
L 1.30966654 6.15 1.32033337 6.15 2 P 0 ;0,1=92,2=0.000000
L 1.33313327 6.15374911 1.33473297 6.15166624 2 P 0 ;0,1=92,2=0.000000
L 1.33473297 6.15166624 1.3365997 6.15041654 2 P 0 ;0,1=92,2=0.000000
L 1.3365997 6.15041654 1.3389997 6.15 2 P 0 ;0,1=92,2=0.000000
L 1.3389997 6.15 1.3414002 6.15083307 2 P 0 ;0,1=92,2=0.000000
L 1.3414002 6.15083307 1.34326644 6.15249941 2 P 0 ;0,1=92,2=0.000000
L 1.34326644 6.15249941 1.3446 6.15541624 2 P 0 ;0,1=92,2=0.000000
L 1.3446 6.15541624 1.34486663 6.15874961 2 P 0 ;0,1=92,2=0.000000
L 1.34486663 6.15874961 1.34433337 6.16208297 2 P 0 ;0,1=92,2=0.000000
L 1.34433337 6.16208297 1.3429998 6.16416663 2 P 0 ;0,1=92,2=0.000000
L 1.3429998 6.16416663 1.34113307 6.16583297 2 P 0 ;0,1=92,2=0.000000
L 1.34113307 6.16583297 1.33926683 6.16624951 2 P 0 ;0,1=92,2=0.000000
L 1.33926683 6.16624951 1.3374 6.16583297 2 P 0 ;0,1=92,2=0.000000
L 1.3374 6.16583297 1.3350001 6.16416663 2 P 0 ;0,1=92,2=0.000000
L 1.3350001 6.16416663 1.3357999 6.175 2 P 0 ;0,1=92,2=0.000000
L 1.3357999 6.175 1.3429998 6.175 2 P 0 ;0,1=92,2=0.000000
L 0.0349 -2.3038 0.0349 -1.0038 8 P 0 
L 0.0349 -1.0038 4.5349 -1.0038 8 P 0 
L 4.5349 -1.0038 4.5349 -2.3038 8 P 0 
L 4.5349 -2.3038 0.0349 -2.3038 8 P 0 
L 0.0349 -1.6038 4.5349 -1.6038 8 P 0 
L 0.0349 -1.8038 4.5349 -1.8038 8 P 0 
L 2.4349 -2.1038 4.0349 -2.1038 8 P 0 
L 2.4349 -2.3038 2.4349 -1.8038 8 P 0 
L 3.2349 -2.1038 3.2349 -1.8038 8 P 0 
L 4.0349 -2.3038 4.0349 -1.8038 8 P 0 
L 0.0723999 -1.6844687 0.07906663 -1.69030079 2 P 0 ;0,1=93,2=0.000000
L 0.07906663 -1.69030079 0.08656654 -1.6938 2 P 0 ;0,1=93,2=0.000000
L 0.08656654 -1.6938 0.09323337 -1.6938 2 P 0 ;0,1=93,2=0.000000
L 0.09323337 -1.6938 0.0999001 -1.69030079 2 P 0 ;0,1=93,2=0.000000
L 0.0999001 -1.69030079 0.10490059 -1.6844687 2 P 0 ;0,1=93,2=0.000000
L 0.10490059 -1.6844687 0.1074 -1.67629951 2 P 0 ;0,1=93,2=0.000000
L 0.1074 -1.67629951 0.10573376 -1.66813455 2 P 0 ;0,1=93,2=0.000000
L 0.10573376 -1.66813455 0.10156644 -1.66113396 2 P 0 ;0,1=93,2=0.000000
L 0.10156644 -1.66113396 0.09406654 -1.65646614 2 P 0 ;0,1=93,2=0.000000
L 0.09406654 -1.65646614 0.08406713 -1.65413327 2 P 0 ;0,1=93,2=0.000000
L 0.08406713 -1.65413327 0.07823346 -1.64946762 2 P 0 ;0,1=93,2=0.000000
L 0.07823346 -1.64946762 0.07573248 -1.64130059 2 P 0 ;0,1=93,2=0.000000
L 0.07573248 -1.64130059 0.0774003 -1.63313356 2 P 0 ;0,1=93,2=0.000000
L 0.0774003 -1.63313356 0.08156614 -1.62730148 2 P 0 ;0,1=93,2=0.000000
L 0.08156614 -1.62730148 0.0873997 -1.6238 2 P 0 ;0,1=93,2=0.000000
L 0.0873997 -1.6238 0.09323337 -1.6238 2 P 0 ;0,1=93,2=0.000000
L 0.09323337 -1.6238 0.09906693 -1.62613287 2 P 0 ;0,1=93,2=0.000000
L 0.09906693 -1.62613287 0.10406742 -1.63196713 2 P 0 ;0,1=93,2=0.000000
L 0.1383999 -1.6938 0.1383999 -1.6238 2 P 0 ;0,1=93,2=0.000000
L 0.1734 -1.6238 0.1734 -1.6938 2 P 0 ;0,1=93,2=0.000000
L 0.1734 -1.65880108 0.1383999 -1.65880108 2 P 0 ;0,1=93,2=0.000000
L 0.23856683 -1.6938 0.20523307 -1.6938 2 P 0 ;0,1=93,2=0.000000
L 0.20523307 -1.6938 0.20523307 -1.6238 2 P 0 ;0,1=93,2=0.000000
L 0.20523307 -1.6238 0.23856683 -1.6238 2 P 0 ;0,1=93,2=0.000000
L 0.22523337 -1.65763258 0.20523307 -1.65763258 2 P 0 ;0,1=93,2=0.000000
L 0.30456683 -1.6938 0.27123307 -1.6938 2 P 0 ;0,1=93,2=0.000000
L 0.27123307 -1.6938 0.27123307 -1.6238 2 P 0 ;0,1=93,2=0.000000
L 0.27123307 -1.6238 0.30456683 -1.6238 2 P 0 ;0,1=93,2=0.000000
L 0.29123337 -1.65763258 0.27123307 -1.65763258 2 P 0 ;0,1=93,2=0.000000
L 0.35389921 -1.6238 0.35389921 -1.6938 2 P 0 ;0,1=93,2=0.000000
L 0.33473356 -1.6238 0.37306634 -1.6238 2 P 0 ;0,1=93,2=0.000000
L 0.09489921 -1.7188 0.09489921 -1.7888 2 P 0 ;0,1=94,2=0.000000
L 0.07573356 -1.7188 0.11406634 -1.7188 2 P 0 ;0,1=94,2=0.000000
L 0.1508998 -1.7188 0.17089862 -1.7188 2 P 0 ;0,1=94,2=0.000000
L 0.16089921 -1.7188 0.16089921 -1.7888 2 P 0 ;0,1=94,2=0.000000
L 0.1508998 -1.7888 0.17089862 -1.7888 2 P 0 ;0,1=94,2=0.000000
L 0.22689921 -1.7188 0.22689921 -1.7888 2 P 0 ;0,1=94,2=0.000000
L 0.20773356 -1.7188 0.24606634 -1.7188 2 P 0 ;0,1=94,2=0.000000
L 0.27623307 -1.7188 0.27623307 -1.7888 2 P 0 ;0,1=94,2=0.000000
L 0.27623307 -1.7888 0.30956683 -1.7888 2 P 0 ;0,1=94,2=0.000000
L 0.37556683 -1.7888 0.34223307 -1.7888 2 P 0 ;0,1=94,2=0.000000
L 0.34223307 -1.7888 0.34223307 -1.7188 2 P 0 ;0,1=94,2=0.000000
L 0.34223307 -1.7188 0.37556683 -1.7188 2 P 0 ;0,1=94,2=0.000000
L 0.36223337 -1.75263258 0.34223307 -1.75263258 2 P 0 ;0,1=94,2=0.000000
L 2.5438999 -1.96813563 2.5519 -1.97480089 2 P 0 ;0,1=95,2=0.000000
L 2.5519 -1.97480089 2.5608999 -1.9788 2 P 0 ;0,1=95,2=0.000000
L 2.5608999 -1.9788 2.5689 -1.9788 2 P 0 ;0,1=95,2=0.000000
L 2.5689 -1.9788 2.5769001 -1.97480089 2 P 0 ;0,1=95,2=0.000000
L 2.5769001 -1.97480089 2.58290069 -1.96813563 2 P 0 ;0,1=95,2=0.000000
L 2.58290069 -1.96813563 2.5859 -1.95879941 2 P 0 ;0,1=95,2=0.000000
L 2.5859 -1.95879941 2.58390049 -1.94946811 2 P 0 ;0,1=95,2=0.000000
L 2.58390049 -1.94946811 2.5788997 -1.94146732 2 P 0 ;0,1=95,2=0.000000
L 2.5788997 -1.94146732 2.5698998 -1.93613278 2 P 0 ;0,1=95,2=0.000000
L 2.5698998 -1.93613278 2.55790049 -1.93346663 2 P 0 ;0,1=95,2=0.000000
L 2.55790049 -1.93346663 2.5509002 -1.92813445 2 P 0 ;0,1=95,2=0.000000
L 2.5509002 -1.92813445 2.54789902 -1.91880069 2 P 0 ;0,1=95,2=0.000000
L 2.54789902 -1.91880069 2.54990039 -1.90946683 2 P 0 ;0,1=95,2=0.000000
L 2.54990039 -1.90946683 2.55489931 -1.90280167 2 P 0 ;0,1=95,2=0.000000
L 2.55489931 -1.90280167 2.5618997 -1.8988 2 P 0 ;0,1=95,2=0.000000
L 2.5618997 -1.8988 2.5689 -1.8988 2 P 0 ;0,1=95,2=0.000000
L 2.5689 -1.8988 2.57590039 -1.90146614 2 P 0 ;0,1=95,2=0.000000
L 2.57590039 -1.90146614 2.58190089 -1.90813386 2 P 0 ;0,1=95,2=0.000000
L 2.6648998 -1.90546772 2.65889931 -1.90146614 2 P 0 ;0,1=95,2=0.000000
L 2.65889931 -1.90146614 2.65190079 -1.8988 2 P 0 ;0,1=95,2=0.000000
L 2.65190079 -1.8988 2.64390069 -1.8988 2 P 0 ;0,1=95,2=0.000000
L 2.64390069 -1.8988 2.63489892 -1.90280167 2 P 0 ;0,1=95,2=0.000000
L 2.63489892 -1.90280167 2.62790039 -1.90946683 2 P 0 ;0,1=95,2=0.000000
L 2.62790039 -1.90946683 2.62289961 -1.91746762 2 P 0 ;0,1=95,2=0.000000
L 2.62289961 -1.91746762 2.61889862 -1.93080049 2 P 0 ;0,1=95,2=0.000000
L 2.61889862 -1.93080049 2.61789892 -1.94280039 2 P 0 ;0,1=95,2=0.000000
L 2.61789892 -1.94280039 2.6199003 -1.9548003 2 P 0 ;0,1=95,2=0.000000
L 2.6199003 -1.9548003 2.62289961 -1.96280098 2 P 0 ;0,1=95,2=0.000000
L 2.62289961 -1.96280098 2.6289002 -1.97080177 2 P 0 ;0,1=95,2=0.000000
L 2.6289002 -1.97080177 2.63590049 -1.97613396 2 P 0 ;0,1=95,2=0.000000
L 2.63590049 -1.97613396 2.64289902 -1.9788 2 P 0 ;0,1=95,2=0.000000
L 2.64289902 -1.9788 2.64989941 -1.9788 2 P 0 ;0,1=95,2=0.000000
L 2.64989941 -1.9788 2.6568997 -1.97613396 2 P 0 ;0,1=95,2=0.000000
L 2.6568997 -1.97613396 2.6629003 -1.97213484 2 P 0 ;0,1=95,2=0.000000
L 2.6629003 -1.97213484 2.66790098 -1.96680266 2 P 0 ;0,1=95,2=0.000000
L 2.69589892 -1.9788 2.72089902 -1.8988 2 P 0 ;0,1=95,2=0.000000
L 2.72089902 -1.8988 2.74590098 -1.9788 2 P 0 ;0,1=95,2=0.000000
L 2.73689931 -1.95080118 2.70489882 -1.95080118 2 P 0 ;0,1=95,2=0.000000
L 2.77889961 -1.8988 2.77889961 -1.9788 2 P 0 ;0,1=95,2=0.000000
L 2.77889961 -1.9788 2.8189003 -1.9788 2 P 0 ;0,1=95,2=0.000000
L 2.8969003 -1.9788 2.85689961 -1.9788 2 P 0 ;0,1=95,2=0.000000
L 2.85689961 -1.9788 2.85689961 -1.8988 2 P 0 ;0,1=95,2=0.000000
L 2.85689961 -1.8988 2.8969003 -1.8988 2 P 0 ;0,1=95,2=0.000000
L 2.8809 -1.93746575 2.85689961 -1.93746575 2 P 0 ;0,1=95,2=0.000000
L 3.03289902 -1.9788 3.03289902 -1.8988 2 P 0 ;0,1=95,2=0.000000
L 3.03289902 -1.8988 3.0208998 -1.91479911 2 P 0 ;0,1=95,2=0.000000
L 3.0208998 -1.9788 3.04489833 -1.9788 2 P 0 ;0,1=95,2=0.000000
L 3.11089902 -1.98146604 3.10889951 -1.98013297 2 P 0 ;0,1=95,2=0.000000
L 3.10889951 -1.98013297 3.10889951 -1.97746703 2 P 0 ;0,1=95,2=0.000000
L 3.10889951 -1.97746703 3.11089902 -1.97613396 2 P 0 ;0,1=95,2=0.000000
L 3.11089902 -1.97613396 3.11290039 -1.97746703 2 P 0 ;0,1=95,2=0.000000
L 3.11290039 -1.97746703 3.11290039 -1.98013297 2 P 0 ;0,1=95,2=0.000000
L 3.11290039 -1.98013297 3.11089902 -1.98146604 2 P 0 ;0,1=95,2=0.000000
L 3.11089902 -1.945469 3.10889951 -1.94413346 2 P 0 ;0,1=95,2=0.000000
L 3.10889951 -1.94413346 3.10889951 -1.94146732 2 P 0 ;0,1=95,2=0.000000
L 3.10889951 -1.94146732 3.11089902 -1.94013435 2 P 0 ;0,1=95,2=0.000000
L 3.11089902 -1.94013435 3.11290039 -1.94146732 2 P 0 ;0,1=95,2=0.000000
L 3.11290039 -1.94146732 3.11290039 -1.94413346 2 P 0 ;0,1=95,2=0.000000
L 3.11290039 -1.94413346 3.11089902 -1.945469 2 P 0 ;0,1=95,2=0.000000
L 3.18889902 -1.9788 3.18889902 -1.8988 2 P 0 ;0,1=95,2=0.000000
L 3.18889902 -1.8988 3.1768998 -1.91479911 2 P 0 ;0,1=95,2=0.000000
L 3.1768998 -1.9788 3.20089833 -1.9788 2 P 0 ;0,1=95,2=0.000000
L 2.5138999 -2.23313563 2.5219 -2.23980089 2 P 0 ;0,1=93,2=0.000000
L 2.5219 -2.23980089 2.5308999 -2.2438 2 P 0 ;0,1=93,2=0.000000
L 2.5308999 -2.2438 2.5389 -2.2438 2 P 0 ;0,1=93,2=0.000000
L 2.5389 -2.2438 2.5469001 -2.23980089 2 P 0 ;0,1=93,2=0.000000
L 2.5469001 -2.23980089 2.55290069 -2.23313563 2 P 0 ;0,1=93,2=0.000000
L 2.55290069 -2.23313563 2.5559 -2.22379941 2 P 0 ;0,1=93,2=0.000000
L 2.5559 -2.22379941 2.55390049 -2.21446811 2 P 0 ;0,1=93,2=0.000000
L 2.55390049 -2.21446811 2.5488997 -2.20646732 2 P 0 ;0,1=93,2=0.000000
L 2.5488997 -2.20646732 2.5398998 -2.20113278 2 P 0 ;0,1=93,2=0.000000
L 2.5398998 -2.20113278 2.52790049 -2.19846663 2 P 0 ;0,1=93,2=0.000000
L 2.52790049 -2.19846663 2.5209002 -2.19313445 2 P 0 ;0,1=93,2=0.000000
L 2.5209002 -2.19313445 2.51789902 -2.18380069 2 P 0 ;0,1=93,2=0.000000
L 2.51789902 -2.18380069 2.51990039 -2.17446683 2 P 0 ;0,1=93,2=0.000000
L 2.51990039 -2.17446683 2.52489931 -2.16780167 2 P 0 ;0,1=93,2=0.000000
L 2.52489931 -2.16780167 2.5318997 -2.1638 2 P 0 ;0,1=93,2=0.000000
L 2.5318997 -2.1638 2.5389 -2.1638 2 P 0 ;0,1=93,2=0.000000
L 2.5389 -2.1638 2.54590039 -2.16646614 2 P 0 ;0,1=93,2=0.000000
L 2.54590039 -2.16646614 2.55190089 -2.17313386 2 P 0 ;0,1=93,2=0.000000
L 2.5918999 -2.2438 2.5918999 -2.1638 2 P 0 ;0,1=93,2=0.000000
L 2.6339 -2.1638 2.6339 -2.2438 2 P 0 ;0,1=93,2=0.000000
L 2.6339 -2.20380128 2.5918999 -2.20380128 2 P 0 ;0,1=93,2=0.000000
L 2.7109003 -2.2438 2.67089961 -2.2438 2 P 0 ;0,1=93,2=0.000000
L 2.67089961 -2.2438 2.67089961 -2.1638 2 P 0 ;0,1=93,2=0.000000
L 2.67089961 -2.1638 2.7109003 -2.1638 2 P 0 ;0,1=93,2=0.000000
L 2.6949 -2.20246575 2.67089961 -2.20246575 2 P 0 ;0,1=93,2=0.000000
L 2.7889003 -2.2438 2.74889961 -2.2438 2 P 0 ;0,1=93,2=0.000000
L 2.74889961 -2.2438 2.74889961 -2.1638 2 P 0 ;0,1=93,2=0.000000
L 2.74889961 -2.1638 2.7889003 -2.1638 2 P 0 ;0,1=93,2=0.000000
L 2.7729 -2.20246575 2.74889961 -2.20246575 2 P 0 ;0,1=93,2=0.000000
L 2.84689902 -2.1638 2.84689902 -2.2438 2 P 0 ;0,1=93,2=0.000000
L 2.8239003 -2.1638 2.86989961 -2.1638 2 P 0 ;0,1=93,2=0.000000
L 3.29489961 -1.9238 3.29489961 -2.0038 2 P 0 ;0,1=96,2=0.000000
L 3.29489961 -2.0038 3.3349003 -2.0038 2 P 0 ;0,1=96,2=0.000000
L 3.36789892 -2.0038 3.39289902 -1.9238 2 P 0 ;0,1=96,2=0.000000
L 3.39289902 -1.9238 3.41790098 -2.0038 2 P 0 ;0,1=96,2=0.000000
L 3.40889931 -1.97580118 3.37689882 -1.97580118 2 P 0 ;0,1=96,2=0.000000
L 3.47089902 -2.0038 3.47089902 -1.96780039 2 P 0 ;0,1=96,2=0.000000
L 3.47089902 -1.96780039 3.45089961 -1.9238 2 P 0 ;0,1=96,2=0.000000
L 3.4909003 -1.9238 3.47089902 -1.96780039 2 P 0 ;0,1=96,2=0.000000
L 3.5689003 -2.0038 3.52889961 -2.0038 2 P 0 ;0,1=96,2=0.000000
L 3.52889961 -2.0038 3.52889961 -1.9238 2 P 0 ;0,1=96,2=0.000000
L 3.52889961 -1.9238 3.5689003 -1.9238 2 P 0 ;0,1=96,2=0.000000
L 3.5529 -1.96246575 3.52889961 -1.96246575 2 P 0 ;0,1=96,2=0.000000
L 3.60689961 -2.0038 3.60689961 -1.9238 2 P 0 ;0,1=96,2=0.000000
L 3.60689961 -1.9238 3.6318998 -1.9238 2 P 0 ;0,1=96,2=0.000000
L 3.6318998 -1.9238 3.6398999 -1.92780167 2 P 0 ;0,1=96,2=0.000000
L 3.6398999 -1.92780167 3.64490069 -1.93313386 2 P 0 ;0,1=96,2=0.000000
L 3.64490069 -1.93313386 3.6469003 -1.94380069 2 P 0 ;0,1=96,2=0.000000
L 3.6469003 -1.94380069 3.64490069 -1.95446752 2 P 0 ;0,1=96,2=0.000000
L 3.64490069 -1.95446752 3.6389001 -1.96113278 2 P 0 ;0,1=96,2=0.000000
L 3.6389001 -1.96113278 3.6318998 -1.96513435 2 P 0 ;0,1=96,2=0.000000
L 3.6318998 -1.96513435 3.60689961 -1.96513435 2 P 0 ;0,1=96,2=0.000000
L 3.6318998 -1.96513435 3.6469003 -2.0038 2 P 0 ;0,1=96,2=0.000000
L 3.33989902 -2.2538 3.33189892 -2.25246703 2 P 0 ;0,1=97,2=0.000000
L 3.33189892 -2.25246703 3.32490039 -2.24713484 2 P 0 ;0,1=97,2=0.000000
L 3.32490039 -2.24713484 3.3188999 -2.23913406 2 P 0 ;0,1=97,2=0.000000
L 3.3188999 -2.23913406 3.31489892 -2.2298003 2 P 0 ;0,1=97,2=0.000000
L 3.31489892 -2.2298003 3.31289931 -2.21913346 2 P 0 ;0,1=97,2=0.000000
L 3.31289931 -2.21913346 3.31289931 -2.20846663 2 P 0 ;0,1=97,2=0.000000
L 3.31289931 -2.20846663 3.31489892 -2.1977998 2 P 0 ;0,1=97,2=0.000000
L 3.31489892 -2.1977998 3.3188999 -2.18846604 2 P 0 ;0,1=97,2=0.000000
L 3.3188999 -2.18846604 3.32490039 -2.18046772 2 P 0 ;0,1=97,2=0.000000
L 3.32490039 -2.18046772 3.33189892 -2.17513307 2 P 0 ;0,1=97,2=0.000000
L 3.33189892 -2.17513307 3.33989902 -2.1738 2 P 0 ;0,1=97,2=0.000000
L 3.33989902 -2.1738 3.34789911 -2.17513307 2 P 0 ;0,1=97,2=0.000000
L 3.34789911 -2.17513307 3.35489951 -2.18046772 2 P 0 ;0,1=97,2=0.000000
L 3.35489951 -2.18046772 3.3609 -2.18846604 2 P 0 ;0,1=97,2=0.000000
L 3.3609 -2.18846604 3.36490098 -2.1977998 2 P 0 ;0,1=97,2=0.000000
L 3.36490098 -2.1977998 3.36690059 -2.20846663 2 P 0 ;0,1=97,2=0.000000
L 3.36690059 -2.20846663 3.36690059 -2.21913346 2 P 0 ;0,1=97,2=0.000000
L 3.36690059 -2.21913346 3.36490098 -2.2298003 2 P 0 ;0,1=97,2=0.000000
L 3.36490098 -2.2298003 3.3609 -2.23913406 2 P 0 ;0,1=97,2=0.000000
L 3.3609 -2.23913406 3.35489951 -2.24713484 2 P 0 ;0,1=97,2=0.000000
L 3.35489951 -2.24713484 3.34789911 -2.25246703 2 P 0 ;0,1=97,2=0.000000
L 3.34789911 -2.25246703 3.33989902 -2.2538 2 P 0 ;0,1=97,2=0.000000
L 3.39889941 -2.2538 3.39889941 -2.1738 2 P 0 ;0,1=97,2=0.000000
L 3.39889941 -2.1738 3.43690049 -2.1738 2 P 0 ;0,1=97,2=0.000000
L 3.4228998 -2.21246575 3.39889941 -2.21246575 2 P 0 ;0,1=97,2=0.000000
L 0.16489872 -1.0538 0.16489872 -1.1538 2 P 0 ;0,1=94,2=0.000000
L 0.13423376 -1.0538 0.19556614 -1.0538 2 P 0 ;0,1=94,2=0.000000
L 0.2588997 -1.0538 0.29089774 -1.0538 2 P 0 ;0,1=94,2=0.000000
L 0.27489872 -1.0538 0.27489872 -1.1538 2 P 0 ;0,1=94,2=0.000000
L 0.2588997 -1.1538 0.29089774 -1.1538 2 P 0 ;0,1=94,2=0.000000
L 0.38489872 -1.0538 0.38489872 -1.1538 2 P 0 ;0,1=94,2=0.000000
L 0.35423376 -1.0538 0.41556614 -1.0538 2 P 0 ;0,1=94,2=0.000000
L 0.46823287 -1.0538 0.46823287 -1.1538 2 P 0 ;0,1=94,2=0.000000
L 0.46823287 -1.1538 0.52156703 -1.1538 2 P 0 ;0,1=94,2=0.000000
L 0.63156703 -1.1538 0.57823287 -1.1538 2 P 0 ;0,1=94,2=0.000000
L 0.57823287 -1.1538 0.57823287 -1.0538 2 P 0 ;0,1=94,2=0.000000
L 0.57823287 -1.0538 0.63156703 -1.0538 2 P 0 ;0,1=94,2=0.000000
L 0.61023337 -1.10213219 0.57823287 -1.10213219 2 P 0 ;0,1=94,2=0.000000
L 4.18989892 -1.9538 4.21489902 -1.8738 2 P 0 ;0,1=98,2=0.000000
L 4.21489902 -1.8738 4.23990098 -1.9538 2 P 0 ;0,1=98,2=0.000000
L 4.23089931 -1.92580118 4.19889882 -1.92580118 2 P 0 ;0,1=98,2=0.000000
L 4.27289961 -1.9538 4.27289961 -1.8738 2 P 0 ;0,1=98,2=0.000000
L 4.27289961 -1.8738 4.2978998 -1.8738 2 P 0 ;0,1=98,2=0.000000
L 4.2978998 -1.8738 4.3058999 -1.87780167 2 P 0 ;0,1=98,2=0.000000
L 4.3058999 -1.87780167 4.31090069 -1.88313386 2 P 0 ;0,1=98,2=0.000000
L 4.31090069 -1.88313386 4.3129003 -1.89380069 2 P 0 ;0,1=98,2=0.000000
L 4.3129003 -1.89380069 4.31090069 -1.90446752 2 P 0 ;0,1=98,2=0.000000
L 4.31090069 -1.90446752 4.3049001 -1.91113278 2 P 0 ;0,1=98,2=0.000000
L 4.3049001 -1.91113278 4.2978998 -1.91513435 2 P 0 ;0,1=98,2=0.000000
L 4.2978998 -1.91513435 4.27289961 -1.91513435 2 P 0 ;0,1=98,2=0.000000
L 4.2978998 -1.91513435 4.3129003 -1.9538 2 P 0 ;0,1=98,2=0.000000
L 4.37089902 -1.8738 4.37089902 -1.9538 2 P 0 ;0,1=98,2=0.000000
L 4.3479003 -1.8738 4.39389961 -1.8738 2 P 0 ;0,1=98,2=0.000000
L 0.5453998 -1.74180266 0.55473337 -1.74930098 2 P 0 ;0,1=99,2=0.000000
L 0.55473337 -1.74930098 0.56523317 -1.7538 2 P 0 ;0,1=99,2=0.000000
L 0.56523317 -1.7538 0.57456673 -1.7538 2 P 0 ;0,1=99,2=0.000000
L 0.57456673 -1.7538 0.5839002 -1.74930098 2 P 0 ;0,1=99,2=0.000000
L 0.5839002 -1.74930098 0.59090079 -1.74180266 2 P 0 ;0,1=99,2=0.000000
L 0.59090079 -1.74180266 0.5944001 -1.73129941 2 P 0 ;0,1=99,2=0.000000
L 0.5944001 -1.73129941 0.59206722 -1.72080157 2 P 0 ;0,1=99,2=0.000000
L 0.59206722 -1.72080157 0.58623297 -1.71180079 2 P 0 ;0,1=99,2=0.000000
L 0.58623297 -1.71180079 0.57573307 -1.70579931 2 P 0 ;0,1=99,2=0.000000
L 0.57573307 -1.70579931 0.56173396 -1.7028 2 P 0 ;0,1=99,2=0.000000
L 0.56173396 -1.7028 0.55356693 -1.69680128 2 P 0 ;0,1=99,2=0.000000
L 0.55356693 -1.69680128 0.55006555 -1.68630069 2 P 0 ;0,1=99,2=0.000000
L 0.55006555 -1.68630069 0.55240049 -1.6758002 2 P 0 ;0,1=99,2=0.000000
L 0.55240049 -1.6758002 0.55823258 -1.66830187 2 P 0 ;0,1=99,2=0.000000
L 0.55823258 -1.66830187 0.56639961 -1.6638 2 P 0 ;0,1=99,2=0.000000
L 0.56639961 -1.6638 0.57456673 -1.6638 2 P 0 ;0,1=99,2=0.000000
L 0.57456673 -1.6638 0.58273376 -1.66679941 2 P 0 ;0,1=99,2=0.000000
L 0.58273376 -1.66679941 0.58973435 -1.67430059 2 P 0 ;0,1=99,2=0.000000
L 0.6458997 -1.6638 0.67389803 -1.6638 2 P 0 ;0,1=99,2=0.000000
L 0.65989892 -1.6638 0.65989892 -1.7538 2 P 0 ;0,1=99,2=0.000000
L 0.6458997 -1.7538 0.67389803 -1.7538 2 P 0 ;0,1=99,2=0.000000
L 0.72656624 -1.6638 0.72656624 -1.7538 2 P 0 ;0,1=99,2=0.000000
L 0.72656624 -1.7538 0.77323366 -1.7538 2 P 0 ;0,1=99,2=0.000000
L 0.81423346 -1.7538 0.81423346 -1.6638 2 P 0 ;0,1=99,2=0.000000
L 0.85856585 -1.6638 0.81423346 -1.71930197 2 P 0 ;0,1=99,2=0.000000
L 0.86556644 -1.7538 0.83406683 -1.69380187 2 P 0 ;0,1=99,2=0.000000
L 0.9953998 -1.74180266 1.00473337 -1.74930098 2 P 0 ;0,1=99,2=0.000000
L 1.00473337 -1.74930098 1.01523317 -1.7538 2 P 0 ;0,1=99,2=0.000000
L 1.01523317 -1.7538 1.02456673 -1.7538 2 P 0 ;0,1=99,2=0.000000
L 1.02456673 -1.7538 1.0339002 -1.74930098 2 P 0 ;0,1=99,2=0.000000
L 1.0339002 -1.74930098 1.04090079 -1.74180266 2 P 0 ;0,1=99,2=0.000000
L 1.04090079 -1.74180266 1.0444001 -1.73129941 2 P 0 ;0,1=99,2=0.000000
L 1.0444001 -1.73129941 1.04206722 -1.72080157 2 P 0 ;0,1=99,2=0.000000
L 1.04206722 -1.72080157 1.03623297 -1.71180079 2 P 0 ;0,1=99,2=0.000000
L 1.03623297 -1.71180079 1.02573307 -1.70579931 2 P 0 ;0,1=99,2=0.000000
L 1.02573307 -1.70579931 1.01173396 -1.7028 2 P 0 ;0,1=99,2=0.000000
L 1.01173396 -1.7028 1.00356693 -1.69680128 2 P 0 ;0,1=99,2=0.000000
L 1.00356693 -1.69680128 1.00006555 -1.68630069 2 P 0 ;0,1=99,2=0.000000
L 1.00006555 -1.68630069 1.00240049 -1.6758002 2 P 0 ;0,1=99,2=0.000000
L 1.00240049 -1.6758002 1.00823258 -1.66830187 2 P 0 ;0,1=99,2=0.000000
L 1.00823258 -1.66830187 1.01639961 -1.6638 2 P 0 ;0,1=99,2=0.000000
L 1.01639961 -1.6638 1.02456673 -1.6638 2 P 0 ;0,1=99,2=0.000000
L 1.02456673 -1.6638 1.03273376 -1.66679941 2 P 0 ;0,1=99,2=0.000000
L 1.03273376 -1.66679941 1.03973435 -1.67430059 2 P 0 ;0,1=99,2=0.000000
L 1.13556644 -1.67130118 1.12856585 -1.66679941 2 P 0 ;0,1=99,2=0.000000
L 1.12856585 -1.66679941 1.12040089 -1.6638 2 P 0 ;0,1=99,2=0.000000
L 1.12040089 -1.6638 1.11106742 -1.6638 2 P 0 ;0,1=99,2=0.000000
L 1.11106742 -1.6638 1.10056545 -1.66830187 2 P 0 ;0,1=99,2=0.000000
L 1.10056545 -1.66830187 1.09240049 -1.6758002 2 P 0 ;0,1=99,2=0.000000
L 1.09240049 -1.6758002 1.08656624 -1.68480108 2 P 0 ;0,1=99,2=0.000000
L 1.08656624 -1.68480108 1.08189843 -1.69980059 2 P 0 ;0,1=99,2=0.000000
L 1.08189843 -1.69980059 1.08073209 -1.71330049 2 P 0 ;0,1=99,2=0.000000
L 1.08073209 -1.71330049 1.08306703 -1.7268003 2 P 0 ;0,1=99,2=0.000000
L 1.08306703 -1.7268003 1.08656624 -1.73580118 2 P 0 ;0,1=99,2=0.000000
L 1.08656624 -1.73580118 1.09356693 -1.74480197 2 P 0 ;0,1=99,2=0.000000
L 1.09356693 -1.74480197 1.10173396 -1.75080069 2 P 0 ;0,1=99,2=0.000000
L 1.10173396 -1.75080069 1.10989892 -1.7538 2 P 0 ;0,1=99,2=0.000000
L 1.10989892 -1.7538 1.11806594 -1.7538 2 P 0 ;0,1=99,2=0.000000
L 1.11806594 -1.7538 1.12623297 -1.75080069 2 P 0 ;0,1=99,2=0.000000
L 1.12623297 -1.75080069 1.13323366 -1.74630167 2 P 0 ;0,1=99,2=0.000000
L 1.13323366 -1.74630167 1.13906782 -1.74030295 2 P 0 ;0,1=99,2=0.000000
L 1.17656624 -1.7538 1.17656624 -1.6638 2 P 0 ;0,1=99,2=0.000000
L 1.17656624 -1.6638 1.20573307 -1.6638 2 P 0 ;0,1=99,2=0.000000
L 1.20573307 -1.6638 1.21506654 -1.66830187 2 P 0 ;0,1=99,2=0.000000
L 1.21506654 -1.66830187 1.22090079 -1.67430059 2 P 0 ;0,1=99,2=0.000000
L 1.22090079 -1.67430059 1.22323366 -1.68630069 2 P 0 ;0,1=99,2=0.000000
L 1.22323366 -1.68630069 1.22090079 -1.69830089 2 P 0 ;0,1=99,2=0.000000
L 1.22090079 -1.69830089 1.2139002 -1.70579931 2 P 0 ;0,1=99,2=0.000000
L 1.2139002 -1.70579931 1.20573307 -1.71030108 2 P 0 ;0,1=99,2=0.000000
L 1.20573307 -1.71030108 1.17656624 -1.71030108 2 P 0 ;0,1=99,2=0.000000
L 1.20573307 -1.71030108 1.22323366 -1.7538 2 P 0 ;0,1=99,2=0.000000
L 1.31323366 -1.7538 1.26656624 -1.7538 2 P 0 ;0,1=99,2=0.000000
L 1.26656624 -1.7538 1.26656624 -1.6638 2 P 0 ;0,1=99,2=0.000000
L 1.26656624 -1.6638 1.31323366 -1.6638 2 P 0 ;0,1=99,2=0.000000
L 1.29456673 -1.70729902 1.26656624 -1.70729902 2 P 0 ;0,1=99,2=0.000000
L 1.40323366 -1.7538 1.35656624 -1.7538 2 P 0 ;0,1=99,2=0.000000
L 1.35656624 -1.7538 1.35656624 -1.6638 2 P 0 ;0,1=99,2=0.000000
L 1.35656624 -1.6638 1.40323366 -1.6638 2 P 0 ;0,1=99,2=0.000000
L 1.38456673 -1.70729902 1.35656624 -1.70729902 2 P 0 ;0,1=99,2=0.000000
L 1.44306703 -1.7538 1.44306703 -1.6638 2 P 0 ;0,1=99,2=0.000000
L 1.44306703 -1.6638 1.49673287 -1.7538 2 P 0 ;0,1=99,2=0.000000
L 1.49673287 -1.7538 1.49673287 -1.6638 2 P 0 ;0,1=99,2=0.000000
L 1.64406683 -1.78379902 1.63240049 -1.76879951 2 P 0 ;0,1=99,2=0.000000
L 1.63240049 -1.76879951 1.62656624 -1.7538 2 P 0 ;0,1=99,2=0.000000
L 1.62656624 -1.7538 1.62656624 -1.69380187 2 P 0 ;0,1=99,2=0.000000
L 1.62656624 -1.69380187 1.63240049 -1.67879961 2 P 0 ;0,1=99,2=0.000000
L 1.63240049 -1.67879961 1.64406683 -1.6638 2 P 0 ;0,1=99,2=0.000000
L 1.82989892 -1.6638 1.82989892 -1.7538 2 P 0 ;0,1=99,2=0.000000
L 1.80306703 -1.6638 1.85673287 -1.6638 2 P 0 ;0,1=99,2=0.000000
L 1.91989892 -1.7538 1.91056545 -1.75230039 2 P 0 ;0,1=99,2=0.000000
L 1.91056545 -1.75230039 1.90240049 -1.74630167 2 P 0 ;0,1=99,2=0.000000
L 1.90240049 -1.74630167 1.8953998 -1.73730079 2 P 0 ;0,1=99,2=0.000000
L 1.8953998 -1.73730079 1.89073209 -1.7268003 2 P 0 ;0,1=99,2=0.000000
L 1.89073209 -1.7268003 1.88839921 -1.7148001 2 P 0 ;0,1=99,2=0.000000
L 1.88839921 -1.7148001 1.88839921 -1.7028 2 P 0 ;0,1=99,2=0.000000
L 1.88839921 -1.7028 1.89073209 -1.6907998 2 P 0 ;0,1=99,2=0.000000
L 1.89073209 -1.6907998 1.8953998 -1.68029931 2 P 0 ;0,1=99,2=0.000000
L 1.8953998 -1.68029931 1.90240049 -1.67130118 2 P 0 ;0,1=99,2=0.000000
L 1.90240049 -1.67130118 1.91056545 -1.6652997 2 P 0 ;0,1=99,2=0.000000
L 1.91056545 -1.6652997 1.91989892 -1.6638 2 P 0 ;0,1=99,2=0.000000
L 1.91989892 -1.6638 1.92923238 -1.6652997 2 P 0 ;0,1=99,2=0.000000
L 1.92923238 -1.6652997 1.93739941 -1.67130118 2 P 0 ;0,1=99,2=0.000000
L 1.93739941 -1.67130118 1.9444001 -1.68029931 2 P 0 ;0,1=99,2=0.000000
L 1.9444001 -1.68029931 1.94906782 -1.6907998 2 P 0 ;0,1=99,2=0.000000
L 1.94906782 -1.6907998 1.95140069 -1.7028 2 P 0 ;0,1=99,2=0.000000
L 1.95140069 -1.7028 1.95140069 -1.7148001 2 P 0 ;0,1=99,2=0.000000
L 1.95140069 -1.7148001 1.94906782 -1.7268003 2 P 0 ;0,1=99,2=0.000000
L 1.94906782 -1.7268003 1.9444001 -1.73730079 2 P 0 ;0,1=99,2=0.000000
L 1.9444001 -1.73730079 1.93739941 -1.74630167 2 P 0 ;0,1=99,2=0.000000
L 1.93739941 -1.74630167 1.92923238 -1.75230039 2 P 0 ;0,1=99,2=0.000000
L 1.92923238 -1.75230039 1.91989892 -1.7538 2 P 0 ;0,1=99,2=0.000000
L 1.98656624 -1.7538 1.98656624 -1.6638 2 P 0 ;0,1=99,2=0.000000
L 1.98656624 -1.6638 2.01456673 -1.6638 2 P 0 ;0,1=99,2=0.000000
L 2.01456673 -1.6638 2.0239002 -1.66830187 2 P 0 ;0,1=99,2=0.000000
L 2.0239002 -1.66830187 2.03090079 -1.67879961 2 P 0 ;0,1=99,2=0.000000
L 2.03090079 -1.67879961 2.03323366 -1.6907998 2 P 0 ;0,1=99,2=0.000000
L 2.03323366 -1.6907998 2.03090079 -1.7028 2 P 0 ;0,1=99,2=0.000000
L 2.03090079 -1.7028 2.02506654 -1.71180079 2 P 0 ;0,1=99,2=0.000000
L 2.02506654 -1.71180079 2.01456673 -1.71630256 2 P 0 ;0,1=99,2=0.000000
L 2.01456673 -1.71630256 1.98656624 -1.71630256 2 P 0 ;0,1=99,2=0.000000
L 2.19573307 -1.78379902 2.20739941 -1.76879951 2 P 0 ;0,1=99,2=0.000000
L 2.20739941 -1.76879951 2.21323366 -1.7538 2 P 0 ;0,1=99,2=0.000000
L 2.21323366 -1.7538 2.21323366 -1.69380187 2 P 0 ;0,1=99,2=0.000000
L 2.21323366 -1.69380187 2.20739941 -1.67879961 2 P 0 ;0,1=99,2=0.000000
L 2.20739941 -1.67879961 2.19573307 -1.6638 2 P 0 ;0,1=99,2=0.000000
L 3.72973337 -1.97380098 3.76006654 -1.97380098 2 P 0 ;0,1=100,2=0.000000
L 3.06989892 -2.2538 3.06989892 -2.1638 2 P 0 ;0,1=52,2=0.000000
L 3.06989892 -2.1638 3.0558997 -2.18179892 2 P 0 ;0,1=52,2=0.000000
L 3.0558997 -2.2538 3.08389803 -2.2538 2 P 0 ;0,1=52,2=0.000000
L 3.64489892 -2.2538 3.64489892 -2.1638 2 P 0 ;0,1=52,2=0.000000
L 3.64489892 -2.1638 3.6308997 -2.18179892 2 P 0 ;0,1=52,2=0.000000
L 3.6308997 -2.2538 3.65889803 -2.2538 2 P 0 ;0,1=52,2=0.000000
L 0.59099833 -1.36499882 0.5990003 -1.35750039 2 P 0 ;0,1=101,2=0.000000
L 0.5990003 -1.35750039 0.60499902 -1.34500315 2 P 0 ;0,1=101,2=0.000000
L 0.60499902 -1.34500315 0.60900187 -1.32749764 2 P 0 ;0,1=101,2=0.000000
L 0.60900187 -1.32749764 0.60499902 -1.31250089 2 P 0 ;0,1=101,2=0.000000
L 0.60499902 -1.31250089 0.59700079 -1.30250305 2 P 0 ;0,1=101,2=0.000000
L 0.59700079 -1.30250305 0.5830001 -1.295 2 P 0 ;0,1=101,2=0.000000
L 0.5830001 -1.295 0.52900059 -1.295 2 P 0 ;0,1=101,2=0.000000
L 0.52900059 -1.295 0.52900059 -1.445 2 P 0 ;0,1=101,2=0.000000
L 0.52900059 -1.445 0.59500118 -1.445 2 P 0 ;0,1=101,2=0.000000
L 0.59500118 -1.445 0.60900187 -1.43500217 2 P 0 ;0,1=101,2=0.000000
L 0.60900187 -1.43500217 0.6170001 -1.42000079 2 P 0 ;0,1=101,2=0.000000
L 0.6170001 -1.42000079 0.62099931 -1.4025 2 P 0 ;0,1=101,2=0.000000
L 0.62099931 -1.4025 0.6170001 -1.38500374 2 P 0 ;0,1=101,2=0.000000
L 0.6170001 -1.38500374 0.60499902 -1.37000236 2 P 0 ;0,1=101,2=0.000000
L 0.60499902 -1.37000236 0.59099833 -1.36499882 2 P 0 ;0,1=101,2=0.000000
L 0.59099833 -1.36499882 0.52900059 -1.36499882 2 P 0 ;0,1=101,2=0.000000
L 0.77100138 -1.445 0.77100138 -1.34500315 2 P 0 ;0,1=101,2=0.000000
L 0.77100138 -1.36249941 0.76299951 -1.35250148 2 P 0 ;0,1=101,2=0.000000
L 0.76299951 -1.35250148 0.75099833 -1.34750256 2 P 0 ;0,1=101,2=0.000000
L 0.75099833 -1.34750256 0.73700138 -1.34500315 2 P 0 ;0,1=101,2=0.000000
L 0.73700138 -1.34500315 0.72300069 -1.35000207 2 P 0 ;0,1=101,2=0.000000
L 0.72300069 -1.35000207 0.71099961 -1.3599999 2 P 0 ;0,1=101,2=0.000000
L 0.71099961 -1.3599999 0.70299764 -1.37500128 2 P 0 ;0,1=101,2=0.000000
L 0.70299764 -1.37500128 0.69899852 -1.39500157 2 P 0 ;0,1=101,2=0.000000
L 0.69899852 -1.39500157 0.70299764 -1.41500187 2 P 0 ;0,1=101,2=0.000000
L 0.70299764 -1.41500187 0.71099961 -1.43000325 2 P 0 ;0,1=101,2=0.000000
L 0.71099961 -1.43000325 0.72300069 -1.44000108 2 P 0 ;0,1=101,2=0.000000
L 0.72300069 -1.44000108 0.73700138 -1.445 2 P 0 ;0,1=101,2=0.000000
L 0.73700138 -1.445 0.75099833 -1.44250059 2 P 0 ;0,1=101,2=0.000000
L 0.75099833 -1.44250059 0.76299951 -1.43500217 2 P 0 ;0,1=101,2=0.000000
L 0.76299951 -1.43500217 0.77100138 -1.42500433 2 P 0 ;0,1=101,2=0.000000
L 0.86700039 -1.445 0.86700039 -1.34500315 2 P 0 ;0,1=101,2=0.000000
L 0.86700039 -1.36499882 0.87699833 -1.35500098 2 P 0 ;0,1=101,2=0.000000
L 0.87699833 -1.35500098 0.8869998 -1.34750256 2 P 0 ;0,1=101,2=0.000000
L 0.8869998 -1.34750256 0.90100049 -1.34500315 2 P 0 ;0,1=101,2=0.000000
L 0.90100049 -1.34500315 0.91099833 -1.34750256 2 P 0 ;0,1=101,2=0.000000
L 0.91099833 -1.34750256 0.92299951 -1.35500098 2 P 0 ;0,1=101,2=0.000000
L 1.02700039 -1.445 1.02700039 -1.34500315 2 P 0 ;0,1=101,2=0.000000
L 1.02700039 -1.36499882 1.03699833 -1.35500098 2 P 0 ;0,1=101,2=0.000000
L 1.03699833 -1.35500098 1.0469998 -1.34750256 2 P 0 ;0,1=101,2=0.000000
L 1.0469998 -1.34750256 1.06100049 -1.34500315 2 P 0 ;0,1=101,2=0.000000
L 1.06100049 -1.34500315 1.07099833 -1.34750256 2 P 0 ;0,1=101,2=0.000000
L 1.07099833 -1.34750256 1.08299951 -1.35500098 2 P 0 ;0,1=101,2=0.000000
L 1.18500089 -1.37750069 1.24900187 -1.37750069 2 P 0 ;0,1=101,2=0.000000
L 1.24900187 -1.37750069 1.24299951 -1.3599999 2 P 0 ;0,1=101,2=0.000000
L 1.24299951 -1.3599999 1.23300157 -1.35000207 2 P 0 ;0,1=101,2=0.000000
L 1.23300157 -1.35000207 1.21900089 -1.34500315 2 P 0 ;0,1=101,2=0.000000
L 1.21900089 -1.34500315 1.2050003 -1.34750256 2 P 0 ;0,1=101,2=0.000000
L 1.2050003 -1.34750256 1.19299911 -1.35500098 2 P 0 ;0,1=101,2=0.000000
L 1.19299911 -1.35500098 1.18500089 -1.37250177 2 P 0 ;0,1=101,2=0.000000
L 1.18500089 -1.37250177 1.18099803 -1.38750315 2 P 0 ;0,1=101,2=0.000000
L 1.18099803 -1.38750315 1.18099803 -1.4025 2 P 0 ;0,1=101,2=0.000000
L 1.18099803 -1.4025 1.18500089 -1.41750138 2 P 0 ;0,1=101,2=0.000000
L 1.18500089 -1.41750138 1.19499872 -1.43250276 2 P 0 ;0,1=101,2=0.000000
L 1.19499872 -1.43250276 1.2069998 -1.44250059 2 P 0 ;0,1=101,2=0.000000
L 1.2069998 -1.44250059 1.22100049 -1.445 2 P 0 ;0,1=101,2=0.000000
L 1.22100049 -1.445 1.23500118 -1.44000108 2 P 0 ;0,1=101,2=0.000000
L 1.23500118 -1.44000108 1.24900187 -1.42500433 2 P 0 ;0,1=101,2=0.000000
L 1.37499813 -1.445 1.37499813 -1.295 2 P 0 ;0,1=101,2=0.000000
L 1.50500089 -1.37750069 1.56900187 -1.37750069 2 P 0 ;0,1=101,2=0.000000
L 1.56900187 -1.37750069 1.56299951 -1.3599999 2 P 0 ;0,1=101,2=0.000000
L 1.56299951 -1.3599999 1.55300157 -1.35000207 2 P 0 ;0,1=101,2=0.000000
L 1.55300157 -1.35000207 1.53900089 -1.34500315 2 P 0 ;0,1=101,2=0.000000
L 1.53900089 -1.34500315 1.5250003 -1.34750256 2 P 0 ;0,1=101,2=0.000000
L 1.5250003 -1.34750256 1.51299911 -1.35500098 2 P 0 ;0,1=101,2=0.000000
L 1.51299911 -1.35500098 1.50500089 -1.37250177 2 P 0 ;0,1=101,2=0.000000
L 1.50500089 -1.37250177 1.50099803 -1.38750315 2 P 0 ;0,1=101,2=0.000000
L 1.50099803 -1.38750315 1.50099803 -1.4025 2 P 0 ;0,1=101,2=0.000000
L 1.50099803 -1.4025 1.50500089 -1.41750138 2 P 0 ;0,1=101,2=0.000000
L 1.50500089 -1.41750138 1.51499872 -1.43250276 2 P 0 ;0,1=101,2=0.000000
L 1.51499872 -1.43250276 1.5269998 -1.44250059 2 P 0 ;0,1=101,2=0.000000
L 1.5269998 -1.44250059 1.54100049 -1.445 2 P 0 ;0,1=101,2=0.000000
L 1.54100049 -1.445 1.55500118 -1.44000108 2 P 0 ;0,1=101,2=0.000000
L 1.55500118 -1.44000108 1.56900187 -1.42500433 2 P 0 ;0,1=101,2=0.000000
L 1.6529998 -1.48999951 1.66500089 -1.49499843 2 P 0 ;0,1=101,2=0.000000
L 1.66500089 -1.49499843 1.68100108 -1.48999951 2 P 0 ;0,1=101,2=0.000000
L 1.68100108 -1.48999951 1.69099902 -1.48000167 2 P 0 ;0,1=101,2=0.000000
L 1.69099902 -1.48000167 1.69900089 -1.4674997 2 P 0 ;0,1=101,2=0.000000
L 1.69900089 -1.4674997 1.71099833 -1.42750374 2 P 0 ;0,1=101,2=0.000000
L 1.71099833 -1.42750374 1.7370001 -1.34500315 2 P 0 ;0,1=101,2=0.000000
L 1.67299911 -1.34500315 1.71099833 -1.42750374 2 P 0 ;0,1=101,2=0.000000
L 1.82500089 -1.37750069 1.88900187 -1.37750069 2 P 0 ;0,1=101,2=0.000000
L 1.88900187 -1.37750069 1.88299951 -1.3599999 2 P 0 ;0,1=101,2=0.000000
L 1.88299951 -1.3599999 1.87300157 -1.35000207 2 P 0 ;0,1=101,2=0.000000
L 1.87300157 -1.35000207 1.85900089 -1.34500315 2 P 0 ;0,1=101,2=0.000000
L 1.85900089 -1.34500315 1.8450003 -1.34750256 2 P 0 ;0,1=101,2=0.000000
L 1.8450003 -1.34750256 1.83299911 -1.35500098 2 P 0 ;0,1=101,2=0.000000
L 1.83299911 -1.35500098 1.82500089 -1.37250177 2 P 0 ;0,1=101,2=0.000000
L 1.82500089 -1.37250177 1.82099803 -1.38750315 2 P 0 ;0,1=101,2=0.000000
L 1.82099803 -1.38750315 1.82099803 -1.4025 2 P 0 ;0,1=101,2=0.000000
L 1.82099803 -1.4025 1.82500089 -1.41750138 2 P 0 ;0,1=101,2=0.000000
L 1.82500089 -1.41750138 1.83499872 -1.43250276 2 P 0 ;0,1=101,2=0.000000
L 1.83499872 -1.43250276 1.8469998 -1.44250059 2 P 0 ;0,1=101,2=0.000000
L 1.8469998 -1.44250059 1.86100049 -1.445 2 P 0 ;0,1=101,2=0.000000
L 1.86100049 -1.445 1.87500118 -1.44000108 2 P 0 ;0,1=101,2=0.000000
L 1.87500118 -1.44000108 1.88900187 -1.42500433 2 P 0 ;0,1=101,2=0.000000
L 2.18699921 -1.37000236 2.22700167 -1.37000236 2 P 0 ;0,1=101,2=0.000000
L 2.22700167 -1.37000236 2.22700167 -1.41500187 2 P 0 ;0,1=101,2=0.000000
L 2.22700167 -1.41500187 2.21500059 -1.43000325 2 P 0 ;0,1=101,2=0.000000
L 2.21500059 -1.43000325 2.2009999 -1.44000108 2 P 0 ;0,1=101,2=0.000000
L 2.2009999 -1.44000108 2.18100049 -1.445 2 P 0 ;0,1=101,2=0.000000
L 2.18100049 -1.445 2.16100108 -1.44000108 2 P 0 ;0,1=101,2=0.000000
L 2.16100108 -1.44000108 2.14700039 -1.43000325 2 P 0 ;0,1=101,2=0.000000
L 2.14700039 -1.43000325 2.13499931 -1.41500187 2 P 0 ;0,1=101,2=0.000000
L 2.13499931 -1.41500187 2.12699734 -1.39750108 2 P 0 ;0,1=101,2=0.000000
L 2.12699734 -1.39750108 2.12299823 -1.37750069 2 P 0 ;0,1=101,2=0.000000
L 2.12299823 -1.37750069 2.12299823 -1.3599999 2 P 0 ;0,1=101,2=0.000000
L 2.12299823 -1.3599999 2.12699734 -1.34500315 2 P 0 ;0,1=101,2=0.000000
L 2.12699734 -1.34500315 2.13499931 -1.32749764 2 P 0 ;0,1=101,2=0.000000
L 2.13499931 -1.32749764 2.14700039 -1.31250089 2 P 0 ;0,1=101,2=0.000000
L 2.14700039 -1.31250089 2.15899783 -1.30250305 2 P 0 ;0,1=101,2=0.000000
L 2.15899783 -1.30250305 2.17499813 -1.295 2 P 0 ;0,1=101,2=0.000000
L 2.17499813 -1.295 2.18899882 -1.295 2 P 0 ;0,1=101,2=0.000000
L 2.18899882 -1.295 2.20499902 -1.29999902 2 P 0 ;0,1=101,2=0.000000
L 2.20499902 -1.29999902 2.2170001 -1.31000138 2 P 0 ;0,1=101,2=0.000000
L 2.29699892 -1.31999931 2.309 -1.30500246 2 P 0 ;0,1=101,2=0.000000
L 2.309 -1.30500246 2.32300069 -1.29749951 2 P 0 ;0,1=101,2=0.000000
L 2.32300069 -1.29749951 2.33900089 -1.295 2 P 0 ;0,1=101,2=0.000000
L 2.33900089 -1.295 2.3590003 -1.29999902 2 P 0 ;0,1=101,2=0.000000
L 2.3590003 -1.29999902 2.37300098 -1.31250089 2 P 0 ;0,1=101,2=0.000000
L 2.37300098 -1.31250089 2.3770001 -1.32749764 2 P 0 ;0,1=101,2=0.000000
L 2.3770001 -1.32749764 2.37500059 -1.34250364 2 P 0 ;0,1=101,2=0.000000
L 2.37500059 -1.34250364 2.36699862 -1.35500098 2 P 0 ;0,1=101,2=0.000000
L 2.36699862 -1.35500098 2.3269998 -1.3800002 2 P 0 ;0,1=101,2=0.000000
L 2.3269998 -1.3800002 2.309 -1.39750108 2 P 0 ;0,1=101,2=0.000000
L 2.309 -1.39750108 2.29699892 -1.42250482 2 P 0 ;0,1=101,2=0.000000
L 2.29699892 -1.42250482 2.2929998 -1.445 2 P 0 ;0,1=101,2=0.000000
L 2.2929998 -1.445 2.3770001 -1.445 2 P 0 ;0,1=101,2=0.000000
L 2.6129998 -1.42500433 2.629 -1.43750167 2 P 0 ;0,1=101,2=0.000000
L 2.629 -1.43750167 2.6469998 -1.445 2 P 0 ;0,1=101,2=0.000000
L 2.6469998 -1.445 2.6630001 -1.445 2 P 0 ;0,1=101,2=0.000000
L 2.6630001 -1.445 2.6790003 -1.43750167 2 P 0 ;0,1=101,2=0.000000
L 2.6790003 -1.43750167 2.69100138 -1.42500433 2 P 0 ;0,1=101,2=0.000000
L 2.69100138 -1.42500433 2.6970001 -1.40749892 2 P 0 ;0,1=101,2=0.000000
L 2.6970001 -1.40749892 2.69300098 -1.39000266 2 P 0 ;0,1=101,2=0.000000
L 2.69300098 -1.39000266 2.68299951 -1.37500128 2 P 0 ;0,1=101,2=0.000000
L 2.68299951 -1.37500128 2.66499961 -1.36499882 2 P 0 ;0,1=101,2=0.000000
L 2.66499961 -1.36499882 2.64100108 -1.3599999 2 P 0 ;0,1=101,2=0.000000
L 2.64100108 -1.3599999 2.62700039 -1.35000207 2 P 0 ;0,1=101,2=0.000000
L 2.62700039 -1.35000207 2.62099803 -1.33250118 2 P 0 ;0,1=101,2=0.000000
L 2.62099803 -1.33250118 2.62500089 -1.31500039 2 P 0 ;0,1=101,2=0.000000
L 2.62500089 -1.31500039 2.63499872 -1.30250305 2 P 0 ;0,1=101,2=0.000000
L 2.63499872 -1.30250305 2.64899941 -1.295 2 P 0 ;0,1=101,2=0.000000
L 2.64899941 -1.295 2.6630001 -1.295 2 P 0 ;0,1=101,2=0.000000
L 2.6630001 -1.295 2.67700079 -1.29999902 2 P 0 ;0,1=101,2=0.000000
L 2.67700079 -1.29999902 2.68900187 -1.31250089 2 P 0 ;0,1=101,2=0.000000
L 2.7729998 -1.445 2.8570001 -1.295 2 P 0 ;0,1=101,2=0.000000
L 2.7729998 -1.295 2.8570001 -1.445 2 P 0 ;0,1=101,2=0.000000
L 2.92299823 -1.445 2.92299823 -1.295 2 P 0 ;0,1=101,2=0.000000
L 2.92299823 -1.295 2.97499813 -1.42000079 2 P 0 ;0,1=101,2=0.000000
L 2.97499813 -1.42000079 3.02700167 -1.295 2 P 0 ;0,1=101,2=0.000000
L 3.02700167 -1.295 3.02700167 -1.445 2 P 0 ;0,1=101,2=0.000000
L 3.09699892 -1.31999931 3.109 -1.30500246 2 P 0 ;0,1=101,2=0.000000
L 3.109 -1.30500246 3.12300069 -1.29749951 2 P 0 ;0,1=101,2=0.000000
L 3.12300069 -1.29749951 3.13900089 -1.295 2 P 0 ;0,1=101,2=0.000000
L 3.13900089 -1.295 3.1590003 -1.29999902 2 P 0 ;0,1=101,2=0.000000
L 3.1590003 -1.29999902 3.17300098 -1.31250089 2 P 0 ;0,1=101,2=0.000000
L 3.17300098 -1.31250089 3.1770001 -1.32749764 2 P 0 ;0,1=101,2=0.000000
L 3.1770001 -1.32749764 3.17500059 -1.34250364 2 P 0 ;0,1=101,2=0.000000
L 3.17500059 -1.34250364 3.16699862 -1.35500098 2 P 0 ;0,1=101,2=0.000000
L 3.16699862 -1.35500098 3.1269998 -1.3800002 2 P 0 ;0,1=101,2=0.000000
L 3.1269998 -1.3800002 3.109 -1.39750108 2 P 0 ;0,1=101,2=0.000000
L 3.109 -1.39750108 3.09699892 -1.42250482 2 P 0 ;0,1=101,2=0.000000
L 3.09699892 -1.42250482 3.0929998 -1.445 2 P 0 ;0,1=101,2=0.000000
L 3.0929998 -1.445 3.1770001 -1.445 2 P 0 ;0,1=101,2=0.000000
L 3.269 -1.39500157 3.3209999 -1.39500157 2 P 0 ;0,1=101,2=0.000000
L 3.41499931 -1.445 3.41499931 -1.295 2 P 0 ;0,1=101,2=0.000000
L 3.41499931 -1.295 3.46499961 -1.295 2 P 0 ;0,1=101,2=0.000000
L 3.46499961 -1.295 3.4809999 -1.30250305 2 P 0 ;0,1=101,2=0.000000
L 3.4809999 -1.30250305 3.49100138 -1.31250089 2 P 0 ;0,1=101,2=0.000000
L 3.49100138 -1.31250089 3.49500059 -1.33250118 2 P 0 ;0,1=101,2=0.000000
L 3.49500059 -1.33250118 3.49100138 -1.35250148 2 P 0 ;0,1=101,2=0.000000
L 3.49100138 -1.35250148 3.4790003 -1.36499882 2 P 0 ;0,1=101,2=0.000000
L 3.4790003 -1.36499882 3.46499961 -1.37250177 2 P 0 ;0,1=101,2=0.000000
L 3.46499961 -1.37250177 3.41499931 -1.37250177 2 P 0 ;0,1=101,2=0.000000
L 3.46499961 -1.37250177 3.49500059 -1.445 2 P 0 ;0,1=101,2=0.000000
L 3.61499813 -1.34500315 3.61499813 -1.445 2 P 0 ;0,1=101,2=0.000000
L 3.61499813 -1.30500246 3.61099902 -1.30250305 2 P 0 ;0,1=101,2=0.000000
L 3.61099902 -1.30250305 3.61099902 -1.29749951 2 P 0 ;0,1=101,2=0.000000
L 3.61099902 -1.29749951 3.61499813 -1.295 2 P 0 ;0,1=101,2=0.000000
L 3.61499813 -1.295 3.61900089 -1.29749951 2 P 0 ;0,1=101,2=0.000000
L 3.61900089 -1.29749951 3.61900089 -1.30250305 2 P 0 ;0,1=101,2=0.000000
L 3.61900089 -1.30250305 3.61499813 -1.30500246 2 P 0 ;0,1=101,2=0.000000
L 3.74500089 -1.42750374 3.75499872 -1.43750167 2 P 0 ;0,1=101,2=0.000000
L 3.75499872 -1.43750167 3.76899941 -1.445 2 P 0 ;0,1=101,2=0.000000
L 3.76899941 -1.445 3.78100049 -1.445 2 P 0 ;0,1=101,2=0.000000
L 3.78100049 -1.445 3.79300157 -1.44000108 2 P 0 ;0,1=101,2=0.000000
L 3.79300157 -1.44000108 3.8009999 -1.43250276 2 P 0 ;0,1=101,2=0.000000
L 3.8009999 -1.43250276 3.80499902 -1.42250482 2 P 0 ;0,1=101,2=0.000000
L 3.80499902 -1.42250482 3.80299951 -1.40749892 2 P 0 ;0,1=101,2=0.000000
L 3.80299951 -1.40749892 3.79500118 -1.40000049 2 P 0 ;0,1=101,2=0.000000
L 3.79500118 -1.40000049 3.75899783 -1.38500374 2 P 0 ;0,1=101,2=0.000000
L 3.75899783 -1.38500374 3.75099961 -1.36749833 2 P 0 ;0,1=101,2=0.000000
L 3.75099961 -1.36749833 3.75499872 -1.35500098 2 P 0 ;0,1=101,2=0.000000
L 3.75499872 -1.35500098 3.76300069 -1.34750256 2 P 0 ;0,1=101,2=0.000000
L 3.76300069 -1.34750256 3.77499813 -1.34500315 2 P 0 ;0,1=101,2=0.000000
L 3.77499813 -1.34500315 3.78699921 -1.34750256 2 P 0 ;0,1=101,2=0.000000
L 3.78699921 -1.34750256 3.7990003 -1.35500098 2 P 0 ;0,1=101,2=0.000000
L 3.90500089 -1.37750069 3.96900187 -1.37750069 2 P 0 ;0,1=101,2=0.000000
L 3.96900187 -1.37750069 3.96299951 -1.3599999 2 P 0 ;0,1=101,2=0.000000
L 3.96299951 -1.3599999 3.95300157 -1.35000207 2 P 0 ;0,1=101,2=0.000000
L 3.95300157 -1.35000207 3.93900089 -1.34500315 2 P 0 ;0,1=101,2=0.000000
L 3.93900089 -1.34500315 3.9250003 -1.34750256 2 P 0 ;0,1=101,2=0.000000
L 3.9250003 -1.34750256 3.91299911 -1.35500098 2 P 0 ;0,1=101,2=0.000000
L 3.91299911 -1.35500098 3.90500089 -1.37250177 2 P 0 ;0,1=101,2=0.000000
L 3.90500089 -1.37250177 3.90099803 -1.38750315 2 P 0 ;0,1=101,2=0.000000
L 3.90099803 -1.38750315 3.90099803 -1.4025 2 P 0 ;0,1=101,2=0.000000
L 3.90099803 -1.4025 3.90500089 -1.41750138 2 P 0 ;0,1=101,2=0.000000
L 3.90500089 -1.41750138 3.91499872 -1.43250276 2 P 0 ;0,1=101,2=0.000000
L 3.91499872 -1.43250276 3.9269998 -1.44250059 2 P 0 ;0,1=101,2=0.000000
L 3.9269998 -1.44250059 3.94100049 -1.445 2 P 0 ;0,1=101,2=0.000000
L 3.94100049 -1.445 3.95500118 -1.44000108 2 P 0 ;0,1=101,2=0.000000
L 3.95500118 -1.44000108 3.96900187 -1.42500433 2 P 0 ;0,1=101,2=0.000000
L 4.06700039 -1.445 4.06700039 -1.34500315 2 P 0 ;0,1=101,2=0.000000
L 4.06700039 -1.36499882 4.07699833 -1.35500098 2 P 0 ;0,1=101,2=0.000000
L 4.07699833 -1.35500098 4.0869998 -1.34750256 2 P 0 ;0,1=101,2=0.000000
L 4.0869998 -1.34750256 4.10100049 -1.34500315 2 P 0 ;0,1=101,2=0.000000
L 4.10100049 -1.34500315 4.11099833 -1.34750256 2 P 0 ;0,1=101,2=0.000000
L 4.11099833 -1.34750256 4.12299951 -1.35500098 2 P 0 ;0,1=101,2=0.000000
L 4.16964783 -2.2038 4.21839813 -2.0478 2 P 0 ;0,1=40,2=0.000000
L 4.21839813 -2.0478 4.26715207 -2.2038 2 P 0 ;0,1=40,2=0.000000
L 4.24959862 -2.14920217 4.18719774 -2.14920217 2 P 0 ;0,1=40,2=0.000000
L 4.37939813 -2.2038 4.37939813 -2.0478 2 P 0 ;0,1=40,2=0.000000
L 4.37939813 -2.0478 4.35599961 -2.07899813 2 P 0 ;0,1=40,2=0.000000
L 4.35599961 -2.2038 4.40279675 -2.2038 2 P 0 ;0,1=40,2=0.000000
L 2.0009002 -0.9538 2.0009002 -0.8038 2 P 0 ;0,1=102,2=0.000000
L 2.0009002 -0.8038 2.04089902 -0.8038 2 P 0 ;0,1=102,2=0.000000
L 2.04089902 -0.8038 2.05689921 -0.81130305 2 P 0 ;0,1=102,2=0.000000
L 2.05689921 -0.81130305 2.0689003 -0.82130089 2 P 0 ;0,1=102,2=0.000000
L 2.0689003 -0.82130089 2.07890187 -0.83629764 2 P 0 ;0,1=102,2=0.000000
L 2.07890187 -0.83629764 2.0869001 -0.85380315 2 P 0 ;0,1=102,2=0.000000
L 2.0869001 -0.85380315 2.0888997 -0.87880236 2 P 0 ;0,1=102,2=0.000000
L 2.0888997 -0.87880236 2.0869001 -0.90380157 2 P 0 ;0,1=102,2=0.000000
L 2.0869001 -0.90380157 2.07890187 -0.92130246 2 P 0 ;0,1=102,2=0.000000
L 2.07890187 -0.92130246 2.0689003 -0.93630374 2 P 0 ;0,1=102,2=0.000000
L 2.0689003 -0.93630374 2.05689921 -0.94630167 2 P 0 ;0,1=102,2=0.000000
L 2.05689921 -0.94630167 2.04089902 -0.9538 2 P 0 ;0,1=102,2=0.000000
L 2.04089902 -0.9538 2.0009002 -0.9538 2 P 0 ;0,1=102,2=0.000000
L 2.15489783 -0.9538 2.20489813 -0.8038 2 P 0 ;0,1=102,2=0.000000
L 2.20489813 -0.8038 2.25490207 -0.9538 2 P 0 ;0,1=102,2=0.000000
L 2.23689862 -0.90130207 2.17289764 -0.90130207 2 P 0 ;0,1=102,2=0.000000
L 2.36489813 -0.8038 2.36489813 -0.9538 2 P 0 ;0,1=102,2=0.000000
L 2.31890059 -0.8038 2.41089931 -0.8038 2 P 0 ;0,1=102,2=0.000000
L 2.56490059 -0.9538 2.48489931 -0.9538 2 P 0 ;0,1=102,2=0.000000
L 2.48489931 -0.9538 2.48489931 -0.8038 2 P 0 ;0,1=102,2=0.000000
L 2.48489931 -0.8038 2.56490059 -0.8038 2 P 0 ;0,1=102,2=0.000000
L 2.5329001 -0.87629833 2.48489931 -0.87629833 2 P 0 ;0,1=102,2=0.000000
L 2.84489813 -0.9538 2.82889783 -0.95130059 2 P 0 ;0,1=102,2=0.000000
L 2.82889783 -0.95130059 2.81490089 -0.94130276 2 P 0 ;0,1=102,2=0.000000
L 2.81490089 -0.94130276 2.8028998 -0.92630138 2 P 0 ;0,1=102,2=0.000000
L 2.8028998 -0.92630138 2.79489783 -0.90880049 2 P 0 ;0,1=102,2=0.000000
L 2.79489783 -0.90880049 2.79089862 -0.8888002 2 P 0 ;0,1=102,2=0.000000
L 2.79089862 -0.8888002 2.79089862 -0.8687999 2 P 0 ;0,1=102,2=0.000000
L 2.79089862 -0.8687999 2.79489783 -0.84879961 2 P 0 ;0,1=102,2=0.000000
L 2.79489783 -0.84879961 2.8028998 -0.83129872 2 P 0 ;0,1=102,2=0.000000
L 2.8028998 -0.83129872 2.81490089 -0.81630197 2 P 0 ;0,1=102,2=0.000000
L 2.81490089 -0.81630197 2.82889783 -0.80629951 2 P 0 ;0,1=102,2=0.000000
L 2.82889783 -0.80629951 2.84489813 -0.8038 2 P 0 ;0,1=102,2=0.000000
L 2.84489813 -0.8038 2.86089833 -0.80629951 2 P 0 ;0,1=102,2=0.000000
L 2.86089833 -0.80629951 2.87489902 -0.81630197 2 P 0 ;0,1=102,2=0.000000
L 2.87489902 -0.81630197 2.8869001 -0.83129872 2 P 0 ;0,1=102,2=0.000000
L 2.8869001 -0.83129872 2.89490207 -0.84879961 2 P 0 ;0,1=102,2=0.000000
L 2.89490207 -0.84879961 2.89890128 -0.8687999 2 P 0 ;0,1=102,2=0.000000
L 2.89890128 -0.8687999 2.89890128 -0.8888002 2 P 0 ;0,1=102,2=0.000000
L 2.89890128 -0.8888002 2.89490207 -0.90880049 2 P 0 ;0,1=102,2=0.000000
L 2.89490207 -0.90880049 2.8869001 -0.92630138 2 P 0 ;0,1=102,2=0.000000
L 2.8869001 -0.92630138 2.87489902 -0.94130276 2 P 0 ;0,1=102,2=0.000000
L 2.87489902 -0.94130276 2.86089833 -0.95130059 2 P 0 ;0,1=102,2=0.000000
L 2.86089833 -0.95130059 2.84489813 -0.9538 2 P 0 ;0,1=102,2=0.000000
L 3.0488997 -0.81630197 3.03689862 -0.80879902 2 P 0 ;0,1=102,2=0.000000
L 3.03689862 -0.80879902 3.02290157 -0.8038 2 P 0 ;0,1=102,2=0.000000
L 3.02290157 -0.8038 3.00690138 -0.8038 2 P 0 ;0,1=102,2=0.000000
L 3.00690138 -0.8038 2.98889783 -0.81130305 2 P 0 ;0,1=102,2=0.000000
L 2.98889783 -0.81130305 2.97490089 -0.82380039 2 P 0 ;0,1=102,2=0.000000
L 2.97490089 -0.82380039 2.96489931 -0.83880177 2 P 0 ;0,1=102,2=0.000000
L 2.96489931 -0.83880177 2.95689734 -0.86380098 2 P 0 ;0,1=102,2=0.000000
L 2.95689734 -0.86380098 2.95489783 -0.88630069 2 P 0 ;0,1=102,2=0.000000
L 2.95489783 -0.88630069 2.95890059 -0.90880049 2 P 0 ;0,1=102,2=0.000000
L 2.95890059 -0.90880049 2.96489931 -0.92380187 2 P 0 ;0,1=102,2=0.000000
L 2.96489931 -0.92380187 2.97690039 -0.93880325 2 P 0 ;0,1=102,2=0.000000
L 2.97690039 -0.93880325 2.99090108 -0.94880108 2 P 0 ;0,1=102,2=0.000000
L 2.99090108 -0.94880108 3.00489813 -0.9538 2 P 0 ;0,1=102,2=0.000000
L 3.00489813 -0.9538 3.01889882 -0.9538 2 P 0 ;0,1=102,2=0.000000
L 3.01889882 -0.9538 3.03289951 -0.94880108 2 P 0 ;0,1=102,2=0.000000
L 3.03289951 -0.94880108 3.04490059 -0.94130276 2 P 0 ;0,1=102,2=0.000000
L 3.04490059 -0.94130276 3.05490207 -0.93130482 2 P 0 ;0,1=102,2=0.000000
L 3.16489813 -0.8038 3.16489813 -0.9538 2 P 0 ;0,1=102,2=0.000000
L 3.11890059 -0.8038 3.21089931 -0.8038 2 P 0 ;0,1=102,2=0.000000
L 3.28889852 -0.95879892 3.36090138 -0.8038 2 P 0 ;0,1=102,2=0.000000
L 3.44689892 -0.82879931 3.4589 -0.81380246 2 P 0 ;0,1=102,2=0.000000
L 3.4589 -0.81380246 3.47290069 -0.80629951 2 P 0 ;0,1=102,2=0.000000
L 3.47290069 -0.80629951 3.48890089 -0.8038 2 P 0 ;0,1=102,2=0.000000
L 3.48890089 -0.8038 3.5089003 -0.80879902 2 P 0 ;0,1=102,2=0.000000
L 3.5089003 -0.80879902 3.52290098 -0.82130089 2 P 0 ;0,1=102,2=0.000000
L 3.52290098 -0.82130089 3.5269001 -0.83629764 2 P 0 ;0,1=102,2=0.000000
L 3.5269001 -0.83629764 3.52490059 -0.85130364 2 P 0 ;0,1=102,2=0.000000
L 3.52490059 -0.85130364 3.51689862 -0.86380098 2 P 0 ;0,1=102,2=0.000000
L 3.51689862 -0.86380098 3.4768998 -0.8888002 2 P 0 ;0,1=102,2=0.000000
L 3.4768998 -0.8888002 3.4589 -0.90630108 2 P 0 ;0,1=102,2=0.000000
L 3.4589 -0.90630108 3.44689892 -0.93130482 2 P 0 ;0,1=102,2=0.000000
L 3.44689892 -0.93130482 3.4428998 -0.9538 2 P 0 ;0,1=102,2=0.000000
L 3.4428998 -0.9538 3.5269001 -0.9538 2 P 0 ;0,1=102,2=0.000000
L 3.64089902 -0.9538 3.64489813 -0.92130246 2 P 0 ;0,1=102,2=0.000000
L 3.64489813 -0.92130246 3.65090049 -0.89380374 2 P 0 ;0,1=102,2=0.000000
L 3.65090049 -0.89380374 3.65889882 -0.8687999 2 P 0 ;0,1=102,2=0.000000
L 3.65889882 -0.8687999 3.6689003 -0.84130118 2 P 0 ;0,1=102,2=0.000000
L 3.6689003 -0.84130118 3.68490059 -0.8038 2 P 0 ;0,1=102,2=0.000000
L 3.68490059 -0.8038 3.60489931 -0.8038 2 P 0 ;0,1=102,2=0.000000
L 3.76889852 -0.95879892 3.84090138 -0.8038 2 P 0 ;0,1=102,2=0.000000
L 3.92689892 -0.82879931 3.9389 -0.81380246 2 P 0 ;0,1=102,2=0.000000
L 3.9389 -0.81380246 3.95290069 -0.80629951 2 P 0 ;0,1=102,2=0.000000
L 3.95290069 -0.80629951 3.96890089 -0.8038 2 P 0 ;0,1=102,2=0.000000
L 3.96890089 -0.8038 3.9889003 -0.80879902 2 P 0 ;0,1=102,2=0.000000
L 3.9889003 -0.80879902 4.00290098 -0.82130089 2 P 0 ;0,1=102,2=0.000000
L 4.00290098 -0.82130089 4.0069001 -0.83629764 2 P 0 ;0,1=102,2=0.000000
L 4.0069001 -0.83629764 4.00490059 -0.85130364 2 P 0 ;0,1=102,2=0.000000
L 4.00490059 -0.85130364 3.99689862 -0.86380098 2 P 0 ;0,1=102,2=0.000000
L 3.99689862 -0.86380098 3.9568998 -0.8888002 2 P 0 ;0,1=102,2=0.000000
L 3.9568998 -0.8888002 3.9389 -0.90630108 2 P 0 ;0,1=102,2=0.000000
L 3.9389 -0.90630108 3.92689892 -0.93130482 2 P 0 ;0,1=102,2=0.000000
L 3.92689892 -0.93130482 3.9228998 -0.9538 2 P 0 ;0,1=102,2=0.000000
L 3.9228998 -0.9538 4.0069001 -0.9538 2 P 0 ;0,1=102,2=0.000000
L 4.12489813 -0.8038 4.10889783 -0.80879902 2 P 0 ;0,1=102,2=0.000000
L 4.10889783 -0.80879902 4.09690039 -0.82130089 2 P 0 ;0,1=102,2=0.000000
L 4.09690039 -0.82130089 4.08889852 -0.83629764 2 P 0 ;0,1=102,2=0.000000
L 4.08889852 -0.83629764 4.0828998 -0.85630256 2 P 0 ;0,1=102,2=0.000000
L 4.0828998 -0.85630256 4.0809002 -0.87880236 2 P 0 ;0,1=102,2=0.000000
L 4.0809002 -0.87880236 4.0828998 -0.90130207 2 P 0 ;0,1=102,2=0.000000
L 4.0828998 -0.90130207 4.08889852 -0.92130246 2 P 0 ;0,1=102,2=0.000000
L 4.08889852 -0.92130246 4.09690039 -0.93630374 2 P 0 ;0,1=102,2=0.000000
L 4.09690039 -0.93630374 4.10889783 -0.94880108 2 P 0 ;0,1=102,2=0.000000
L 4.10889783 -0.94880108 4.12489813 -0.9538 2 P 0 ;0,1=102,2=0.000000
L 4.12489813 -0.9538 4.14089833 -0.94880108 2 P 0 ;0,1=102,2=0.000000
L 4.14089833 -0.94880108 4.15289951 -0.93630374 2 P 0 ;0,1=102,2=0.000000
L 4.15289951 -0.93630374 4.16090138 -0.92130246 2 P 0 ;0,1=102,2=0.000000
L 4.16090138 -0.92130246 4.1669001 -0.90130207 2 P 0 ;0,1=102,2=0.000000
L 4.1669001 -0.90130207 4.1688997 -0.87880236 2 P 0 ;0,1=102,2=0.000000
L 4.1688997 -0.87880236 4.1669001 -0.85630256 2 P 0 ;0,1=102,2=0.000000
L 4.1669001 -0.85630256 4.16090138 -0.83629764 2 P 0 ;0,1=102,2=0.000000
L 4.16090138 -0.83629764 4.15289951 -0.82130089 2 P 0 ;0,1=102,2=0.000000
L 4.15289951 -0.82130089 4.14089833 -0.80879902 2 P 0 ;0,1=102,2=0.000000
L 4.14089833 -0.80879902 4.12489813 -0.8038 2 P 0 ;0,1=102,2=0.000000
L 4.28489813 -0.9538 4.28489813 -0.8038 2 P 0 ;0,1=102,2=0.000000
L 4.28489813 -0.8038 4.26089961 -0.83379823 2 P 0 ;0,1=102,2=0.000000
L 4.26089961 -0.9538 4.30889665 -0.9538 2 P 0 ;0,1=102,2=0.000000
L 4.44089902 -0.9538 4.44489813 -0.92130246 2 P 0 ;0,1=102,2=0.000000
L 4.44489813 -0.92130246 4.45090049 -0.89380374 2 P 0 ;0,1=102,2=0.000000
L 4.45090049 -0.89380374 4.45889882 -0.8687999 2 P 0 ;0,1=102,2=0.000000
L 4.45889882 -0.8687999 4.4689003 -0.84130118 2 P 0 ;0,1=102,2=0.000000
L 4.4689003 -0.84130118 4.48490059 -0.8038 2 P 0 ;0,1=102,2=0.000000
L 4.48490059 -0.8038 4.40489931 -0.8038 2 P 0 ;0,1=102,2=0.000000
L 12.38089321 6.19586998 12.38089321 6.22086998 2 P 0 ;0,1=103,2=0.000000
L 12.38089321 6.22086998 12.39102677 6.22086998 2 P 0 ;0,1=103,2=0.000000
L 12.38729331 6.20878691 12.38089321 6.20878691 2 P 0 ;0,1=103,2=0.000000
L 12.40409331 6.19586998 12.40409331 6.22086998 2 P 0 ;0,1=103,2=0.000000
L 12.40409331 6.22086998 12.40942657 6.22086998 2 P 0 ;0,1=103,2=0.000000
L 12.40942657 6.22086998 12.41155994 6.21961939 2 P 0 ;0,1=103,2=0.000000
L 12.41155994 6.21961939 12.41316004 6.21795315 2 P 0 ;0,1=103,2=0.000000
L 12.41316004 6.21795315 12.4144936 6.21545364 2 P 0 ;0,1=103,2=0.000000
L 12.4144936 6.21545364 12.41556004 6.21253612 2 P 0 ;0,1=103,2=0.000000
L 12.41556004 6.21253612 12.41582667 6.20836959 2 P 0 ;0,1=103,2=0.000000
L 12.41582667 6.20836959 12.41556004 6.20420305 2 P 0 ;0,1=103,2=0.000000
L 12.41556004 6.20420305 12.4144936 6.20128622 2 P 0 ;0,1=103,2=0.000000
L 12.4144936 6.20128622 12.41316004 6.19878602 2 P 0 ;0,1=103,2=0.000000
L 12.41316004 6.19878602 12.41155994 6.19711969 2 P 0 ;0,1=103,2=0.000000
L 12.41155994 6.19711969 12.40942657 6.19586998 2 P 0 ;0,1=103,2=0.000000
L 12.40942657 6.19586998 12.40409331 6.19586998 2 P 0 ;0,1=103,2=0.000000
L 12.43395974 6.19586998 12.43395974 6.22086998 2 P 0 ;0,1=103,2=0.000000
L 12.43395974 6.22086998 12.43075994 6.21587028 2 P 0 ;0,1=103,2=0.000000
L 12.43075994 6.19586998 12.43715955 6.19586998 2 P 0 ;0,1=103,2=0.000000
L 12.45209331 6.20086959 12.45369301 6.19795285 2 P 0 ;0,1=103,2=0.000000
L 12.45369301 6.19795285 12.45582638 6.19628652 2 P 0 ;0,1=103,2=0.000000
L 12.45582638 6.19628652 12.45822687 6.19586998 2 P 0 ;0,1=103,2=0.000000
L 12.45822687 6.19586998 12.46036024 6.19628652 2 P 0 ;0,1=103,2=0.000000
L 12.46036024 6.19628652 12.4624936 6.19836939 2 P 0 ;0,1=103,2=0.000000
L 12.4624936 6.19836939 12.46382667 6.20086959 2 P 0 ;0,1=103,2=0.000000
L 12.46382667 6.20086959 12.46409321 6.20336988 2 P 0 ;0,1=103,2=0.000000
L 12.46409321 6.20336988 12.46356004 6.20628593 2 P 0 ;0,1=103,2=0.000000
L 12.46356004 6.20628593 12.46169331 6.20836959 2 P 0 ;0,1=103,2=0.000000
L 12.46169331 6.20836959 12.45982648 6.20920344 2 P 0 ;0,1=103,2=0.000000
L 12.45982648 6.20920344 12.45742657 6.20920344 2 P 0 ;0,1=103,2=0.000000
L 12.45982648 6.20920344 12.46142667 6.21045325 2 P 0 ;0,1=103,2=0.000000
L 12.46142667 6.21045325 12.46276014 6.21253612 2 P 0 ;0,1=103,2=0.000000
L 12.46276014 6.21253612 12.46329341 6.21503632 2 P 0 ;0,1=103,2=0.000000
L 12.46329341 6.21503632 12.46276014 6.21753652 2 P 0 ;0,1=103,2=0.000000
L 12.46276014 6.21753652 12.46142667 6.21961939 2 P 0 ;0,1=103,2=0.000000
L 12.46142667 6.21961939 12.45902667 6.22086998 2 P 0 ;0,1=103,2=0.000000
L 12.45902667 6.22086998 12.45662667 6.22045335 2 P 0 ;0,1=103,2=0.000000
L 12.45662667 6.22045335 12.45422667 6.21878632 2 P 0 ;0,1=103,2=0.000000
L 0.45793317 6.45 0.45793317 6.475 2 P 0 ;0,1=104,2=0.000000
L 0.45793317 6.475 0.46806673 6.475 2 P 0 ;0,1=104,2=0.000000
L 0.46433327 6.46291693 0.45793317 6.46291693 2 P 0 ;0,1=104,2=0.000000
L 0.48113327 6.45 0.48113327 6.475 2 P 0 ;0,1=104,2=0.000000
L 0.48113327 6.475 0.48646654 6.475 2 P 0 ;0,1=104,2=0.000000
L 0.48646654 6.475 0.4885999 6.47374941 2 P 0 ;0,1=104,2=0.000000
L 0.4885999 6.47374941 0.4902 6.47208317 2 P 0 ;0,1=104,2=0.000000
L 0.4902 6.47208317 0.49153356 6.46958366 2 P 0 ;0,1=104,2=0.000000
L 0.49153356 6.46958366 0.4926 6.46666614 2 P 0 ;0,1=104,2=0.000000
L 0.4926 6.46666614 0.49286663 6.46249961 2 P 0 ;0,1=104,2=0.000000
L 0.49286663 6.46249961 0.4926 6.45833307 2 P 0 ;0,1=104,2=0.000000
L 0.4926 6.45833307 0.49153356 6.45541624 2 P 0 ;0,1=104,2=0.000000
L 0.49153356 6.45541624 0.4902 6.45291604 2 P 0 ;0,1=104,2=0.000000
L 0.4902 6.45291604 0.4885999 6.4512497 2 P 0 ;0,1=104,2=0.000000
L 0.4885999 6.4512497 0.48646654 6.45 2 P 0 ;0,1=104,2=0.000000
L 0.48646654 6.45 0.48113327 6.45 2 P 0 ;0,1=104,2=0.000000
L 0.5109997 6.45 0.5109997 6.475 2 P 0 ;0,1=104,2=0.000000
L 0.5109997 6.475 0.5077999 6.4700003 2 P 0 ;0,1=104,2=0.000000
L 0.5077999 6.45 0.51419951 6.45 2 P 0 ;0,1=104,2=0.000000
L 0.5382 6.45 0.5382 6.475 2 P 0 ;0,1=104,2=0.000000
L 0.5382 6.475 0.52833297 6.45708327 2 P 0 ;0,1=104,2=0.000000
L 0.52833297 6.45708327 0.54166693 6.45708327 2 P 0 ;0,1=104,2=0.000000
L 12.38793317 -0.415 12.38793317 -0.39 2 P 0 ;0,1=105,2=0.000000
L 12.38793317 -0.39 12.39806673 -0.39 2 P 0 ;0,1=105,2=0.000000
L 12.39433327 -0.40208307 12.38793317 -0.40208307 2 P 0 ;0,1=105,2=0.000000
L 12.41113327 -0.415 12.41113327 -0.39 2 P 0 ;0,1=105,2=0.000000
L 12.41113327 -0.39 12.41646654 -0.39 2 P 0 ;0,1=105,2=0.000000
L 12.41646654 -0.39 12.4185999 -0.39125059 2 P 0 ;0,1=105,2=0.000000
L 12.4185999 -0.39125059 12.4202 -0.39291683 2 P 0 ;0,1=105,2=0.000000
L 12.4202 -0.39291683 12.42153356 -0.39541634 2 P 0 ;0,1=105,2=0.000000
L 12.42153356 -0.39541634 12.4226 -0.39833386 2 P 0 ;0,1=105,2=0.000000
L 12.4226 -0.39833386 12.42286663 -0.40250039 2 P 0 ;0,1=105,2=0.000000
L 12.42286663 -0.40250039 12.4226 -0.40666693 2 P 0 ;0,1=105,2=0.000000
L 12.4226 -0.40666693 12.42153356 -0.40958376 2 P 0 ;0,1=105,2=0.000000
L 12.42153356 -0.40958376 12.4202 -0.41208396 2 P 0 ;0,1=105,2=0.000000
L 12.4202 -0.41208396 12.4185999 -0.4137503 2 P 0 ;0,1=105,2=0.000000
L 12.4185999 -0.4137503 12.41646654 -0.415 2 P 0 ;0,1=105,2=0.000000
L 12.41646654 -0.415 12.41113327 -0.415 2 P 0 ;0,1=105,2=0.000000
L 12.4409997 -0.415 12.4409997 -0.39 2 P 0 ;0,1=105,2=0.000000
L 12.4409997 -0.39 12.4377999 -0.3949997 2 P 0 ;0,1=105,2=0.000000
L 12.4377999 -0.415 12.44419951 -0.415 2 P 0 ;0,1=105,2=0.000000
L 12.45913327 -0.41125089 12.46073297 -0.41333376 2 P 0 ;0,1=105,2=0.000000
L 12.46073297 -0.41333376 12.4625997 -0.41458346 2 P 0 ;0,1=105,2=0.000000
L 12.4625997 -0.41458346 12.4649997 -0.415 2 P 0 ;0,1=105,2=0.000000
L 12.4649997 -0.415 12.4674002 -0.41416693 2 P 0 ;0,1=105,2=0.000000
L 12.4674002 -0.41416693 12.46926644 -0.41250059 2 P 0 ;0,1=105,2=0.000000
L 12.46926644 -0.41250059 12.4706 -0.40958376 2 P 0 ;0,1=105,2=0.000000
L 12.4706 -0.40958376 12.47086663 -0.40625039 2 P 0 ;0,1=105,2=0.000000
L 12.47086663 -0.40625039 12.47033337 -0.40291703 2 P 0 ;0,1=105,2=0.000000
L 12.47033337 -0.40291703 12.4689998 -0.40083337 2 P 0 ;0,1=105,2=0.000000
L 12.4689998 -0.40083337 12.46713307 -0.39916703 2 P 0 ;0,1=105,2=0.000000
L 12.46713307 -0.39916703 12.46526683 -0.39875049 2 P 0 ;0,1=105,2=0.000000
L 12.46526683 -0.39875049 12.4634 -0.39916703 2 P 0 ;0,1=105,2=0.000000
L 12.4634 -0.39916703 12.4610001 -0.40083337 2 P 0 ;0,1=105,2=0.000000
L 12.4610001 -0.40083337 12.4617999 -0.39 2 P 0 ;0,1=105,2=0.000000
L 12.4617999 -0.39 12.4689998 -0.39 2 P 0 ;0,1=105,2=0.000000
L 0.47293317 -0.2 0.47293317 -0.175 2 P 0 ;0,1=106,2=0.000000
L 0.47293317 -0.175 0.48306673 -0.175 2 P 0 ;0,1=106,2=0.000000
L 0.47933327 -0.18708307 0.47293317 -0.18708307 2 P 0 ;0,1=106,2=0.000000
L 0.49613327 -0.2 0.49613327 -0.175 2 P 0 ;0,1=106,2=0.000000
L 0.49613327 -0.175 0.50146654 -0.175 2 P 0 ;0,1=106,2=0.000000
L 0.50146654 -0.175 0.5035999 -0.17625059 2 P 0 ;0,1=106,2=0.000000
L 0.5035999 -0.17625059 0.5052 -0.17791683 2 P 0 ;0,1=106,2=0.000000
L 0.5052 -0.17791683 0.50653356 -0.18041634 2 P 0 ;0,1=106,2=0.000000
L 0.50653356 -0.18041634 0.5076 -0.18333386 2 P 0 ;0,1=106,2=0.000000
L 0.5076 -0.18333386 0.50786663 -0.18750039 2 P 0 ;0,1=106,2=0.000000
L 0.50786663 -0.18750039 0.5076 -0.19166693 2 P 0 ;0,1=106,2=0.000000
L 0.5076 -0.19166693 0.50653356 -0.19458376 2 P 0 ;0,1=106,2=0.000000
L 0.50653356 -0.19458376 0.5052 -0.19708396 2 P 0 ;0,1=106,2=0.000000
L 0.5052 -0.19708396 0.5035999 -0.1987503 2 P 0 ;0,1=106,2=0.000000
L 0.5035999 -0.1987503 0.50146654 -0.2 2 P 0 ;0,1=106,2=0.000000
L 0.50146654 -0.2 0.49613327 -0.2 2 P 0 ;0,1=106,2=0.000000
L 0.52093317 -0.17916663 0.52253327 -0.17666713 2 P 0 ;0,1=106,2=0.000000
L 0.52253327 -0.17666713 0.5244 -0.17541663 2 P 0 ;0,1=106,2=0.000000
L 0.5244 -0.17541663 0.52653337 -0.175 2 P 0 ;0,1=106,2=0.000000
L 0.52653337 -0.175 0.5292 -0.17583317 2 P 0 ;0,1=106,2=0.000000
L 0.5292 -0.17583317 0.53106673 -0.17791683 2 P 0 ;0,1=106,2=0.000000
L 0.53106673 -0.17791683 0.5316 -0.18041634 2 P 0 ;0,1=106,2=0.000000
L 0.5316 -0.18041634 0.53133337 -0.18291732 2 P 0 ;0,1=106,2=0.000000
L 0.53133337 -0.18291732 0.53026644 -0.1850002 2 P 0 ;0,1=106,2=0.000000
L 0.53026644 -0.1850002 0.52493327 -0.18916673 2 P 0 ;0,1=106,2=0.000000
L 0.52493327 -0.18916673 0.52253327 -0.19208356 2 P 0 ;0,1=106,2=0.000000
L 0.52253327 -0.19208356 0.52093317 -0.19625089 2 P 0 ;0,1=106,2=0.000000
L 0.52093317 -0.19625089 0.5203999 -0.2 2 P 0 ;0,1=106,2=0.000000
L 0.5203999 -0.2 0.5316 -0.2 2 P 0 ;0,1=106,2=0.000000
L 11.95793317 0.17 11.95793317 0.195 2 P 0 ;0,1=107,2=0.000000
L 11.95793317 0.195 11.96806673 0.195 2 P 0 ;0,1=107,2=0.000000
L 11.96433327 0.18291693 11.95793317 0.18291693 2 P 0 ;0,1=107,2=0.000000
L 11.98113327 0.17 11.98113327 0.195 2 P 0 ;0,1=107,2=0.000000
L 11.98113327 0.195 11.98646654 0.195 2 P 0 ;0,1=107,2=0.000000
L 11.98646654 0.195 11.9885999 0.19374941 2 P 0 ;0,1=107,2=0.000000
L 11.9885999 0.19374941 11.9902 0.19208317 2 P 0 ;0,1=107,2=0.000000
L 11.9902 0.19208317 11.99153356 0.18958366 2 P 0 ;0,1=107,2=0.000000
L 11.99153356 0.18958366 11.9926 0.18666614 2 P 0 ;0,1=107,2=0.000000
L 11.9926 0.18666614 11.99286663 0.18249961 2 P 0 ;0,1=107,2=0.000000
L 11.99286663 0.18249961 11.9926 0.17833307 2 P 0 ;0,1=107,2=0.000000
L 11.9926 0.17833307 11.99153356 0.17541624 2 P 0 ;0,1=107,2=0.000000
L 11.99153356 0.17541624 11.9902 0.17291604 2 P 0 ;0,1=107,2=0.000000
L 11.9902 0.17291604 11.9885999 0.1712497 2 P 0 ;0,1=107,2=0.000000
L 11.9885999 0.1712497 11.98646654 0.17 2 P 0 ;0,1=107,2=0.000000
L 11.98646654 0.17 11.98113327 0.17 2 P 0 ;0,1=107,2=0.000000
L 12.01046654 0.17 12.0109997 0.17541624 2 P 0 ;0,1=107,2=0.000000
L 12.0109997 0.17541624 12.0118 0.17999931 2 P 0 ;0,1=107,2=0.000000
L 12.0118 0.17999931 12.01286644 0.18416663 2 P 0 ;0,1=107,2=0.000000
L 12.01286644 0.18416663 12.0142 0.1887498 2 P 0 ;0,1=107,2=0.000000
L 12.0142 0.1887498 12.01633337 0.195 2 P 0 ;0,1=107,2=0.000000
L 12.01633337 0.195 12.00566654 0.195 2 P 0 ;0,1=107,2=0.000000
L 0.89403317 0.1604 0.89403317 0.1854 2 P 0 ;0,1=108,2=0.000000
L 0.89403317 0.1854 0.90416673 0.1854 2 P 0 ;0,1=108,2=0.000000
L 0.90043327 0.17331693 0.89403317 0.17331693 2 P 0 ;0,1=108,2=0.000000
L 0.91723327 0.1604 0.91723327 0.1854 2 P 0 ;0,1=108,2=0.000000
L 0.91723327 0.1854 0.92256654 0.1854 2 P 0 ;0,1=108,2=0.000000
L 0.92256654 0.1854 0.9246999 0.18414941 2 P 0 ;0,1=108,2=0.000000
L 0.9246999 0.18414941 0.9263 0.18248317 2 P 0 ;0,1=108,2=0.000000
L 0.9263 0.18248317 0.92763356 0.17998366 2 P 0 ;0,1=108,2=0.000000
L 0.92763356 0.17998366 0.9287 0.17706614 2 P 0 ;0,1=108,2=0.000000
L 0.9287 0.17706614 0.92896663 0.17289961 2 P 0 ;0,1=108,2=0.000000
L 0.92896663 0.17289961 0.9287 0.16873307 2 P 0 ;0,1=108,2=0.000000
L 0.9287 0.16873307 0.92763356 0.16581624 2 P 0 ;0,1=108,2=0.000000
L 0.92763356 0.16581624 0.9263 0.16331604 2 P 0 ;0,1=108,2=0.000000
L 0.9263 0.16331604 0.9246999 0.1616497 2 P 0 ;0,1=108,2=0.000000
L 0.9246999 0.1616497 0.92256654 0.1604 2 P 0 ;0,1=108,2=0.000000
L 0.92256654 0.1604 0.91723327 0.1604 2 P 0 ;0,1=108,2=0.000000
L 0.9470997 0.1604 0.94896644 0.16081654 2 P 0 ;0,1=108,2=0.000000
L 0.94896644 0.16081654 0.9510998 0.16206624 2 P 0 ;0,1=108,2=0.000000
L 0.9510998 0.16206624 0.95243337 0.16414911 2 P 0 ;0,1=108,2=0.000000
L 0.95243337 0.16414911 0.95296663 0.16706673 2 P 0 ;0,1=108,2=0.000000
L 0.95296663 0.16706673 0.95243337 0.16998278 2 P 0 ;0,1=108,2=0.000000
L 0.95243337 0.16998278 0.95083327 0.17248297 2 P 0 ;0,1=108,2=0.000000
L 0.95083327 0.17248297 0.94843327 0.17373346 2 P 0 ;0,1=108,2=0.000000
L 0.94843327 0.17373346 0.94576663 0.17373346 2 P 0 ;0,1=108,2=0.000000
L 0.94576663 0.17373346 0.94416654 0.17456663 2 P 0 ;0,1=108,2=0.000000
L 0.94416654 0.17456663 0.94283297 0.17664951 2 P 0 ;0,1=108,2=0.000000
L 0.94283297 0.17664951 0.9422998 0.17956634 2 P 0 ;0,1=108,2=0.000000
L 0.9422998 0.17956634 0.9431001 0.18248317 2 P 0 ;0,1=108,2=0.000000
L 0.9431001 0.18248317 0.94496634 0.18456683 2 P 0 ;0,1=108,2=0.000000
L 0.94496634 0.18456683 0.9470997 0.1854 2 P 0 ;0,1=108,2=0.000000
L 0.9470997 0.1854 0.94923307 0.18456683 2 P 0 ;0,1=108,2=0.000000
L 0.94923307 0.18456683 0.9510998 0.18248317 2 P 0 ;0,1=108,2=0.000000
L 0.9510998 0.18248317 0.9519001 0.17956634 2 P 0 ;0,1=108,2=0.000000
L 0.9519001 0.17956634 0.95136644 0.17664951 2 P 0 ;0,1=108,2=0.000000
L 0.95136644 0.17664951 0.95003337 0.17456663 2 P 0 ;0,1=108,2=0.000000
L 0.95003337 0.17456663 0.94843327 0.17373346 2 P 0 ;0,1=108,2=0.000000
L 0.94843327 0.17373346 0.94576663 0.17373346 2 P 0 ;0,1=108,2=0.000000
L 0.94576663 0.17373346 0.94336663 0.17248297 2 P 0 ;0,1=108,2=0.000000
L 0.94336663 0.17248297 0.94176654 0.16998278 2 P 0 ;0,1=108,2=0.000000
L 0.94176654 0.16998278 0.94123327 0.16706673 2 P 0 ;0,1=108,2=0.000000
L 0.94123327 0.16706673 0.94176654 0.16414911 2 P 0 ;0,1=108,2=0.000000
L 0.94176654 0.16414911 0.9431001 0.16206624 2 P 0 ;0,1=108,2=0.000000
L 0.9431001 0.16206624 0.94523346 0.16081654 2 P 0 ;0,1=108,2=0.000000
L 0.94523346 0.16081654 0.9470997 0.1604 2 P 0 ;0,1=108,2=0.000000
L 0.55653317 5.2537 0.55653317 5.2787 2 P 0 ;0,1=109,2=0.000000
L 0.55653317 5.2787 0.56666673 5.2787 2 P 0 ;0,1=109,2=0.000000
L 0.56293327 5.26661693 0.55653317 5.26661693 2 P 0 ;0,1=109,2=0.000000
L 0.57973327 5.2537 0.57973327 5.2787 2 P 0 ;0,1=109,2=0.000000
L 0.57973327 5.2787 0.58506654 5.2787 2 P 0 ;0,1=109,2=0.000000
L 0.58506654 5.2787 0.5871999 5.27744941 2 P 0 ;0,1=109,2=0.000000
L 0.5871999 5.27744941 0.5888 5.27578317 2 P 0 ;0,1=109,2=0.000000
L 0.5888 5.27578317 0.59013356 5.27328366 2 P 0 ;0,1=109,2=0.000000
L 0.59013356 5.27328366 0.5912 5.27036614 2 P 0 ;0,1=109,2=0.000000
L 0.5912 5.27036614 0.59146663 5.26619961 2 P 0 ;0,1=109,2=0.000000
L 0.59146663 5.26619961 0.5912 5.26203307 2 P 0 ;0,1=109,2=0.000000
L 0.5912 5.26203307 0.59013356 5.25911624 2 P 0 ;0,1=109,2=0.000000
L 0.59013356 5.25911624 0.5888 5.25661604 2 P 0 ;0,1=109,2=0.000000
L 0.5888 5.25661604 0.5871999 5.2549497 2 P 0 ;0,1=109,2=0.000000
L 0.5871999 5.2549497 0.58506654 5.2537 2 P 0 ;0,1=109,2=0.000000
L 0.58506654 5.2537 0.57973327 5.2537 2 P 0 ;0,1=109,2=0.000000
L 0.60506634 5.25661604 0.60693317 5.25453307 2 P 0 ;0,1=109,2=0.000000
L 0.60693317 5.25453307 0.60906654 5.2537 2 P 0 ;0,1=109,2=0.000000
L 0.60906654 5.2537 0.6111999 5.25453307 2 P 0 ;0,1=109,2=0.000000
L 0.6111999 5.25453307 0.61306663 5.25703258 2 P 0 ;0,1=109,2=0.000000
L 0.61306663 5.25703258 0.6144001 5.26078327 2 P 0 ;0,1=109,2=0.000000
L 0.6144001 5.26078327 0.61493337 5.26453327 2 P 0 ;0,1=109,2=0.000000
L 0.61493337 5.26453327 0.61493337 5.26911634 2 P 0 ;0,1=109,2=0.000000
L 0.61493337 5.26911634 0.6144001 5.27286634 2 P 0 ;0,1=109,2=0.000000
L 0.6144001 5.27286634 0.61306663 5.2761997 2 P 0 ;0,1=109,2=0.000000
L 0.61306663 5.2761997 0.61146644 5.27786683 2 P 0 ;0,1=109,2=0.000000
L 0.61146644 5.27786683 0.6095997 5.2787 2 P 0 ;0,1=109,2=0.000000
L 0.6095997 5.2787 0.60746634 5.27786683 2 P 0 ;0,1=109,2=0.000000
L 0.60746634 5.27786683 0.60586663 5.2761997 2 P 0 ;0,1=109,2=0.000000
L 0.60586663 5.2761997 0.6047998 5.2737003 2 P 0 ;0,1=109,2=0.000000
L 0.6047998 5.2737003 0.60426654 5.27036614 2 P 0 ;0,1=109,2=0.000000
L 0.60426654 5.27036614 0.6047998 5.2674501 2 P 0 ;0,1=109,2=0.000000
L 0.6047998 5.2674501 0.60613327 5.26453327 2 P 0 ;0,1=109,2=0.000000
L 0.60613327 5.26453327 0.60773346 5.26286614 2 P 0 ;0,1=109,2=0.000000
L 0.60773346 5.26286614 0.6095997 5.26244961 2 P 0 ;0,1=109,2=0.000000
L 0.6095997 5.26244961 0.61173307 5.26328278 2 P 0 ;0,1=109,2=0.000000
L 0.61173307 5.26328278 0.61333327 5.26536644 2 P 0 ;0,1=109,2=0.000000
L 0.61333327 5.26536644 0.61493337 5.26911634 2 P 0 ;0,1=109,2=0.000000
L 12.54322992 6.16661998 12.54322992 6.19161998 2 P 0 ;0,1=110,2=0.000000
L 12.55443002 6.19161998 12.55443002 6.16661998 2 P 0 ;0,1=110,2=0.000000
L 12.55443002 6.17911959 12.54322992 6.17911959 2 P 0 ;0,1=110,2=0.000000
L 12.56776319 6.18745335 12.56936329 6.18995285 2 P 0 ;0,1=110,2=0.000000
L 12.56936329 6.18995285 12.57123002 6.19120335 2 P 0 ;0,1=110,2=0.000000
L 12.57123002 6.19120335 12.57336339 6.19161998 2 P 0 ;0,1=110,2=0.000000
L 12.57336339 6.19161998 12.57603002 6.19078681 2 P 0 ;0,1=110,2=0.000000
L 12.57603002 6.19078681 12.57789675 6.18870315 2 P 0 ;0,1=110,2=0.000000
L 12.57789675 6.18870315 12.57843002 6.18620364 2 P 0 ;0,1=110,2=0.000000
L 12.57843002 6.18620364 12.57816339 6.18370266 2 P 0 ;0,1=110,2=0.000000
L 12.57816339 6.18370266 12.57709646 6.18161978 2 P 0 ;0,1=110,2=0.000000
L 12.57709646 6.18161978 12.57176329 6.17745325 2 P 0 ;0,1=110,2=0.000000
L 12.57176329 6.17745325 12.56936329 6.17453642 2 P 0 ;0,1=110,2=0.000000
L 12.56936329 6.17453642 12.56776319 6.17036909 2 P 0 ;0,1=110,2=0.000000
L 12.56776319 6.17036909 12.56722992 6.16661998 2 P 0 ;0,1=110,2=0.000000
L 12.56722992 6.16661998 12.57843002 6.16661998 2 P 0 ;0,1=110,2=0.000000
L 12.60003002 6.16661998 12.60003002 6.19161998 2 P 0 ;0,1=110,2=0.000000
L 12.60003002 6.19161998 12.59016299 6.17370325 2 P 0 ;0,1=110,2=0.000000
L 12.59016299 6.17370325 12.60349695 6.17370325 2 P 0 ;0,1=110,2=0.000000
L 0.3173999 6.455 0.3173999 6.48 2 P 0 ;0,1=111,2=0.000000
L 0.3286 6.48 0.3286 6.455 2 P 0 ;0,1=111,2=0.000000
L 0.3286 6.46749961 0.3173999 6.46749961 2 P 0 ;0,1=111,2=0.000000
L 0.34193317 6.47583337 0.34353327 6.47833287 2 P 0 ;0,1=111,2=0.000000
L 0.34353327 6.47833287 0.3454 6.47958337 2 P 0 ;0,1=111,2=0.000000
L 0.3454 6.47958337 0.34753337 6.48 2 P 0 ;0,1=111,2=0.000000
L 0.34753337 6.48 0.3502 6.47916683 2 P 0 ;0,1=111,2=0.000000
L 0.3502 6.47916683 0.35206673 6.47708317 2 P 0 ;0,1=111,2=0.000000
L 0.35206673 6.47708317 0.3526 6.47458366 2 P 0 ;0,1=111,2=0.000000
L 0.3526 6.47458366 0.35233337 6.47208268 2 P 0 ;0,1=111,2=0.000000
L 0.35233337 6.47208268 0.35126644 6.4699998 2 P 0 ;0,1=111,2=0.000000
L 0.35126644 6.4699998 0.34593327 6.46583327 2 P 0 ;0,1=111,2=0.000000
L 0.34593327 6.46583327 0.34353327 6.46291644 2 P 0 ;0,1=111,2=0.000000
L 0.34353327 6.46291644 0.34193317 6.45874911 2 P 0 ;0,1=111,2=0.000000
L 0.34193317 6.45874911 0.3413999 6.455 2 P 0 ;0,1=111,2=0.000000
L 0.3413999 6.455 0.3526 6.455 2 P 0 ;0,1=111,2=0.000000
L 0.36513327 6.45999961 0.36673297 6.45708287 2 P 0 ;0,1=111,2=0.000000
L 0.36673297 6.45708287 0.36886634 6.45541654 2 P 0 ;0,1=111,2=0.000000
L 0.36886634 6.45541654 0.37126683 6.455 2 P 0 ;0,1=111,2=0.000000
L 0.37126683 6.455 0.3734002 6.45541654 2 P 0 ;0,1=111,2=0.000000
L 0.3734002 6.45541654 0.37553356 6.45749941 2 P 0 ;0,1=111,2=0.000000
L 0.37553356 6.45749941 0.37686663 6.45999961 2 P 0 ;0,1=111,2=0.000000
L 0.37686663 6.45999961 0.37713317 6.4624999 2 P 0 ;0,1=111,2=0.000000
L 0.37713317 6.4624999 0.3766 6.46541594 2 P 0 ;0,1=111,2=0.000000
L 0.3766 6.46541594 0.37473327 6.46749961 2 P 0 ;0,1=111,2=0.000000
L 0.37473327 6.46749961 0.37286644 6.46833346 2 P 0 ;0,1=111,2=0.000000
L 0.37286644 6.46833346 0.37046654 6.46833346 2 P 0 ;0,1=111,2=0.000000
L 0.37286644 6.46833346 0.37446663 6.46958327 2 P 0 ;0,1=111,2=0.000000
L 0.37446663 6.46958327 0.3758001 6.47166614 2 P 0 ;0,1=111,2=0.000000
L 0.3758001 6.47166614 0.37633337 6.47416634 2 P 0 ;0,1=111,2=0.000000
L 0.37633337 6.47416634 0.3758001 6.47666654 2 P 0 ;0,1=111,2=0.000000
L 0.3758001 6.47666654 0.37446663 6.47874941 2 P 0 ;0,1=111,2=0.000000
L 0.37446663 6.47874941 0.37206663 6.48 2 P 0 ;0,1=111,2=0.000000
L 0.37206663 6.48 0.36966663 6.47958337 2 P 0 ;0,1=111,2=0.000000
L 0.36966663 6.47958337 0.36726663 6.47791634 2 P 0 ;0,1=111,2=0.000000
L 12.8323999 -0.155 12.8323999 -0.13 2 P 0 ;0,1=112,2=0.000000
L 12.8436 -0.13 12.8436 -0.155 2 P 0 ;0,1=112,2=0.000000
L 12.8436 -0.14250039 12.8323999 -0.14250039 2 P 0 ;0,1=112,2=0.000000
L 12.85693317 -0.13416663 12.85853327 -0.13166713 2 P 0 ;0,1=112,2=0.000000
L 12.85853327 -0.13166713 12.8604 -0.13041663 2 P 0 ;0,1=112,2=0.000000
L 12.8604 -0.13041663 12.86253337 -0.13 2 P 0 ;0,1=112,2=0.000000
L 12.86253337 -0.13 12.8652 -0.13083317 2 P 0 ;0,1=112,2=0.000000
L 12.8652 -0.13083317 12.86706673 -0.13291683 2 P 0 ;0,1=112,2=0.000000
L 12.86706673 -0.13291683 12.8676 -0.13541634 2 P 0 ;0,1=112,2=0.000000
L 12.8676 -0.13541634 12.86733337 -0.13791732 2 P 0 ;0,1=112,2=0.000000
L 12.86733337 -0.13791732 12.86626644 -0.1400002 2 P 0 ;0,1=112,2=0.000000
L 12.86626644 -0.1400002 12.86093327 -0.14416673 2 P 0 ;0,1=112,2=0.000000
L 12.86093327 -0.14416673 12.85853327 -0.14708356 2 P 0 ;0,1=112,2=0.000000
L 12.85853327 -0.14708356 12.85693317 -0.15125089 2 P 0 ;0,1=112,2=0.000000
L 12.85693317 -0.15125089 12.8563999 -0.155 2 P 0 ;0,1=112,2=0.000000
L 12.8563999 -0.155 12.8676 -0.155 2 P 0 ;0,1=112,2=0.000000
L 12.88093317 -0.13416663 12.88253327 -0.13166713 2 P 0 ;0,1=112,2=0.000000
L 12.88253327 -0.13166713 12.8844 -0.13041663 2 P 0 ;0,1=112,2=0.000000
L 12.8844 -0.13041663 12.88653337 -0.13 2 P 0 ;0,1=112,2=0.000000
L 12.88653337 -0.13 12.8892 -0.13083317 2 P 0 ;0,1=112,2=0.000000
L 12.8892 -0.13083317 12.89106673 -0.13291683 2 P 0 ;0,1=112,2=0.000000
L 12.89106673 -0.13291683 12.8916 -0.13541634 2 P 0 ;0,1=112,2=0.000000
L 12.8916 -0.13541634 12.89133337 -0.13791732 2 P 0 ;0,1=112,2=0.000000
L 12.89133337 -0.13791732 12.89026644 -0.1400002 2 P 0 ;0,1=112,2=0.000000
L 12.89026644 -0.1400002 12.88493327 -0.14416673 2 P 0 ;0,1=112,2=0.000000
L 12.88493327 -0.14416673 12.88253327 -0.14708356 2 P 0 ;0,1=112,2=0.000000
L 12.88253327 -0.14708356 12.88093317 -0.15125089 2 P 0 ;0,1=112,2=0.000000
L 12.88093317 -0.15125089 12.8803999 -0.155 2 P 0 ;0,1=112,2=0.000000
L 12.8803999 -0.155 12.8916 -0.155 2 P 0 ;0,1=112,2=0.000000
L 0.0323999 -0.165 0.0323999 -0.14 2 P 0 ;0,1=113,2=0.000000
L 0.0436 -0.14 0.0436 -0.165 2 P 0 ;0,1=113,2=0.000000
L 0.0436 -0.15250039 0.0323999 -0.15250039 2 P 0 ;0,1=113,2=0.000000
L 0.0652 -0.165 0.0652 -0.14 2 P 0 ;0,1=113,2=0.000000
L 0.0652 -0.14 0.05533297 -0.15791673 2 P 0 ;0,1=113,2=0.000000
L 0.05533297 -0.15791673 0.06866693 -0.15791673 2 P 0 ;0,1=113,2=0.000000
L 12.2473999 0.07 12.2473999 0.095 2 P 0 ;0,1=114,2=0.000000
L 12.2586 0.095 12.2586 0.07 2 P 0 ;0,1=114,2=0.000000
L 12.2586 0.08249961 12.2473999 0.08249961 2 P 0 ;0,1=114,2=0.000000
L 12.27113327 0.07499961 12.27273297 0.07208287 2 P 0 ;0,1=114,2=0.000000
L 12.27273297 0.07208287 12.27486634 0.07041654 2 P 0 ;0,1=114,2=0.000000
L 12.27486634 0.07041654 12.27726683 0.07 2 P 0 ;0,1=114,2=0.000000
L 12.27726683 0.07 12.2794002 0.07041654 2 P 0 ;0,1=114,2=0.000000
L 12.2794002 0.07041654 12.28153356 0.07249941 2 P 0 ;0,1=114,2=0.000000
L 12.28153356 0.07249941 12.28286663 0.07499961 2 P 0 ;0,1=114,2=0.000000
L 12.28286663 0.07499961 12.28313317 0.0774999 2 P 0 ;0,1=114,2=0.000000
L 12.28313317 0.0774999 12.2826 0.08041594 2 P 0 ;0,1=114,2=0.000000
L 12.2826 0.08041594 12.28073327 0.08249961 2 P 0 ;0,1=114,2=0.000000
L 12.28073327 0.08249961 12.27886644 0.08333346 2 P 0 ;0,1=114,2=0.000000
L 12.27886644 0.08333346 12.27646654 0.08333346 2 P 0 ;0,1=114,2=0.000000
L 12.27886644 0.08333346 12.28046663 0.08458327 2 P 0 ;0,1=114,2=0.000000
L 12.28046663 0.08458327 12.2818001 0.08666614 2 P 0 ;0,1=114,2=0.000000
L 12.2818001 0.08666614 12.28233337 0.08916634 2 P 0 ;0,1=114,2=0.000000
L 12.28233337 0.08916634 12.2818001 0.09166654 2 P 0 ;0,1=114,2=0.000000
L 12.2818001 0.09166654 12.28046663 0.09374941 2 P 0 ;0,1=114,2=0.000000
L 12.28046663 0.09374941 12.27806663 0.095 2 P 0 ;0,1=114,2=0.000000
L 12.27806663 0.095 12.27566663 0.09458337 2 P 0 ;0,1=114,2=0.000000
L 12.27566663 0.09458337 12.27326663 0.09291634 2 P 0 ;0,1=114,2=0.000000
L 0.0634499 5.66 0.0634499 5.692 2 P 0 ;0,1=115,2=0.000000
L 0.07955 5.692 0.07955 5.66 2 P 0 ;0,1=115,2=0.000000
L 0.07955 5.67599951 0.0634499 5.67599951 2 P 0 ;0,1=115,2=0.000000
L 0.10249961 5.66 0.10249961 5.692 2 P 0 ;0,1=115,2=0.000000
L 0.10249961 5.692 0.0978999 5.6856003 2 P 0 ;0,1=115,2=0.000000
L 0.0978999 5.66 0.10709931 5.66 2 P 0 ;0,1=115,2=0.000000
L 0.6423999 0.08 0.6423999 0.105 2 P 0 ;0,1=116,2=0.000000
L 0.6536 0.105 0.6536 0.08 2 P 0 ;0,1=116,2=0.000000
L 0.6536 0.09249961 0.6423999 0.09249961 2 P 0 ;0,1=116,2=0.000000
L 0.66693317 0.10083337 0.66853327 0.10333287 2 P 0 ;0,1=116,2=0.000000
L 0.66853327 0.10333287 0.6704 0.10458337 2 P 0 ;0,1=116,2=0.000000
L 0.6704 0.10458337 0.67253337 0.105 2 P 0 ;0,1=116,2=0.000000
L 0.67253337 0.105 0.6752 0.10416683 2 P 0 ;0,1=116,2=0.000000
L 0.6752 0.10416683 0.67706673 0.10208317 2 P 0 ;0,1=116,2=0.000000
L 0.67706673 0.10208317 0.6776 0.09958366 2 P 0 ;0,1=116,2=0.000000
L 0.6776 0.09958366 0.67733337 0.09708268 2 P 0 ;0,1=116,2=0.000000
L 0.67733337 0.09708268 0.67626644 0.0949998 2 P 0 ;0,1=116,2=0.000000
L 0.67626644 0.0949998 0.67093327 0.09083327 2 P 0 ;0,1=116,2=0.000000
L 0.67093327 0.09083327 0.66853327 0.08791644 2 P 0 ;0,1=116,2=0.000000
L 0.66853327 0.08791644 0.66693317 0.08374911 2 P 0 ;0,1=116,2=0.000000
L 0.66693317 0.08374911 0.6663999 0.08 2 P 0 ;0,1=116,2=0.000000
L 0.6663999 0.08 0.6776 0.08 2 P 0 ;0,1=116,2=0.000000
L 4.86786998 5.75 4.85213002 5.75 3 P 0 
L 4.86 5.79766654 4.835 5.79766654 2 P 0 ;0,1=117,2=270.000000
L 4.835 5.79766654 4.835 5.80433327 2 P 0 ;0,1=117,2=270.000000
L 4.835 5.80433327 4.83625059 5.80646663 2 P 0 ;0,1=117,2=270.000000
L 4.83625059 5.80646663 4.83791683 5.8078001 2 P 0 ;0,1=117,2=270.000000
L 4.83791683 5.8078001 4.8412502 5.80833337 2 P 0 ;0,1=117,2=270.000000
L 4.8412502 5.80833337 4.84458366 5.8078001 2 P 0 ;0,1=117,2=270.000000
L 4.84458366 5.8078001 4.84666654 5.8062 2 P 0 ;0,1=117,2=270.000000
L 4.84666654 5.8062 4.84791703 5.80433327 2 P 0 ;0,1=117,2=270.000000
L 4.84791703 5.80433327 4.84791703 5.79766654 2 P 0 ;0,1=117,2=270.000000
L 4.84791703 5.80433327 4.86 5.80833337 2 P 0 ;0,1=117,2=270.000000
L 4.86 5.8269997 4.835 5.8269997 2 P 0 ;0,1=117,2=270.000000
L 4.835 5.8269997 4.8399997 5.8237999 2 P 0 ;0,1=117,2=270.000000
L 4.86 5.8237999 4.86 5.83019951 2 P 0 ;0,1=117,2=270.000000
L 4.84958406 5.84593317 4.84666654 5.8477999 2 P 0 ;0,1=117,2=270.000000
L 4.84666654 5.8477999 4.8450002 5.8494 2 P 0 ;0,1=117,2=270.000000
L 4.8450002 5.8494 4.84416703 5.85153337 2 P 0 ;0,1=117,2=270.000000
L 4.84416703 5.85153337 4.8450002 5.8534002 2 P 0 ;0,1=117,2=270.000000
L 4.8450002 5.8534002 4.84666654 5.85473327 2 P 0 ;0,1=117,2=270.000000
L 4.84666654 5.85473327 4.84916673 5.8558001 2 P 0 ;0,1=117,2=270.000000
L 4.84916673 5.8558001 4.85208356 5.85606673 2 P 0 ;0,1=117,2=270.000000
L 4.85208356 5.85606673 4.85458376 5.8558001 2 P 0 ;0,1=117,2=270.000000
L 4.85458376 5.8558001 4.85708396 5.85473327 2 P 0 ;0,1=117,2=270.000000
L 4.85708396 5.85473327 4.85916693 5.85313307 2 P 0 ;0,1=117,2=270.000000
L 4.85916693 5.85313307 4.86 5.85126683 2 P 0 ;0,1=117,2=270.000000
L 4.86 5.85126683 4.85916693 5.84913346 2 P 0 ;0,1=117,2=270.000000
L 4.85916693 5.84913346 4.85666742 5.84726663 2 P 0 ;0,1=117,2=270.000000
L 4.85666742 5.84726663 4.85291673 5.8461998 2 P 0 ;0,1=117,2=270.000000
L 4.85291673 5.8461998 4.8487502 5.84593317 2 P 0 ;0,1=117,2=270.000000
L 4.8487502 5.84593317 4.84333386 5.84646634 2 P 0 ;0,1=117,2=270.000000
L 4.84333386 5.84646634 4.84041634 5.84726663 2 P 0 ;0,1=117,2=270.000000
L 4.84041634 5.84726663 4.8375003 5.8485997 2 P 0 ;0,1=117,2=270.000000
L 4.8375003 5.8485997 4.83541663 5.85046654 2 P 0 ;0,1=117,2=270.000000
L 4.83541663 5.85046654 4.835 5.85233327 2 P 0 ;0,1=117,2=270.000000
L 4.835 5.85233327 4.83583317 5.8542 2 P 0 ;0,1=117,2=270.000000
L 4.83583317 5.8542 4.83791683 5.85553356 2 P 0 ;0,1=117,2=270.000000
L 4.86 5.8749997 4.835 5.8749997 2 P 0 ;0,1=117,2=270.000000
L 4.835 5.8749997 4.8399997 5.8717999 2 P 0 ;0,1=117,2=270.000000
L 4.86 5.8717999 4.86 5.87819951 2 P 0 ;0,1=117,2=270.000000
L 4.86 5.8989997 4.85958346 5.90086644 2 P 0 ;0,1=117,2=270.000000
L 4.85958346 5.90086644 4.85833376 5.9029998 2 P 0 ;0,1=117,2=270.000000
L 4.85833376 5.9029998 4.85625089 5.90433337 2 P 0 ;0,1=117,2=270.000000
L 4.85625089 5.90433337 4.85333327 5.90486663 2 P 0 ;0,1=117,2=270.000000
L 4.85333327 5.90486663 4.85041722 5.90433337 2 P 0 ;0,1=117,2=270.000000
L 4.85041722 5.90433337 4.84791703 5.90273327 2 P 0 ;0,1=117,2=270.000000
L 4.84791703 5.90273327 4.84666654 5.90033327 2 P 0 ;0,1=117,2=270.000000
L 4.84666654 5.90033327 4.84666654 5.89766663 2 P 0 ;0,1=117,2=270.000000
L 4.84666654 5.89766663 4.84583337 5.89606654 2 P 0 ;0,1=117,2=270.000000
L 4.84583337 5.89606654 4.84375049 5.89473297 2 P 0 ;0,1=117,2=270.000000
L 4.84375049 5.89473297 4.84083366 5.8941998 2 P 0 ;0,1=117,2=270.000000
L 4.84083366 5.8941998 4.83791683 5.8950001 2 P 0 ;0,1=117,2=270.000000
L 4.83791683 5.8950001 4.83583317 5.89686634 2 P 0 ;0,1=117,2=270.000000
L 4.83583317 5.89686634 4.835 5.8989997 2 P 0 ;0,1=117,2=270.000000
L 4.835 5.8989997 4.83583317 5.90113307 2 P 0 ;0,1=117,2=270.000000
L 4.83583317 5.90113307 4.83791683 5.9029998 2 P 0 ;0,1=117,2=270.000000
L 4.83791683 5.9029998 4.84083366 5.9038001 2 P 0 ;0,1=117,2=270.000000
L 4.84083366 5.9038001 4.84375049 5.90326644 2 P 0 ;0,1=117,2=270.000000
L 4.84375049 5.90326644 4.84583337 5.90193337 2 P 0 ;0,1=117,2=270.000000
L 4.84583337 5.90193337 4.84666654 5.90033327 2 P 0 ;0,1=117,2=270.000000
L 4.84666654 5.90033327 4.84666654 5.89766663 2 P 0 ;0,1=117,2=270.000000
L 4.84666654 5.89766663 4.84791703 5.89526663 2 P 0 ;0,1=117,2=270.000000
L 4.84791703 5.89526663 4.85041722 5.89366654 2 P 0 ;0,1=117,2=270.000000
L 4.85041722 5.89366654 4.85333327 5.89313327 2 P 0 ;0,1=117,2=270.000000
L 4.85333327 5.89313327 4.85625089 5.89366654 2 P 0 ;0,1=117,2=270.000000
L 4.85625089 5.89366654 4.85833376 5.8950001 2 P 0 ;0,1=117,2=270.000000
L 4.85833376 5.8950001 4.85958346 5.89713346 2 P 0 ;0,1=117,2=270.000000
L 4.85958346 5.89713346 4.86 5.8989997 2 P 0 ;0,1=117,2=270.000000
L 4.75213002 5.425 4.76786998 5.425 3 P 0 
L 4.775 5.24266654 4.75 5.24266654 2 P 0 ;0,1=118,2=270.000000
L 4.75 5.24266654 4.75 5.24933327 2 P 0 ;0,1=118,2=270.000000
L 4.75 5.24933327 4.75125059 5.25146663 2 P 0 ;0,1=118,2=270.000000
L 4.75125059 5.25146663 4.75291683 5.2528001 2 P 0 ;0,1=118,2=270.000000
L 4.75291683 5.2528001 4.7562502 5.25333337 2 P 0 ;0,1=118,2=270.000000
L 4.7562502 5.25333337 4.75958366 5.2528001 2 P 0 ;0,1=118,2=270.000000
L 4.75958366 5.2528001 4.76166654 5.2512 2 P 0 ;0,1=118,2=270.000000
L 4.76166654 5.2512 4.76291703 5.24933327 2 P 0 ;0,1=118,2=270.000000
L 4.76291703 5.24933327 4.76291703 5.24266654 2 P 0 ;0,1=118,2=270.000000
L 4.76291703 5.24933327 4.775 5.25333337 2 P 0 ;0,1=118,2=270.000000
L 4.775 5.2719997 4.75 5.2719997 2 P 0 ;0,1=118,2=270.000000
L 4.75 5.2719997 4.7549997 5.2687999 2 P 0 ;0,1=118,2=270.000000
L 4.775 5.2687999 4.775 5.27519951 2 P 0 ;0,1=118,2=270.000000
L 4.76458406 5.29093317 4.76166654 5.2927999 2 P 0 ;0,1=118,2=270.000000
L 4.76166654 5.2927999 4.7600002 5.2944 2 P 0 ;0,1=118,2=270.000000
L 4.7600002 5.2944 4.75916703 5.29653337 2 P 0 ;0,1=118,2=270.000000
L 4.75916703 5.29653337 4.7600002 5.2984002 2 P 0 ;0,1=118,2=270.000000
L 4.7600002 5.2984002 4.76166654 5.29973327 2 P 0 ;0,1=118,2=270.000000
L 4.76166654 5.29973327 4.76416673 5.3008001 2 P 0 ;0,1=118,2=270.000000
L 4.76416673 5.3008001 4.76708356 5.30106673 2 P 0 ;0,1=118,2=270.000000
L 4.76708356 5.30106673 4.76958376 5.3008001 2 P 0 ;0,1=118,2=270.000000
L 4.76958376 5.3008001 4.77208396 5.29973327 2 P 0 ;0,1=118,2=270.000000
L 4.77208396 5.29973327 4.77416693 5.29813307 2 P 0 ;0,1=118,2=270.000000
L 4.77416693 5.29813307 4.775 5.29626683 2 P 0 ;0,1=118,2=270.000000
L 4.775 5.29626683 4.77416693 5.29413346 2 P 0 ;0,1=118,2=270.000000
L 4.77416693 5.29413346 4.77166742 5.29226663 2 P 0 ;0,1=118,2=270.000000
L 4.77166742 5.29226663 4.76791673 5.2911998 2 P 0 ;0,1=118,2=270.000000
L 4.76791673 5.2911998 4.7637502 5.29093317 2 P 0 ;0,1=118,2=270.000000
L 4.7637502 5.29093317 4.75833386 5.29146634 2 P 0 ;0,1=118,2=270.000000
L 4.75833386 5.29146634 4.75541634 5.29226663 2 P 0 ;0,1=118,2=270.000000
L 4.75541634 5.29226663 4.7525003 5.2935997 2 P 0 ;0,1=118,2=270.000000
L 4.7525003 5.2935997 4.75041663 5.29546654 2 P 0 ;0,1=118,2=270.000000
L 4.75041663 5.29546654 4.75 5.29733327 2 P 0 ;0,1=118,2=270.000000
L 4.75 5.29733327 4.75083317 5.2992 2 P 0 ;0,1=118,2=270.000000
L 4.75083317 5.2992 4.75291683 5.30053356 2 P 0 ;0,1=118,2=270.000000
L 4.75416663 5.31493317 4.75166713 5.31653327 2 P 0 ;0,1=118,2=270.000000
L 4.75166713 5.31653327 4.75041663 5.3184 2 P 0 ;0,1=118,2=270.000000
L 4.75041663 5.3184 4.75 5.32053337 2 P 0 ;0,1=118,2=270.000000
L 4.75 5.32053337 4.75083317 5.3232 2 P 0 ;0,1=118,2=270.000000
L 4.75083317 5.3232 4.75291683 5.32506673 2 P 0 ;0,1=118,2=270.000000
L 4.75291683 5.32506673 4.75541634 5.3256 2 P 0 ;0,1=118,2=270.000000
L 4.75541634 5.3256 4.75791732 5.32533337 2 P 0 ;0,1=118,2=270.000000
L 4.75791732 5.32533337 4.7600002 5.32426644 2 P 0 ;0,1=118,2=270.000000
L 4.7600002 5.32426644 4.76416673 5.31893327 2 P 0 ;0,1=118,2=270.000000
L 4.76416673 5.31893327 4.76708356 5.31653327 2 P 0 ;0,1=118,2=270.000000
L 4.76708356 5.31653327 4.77125089 5.31493317 2 P 0 ;0,1=118,2=270.000000
L 4.77125089 5.31493317 4.775 5.3143999 2 P 0 ;0,1=118,2=270.000000
L 4.775 5.3143999 4.775 5.3256 2 P 0 ;0,1=118,2=270.000000
L 4.775 5.34346654 4.76958376 5.3439997 2 P 0 ;0,1=118,2=270.000000
L 4.76958376 5.3439997 4.76500069 5.3448 2 P 0 ;0,1=118,2=270.000000
L 4.76500069 5.3448 4.76083337 5.34586644 2 P 0 ;0,1=118,2=270.000000
L 4.76083337 5.34586644 4.7562502 5.3472 2 P 0 ;0,1=118,2=270.000000
L 4.7562502 5.3472 4.75 5.34933337 2 P 0 ;0,1=118,2=270.000000
L 4.75 5.34933337 4.75 5.33866654 2 P 0 ;0,1=118,2=270.000000
L 0.68786998 5.13 0.67213002 5.13 3 P 0 
L 0.615 5.08766654 0.59 5.08766654 2 P 0 ;0,1=119,2=270.000000
L 0.59 5.08766654 0.59 5.09433327 2 P 0 ;0,1=119,2=270.000000
L 0.59 5.09433327 0.59125059 5.09646663 2 P 0 ;0,1=119,2=270.000000
L 0.59125059 5.09646663 0.59291683 5.0978001 2 P 0 ;0,1=119,2=270.000000
L 0.59291683 5.0978001 0.5962502 5.09833337 2 P 0 ;0,1=119,2=270.000000
L 0.5962502 5.09833337 0.59958366 5.0978001 2 P 0 ;0,1=119,2=270.000000
L 0.59958366 5.0978001 0.60166654 5.0962 2 P 0 ;0,1=119,2=270.000000
L 0.60166654 5.0962 0.60291703 5.09433327 2 P 0 ;0,1=119,2=270.000000
L 0.60291703 5.09433327 0.60291703 5.08766654 2 P 0 ;0,1=119,2=270.000000
L 0.60291703 5.09433327 0.615 5.09833337 2 P 0 ;0,1=119,2=270.000000
L 0.615 5.1169997 0.59 5.1169997 2 P 0 ;0,1=119,2=270.000000
L 0.59 5.1169997 0.5949997 5.1137999 2 P 0 ;0,1=119,2=270.000000
L 0.615 5.1137999 0.615 5.12019951 2 P 0 ;0,1=119,2=270.000000
L 0.60458406 5.13593317 0.60166654 5.1377999 2 P 0 ;0,1=119,2=270.000000
L 0.60166654 5.1377999 0.6000002 5.1394 2 P 0 ;0,1=119,2=270.000000
L 0.6000002 5.1394 0.59916703 5.14153337 2 P 0 ;0,1=119,2=270.000000
L 0.59916703 5.14153337 0.6000002 5.1434002 2 P 0 ;0,1=119,2=270.000000
L 0.6000002 5.1434002 0.60166654 5.14473327 2 P 0 ;0,1=119,2=270.000000
L 0.60166654 5.14473327 0.60416673 5.1458001 2 P 0 ;0,1=119,2=270.000000
L 0.60416673 5.1458001 0.60708356 5.14606673 2 P 0 ;0,1=119,2=270.000000
L 0.60708356 5.14606673 0.60958376 5.1458001 2 P 0 ;0,1=119,2=270.000000
L 0.60958376 5.1458001 0.61208396 5.14473327 2 P 0 ;0,1=119,2=270.000000
L 0.61208396 5.14473327 0.61416693 5.14313307 2 P 0 ;0,1=119,2=270.000000
L 0.61416693 5.14313307 0.615 5.14126683 2 P 0 ;0,1=119,2=270.000000
L 0.615 5.14126683 0.61416693 5.13913346 2 P 0 ;0,1=119,2=270.000000
L 0.61416693 5.13913346 0.61166742 5.13726663 2 P 0 ;0,1=119,2=270.000000
L 0.61166742 5.13726663 0.60791673 5.1361998 2 P 0 ;0,1=119,2=270.000000
L 0.60791673 5.1361998 0.6037502 5.13593317 2 P 0 ;0,1=119,2=270.000000
L 0.6037502 5.13593317 0.59833386 5.13646634 2 P 0 ;0,1=119,2=270.000000
L 0.59833386 5.13646634 0.59541634 5.13726663 2 P 0 ;0,1=119,2=270.000000
L 0.59541634 5.13726663 0.5925003 5.1385997 2 P 0 ;0,1=119,2=270.000000
L 0.5925003 5.1385997 0.59041663 5.14046654 2 P 0 ;0,1=119,2=270.000000
L 0.59041663 5.14046654 0.59 5.14233327 2 P 0 ;0,1=119,2=270.000000
L 0.59 5.14233327 0.59083317 5.1442 2 P 0 ;0,1=119,2=270.000000
L 0.59083317 5.1442 0.59291683 5.14553356 2 P 0 ;0,1=119,2=270.000000
L 0.615 5.1649997 0.59 5.1649997 2 P 0 ;0,1=119,2=270.000000
L 0.59 5.1649997 0.5949997 5.1617999 2 P 0 ;0,1=119,2=270.000000
L 0.615 5.1617999 0.615 5.16819951 2 P 0 ;0,1=119,2=270.000000
L 0.61000039 5.18313327 0.61291713 5.18473297 2 P 0 ;0,1=119,2=270.000000
L 0.61291713 5.18473297 0.61458346 5.18686634 2 P 0 ;0,1=119,2=270.000000
L 0.61458346 5.18686634 0.615 5.18926683 2 P 0 ;0,1=119,2=270.000000
L 0.615 5.18926683 0.61458346 5.1914002 2 P 0 ;0,1=119,2=270.000000
L 0.61458346 5.1914002 0.61250059 5.19353356 2 P 0 ;0,1=119,2=270.000000
L 0.61250059 5.19353356 0.61000039 5.19486663 2 P 0 ;0,1=119,2=270.000000
L 0.61000039 5.19486663 0.6075001 5.19513317 2 P 0 ;0,1=119,2=270.000000
L 0.6075001 5.19513317 0.60458406 5.1946 2 P 0 ;0,1=119,2=270.000000
L 0.60458406 5.1946 0.60250039 5.19273327 2 P 0 ;0,1=119,2=270.000000
L 0.60250039 5.19273327 0.60166654 5.19086644 2 P 0 ;0,1=119,2=270.000000
L 0.60166654 5.19086644 0.60166654 5.18846654 2 P 0 ;0,1=119,2=270.000000
L 0.60166654 5.19086644 0.60041673 5.19246663 2 P 0 ;0,1=119,2=270.000000
L 0.60041673 5.19246663 0.59833386 5.1938001 2 P 0 ;0,1=119,2=270.000000
L 0.59833386 5.1938001 0.59583366 5.19433337 2 P 0 ;0,1=119,2=270.000000
L 0.59583366 5.19433337 0.59333346 5.1938001 2 P 0 ;0,1=119,2=270.000000
L 0.59333346 5.1938001 0.59125059 5.19246663 2 P 0 ;0,1=119,2=270.000000
L 0.59125059 5.19246663 0.59 5.19006663 2 P 0 ;0,1=119,2=270.000000
L 0.59 5.19006663 0.59041663 5.18766663 2 P 0 ;0,1=119,2=270.000000
L 0.59041663 5.18766663 0.59208366 5.18526663 2 P 0 ;0,1=119,2=270.000000
L 4.08 4.58213002 4.08 4.59786998 3 P 0 
L 3.98766654 4.155 3.98766654 4.18 2 P 0 ;0,1=120,2=0.000000
L 3.98766654 4.18 3.99433327 4.18 2 P 0 ;0,1=120,2=0.000000
L 3.99433327 4.18 3.99646663 4.17874941 2 P 0 ;0,1=120,2=0.000000
L 3.99646663 4.17874941 3.9978001 4.17708317 2 P 0 ;0,1=120,2=0.000000
L 3.9978001 4.17708317 3.99833337 4.1737498 2 P 0 ;0,1=120,2=0.000000
L 3.99833337 4.1737498 3.9978001 4.17041634 2 P 0 ;0,1=120,2=0.000000
L 3.9978001 4.17041634 3.9962 4.16833346 2 P 0 ;0,1=120,2=0.000000
L 3.9962 4.16833346 3.99433327 4.16708297 2 P 0 ;0,1=120,2=0.000000
L 3.99433327 4.16708297 3.98766654 4.16708297 2 P 0 ;0,1=120,2=0.000000
L 3.99433327 4.16708297 3.99833337 4.155 2 P 0 ;0,1=120,2=0.000000
L 4.0169997 4.155 4.0169997 4.18 2 P 0 ;0,1=120,2=0.000000
L 4.0169997 4.18 4.0137999 4.1750003 2 P 0 ;0,1=120,2=0.000000
L 4.0137999 4.155 4.02019951 4.155 2 P 0 ;0,1=120,2=0.000000
L 4.03593317 4.16541594 4.0377999 4.16833346 2 P 0 ;0,1=120,2=0.000000
L 4.0377999 4.16833346 4.0394 4.1699998 2 P 0 ;0,1=120,2=0.000000
L 4.0394 4.1699998 4.04153337 4.17083297 2 P 0 ;0,1=120,2=0.000000
L 4.04153337 4.17083297 4.0434002 4.1699998 2 P 0 ;0,1=120,2=0.000000
L 4.0434002 4.1699998 4.04473327 4.16833346 2 P 0 ;0,1=120,2=0.000000
L 4.04473327 4.16833346 4.0458001 4.16583327 2 P 0 ;0,1=120,2=0.000000
L 4.0458001 4.16583327 4.04606673 4.16291644 2 P 0 ;0,1=120,2=0.000000
L 4.04606673 4.16291644 4.0458001 4.16041624 2 P 0 ;0,1=120,2=0.000000
L 4.0458001 4.16041624 4.04473327 4.15791604 2 P 0 ;0,1=120,2=0.000000
L 4.04473327 4.15791604 4.04313307 4.15583307 2 P 0 ;0,1=120,2=0.000000
L 4.04313307 4.15583307 4.04126683 4.155 2 P 0 ;0,1=120,2=0.000000
L 4.04126683 4.155 4.03913346 4.15583307 2 P 0 ;0,1=120,2=0.000000
L 4.03913346 4.15583307 4.03726663 4.15833258 2 P 0 ;0,1=120,2=0.000000
L 4.03726663 4.15833258 4.0361998 4.16208327 2 P 0 ;0,1=120,2=0.000000
L 4.0361998 4.16208327 4.03593317 4.1662498 2 P 0 ;0,1=120,2=0.000000
L 4.03593317 4.1662498 4.03646634 4.17166614 2 P 0 ;0,1=120,2=0.000000
L 4.03646634 4.17166614 4.03726663 4.17458366 2 P 0 ;0,1=120,2=0.000000
L 4.03726663 4.17458366 4.0385997 4.1774997 2 P 0 ;0,1=120,2=0.000000
L 4.0385997 4.1774997 4.04046654 4.17958337 2 P 0 ;0,1=120,2=0.000000
L 4.04046654 4.17958337 4.04233327 4.18 2 P 0 ;0,1=120,2=0.000000
L 4.04233327 4.18 4.0442 4.17916683 2 P 0 ;0,1=120,2=0.000000
L 4.0442 4.17916683 4.04553356 4.17708317 2 P 0 ;0,1=120,2=0.000000
L 4.0649997 4.155 4.0649997 4.18 2 P 0 ;0,1=120,2=0.000000
L 4.0649997 4.18 4.0617999 4.1750003 2 P 0 ;0,1=120,2=0.000000
L 4.0617999 4.155 4.06819951 4.155 2 P 0 ;0,1=120,2=0.000000
L 4.08393317 4.17583337 4.08553327 4.17833287 2 P 0 ;0,1=120,2=0.000000
L 4.08553327 4.17833287 4.0874 4.17958337 2 P 0 ;0,1=120,2=0.000000
L 4.0874 4.17958337 4.08953337 4.18 2 P 0 ;0,1=120,2=0.000000
L 4.08953337 4.18 4.0922 4.17916683 2 P 0 ;0,1=120,2=0.000000
L 4.0922 4.17916683 4.09406673 4.17708317 2 P 0 ;0,1=120,2=0.000000
L 4.09406673 4.17708317 4.0946 4.17458366 2 P 0 ;0,1=120,2=0.000000
L 4.0946 4.17458366 4.09433337 4.17208268 2 P 0 ;0,1=120,2=0.000000
L 4.09433337 4.17208268 4.09326644 4.1699998 2 P 0 ;0,1=120,2=0.000000
L 4.09326644 4.1699998 4.08793327 4.16583327 2 P 0 ;0,1=120,2=0.000000
L 4.08793327 4.16583327 4.08553327 4.16291644 2 P 0 ;0,1=120,2=0.000000
L 4.08553327 4.16291644 4.08393317 4.15874911 2 P 0 ;0,1=120,2=0.000000
L 4.08393317 4.15874911 4.0833999 4.155 2 P 0 ;0,1=120,2=0.000000
L 4.0833999 4.155 4.0946 4.155 2 P 0 ;0,1=120,2=0.000000
L 5.01713002 5.45 5.03286998 5.45 3 P 0 
L 5.045 5.26266654 5.02 5.26266654 2 P 0 ;0,1=121,2=270.000000
L 5.02 5.26266654 5.02 5.26933327 2 P 0 ;0,1=121,2=270.000000
L 5.02 5.26933327 5.02125059 5.27146663 2 P 0 ;0,1=121,2=270.000000
L 5.02125059 5.27146663 5.02291683 5.2728001 2 P 0 ;0,1=121,2=270.000000
L 5.02291683 5.2728001 5.0262502 5.27333337 2 P 0 ;0,1=121,2=270.000000
L 5.0262502 5.27333337 5.02958366 5.2728001 2 P 0 ;0,1=121,2=270.000000
L 5.02958366 5.2728001 5.03166654 5.2712 2 P 0 ;0,1=121,2=270.000000
L 5.03166654 5.2712 5.03291703 5.26933327 2 P 0 ;0,1=121,2=270.000000
L 5.03291703 5.26933327 5.03291703 5.26266654 2 P 0 ;0,1=121,2=270.000000
L 5.03291703 5.26933327 5.045 5.27333337 2 P 0 ;0,1=121,2=270.000000
L 5.045 5.2919997 5.02 5.2919997 2 P 0 ;0,1=121,2=270.000000
L 5.02 5.2919997 5.0249997 5.2887999 2 P 0 ;0,1=121,2=270.000000
L 5.045 5.2887999 5.045 5.29519951 2 P 0 ;0,1=121,2=270.000000
L 5.03458406 5.31093317 5.03166654 5.3127999 2 P 0 ;0,1=121,2=270.000000
L 5.03166654 5.3127999 5.0300002 5.3144 2 P 0 ;0,1=121,2=270.000000
L 5.0300002 5.3144 5.02916703 5.31653337 2 P 0 ;0,1=121,2=270.000000
L 5.02916703 5.31653337 5.0300002 5.3184002 2 P 0 ;0,1=121,2=270.000000
L 5.0300002 5.3184002 5.03166654 5.31973327 2 P 0 ;0,1=121,2=270.000000
L 5.03166654 5.31973327 5.03416673 5.3208001 2 P 0 ;0,1=121,2=270.000000
L 5.03416673 5.3208001 5.03708356 5.32106673 2 P 0 ;0,1=121,2=270.000000
L 5.03708356 5.32106673 5.03958376 5.3208001 2 P 0 ;0,1=121,2=270.000000
L 5.03958376 5.3208001 5.04208396 5.31973327 2 P 0 ;0,1=121,2=270.000000
L 5.04208396 5.31973327 5.04416693 5.31813307 2 P 0 ;0,1=121,2=270.000000
L 5.04416693 5.31813307 5.045 5.31626683 2 P 0 ;0,1=121,2=270.000000
L 5.045 5.31626683 5.04416693 5.31413346 2 P 0 ;0,1=121,2=270.000000
L 5.04416693 5.31413346 5.04166742 5.31226663 2 P 0 ;0,1=121,2=270.000000
L 5.04166742 5.31226663 5.03791673 5.3111998 2 P 0 ;0,1=121,2=270.000000
L 5.03791673 5.3111998 5.0337502 5.31093317 2 P 0 ;0,1=121,2=270.000000
L 5.0337502 5.31093317 5.02833386 5.31146634 2 P 0 ;0,1=121,2=270.000000
L 5.02833386 5.31146634 5.02541634 5.31226663 2 P 0 ;0,1=121,2=270.000000
L 5.02541634 5.31226663 5.0225003 5.3135997 2 P 0 ;0,1=121,2=270.000000
L 5.0225003 5.3135997 5.02041663 5.31546654 2 P 0 ;0,1=121,2=270.000000
L 5.02041663 5.31546654 5.02 5.31733327 2 P 0 ;0,1=121,2=270.000000
L 5.02 5.31733327 5.02083317 5.3192 2 P 0 ;0,1=121,2=270.000000
L 5.02083317 5.3192 5.02291683 5.32053356 2 P 0 ;0,1=121,2=270.000000
L 5.02416663 5.33493317 5.02166713 5.33653327 2 P 0 ;0,1=121,2=270.000000
L 5.02166713 5.33653327 5.02041663 5.3384 2 P 0 ;0,1=121,2=270.000000
L 5.02041663 5.3384 5.02 5.34053337 2 P 0 ;0,1=121,2=270.000000
L 5.02 5.34053337 5.02083317 5.3432 2 P 0 ;0,1=121,2=270.000000
L 5.02083317 5.3432 5.02291683 5.34506673 2 P 0 ;0,1=121,2=270.000000
L 5.02291683 5.34506673 5.02541634 5.3456 2 P 0 ;0,1=121,2=270.000000
L 5.02541634 5.3456 5.02791732 5.34533337 2 P 0 ;0,1=121,2=270.000000
L 5.02791732 5.34533337 5.0300002 5.34426644 2 P 0 ;0,1=121,2=270.000000
L 5.0300002 5.34426644 5.03416673 5.33893327 2 P 0 ;0,1=121,2=270.000000
L 5.03416673 5.33893327 5.03708356 5.33653327 2 P 0 ;0,1=121,2=270.000000
L 5.03708356 5.33653327 5.04125089 5.33493317 2 P 0 ;0,1=121,2=270.000000
L 5.04125089 5.33493317 5.045 5.3343999 2 P 0 ;0,1=121,2=270.000000
L 5.045 5.3343999 5.045 5.3456 2 P 0 ;0,1=121,2=270.000000
L 5.02 5.3639997 5.02083317 5.36186634 2 P 0 ;0,1=121,2=270.000000
L 5.02083317 5.36186634 5.02291683 5.36026663 2 P 0 ;0,1=121,2=270.000000
L 5.02291683 5.36026663 5.02541634 5.3591998 2 P 0 ;0,1=121,2=270.000000
L 5.02541634 5.3591998 5.02875049 5.3583999 2 P 0 ;0,1=121,2=270.000000
L 5.02875049 5.3583999 5.03250039 5.35813327 2 P 0 ;0,1=121,2=270.000000
L 5.03250039 5.35813327 5.03625039 5.3583999 2 P 0 ;0,1=121,2=270.000000
L 5.03625039 5.3583999 5.03958376 5.3591998 2 P 0 ;0,1=121,2=270.000000
L 5.03958376 5.3591998 5.04208396 5.36026663 2 P 0 ;0,1=121,2=270.000000
L 5.04208396 5.36026663 5.04416693 5.36186634 2 P 0 ;0,1=121,2=270.000000
L 5.04416693 5.36186634 5.045 5.3639997 2 P 0 ;0,1=121,2=270.000000
L 5.045 5.3639997 5.04416693 5.36613307 2 P 0 ;0,1=121,2=270.000000
L 5.04416693 5.36613307 5.04208396 5.36773327 2 P 0 ;0,1=121,2=270.000000
L 5.04208396 5.36773327 5.03958376 5.3688001 2 P 0 ;0,1=121,2=270.000000
L 5.03958376 5.3688001 5.03625039 5.3696 2 P 0 ;0,1=121,2=270.000000
L 5.03625039 5.3696 5.03250039 5.36986663 2 P 0 ;0,1=121,2=270.000000
L 5.03250039 5.36986663 5.02875049 5.3696 2 P 0 ;0,1=121,2=270.000000
L 5.02875049 5.3696 5.02541634 5.3688001 2 P 0 ;0,1=121,2=270.000000
L 5.02541634 5.3688001 5.02291683 5.36773327 2 P 0 ;0,1=121,2=270.000000
L 5.02291683 5.36773327 5.02083317 5.36613307 2 P 0 ;0,1=121,2=270.000000
L 5.02083317 5.36613307 5.02 5.3639997 2 P 0 ;0,1=121,2=270.000000
L 4.96213002 5.75 4.97786998 5.75 3 P 0 
L 4.995 5.80266654 4.97 5.80266654 2 P 0 ;0,1=122,2=270.000000
L 4.97 5.80266654 4.97 5.80933327 2 P 0 ;0,1=122,2=270.000000
L 4.97 5.80933327 4.97125059 5.81146663 2 P 0 ;0,1=122,2=270.000000
L 4.97125059 5.81146663 4.97291683 5.8128001 2 P 0 ;0,1=122,2=270.000000
L 4.97291683 5.8128001 4.9762502 5.81333337 2 P 0 ;0,1=122,2=270.000000
L 4.9762502 5.81333337 4.97958366 5.8128001 2 P 0 ;0,1=122,2=270.000000
L 4.97958366 5.8128001 4.98166654 5.8112 2 P 0 ;0,1=122,2=270.000000
L 4.98166654 5.8112 4.98291703 5.80933327 2 P 0 ;0,1=122,2=270.000000
L 4.98291703 5.80933327 4.98291703 5.80266654 2 P 0 ;0,1=122,2=270.000000
L 4.98291703 5.80933327 4.995 5.81333337 2 P 0 ;0,1=122,2=270.000000
L 4.995 5.8319997 4.97 5.8319997 2 P 0 ;0,1=122,2=270.000000
L 4.97 5.8319997 4.9749997 5.8287999 2 P 0 ;0,1=122,2=270.000000
L 4.995 5.8287999 4.995 5.83519951 2 P 0 ;0,1=122,2=270.000000
L 4.98458406 5.85093317 4.98166654 5.8527999 2 P 0 ;0,1=122,2=270.000000
L 4.98166654 5.8527999 4.9800002 5.8544 2 P 0 ;0,1=122,2=270.000000
L 4.9800002 5.8544 4.97916703 5.85653337 2 P 0 ;0,1=122,2=270.000000
L 4.97916703 5.85653337 4.9800002 5.8584002 2 P 0 ;0,1=122,2=270.000000
L 4.9800002 5.8584002 4.98166654 5.85973327 2 P 0 ;0,1=122,2=270.000000
L 4.98166654 5.85973327 4.98416673 5.8608001 2 P 0 ;0,1=122,2=270.000000
L 4.98416673 5.8608001 4.98708356 5.86106673 2 P 0 ;0,1=122,2=270.000000
L 4.98708356 5.86106673 4.98958376 5.8608001 2 P 0 ;0,1=122,2=270.000000
L 4.98958376 5.8608001 4.99208396 5.85973327 2 P 0 ;0,1=122,2=270.000000
L 4.99208396 5.85973327 4.99416693 5.85813307 2 P 0 ;0,1=122,2=270.000000
L 4.99416693 5.85813307 4.995 5.85626683 2 P 0 ;0,1=122,2=270.000000
L 4.995 5.85626683 4.99416693 5.85413346 2 P 0 ;0,1=122,2=270.000000
L 4.99416693 5.85413346 4.99166742 5.85226663 2 P 0 ;0,1=122,2=270.000000
L 4.99166742 5.85226663 4.98791673 5.8511998 2 P 0 ;0,1=122,2=270.000000
L 4.98791673 5.8511998 4.9837502 5.85093317 2 P 0 ;0,1=122,2=270.000000
L 4.9837502 5.85093317 4.97833386 5.85146634 2 P 0 ;0,1=122,2=270.000000
L 4.97833386 5.85146634 4.97541634 5.85226663 2 P 0 ;0,1=122,2=270.000000
L 4.97541634 5.85226663 4.9725003 5.8535997 2 P 0 ;0,1=122,2=270.000000
L 4.9725003 5.8535997 4.97041663 5.85546654 2 P 0 ;0,1=122,2=270.000000
L 4.97041663 5.85546654 4.97 5.85733327 2 P 0 ;0,1=122,2=270.000000
L 4.97 5.85733327 4.97083317 5.8592 2 P 0 ;0,1=122,2=270.000000
L 4.97083317 5.8592 4.97291683 5.86053356 2 P 0 ;0,1=122,2=270.000000
L 4.995 5.8799997 4.97 5.8799997 2 P 0 ;0,1=122,2=270.000000
L 4.97 5.8799997 4.9749997 5.8767999 2 P 0 ;0,1=122,2=270.000000
L 4.995 5.8767999 4.995 5.88319951 2 P 0 ;0,1=122,2=270.000000
L 4.98458406 5.89893317 4.98166654 5.9007999 2 P 0 ;0,1=122,2=270.000000
L 4.98166654 5.9007999 4.9800002 5.9024 2 P 0 ;0,1=122,2=270.000000
L 4.9800002 5.9024 4.97916703 5.90453337 2 P 0 ;0,1=122,2=270.000000
L 4.97916703 5.90453337 4.9800002 5.9064002 2 P 0 ;0,1=122,2=270.000000
L 4.9800002 5.9064002 4.98166654 5.90773327 2 P 0 ;0,1=122,2=270.000000
L 4.98166654 5.90773327 4.98416673 5.9088001 2 P 0 ;0,1=122,2=270.000000
L 4.98416673 5.9088001 4.98708356 5.90906673 2 P 0 ;0,1=122,2=270.000000
L 4.98708356 5.90906673 4.98958376 5.9088001 2 P 0 ;0,1=122,2=270.000000
L 4.98958376 5.9088001 4.99208396 5.90773327 2 P 0 ;0,1=122,2=270.000000
L 4.99208396 5.90773327 4.99416693 5.90613307 2 P 0 ;0,1=122,2=270.000000
L 4.99416693 5.90613307 4.995 5.90426683 2 P 0 ;0,1=122,2=270.000000
L 4.995 5.90426683 4.99416693 5.90213346 2 P 0 ;0,1=122,2=270.000000
L 4.99416693 5.90213346 4.99166742 5.90026663 2 P 0 ;0,1=122,2=270.000000
L 4.99166742 5.90026663 4.98791673 5.8991998 2 P 0 ;0,1=122,2=270.000000
L 4.98791673 5.8991998 4.9837502 5.89893317 2 P 0 ;0,1=122,2=270.000000
L 4.9837502 5.89893317 4.97833386 5.89946634 2 P 0 ;0,1=122,2=270.000000
L 4.97833386 5.89946634 4.97541634 5.90026663 2 P 0 ;0,1=122,2=270.000000
L 4.97541634 5.90026663 4.9725003 5.9015997 2 P 0 ;0,1=122,2=270.000000
L 4.9725003 5.9015997 4.97041663 5.90346654 2 P 0 ;0,1=122,2=270.000000
L 4.97041663 5.90346654 4.97 5.90533327 2 P 0 ;0,1=122,2=270.000000
L 4.97 5.90533327 4.97083317 5.9072 2 P 0 ;0,1=122,2=270.000000
L 4.97083317 5.9072 4.97291683 5.90853356 2 P 0 ;0,1=122,2=270.000000
L 4.90213002 5.425 4.91786998 5.425 3 P 0 
L 4.925 5.23766654 4.9 5.23766654 2 P 0 ;0,1=123,2=270.000000
L 4.9 5.23766654 4.9 5.24433327 2 P 0 ;0,1=123,2=270.000000
L 4.9 5.24433327 4.90125059 5.24646663 2 P 0 ;0,1=123,2=270.000000
L 4.90125059 5.24646663 4.90291683 5.2478001 2 P 0 ;0,1=123,2=270.000000
L 4.90291683 5.2478001 4.9062502 5.24833337 2 P 0 ;0,1=123,2=270.000000
L 4.9062502 5.24833337 4.90958366 5.2478001 2 P 0 ;0,1=123,2=270.000000
L 4.90958366 5.2478001 4.91166654 5.2462 2 P 0 ;0,1=123,2=270.000000
L 4.91166654 5.2462 4.91291703 5.24433327 2 P 0 ;0,1=123,2=270.000000
L 4.91291703 5.24433327 4.91291703 5.23766654 2 P 0 ;0,1=123,2=270.000000
L 4.91291703 5.24433327 4.925 5.24833337 2 P 0 ;0,1=123,2=270.000000
L 4.925 5.2669997 4.9 5.2669997 2 P 0 ;0,1=123,2=270.000000
L 4.9 5.2669997 4.9049997 5.2637999 2 P 0 ;0,1=123,2=270.000000
L 4.925 5.2637999 4.925 5.27019951 2 P 0 ;0,1=123,2=270.000000
L 4.91458406 5.28593317 4.91166654 5.2877999 2 P 0 ;0,1=123,2=270.000000
L 4.91166654 5.2877999 4.9100002 5.2894 2 P 0 ;0,1=123,2=270.000000
L 4.9100002 5.2894 4.90916703 5.29153337 2 P 0 ;0,1=123,2=270.000000
L 4.90916703 5.29153337 4.9100002 5.2934002 2 P 0 ;0,1=123,2=270.000000
L 4.9100002 5.2934002 4.91166654 5.29473327 2 P 0 ;0,1=123,2=270.000000
L 4.91166654 5.29473327 4.91416673 5.2958001 2 P 0 ;0,1=123,2=270.000000
L 4.91416673 5.2958001 4.91708356 5.29606673 2 P 0 ;0,1=123,2=270.000000
L 4.91708356 5.29606673 4.91958376 5.2958001 2 P 0 ;0,1=123,2=270.000000
L 4.91958376 5.2958001 4.92208396 5.29473327 2 P 0 ;0,1=123,2=270.000000
L 4.92208396 5.29473327 4.92416693 5.29313307 2 P 0 ;0,1=123,2=270.000000
L 4.92416693 5.29313307 4.925 5.29126683 2 P 0 ;0,1=123,2=270.000000
L 4.925 5.29126683 4.92416693 5.28913346 2 P 0 ;0,1=123,2=270.000000
L 4.92416693 5.28913346 4.92166742 5.28726663 2 P 0 ;0,1=123,2=270.000000
L 4.92166742 5.28726663 4.91791673 5.2861998 2 P 0 ;0,1=123,2=270.000000
L 4.91791673 5.2861998 4.9137502 5.28593317 2 P 0 ;0,1=123,2=270.000000
L 4.9137502 5.28593317 4.90833386 5.28646634 2 P 0 ;0,1=123,2=270.000000
L 4.90833386 5.28646634 4.90541634 5.28726663 2 P 0 ;0,1=123,2=270.000000
L 4.90541634 5.28726663 4.9025003 5.2885997 2 P 0 ;0,1=123,2=270.000000
L 4.9025003 5.2885997 4.90041663 5.29046654 2 P 0 ;0,1=123,2=270.000000
L 4.90041663 5.29046654 4.9 5.29233327 2 P 0 ;0,1=123,2=270.000000
L 4.9 5.29233327 4.90083317 5.2942 2 P 0 ;0,1=123,2=270.000000
L 4.90083317 5.2942 4.90291683 5.29553356 2 P 0 ;0,1=123,2=270.000000
L 4.925 5.3149997 4.9 5.3149997 2 P 0 ;0,1=123,2=270.000000
L 4.9 5.3149997 4.9049997 5.3117999 2 P 0 ;0,1=123,2=270.000000
L 4.925 5.3117999 4.925 5.31819951 2 P 0 ;0,1=123,2=270.000000
L 4.92125089 5.33313327 4.92333376 5.33473297 2 P 0 ;0,1=123,2=270.000000
L 4.92333376 5.33473297 4.92458346 5.3365997 2 P 0 ;0,1=123,2=270.000000
L 4.92458346 5.3365997 4.925 5.3389997 2 P 0 ;0,1=123,2=270.000000
L 4.925 5.3389997 4.92416693 5.3414002 2 P 0 ;0,1=123,2=270.000000
L 4.92416693 5.3414002 4.92250059 5.34326644 2 P 0 ;0,1=123,2=270.000000
L 4.92250059 5.34326644 4.91958376 5.3446 2 P 0 ;0,1=123,2=270.000000
L 4.91958376 5.3446 4.91625039 5.34486663 2 P 0 ;0,1=123,2=270.000000
L 4.91625039 5.34486663 4.91291703 5.34433337 2 P 0 ;0,1=123,2=270.000000
L 4.91291703 5.34433337 4.91083337 5.3429998 2 P 0 ;0,1=123,2=270.000000
L 4.91083337 5.3429998 4.90916703 5.34113307 2 P 0 ;0,1=123,2=270.000000
L 4.90916703 5.34113307 4.90875049 5.33926683 2 P 0 ;0,1=123,2=270.000000
L 4.90875049 5.33926683 4.90916703 5.3374 2 P 0 ;0,1=123,2=270.000000
L 4.90916703 5.3374 4.91083337 5.3350001 2 P 0 ;0,1=123,2=270.000000
L 4.91083337 5.3350001 4.9 5.3357999 2 P 0 ;0,1=123,2=270.000000
L 4.9 5.3357999 4.9 5.3429998 2 P 0 ;0,1=123,2=270.000000
L 4.85213002 5.425 4.86786998 5.425 3 P 0 
L 4.875 5.23766654 4.85 5.23766654 2 P 0 ;0,1=124,2=270.000000
L 4.85 5.23766654 4.85 5.24433327 2 P 0 ;0,1=124,2=270.000000
L 4.85 5.24433327 4.85125059 5.24646663 2 P 0 ;0,1=124,2=270.000000
L 4.85125059 5.24646663 4.85291683 5.2478001 2 P 0 ;0,1=124,2=270.000000
L 4.85291683 5.2478001 4.8562502 5.24833337 2 P 0 ;0,1=124,2=270.000000
L 4.8562502 5.24833337 4.85958366 5.2478001 2 P 0 ;0,1=124,2=270.000000
L 4.85958366 5.2478001 4.86166654 5.2462 2 P 0 ;0,1=124,2=270.000000
L 4.86166654 5.2462 4.86291703 5.24433327 2 P 0 ;0,1=124,2=270.000000
L 4.86291703 5.24433327 4.86291703 5.23766654 2 P 0 ;0,1=124,2=270.000000
L 4.86291703 5.24433327 4.875 5.24833337 2 P 0 ;0,1=124,2=270.000000
L 4.875 5.2669997 4.85 5.2669997 2 P 0 ;0,1=124,2=270.000000
L 4.85 5.2669997 4.8549997 5.2637999 2 P 0 ;0,1=124,2=270.000000
L 4.875 5.2637999 4.875 5.27019951 2 P 0 ;0,1=124,2=270.000000
L 4.86458406 5.28593317 4.86166654 5.2877999 2 P 0 ;0,1=124,2=270.000000
L 4.86166654 5.2877999 4.8600002 5.2894 2 P 0 ;0,1=124,2=270.000000
L 4.8600002 5.2894 4.85916703 5.29153337 2 P 0 ;0,1=124,2=270.000000
L 4.85916703 5.29153337 4.8600002 5.2934002 2 P 0 ;0,1=124,2=270.000000
L 4.8600002 5.2934002 4.86166654 5.29473327 2 P 0 ;0,1=124,2=270.000000
L 4.86166654 5.29473327 4.86416673 5.2958001 2 P 0 ;0,1=124,2=270.000000
L 4.86416673 5.2958001 4.86708356 5.29606673 2 P 0 ;0,1=124,2=270.000000
L 4.86708356 5.29606673 4.86958376 5.2958001 2 P 0 ;0,1=124,2=270.000000
L 4.86958376 5.2958001 4.87208396 5.29473327 2 P 0 ;0,1=124,2=270.000000
L 4.87208396 5.29473327 4.87416693 5.29313307 2 P 0 ;0,1=124,2=270.000000
L 4.87416693 5.29313307 4.875 5.29126683 2 P 0 ;0,1=124,2=270.000000
L 4.875 5.29126683 4.87416693 5.28913346 2 P 0 ;0,1=124,2=270.000000
L 4.87416693 5.28913346 4.87166742 5.28726663 2 P 0 ;0,1=124,2=270.000000
L 4.87166742 5.28726663 4.86791673 5.2861998 2 P 0 ;0,1=124,2=270.000000
L 4.86791673 5.2861998 4.8637502 5.28593317 2 P 0 ;0,1=124,2=270.000000
L 4.8637502 5.28593317 4.85833386 5.28646634 2 P 0 ;0,1=124,2=270.000000
L 4.85833386 5.28646634 4.85541634 5.28726663 2 P 0 ;0,1=124,2=270.000000
L 4.85541634 5.28726663 4.8525003 5.2885997 2 P 0 ;0,1=124,2=270.000000
L 4.8525003 5.2885997 4.85041663 5.29046654 2 P 0 ;0,1=124,2=270.000000
L 4.85041663 5.29046654 4.85 5.29233327 2 P 0 ;0,1=124,2=270.000000
L 4.85 5.29233327 4.85083317 5.2942 2 P 0 ;0,1=124,2=270.000000
L 4.85083317 5.2942 4.85291683 5.29553356 2 P 0 ;0,1=124,2=270.000000
L 4.85416663 5.30993317 4.85166713 5.31153327 2 P 0 ;0,1=124,2=270.000000
L 4.85166713 5.31153327 4.85041663 5.3134 2 P 0 ;0,1=124,2=270.000000
L 4.85041663 5.3134 4.85 5.31553337 2 P 0 ;0,1=124,2=270.000000
L 4.85 5.31553337 4.85083317 5.3182 2 P 0 ;0,1=124,2=270.000000
L 4.85083317 5.3182 4.85291683 5.32006673 2 P 0 ;0,1=124,2=270.000000
L 4.85291683 5.32006673 4.85541634 5.3206 2 P 0 ;0,1=124,2=270.000000
L 4.85541634 5.3206 4.85791732 5.32033337 2 P 0 ;0,1=124,2=270.000000
L 4.85791732 5.32033337 4.8600002 5.31926644 2 P 0 ;0,1=124,2=270.000000
L 4.8600002 5.31926644 4.86416673 5.31393327 2 P 0 ;0,1=124,2=270.000000
L 4.86416673 5.31393327 4.86708356 5.31153327 2 P 0 ;0,1=124,2=270.000000
L 4.86708356 5.31153327 4.87125089 5.30993317 2 P 0 ;0,1=124,2=270.000000
L 4.87125089 5.30993317 4.875 5.3093999 2 P 0 ;0,1=124,2=270.000000
L 4.875 5.3093999 4.875 5.3206 2 P 0 ;0,1=124,2=270.000000
L 4.87000039 5.33313327 4.87291713 5.33473297 2 P 0 ;0,1=124,2=270.000000
L 4.87291713 5.33473297 4.87458346 5.33686634 2 P 0 ;0,1=124,2=270.000000
L 4.87458346 5.33686634 4.875 5.33926683 2 P 0 ;0,1=124,2=270.000000
L 4.875 5.33926683 4.87458346 5.3414002 2 P 0 ;0,1=124,2=270.000000
L 4.87458346 5.3414002 4.87250059 5.34353356 2 P 0 ;0,1=124,2=270.000000
L 4.87250059 5.34353356 4.87000039 5.34486663 2 P 0 ;0,1=124,2=270.000000
L 4.87000039 5.34486663 4.8675001 5.34513317 2 P 0 ;0,1=124,2=270.000000
L 4.8675001 5.34513317 4.86458406 5.3446 2 P 0 ;0,1=124,2=270.000000
L 4.86458406 5.3446 4.86250039 5.34273327 2 P 0 ;0,1=124,2=270.000000
L 4.86250039 5.34273327 4.86166654 5.34086644 2 P 0 ;0,1=124,2=270.000000
L 4.86166654 5.34086644 4.86166654 5.33846654 2 P 0 ;0,1=124,2=270.000000
L 4.86166654 5.34086644 4.86041673 5.34246663 2 P 0 ;0,1=124,2=270.000000
L 4.86041673 5.34246663 4.85833386 5.3438001 2 P 0 ;0,1=124,2=270.000000
L 4.85833386 5.3438001 4.85583366 5.34433337 2 P 0 ;0,1=124,2=270.000000
L 4.85583366 5.34433337 4.85333346 5.3438001 2 P 0 ;0,1=124,2=270.000000
L 4.85333346 5.3438001 4.85125059 5.34246663 2 P 0 ;0,1=124,2=270.000000
L 4.85125059 5.34246663 4.85 5.34006663 2 P 0 ;0,1=124,2=270.000000
L 4.85 5.34006663 4.85041663 5.33766663 2 P 0 ;0,1=124,2=270.000000
L 4.85041663 5.33766663 4.85208366 5.33526663 2 P 0 ;0,1=124,2=270.000000
L 5.06713002 5.45 5.08286998 5.45 3 P 0 
L 5.09 5.26266654 5.065 5.26266654 2 P 0 ;0,1=125,2=270.000000
L 5.065 5.26266654 5.065 5.26933327 2 P 0 ;0,1=125,2=270.000000
L 5.065 5.26933327 5.06625059 5.27146663 2 P 0 ;0,1=125,2=270.000000
L 5.06625059 5.27146663 5.06791683 5.2728001 2 P 0 ;0,1=125,2=270.000000
L 5.06791683 5.2728001 5.0712502 5.27333337 2 P 0 ;0,1=125,2=270.000000
L 5.0712502 5.27333337 5.07458366 5.2728001 2 P 0 ;0,1=125,2=270.000000
L 5.07458366 5.2728001 5.07666654 5.2712 2 P 0 ;0,1=125,2=270.000000
L 5.07666654 5.2712 5.07791703 5.26933327 2 P 0 ;0,1=125,2=270.000000
L 5.07791703 5.26933327 5.07791703 5.26266654 2 P 0 ;0,1=125,2=270.000000
L 5.07791703 5.26933327 5.09 5.27333337 2 P 0 ;0,1=125,2=270.000000
L 5.09 5.2919997 5.065 5.2919997 2 P 0 ;0,1=125,2=270.000000
L 5.065 5.2919997 5.0699997 5.2887999 2 P 0 ;0,1=125,2=270.000000
L 5.09 5.2887999 5.09 5.29519951 2 P 0 ;0,1=125,2=270.000000
L 5.07958406 5.31093317 5.07666654 5.3127999 2 P 0 ;0,1=125,2=270.000000
L 5.07666654 5.3127999 5.0750002 5.3144 2 P 0 ;0,1=125,2=270.000000
L 5.0750002 5.3144 5.07416703 5.31653337 2 P 0 ;0,1=125,2=270.000000
L 5.07416703 5.31653337 5.0750002 5.3184002 2 P 0 ;0,1=125,2=270.000000
L 5.0750002 5.3184002 5.07666654 5.31973327 2 P 0 ;0,1=125,2=270.000000
L 5.07666654 5.31973327 5.07916673 5.3208001 2 P 0 ;0,1=125,2=270.000000
L 5.07916673 5.3208001 5.08208356 5.32106673 2 P 0 ;0,1=125,2=270.000000
L 5.08208356 5.32106673 5.08458376 5.3208001 2 P 0 ;0,1=125,2=270.000000
L 5.08458376 5.3208001 5.08708396 5.31973327 2 P 0 ;0,1=125,2=270.000000
L 5.08708396 5.31973327 5.08916693 5.31813307 2 P 0 ;0,1=125,2=270.000000
L 5.08916693 5.31813307 5.09 5.31626683 2 P 0 ;0,1=125,2=270.000000
L 5.09 5.31626683 5.08916693 5.31413346 2 P 0 ;0,1=125,2=270.000000
L 5.08916693 5.31413346 5.08666742 5.31226663 2 P 0 ;0,1=125,2=270.000000
L 5.08666742 5.31226663 5.08291673 5.3111998 2 P 0 ;0,1=125,2=270.000000
L 5.08291673 5.3111998 5.0787502 5.31093317 2 P 0 ;0,1=125,2=270.000000
L 5.0787502 5.31093317 5.07333386 5.31146634 2 P 0 ;0,1=125,2=270.000000
L 5.07333386 5.31146634 5.07041634 5.31226663 2 P 0 ;0,1=125,2=270.000000
L 5.07041634 5.31226663 5.0675003 5.3135997 2 P 0 ;0,1=125,2=270.000000
L 5.0675003 5.3135997 5.06541663 5.31546654 2 P 0 ;0,1=125,2=270.000000
L 5.06541663 5.31546654 5.065 5.31733327 2 P 0 ;0,1=125,2=270.000000
L 5.065 5.31733327 5.06583317 5.3192 2 P 0 ;0,1=125,2=270.000000
L 5.06583317 5.3192 5.06791683 5.32053356 2 P 0 ;0,1=125,2=270.000000
L 5.06916663 5.33493317 5.06666713 5.33653327 2 P 0 ;0,1=125,2=270.000000
L 5.06666713 5.33653327 5.06541663 5.3384 2 P 0 ;0,1=125,2=270.000000
L 5.06541663 5.3384 5.065 5.34053337 2 P 0 ;0,1=125,2=270.000000
L 5.065 5.34053337 5.06583317 5.3432 2 P 0 ;0,1=125,2=270.000000
L 5.06583317 5.3432 5.06791683 5.34506673 2 P 0 ;0,1=125,2=270.000000
L 5.06791683 5.34506673 5.07041634 5.3456 2 P 0 ;0,1=125,2=270.000000
L 5.07041634 5.3456 5.07291732 5.34533337 2 P 0 ;0,1=125,2=270.000000
L 5.07291732 5.34533337 5.0750002 5.34426644 2 P 0 ;0,1=125,2=270.000000
L 5.0750002 5.34426644 5.07916673 5.33893327 2 P 0 ;0,1=125,2=270.000000
L 5.07916673 5.33893327 5.08208356 5.33653327 2 P 0 ;0,1=125,2=270.000000
L 5.08208356 5.33653327 5.08625089 5.33493317 2 P 0 ;0,1=125,2=270.000000
L 5.08625089 5.33493317 5.09 5.3343999 2 P 0 ;0,1=125,2=270.000000
L 5.09 5.3343999 5.09 5.3456 2 P 0 ;0,1=125,2=270.000000
L 5.09 5.3639997 5.065 5.3639997 2 P 0 ;0,1=125,2=270.000000
L 5.065 5.3639997 5.0699997 5.3607999 2 P 0 ;0,1=125,2=270.000000
L 5.09 5.3607999 5.09 5.36719951 2 P 0 ;0,1=125,2=270.000000
L 5.11713002 5.45 5.13286998 5.45 3 P 0 
L 5.14 5.26266654 5.115 5.26266654 2 P 0 ;0,1=126,2=270.000000
L 5.115 5.26266654 5.115 5.26933327 2 P 0 ;0,1=126,2=270.000000
L 5.115 5.26933327 5.11625059 5.27146663 2 P 0 ;0,1=126,2=270.000000
L 5.11625059 5.27146663 5.11791683 5.2728001 2 P 0 ;0,1=126,2=270.000000
L 5.11791683 5.2728001 5.1212502 5.27333337 2 P 0 ;0,1=126,2=270.000000
L 5.1212502 5.27333337 5.12458366 5.2728001 2 P 0 ;0,1=126,2=270.000000
L 5.12458366 5.2728001 5.12666654 5.2712 2 P 0 ;0,1=126,2=270.000000
L 5.12666654 5.2712 5.12791703 5.26933327 2 P 0 ;0,1=126,2=270.000000
L 5.12791703 5.26933327 5.12791703 5.26266654 2 P 0 ;0,1=126,2=270.000000
L 5.12791703 5.26933327 5.14 5.27333337 2 P 0 ;0,1=126,2=270.000000
L 5.14 5.2919997 5.115 5.2919997 2 P 0 ;0,1=126,2=270.000000
L 5.115 5.2919997 5.1199997 5.2887999 2 P 0 ;0,1=126,2=270.000000
L 5.14 5.2887999 5.14 5.29519951 2 P 0 ;0,1=126,2=270.000000
L 5.12958406 5.31093317 5.12666654 5.3127999 2 P 0 ;0,1=126,2=270.000000
L 5.12666654 5.3127999 5.1250002 5.3144 2 P 0 ;0,1=126,2=270.000000
L 5.1250002 5.3144 5.12416703 5.31653337 2 P 0 ;0,1=126,2=270.000000
L 5.12416703 5.31653337 5.1250002 5.3184002 2 P 0 ;0,1=126,2=270.000000
L 5.1250002 5.3184002 5.12666654 5.31973327 2 P 0 ;0,1=126,2=270.000000
L 5.12666654 5.31973327 5.12916673 5.3208001 2 P 0 ;0,1=126,2=270.000000
L 5.12916673 5.3208001 5.13208356 5.32106673 2 P 0 ;0,1=126,2=270.000000
L 5.13208356 5.32106673 5.13458376 5.3208001 2 P 0 ;0,1=126,2=270.000000
L 5.13458376 5.3208001 5.13708396 5.31973327 2 P 0 ;0,1=126,2=270.000000
L 5.13708396 5.31973327 5.13916693 5.31813307 2 P 0 ;0,1=126,2=270.000000
L 5.13916693 5.31813307 5.14 5.31626683 2 P 0 ;0,1=126,2=270.000000
L 5.14 5.31626683 5.13916693 5.31413346 2 P 0 ;0,1=126,2=270.000000
L 5.13916693 5.31413346 5.13666742 5.31226663 2 P 0 ;0,1=126,2=270.000000
L 5.13666742 5.31226663 5.13291673 5.3111998 2 P 0 ;0,1=126,2=270.000000
L 5.13291673 5.3111998 5.1287502 5.31093317 2 P 0 ;0,1=126,2=270.000000
L 5.1287502 5.31093317 5.12333386 5.31146634 2 P 0 ;0,1=126,2=270.000000
L 5.12333386 5.31146634 5.12041634 5.31226663 2 P 0 ;0,1=126,2=270.000000
L 5.12041634 5.31226663 5.1175003 5.3135997 2 P 0 ;0,1=126,2=270.000000
L 5.1175003 5.3135997 5.11541663 5.31546654 2 P 0 ;0,1=126,2=270.000000
L 5.11541663 5.31546654 5.115 5.31733327 2 P 0 ;0,1=126,2=270.000000
L 5.115 5.31733327 5.11583317 5.3192 2 P 0 ;0,1=126,2=270.000000
L 5.11583317 5.3192 5.11791683 5.32053356 2 P 0 ;0,1=126,2=270.000000
L 5.11916663 5.33493317 5.11666713 5.33653327 2 P 0 ;0,1=126,2=270.000000
L 5.11666713 5.33653327 5.11541663 5.3384 2 P 0 ;0,1=126,2=270.000000
L 5.11541663 5.3384 5.115 5.34053337 2 P 0 ;0,1=126,2=270.000000
L 5.115 5.34053337 5.11583317 5.3432 2 P 0 ;0,1=126,2=270.000000
L 5.11583317 5.3432 5.11791683 5.34506673 2 P 0 ;0,1=126,2=270.000000
L 5.11791683 5.34506673 5.12041634 5.3456 2 P 0 ;0,1=126,2=270.000000
L 5.12041634 5.3456 5.12291732 5.34533337 2 P 0 ;0,1=126,2=270.000000
L 5.12291732 5.34533337 5.1250002 5.34426644 2 P 0 ;0,1=126,2=270.000000
L 5.1250002 5.34426644 5.12916673 5.33893327 2 P 0 ;0,1=126,2=270.000000
L 5.12916673 5.33893327 5.13208356 5.33653327 2 P 0 ;0,1=126,2=270.000000
L 5.13208356 5.33653327 5.13625089 5.33493317 2 P 0 ;0,1=126,2=270.000000
L 5.13625089 5.33493317 5.14 5.3343999 2 P 0 ;0,1=126,2=270.000000
L 5.14 5.3343999 5.14 5.3456 2 P 0 ;0,1=126,2=270.000000
L 5.13625089 5.35813327 5.13833376 5.35973297 2 P 0 ;0,1=126,2=270.000000
L 5.13833376 5.35973297 5.13958346 5.3615997 2 P 0 ;0,1=126,2=270.000000
L 5.13958346 5.3615997 5.14 5.3639997 2 P 0 ;0,1=126,2=270.000000
L 5.14 5.3639997 5.13916693 5.3664002 2 P 0 ;0,1=126,2=270.000000
L 5.13916693 5.3664002 5.13750059 5.36826644 2 P 0 ;0,1=126,2=270.000000
L 5.13750059 5.36826644 5.13458376 5.3696 2 P 0 ;0,1=126,2=270.000000
L 5.13458376 5.3696 5.13125039 5.36986663 2 P 0 ;0,1=126,2=270.000000
L 5.13125039 5.36986663 5.12791703 5.36933337 2 P 0 ;0,1=126,2=270.000000
L 5.12791703 5.36933337 5.12583337 5.3679998 2 P 0 ;0,1=126,2=270.000000
L 5.12583337 5.3679998 5.12416703 5.36613307 2 P 0 ;0,1=126,2=270.000000
L 5.12416703 5.36613307 5.12375049 5.36426683 2 P 0 ;0,1=126,2=270.000000
L 5.12375049 5.36426683 5.12416703 5.3624 2 P 0 ;0,1=126,2=270.000000
L 5.12416703 5.3624 5.12583337 5.3600001 2 P 0 ;0,1=126,2=270.000000
L 5.12583337 5.3600001 5.115 5.3607999 2 P 0 ;0,1=126,2=270.000000
L 5.115 5.3607999 5.115 5.3679998 2 P 0 ;0,1=126,2=270.000000
L 3.94786998 4.61 3.93213002 4.61 3 P 0 
L 3.925 4.09766654 3.9 4.09766654 2 P 0 ;0,1=127,2=270.000000
L 3.9 4.09766654 3.9 4.10433327 2 P 0 ;0,1=127,2=270.000000
L 3.9 4.10433327 3.90125059 4.10646663 2 P 0 ;0,1=127,2=270.000000
L 3.90125059 4.10646663 3.90291683 4.1078001 2 P 0 ;0,1=127,2=270.000000
L 3.90291683 4.1078001 3.9062502 4.10833337 2 P 0 ;0,1=127,2=270.000000
L 3.9062502 4.10833337 3.90958366 4.1078001 2 P 0 ;0,1=127,2=270.000000
L 3.90958366 4.1078001 3.91166654 4.1062 2 P 0 ;0,1=127,2=270.000000
L 3.91166654 4.1062 3.91291703 4.10433327 2 P 0 ;0,1=127,2=270.000000
L 3.91291703 4.10433327 3.91291703 4.09766654 2 P 0 ;0,1=127,2=270.000000
L 3.91291703 4.10433327 3.925 4.10833337 2 P 0 ;0,1=127,2=270.000000
L 3.925 4.1269997 3.9 4.1269997 2 P 0 ;0,1=127,2=270.000000
L 3.9 4.1269997 3.9049997 4.1237999 2 P 0 ;0,1=127,2=270.000000
L 3.925 4.1237999 3.925 4.13019951 2 P 0 ;0,1=127,2=270.000000
L 3.91458406 4.14593317 3.91166654 4.1477999 2 P 0 ;0,1=127,2=270.000000
L 3.91166654 4.1477999 3.9100002 4.1494 2 P 0 ;0,1=127,2=270.000000
L 3.9100002 4.1494 3.90916703 4.15153337 2 P 0 ;0,1=127,2=270.000000
L 3.90916703 4.15153337 3.9100002 4.1534002 2 P 0 ;0,1=127,2=270.000000
L 3.9100002 4.1534002 3.91166654 4.15473327 2 P 0 ;0,1=127,2=270.000000
L 3.91166654 4.15473327 3.91416673 4.1558001 2 P 0 ;0,1=127,2=270.000000
L 3.91416673 4.1558001 3.91708356 4.15606673 2 P 0 ;0,1=127,2=270.000000
L 3.91708356 4.15606673 3.91958376 4.1558001 2 P 0 ;0,1=127,2=270.000000
L 3.91958376 4.1558001 3.92208396 4.15473327 2 P 0 ;0,1=127,2=270.000000
L 3.92208396 4.15473327 3.92416693 4.15313307 2 P 0 ;0,1=127,2=270.000000
L 3.92416693 4.15313307 3.925 4.15126683 2 P 0 ;0,1=127,2=270.000000
L 3.925 4.15126683 3.92416693 4.14913346 2 P 0 ;0,1=127,2=270.000000
L 3.92416693 4.14913346 3.92166742 4.14726663 2 P 0 ;0,1=127,2=270.000000
L 3.92166742 4.14726663 3.91791673 4.1461998 2 P 0 ;0,1=127,2=270.000000
L 3.91791673 4.1461998 3.9137502 4.14593317 2 P 0 ;0,1=127,2=270.000000
L 3.9137502 4.14593317 3.90833386 4.14646634 2 P 0 ;0,1=127,2=270.000000
L 3.90833386 4.14646634 3.90541634 4.14726663 2 P 0 ;0,1=127,2=270.000000
L 3.90541634 4.14726663 3.9025003 4.1485997 2 P 0 ;0,1=127,2=270.000000
L 3.9025003 4.1485997 3.90041663 4.15046654 2 P 0 ;0,1=127,2=270.000000
L 3.90041663 4.15046654 3.9 4.15233327 2 P 0 ;0,1=127,2=270.000000
L 3.9 4.15233327 3.90083317 4.1542 2 P 0 ;0,1=127,2=270.000000
L 3.90083317 4.1542 3.90291683 4.15553356 2 P 0 ;0,1=127,2=270.000000
L 3.925 4.1749997 3.9 4.1749997 2 P 0 ;0,1=127,2=270.000000
L 3.9 4.1749997 3.9049997 4.1717999 2 P 0 ;0,1=127,2=270.000000
L 3.925 4.1717999 3.925 4.17819951 2 P 0 ;0,1=127,2=270.000000
L 3.92208396 4.19446634 3.92416693 4.19633317 2 P 0 ;0,1=127,2=270.000000
L 3.92416693 4.19633317 3.925 4.19846654 2 P 0 ;0,1=127,2=270.000000
L 3.925 4.19846654 3.92416693 4.2005999 2 P 0 ;0,1=127,2=270.000000
L 3.92416693 4.2005999 3.92166742 4.20246663 2 P 0 ;0,1=127,2=270.000000
L 3.92166742 4.20246663 3.91791673 4.2038001 2 P 0 ;0,1=127,2=270.000000
L 3.91791673 4.2038001 3.91416673 4.20433337 2 P 0 ;0,1=127,2=270.000000
L 3.91416673 4.20433337 3.90958366 4.20433337 2 P 0 ;0,1=127,2=270.000000
L 3.90958366 4.20433337 3.90583366 4.2038001 2 P 0 ;0,1=127,2=270.000000
L 3.90583366 4.2038001 3.9025003 4.20246663 2 P 0 ;0,1=127,2=270.000000
L 3.9025003 4.20246663 3.90083317 4.20086644 2 P 0 ;0,1=127,2=270.000000
L 3.90083317 4.20086644 3.9 4.1989997 2 P 0 ;0,1=127,2=270.000000
L 3.9 4.1989997 3.90083317 4.19686634 2 P 0 ;0,1=127,2=270.000000
L 3.90083317 4.19686634 3.9025003 4.19526663 2 P 0 ;0,1=127,2=270.000000
L 3.9025003 4.19526663 3.9049997 4.1941998 2 P 0 ;0,1=127,2=270.000000
L 3.9049997 4.1941998 3.90833386 4.19366654 2 P 0 ;0,1=127,2=270.000000
L 3.90833386 4.19366654 3.9112499 4.1941998 2 P 0 ;0,1=127,2=270.000000
L 3.9112499 4.1941998 3.91416673 4.19553327 2 P 0 ;0,1=127,2=270.000000
L 3.91416673 4.19553327 3.91583386 4.19713346 2 P 0 ;0,1=127,2=270.000000
L 3.91583386 4.19713346 3.91625039 4.1989997 2 P 0 ;0,1=127,2=270.000000
L 3.91625039 4.1989997 3.91541722 4.20113307 2 P 0 ;0,1=127,2=270.000000
L 3.91541722 4.20113307 3.91333356 4.20273327 2 P 0 ;0,1=127,2=270.000000
L 3.91333356 4.20273327 3.90958366 4.20433337 2 P 0 ;0,1=127,2=270.000000
L 1.02213002 5.01 1.03786998 5.01 3 P 0 
L 1.04 4.69766654 1.015 4.69766654 2 P 0 ;0,1=128,2=270.000000
L 1.015 4.69766654 1.015 4.70433327 2 P 0 ;0,1=128,2=270.000000
L 1.015 4.70433327 1.01625059 4.70646663 2 P 0 ;0,1=128,2=270.000000
L 1.01625059 4.70646663 1.01791683 4.7078001 2 P 0 ;0,1=128,2=270.000000
L 1.01791683 4.7078001 1.0212502 4.70833337 2 P 0 ;0,1=128,2=270.000000
L 1.0212502 4.70833337 1.02458366 4.7078001 2 P 0 ;0,1=128,2=270.000000
L 1.02458366 4.7078001 1.02666654 4.7062 2 P 0 ;0,1=128,2=270.000000
L 1.02666654 4.7062 1.02791703 4.70433327 2 P 0 ;0,1=128,2=270.000000
L 1.02791703 4.70433327 1.02791703 4.69766654 2 P 0 ;0,1=128,2=270.000000
L 1.02791703 4.70433327 1.04 4.70833337 2 P 0 ;0,1=128,2=270.000000
L 1.04 4.7269997 1.015 4.7269997 2 P 0 ;0,1=128,2=270.000000
L 1.015 4.7269997 1.0199997 4.7237999 2 P 0 ;0,1=128,2=270.000000
L 1.04 4.7237999 1.04 4.73019951 2 P 0 ;0,1=128,2=270.000000
L 1.02958406 4.74593317 1.02666654 4.7477999 2 P 0 ;0,1=128,2=270.000000
L 1.02666654 4.7477999 1.0250002 4.7494 2 P 0 ;0,1=128,2=270.000000
L 1.0250002 4.7494 1.02416703 4.75153337 2 P 0 ;0,1=128,2=270.000000
L 1.02416703 4.75153337 1.0250002 4.7534002 2 P 0 ;0,1=128,2=270.000000
L 1.0250002 4.7534002 1.02666654 4.75473327 2 P 0 ;0,1=128,2=270.000000
L 1.02666654 4.75473327 1.02916673 4.7558001 2 P 0 ;0,1=128,2=270.000000
L 1.02916673 4.7558001 1.03208356 4.75606673 2 P 0 ;0,1=128,2=270.000000
L 1.03208356 4.75606673 1.03458376 4.7558001 2 P 0 ;0,1=128,2=270.000000
L 1.03458376 4.7558001 1.03708396 4.75473327 2 P 0 ;0,1=128,2=270.000000
L 1.03708396 4.75473327 1.03916693 4.75313307 2 P 0 ;0,1=128,2=270.000000
L 1.03916693 4.75313307 1.04 4.75126683 2 P 0 ;0,1=128,2=270.000000
L 1.04 4.75126683 1.03916693 4.74913346 2 P 0 ;0,1=128,2=270.000000
L 1.03916693 4.74913346 1.03666742 4.74726663 2 P 0 ;0,1=128,2=270.000000
L 1.03666742 4.74726663 1.03291673 4.7461998 2 P 0 ;0,1=128,2=270.000000
L 1.03291673 4.7461998 1.0287502 4.74593317 2 P 0 ;0,1=128,2=270.000000
L 1.0287502 4.74593317 1.02333386 4.74646634 2 P 0 ;0,1=128,2=270.000000
L 1.02333386 4.74646634 1.02041634 4.74726663 2 P 0 ;0,1=128,2=270.000000
L 1.02041634 4.74726663 1.0175003 4.7485997 2 P 0 ;0,1=128,2=270.000000
L 1.0175003 4.7485997 1.01541663 4.75046654 2 P 0 ;0,1=128,2=270.000000
L 1.01541663 4.75046654 1.015 4.75233327 2 P 0 ;0,1=128,2=270.000000
L 1.015 4.75233327 1.01583317 4.7542 2 P 0 ;0,1=128,2=270.000000
L 1.01583317 4.7542 1.01791683 4.75553356 2 P 0 ;0,1=128,2=270.000000
L 1.04 4.7749997 1.015 4.7749997 2 P 0 ;0,1=128,2=270.000000
L 1.015 4.7749997 1.0199997 4.7717999 2 P 0 ;0,1=128,2=270.000000
L 1.04 4.7717999 1.04 4.77819951 2 P 0 ;0,1=128,2=270.000000
L 1.04 4.8022 1.015 4.8022 2 P 0 ;0,1=128,2=270.000000
L 1.015 4.8022 1.03291673 4.79233297 2 P 0 ;0,1=128,2=270.000000
L 1.03291673 4.79233297 1.03291673 4.80566693 2 P 0 ;0,1=128,2=270.000000
L 5.06786998 5.75 5.05213002 5.75 3 P 0 
L 5.075 5.80266654 5.05 5.80266654 2 P 0 ;0,1=129,2=270.000000
L 5.05 5.80266654 5.05 5.80933327 2 P 0 ;0,1=129,2=270.000000
L 5.05 5.80933327 5.05125059 5.81146663 2 P 0 ;0,1=129,2=270.000000
L 5.05125059 5.81146663 5.05291683 5.8128001 2 P 0 ;0,1=129,2=270.000000
L 5.05291683 5.8128001 5.0562502 5.81333337 2 P 0 ;0,1=129,2=270.000000
L 5.0562502 5.81333337 5.05958366 5.8128001 2 P 0 ;0,1=129,2=270.000000
L 5.05958366 5.8128001 5.06166654 5.8112 2 P 0 ;0,1=129,2=270.000000
L 5.06166654 5.8112 5.06291703 5.80933327 2 P 0 ;0,1=129,2=270.000000
L 5.06291703 5.80933327 5.06291703 5.80266654 2 P 0 ;0,1=129,2=270.000000
L 5.06291703 5.80933327 5.075 5.81333337 2 P 0 ;0,1=129,2=270.000000
L 5.075 5.8319997 5.05 5.8319997 2 P 0 ;0,1=129,2=270.000000
L 5.05 5.8319997 5.0549997 5.8287999 2 P 0 ;0,1=129,2=270.000000
L 5.075 5.8287999 5.075 5.83519951 2 P 0 ;0,1=129,2=270.000000
L 5.06458406 5.85093317 5.06166654 5.8527999 2 P 0 ;0,1=129,2=270.000000
L 5.06166654 5.8527999 5.0600002 5.8544 2 P 0 ;0,1=129,2=270.000000
L 5.0600002 5.8544 5.05916703 5.85653337 2 P 0 ;0,1=129,2=270.000000
L 5.05916703 5.85653337 5.0600002 5.8584002 2 P 0 ;0,1=129,2=270.000000
L 5.0600002 5.8584002 5.06166654 5.85973327 2 P 0 ;0,1=129,2=270.000000
L 5.06166654 5.85973327 5.06416673 5.8608001 2 P 0 ;0,1=129,2=270.000000
L 5.06416673 5.8608001 5.06708356 5.86106673 2 P 0 ;0,1=129,2=270.000000
L 5.06708356 5.86106673 5.06958376 5.8608001 2 P 0 ;0,1=129,2=270.000000
L 5.06958376 5.8608001 5.07208396 5.85973327 2 P 0 ;0,1=129,2=270.000000
L 5.07208396 5.85973327 5.07416693 5.85813307 2 P 0 ;0,1=129,2=270.000000
L 5.07416693 5.85813307 5.075 5.85626683 2 P 0 ;0,1=129,2=270.000000
L 5.075 5.85626683 5.07416693 5.85413346 2 P 0 ;0,1=129,2=270.000000
L 5.07416693 5.85413346 5.07166742 5.85226663 2 P 0 ;0,1=129,2=270.000000
L 5.07166742 5.85226663 5.06791673 5.8511998 2 P 0 ;0,1=129,2=270.000000
L 5.06791673 5.8511998 5.0637502 5.85093317 2 P 0 ;0,1=129,2=270.000000
L 5.0637502 5.85093317 5.05833386 5.85146634 2 P 0 ;0,1=129,2=270.000000
L 5.05833386 5.85146634 5.05541634 5.85226663 2 P 0 ;0,1=129,2=270.000000
L 5.05541634 5.85226663 5.0525003 5.8535997 2 P 0 ;0,1=129,2=270.000000
L 5.0525003 5.8535997 5.05041663 5.85546654 2 P 0 ;0,1=129,2=270.000000
L 5.05041663 5.85546654 5.05 5.85733327 2 P 0 ;0,1=129,2=270.000000
L 5.05 5.85733327 5.05083317 5.8592 2 P 0 ;0,1=129,2=270.000000
L 5.05083317 5.8592 5.05291683 5.86053356 2 P 0 ;0,1=129,2=270.000000
L 5.05416663 5.87493317 5.05166713 5.87653327 2 P 0 ;0,1=129,2=270.000000
L 5.05166713 5.87653327 5.05041663 5.8784 2 P 0 ;0,1=129,2=270.000000
L 5.05041663 5.8784 5.05 5.88053337 2 P 0 ;0,1=129,2=270.000000
L 5.05 5.88053337 5.05083317 5.8832 2 P 0 ;0,1=129,2=270.000000
L 5.05083317 5.8832 5.05291683 5.88506673 2 P 0 ;0,1=129,2=270.000000
L 5.05291683 5.88506673 5.05541634 5.8856 2 P 0 ;0,1=129,2=270.000000
L 5.05541634 5.8856 5.05791732 5.88533337 2 P 0 ;0,1=129,2=270.000000
L 5.05791732 5.88533337 5.0600002 5.88426644 2 P 0 ;0,1=129,2=270.000000
L 5.0600002 5.88426644 5.06416673 5.87893327 2 P 0 ;0,1=129,2=270.000000
L 5.06416673 5.87893327 5.06708356 5.87653327 2 P 0 ;0,1=129,2=270.000000
L 5.06708356 5.87653327 5.07125089 5.87493317 2 P 0 ;0,1=129,2=270.000000
L 5.07125089 5.87493317 5.075 5.8743999 2 P 0 ;0,1=129,2=270.000000
L 5.075 5.8743999 5.075 5.8856 2 P 0 ;0,1=129,2=270.000000
L 5.06458406 5.89893317 5.06166654 5.9007999 2 P 0 ;0,1=129,2=270.000000
L 5.06166654 5.9007999 5.0600002 5.9024 2 P 0 ;0,1=129,2=270.000000
L 5.0600002 5.9024 5.05916703 5.90453337 2 P 0 ;0,1=129,2=270.000000
L 5.05916703 5.90453337 5.0600002 5.9064002 2 P 0 ;0,1=129,2=270.000000
L 5.0600002 5.9064002 5.06166654 5.90773327 2 P 0 ;0,1=129,2=270.000000
L 5.06166654 5.90773327 5.06416673 5.9088001 2 P 0 ;0,1=129,2=270.000000
L 5.06416673 5.9088001 5.06708356 5.90906673 2 P 0 ;0,1=129,2=270.000000
L 5.06708356 5.90906673 5.06958376 5.9088001 2 P 0 ;0,1=129,2=270.000000
L 5.06958376 5.9088001 5.07208396 5.90773327 2 P 0 ;0,1=129,2=270.000000
L 5.07208396 5.90773327 5.07416693 5.90613307 2 P 0 ;0,1=129,2=270.000000
L 5.07416693 5.90613307 5.075 5.90426683 2 P 0 ;0,1=129,2=270.000000
L 5.075 5.90426683 5.07416693 5.90213346 2 P 0 ;0,1=129,2=270.000000
L 5.07416693 5.90213346 5.07166742 5.90026663 2 P 0 ;0,1=129,2=270.000000
L 5.07166742 5.90026663 5.06791673 5.8991998 2 P 0 ;0,1=129,2=270.000000
L 5.06791673 5.8991998 5.0637502 5.89893317 2 P 0 ;0,1=129,2=270.000000
L 5.0637502 5.89893317 5.05833386 5.89946634 2 P 0 ;0,1=129,2=270.000000
L 5.05833386 5.89946634 5.05541634 5.90026663 2 P 0 ;0,1=129,2=270.000000
L 5.05541634 5.90026663 5.0525003 5.9015997 2 P 0 ;0,1=129,2=270.000000
L 5.0525003 5.9015997 5.05041663 5.90346654 2 P 0 ;0,1=129,2=270.000000
L 5.05041663 5.90346654 5.05 5.90533327 2 P 0 ;0,1=129,2=270.000000
L 5.05 5.90533327 5.05083317 5.9072 2 P 0 ;0,1=129,2=270.000000
L 5.05083317 5.9072 5.05291683 5.90853356 2 P 0 ;0,1=129,2=270.000000
L 1.05186998 5.4 1.03613002 5.4 3 P 0 
L 1.2 5.33766654 1.175 5.33766654 2 P 0 ;0,1=130,2=270.000000
L 1.175 5.33766654 1.175 5.34433327 2 P 0 ;0,1=130,2=270.000000
L 1.175 5.34433327 1.17625059 5.34646663 2 P 0 ;0,1=130,2=270.000000
L 1.17625059 5.34646663 1.17791683 5.3478001 2 P 0 ;0,1=130,2=270.000000
L 1.17791683 5.3478001 1.1812502 5.34833337 2 P 0 ;0,1=130,2=270.000000
L 1.1812502 5.34833337 1.18458366 5.3478001 2 P 0 ;0,1=130,2=270.000000
L 1.18458366 5.3478001 1.18666654 5.3462 2 P 0 ;0,1=130,2=270.000000
L 1.18666654 5.3462 1.18791703 5.34433327 2 P 0 ;0,1=130,2=270.000000
L 1.18791703 5.34433327 1.18791703 5.33766654 2 P 0 ;0,1=130,2=270.000000
L 1.18791703 5.34433327 1.2 5.34833337 2 P 0 ;0,1=130,2=270.000000
L 1.2 5.3669997 1.175 5.3669997 2 P 0 ;0,1=130,2=270.000000
L 1.175 5.3669997 1.1799997 5.3637999 2 P 0 ;0,1=130,2=270.000000
L 1.2 5.3637999 1.2 5.37019951 2 P 0 ;0,1=130,2=270.000000
L 1.18958406 5.38593317 1.18666654 5.3877999 2 P 0 ;0,1=130,2=270.000000
L 1.18666654 5.3877999 1.1850002 5.3894 2 P 0 ;0,1=130,2=270.000000
L 1.1850002 5.3894 1.18416703 5.39153337 2 P 0 ;0,1=130,2=270.000000
L 1.18416703 5.39153337 1.1850002 5.3934002 2 P 0 ;0,1=130,2=270.000000
L 1.1850002 5.3934002 1.18666654 5.39473327 2 P 0 ;0,1=130,2=270.000000
L 1.18666654 5.39473327 1.18916673 5.3958001 2 P 0 ;0,1=130,2=270.000000
L 1.18916673 5.3958001 1.19208356 5.39606673 2 P 0 ;0,1=130,2=270.000000
L 1.19208356 5.39606673 1.19458376 5.3958001 2 P 0 ;0,1=130,2=270.000000
L 1.19458376 5.3958001 1.19708396 5.39473327 2 P 0 ;0,1=130,2=270.000000
L 1.19708396 5.39473327 1.19916693 5.39313307 2 P 0 ;0,1=130,2=270.000000
L 1.19916693 5.39313307 1.2 5.39126683 2 P 0 ;0,1=130,2=270.000000
L 1.2 5.39126683 1.19916693 5.38913346 2 P 0 ;0,1=130,2=270.000000
L 1.19916693 5.38913346 1.19666742 5.38726663 2 P 0 ;0,1=130,2=270.000000
L 1.19666742 5.38726663 1.19291673 5.3861998 2 P 0 ;0,1=130,2=270.000000
L 1.19291673 5.3861998 1.1887502 5.38593317 2 P 0 ;0,1=130,2=270.000000
L 1.1887502 5.38593317 1.18333386 5.38646634 2 P 0 ;0,1=130,2=270.000000
L 1.18333386 5.38646634 1.18041634 5.38726663 2 P 0 ;0,1=130,2=270.000000
L 1.18041634 5.38726663 1.1775003 5.3885997 2 P 0 ;0,1=130,2=270.000000
L 1.1775003 5.3885997 1.17541663 5.39046654 2 P 0 ;0,1=130,2=270.000000
L 1.17541663 5.39046654 1.175 5.39233327 2 P 0 ;0,1=130,2=270.000000
L 1.175 5.39233327 1.17583317 5.3942 2 P 0 ;0,1=130,2=270.000000
L 1.17583317 5.3942 1.17791683 5.39553356 2 P 0 ;0,1=130,2=270.000000
L 1.175 5.4149997 1.17583317 5.41286634 2 P 0 ;0,1=130,2=270.000000
L 1.17583317 5.41286634 1.17791683 5.41126663 2 P 0 ;0,1=130,2=270.000000
L 1.17791683 5.41126663 1.18041634 5.4101998 2 P 0 ;0,1=130,2=270.000000
L 1.18041634 5.4101998 1.18375049 5.4093999 2 P 0 ;0,1=130,2=270.000000
L 1.18375049 5.4093999 1.18750039 5.40913327 2 P 0 ;0,1=130,2=270.000000
L 1.18750039 5.40913327 1.19125039 5.4093999 2 P 0 ;0,1=130,2=270.000000
L 1.19125039 5.4093999 1.19458376 5.4101998 2 P 0 ;0,1=130,2=270.000000
L 1.19458376 5.4101998 1.19708396 5.41126663 2 P 0 ;0,1=130,2=270.000000
L 1.19708396 5.41126663 1.19916693 5.41286634 2 P 0 ;0,1=130,2=270.000000
L 1.19916693 5.41286634 1.2 5.4149997 2 P 0 ;0,1=130,2=270.000000
L 1.2 5.4149997 1.19916693 5.41713307 2 P 0 ;0,1=130,2=270.000000
L 1.19916693 5.41713307 1.19708396 5.41873327 2 P 0 ;0,1=130,2=270.000000
L 1.19708396 5.41873327 1.19458376 5.4198001 2 P 0 ;0,1=130,2=270.000000
L 1.19458376 5.4198001 1.19125039 5.4206 2 P 0 ;0,1=130,2=270.000000
L 1.19125039 5.4206 1.18750039 5.42086663 2 P 0 ;0,1=130,2=270.000000
L 1.18750039 5.42086663 1.18375049 5.4206 2 P 0 ;0,1=130,2=270.000000
L 1.18375049 5.4206 1.18041634 5.4198001 2 P 0 ;0,1=130,2=270.000000
L 1.18041634 5.4198001 1.17791683 5.41873327 2 P 0 ;0,1=130,2=270.000000
L 1.17791683 5.41873327 1.17583317 5.41713307 2 P 0 ;0,1=130,2=270.000000
L 1.17583317 5.41713307 1.175 5.4149997 2 P 0 ;0,1=130,2=270.000000
L 1.2 5.43846654 1.19458376 5.4389997 2 P 0 ;0,1=130,2=270.000000
L 1.19458376 5.4389997 1.19000069 5.4398 2 P 0 ;0,1=130,2=270.000000
L 1.19000069 5.4398 1.18583337 5.44086644 2 P 0 ;0,1=130,2=270.000000
L 1.18583337 5.44086644 1.1812502 5.4422 2 P 0 ;0,1=130,2=270.000000
L 1.1812502 5.4422 1.175 5.44433337 2 P 0 ;0,1=130,2=270.000000
L 1.175 5.44433337 1.175 5.43366654 2 P 0 ;0,1=130,2=270.000000
L 3.89786998 4.7 3.88213002 4.7 3 P 0 
L 3.88 4.24266654 3.855 4.24266654 2 P 0 ;0,1=131,2=270.000000
L 3.855 4.24266654 3.855 4.24933327 2 P 0 ;0,1=131,2=270.000000
L 3.855 4.24933327 3.85625059 4.25146663 2 P 0 ;0,1=131,2=270.000000
L 3.85625059 4.25146663 3.85791683 4.2528001 2 P 0 ;0,1=131,2=270.000000
L 3.85791683 4.2528001 3.8612502 4.25333337 2 P 0 ;0,1=131,2=270.000000
L 3.8612502 4.25333337 3.86458366 4.2528001 2 P 0 ;0,1=131,2=270.000000
L 3.86458366 4.2528001 3.86666654 4.2512 2 P 0 ;0,1=131,2=270.000000
L 3.86666654 4.2512 3.86791703 4.24933327 2 P 0 ;0,1=131,2=270.000000
L 3.86791703 4.24933327 3.86791703 4.24266654 2 P 0 ;0,1=131,2=270.000000
L 3.86791703 4.24933327 3.88 4.25333337 2 P 0 ;0,1=131,2=270.000000
L 3.88 4.2719997 3.855 4.2719997 2 P 0 ;0,1=131,2=270.000000
L 3.855 4.2719997 3.8599997 4.2687999 2 P 0 ;0,1=131,2=270.000000
L 3.88 4.2687999 3.88 4.27519951 2 P 0 ;0,1=131,2=270.000000
L 3.86958406 4.29093317 3.86666654 4.2927999 2 P 0 ;0,1=131,2=270.000000
L 3.86666654 4.2927999 3.8650002 4.2944 2 P 0 ;0,1=131,2=270.000000
L 3.8650002 4.2944 3.86416703 4.29653337 2 P 0 ;0,1=131,2=270.000000
L 3.86416703 4.29653337 3.8650002 4.2984002 2 P 0 ;0,1=131,2=270.000000
L 3.8650002 4.2984002 3.86666654 4.29973327 2 P 0 ;0,1=131,2=270.000000
L 3.86666654 4.29973327 3.86916673 4.3008001 2 P 0 ;0,1=131,2=270.000000
L 3.86916673 4.3008001 3.87208356 4.30106673 2 P 0 ;0,1=131,2=270.000000
L 3.87208356 4.30106673 3.87458376 4.3008001 2 P 0 ;0,1=131,2=270.000000
L 3.87458376 4.3008001 3.87708396 4.29973327 2 P 0 ;0,1=131,2=270.000000
L 3.87708396 4.29973327 3.87916693 4.29813307 2 P 0 ;0,1=131,2=270.000000
L 3.87916693 4.29813307 3.88 4.29626683 2 P 0 ;0,1=131,2=270.000000
L 3.88 4.29626683 3.87916693 4.29413346 2 P 0 ;0,1=131,2=270.000000
L 3.87916693 4.29413346 3.87666742 4.29226663 2 P 0 ;0,1=131,2=270.000000
L 3.87666742 4.29226663 3.87291673 4.2911998 2 P 0 ;0,1=131,2=270.000000
L 3.87291673 4.2911998 3.8687502 4.29093317 2 P 0 ;0,1=131,2=270.000000
L 3.8687502 4.29093317 3.86333386 4.29146634 2 P 0 ;0,1=131,2=270.000000
L 3.86333386 4.29146634 3.86041634 4.29226663 2 P 0 ;0,1=131,2=270.000000
L 3.86041634 4.29226663 3.8575003 4.2935997 2 P 0 ;0,1=131,2=270.000000
L 3.8575003 4.2935997 3.85541663 4.29546654 2 P 0 ;0,1=131,2=270.000000
L 3.85541663 4.29546654 3.855 4.29733327 2 P 0 ;0,1=131,2=270.000000
L 3.855 4.29733327 3.85583317 4.2992 2 P 0 ;0,1=131,2=270.000000
L 3.85583317 4.2992 3.85791683 4.30053356 2 P 0 ;0,1=131,2=270.000000
L 3.855 4.3199997 3.85583317 4.31786634 2 P 0 ;0,1=131,2=270.000000
L 3.85583317 4.31786634 3.85791683 4.31626663 2 P 0 ;0,1=131,2=270.000000
L 3.85791683 4.31626663 3.86041634 4.3151998 2 P 0 ;0,1=131,2=270.000000
L 3.86041634 4.3151998 3.86375049 4.3143999 2 P 0 ;0,1=131,2=270.000000
L 3.86375049 4.3143999 3.86750039 4.31413327 2 P 0 ;0,1=131,2=270.000000
L 3.86750039 4.31413327 3.87125039 4.3143999 2 P 0 ;0,1=131,2=270.000000
L 3.87125039 4.3143999 3.87458376 4.3151998 2 P 0 ;0,1=131,2=270.000000
L 3.87458376 4.3151998 3.87708396 4.31626663 2 P 0 ;0,1=131,2=270.000000
L 3.87708396 4.31626663 3.87916693 4.31786634 2 P 0 ;0,1=131,2=270.000000
L 3.87916693 4.31786634 3.88 4.3199997 2 P 0 ;0,1=131,2=270.000000
L 3.88 4.3199997 3.87916693 4.32213307 2 P 0 ;0,1=131,2=270.000000
L 3.87916693 4.32213307 3.87708396 4.32373327 2 P 0 ;0,1=131,2=270.000000
L 3.87708396 4.32373327 3.87458376 4.3248001 2 P 0 ;0,1=131,2=270.000000
L 3.87458376 4.3248001 3.87125039 4.3256 2 P 0 ;0,1=131,2=270.000000
L 3.87125039 4.3256 3.86750039 4.32586663 2 P 0 ;0,1=131,2=270.000000
L 3.86750039 4.32586663 3.86375049 4.3256 2 P 0 ;0,1=131,2=270.000000
L 3.86375049 4.3256 3.86041634 4.3248001 2 P 0 ;0,1=131,2=270.000000
L 3.86041634 4.3248001 3.85791683 4.32373327 2 P 0 ;0,1=131,2=270.000000
L 3.85791683 4.32373327 3.85583317 4.32213307 2 P 0 ;0,1=131,2=270.000000
L 3.85583317 4.32213307 3.855 4.3199997 2 P 0 ;0,1=131,2=270.000000
L 3.85916663 4.33893317 3.85666713 4.34053327 2 P 0 ;0,1=131,2=270.000000
L 3.85666713 4.34053327 3.85541663 4.3424 2 P 0 ;0,1=131,2=270.000000
L 3.85541663 4.3424 3.855 4.34453337 2 P 0 ;0,1=131,2=270.000000
L 3.855 4.34453337 3.85583317 4.3472 2 P 0 ;0,1=131,2=270.000000
L 3.85583317 4.3472 3.85791683 4.34906673 2 P 0 ;0,1=131,2=270.000000
L 3.85791683 4.34906673 3.86041634 4.3496 2 P 0 ;0,1=131,2=270.000000
L 3.86041634 4.3496 3.86291732 4.34933337 2 P 0 ;0,1=131,2=270.000000
L 3.86291732 4.34933337 3.8650002 4.34826644 2 P 0 ;0,1=131,2=270.000000
L 3.8650002 4.34826644 3.86916673 4.34293327 2 P 0 ;0,1=131,2=270.000000
L 3.86916673 4.34293327 3.87208356 4.34053327 2 P 0 ;0,1=131,2=270.000000
L 3.87208356 4.34053327 3.87625089 4.33893317 2 P 0 ;0,1=131,2=270.000000
L 3.87625089 4.33893317 3.88 4.3383999 2 P 0 ;0,1=131,2=270.000000
L 3.88 4.3383999 3.88 4.3496 2 P 0 ;0,1=131,2=270.000000
L 3.90213002 5.46 3.91786998 5.46 3 P 0 
L 3.88 5.44766654 3.855 5.44766654 2 P 0 ;0,1=132,2=270.000000
L 3.855 5.44766654 3.855 5.45433327 2 P 0 ;0,1=132,2=270.000000
L 3.855 5.45433327 3.85625059 5.45646663 2 P 0 ;0,1=132,2=270.000000
L 3.85625059 5.45646663 3.85791683 5.4578001 2 P 0 ;0,1=132,2=270.000000
L 3.85791683 5.4578001 3.8612502 5.45833337 2 P 0 ;0,1=132,2=270.000000
L 3.8612502 5.45833337 3.86458366 5.4578001 2 P 0 ;0,1=132,2=270.000000
L 3.86458366 5.4578001 3.86666654 5.4562 2 P 0 ;0,1=132,2=270.000000
L 3.86666654 5.4562 3.86791703 5.45433327 2 P 0 ;0,1=132,2=270.000000
L 3.86791703 5.45433327 3.86791703 5.44766654 2 P 0 ;0,1=132,2=270.000000
L 3.86791703 5.45433327 3.88 5.45833337 2 P 0 ;0,1=132,2=270.000000
L 3.88 5.4769997 3.855 5.4769997 2 P 0 ;0,1=132,2=270.000000
L 3.855 5.4769997 3.8599997 5.4737999 2 P 0 ;0,1=132,2=270.000000
L 3.88 5.4737999 3.88 5.48019951 2 P 0 ;0,1=132,2=270.000000
L 3.86958406 5.49593317 3.86666654 5.4977999 2 P 0 ;0,1=132,2=270.000000
L 3.86666654 5.4977999 3.8650002 5.4994 2 P 0 ;0,1=132,2=270.000000
L 3.8650002 5.4994 3.86416703 5.50153337 2 P 0 ;0,1=132,2=270.000000
L 3.86416703 5.50153337 3.8650002 5.5034002 2 P 0 ;0,1=132,2=270.000000
L 3.8650002 5.5034002 3.86666654 5.50473327 2 P 0 ;0,1=132,2=270.000000
L 3.86666654 5.50473327 3.86916673 5.5058001 2 P 0 ;0,1=132,2=270.000000
L 3.86916673 5.5058001 3.87208356 5.50606673 2 P 0 ;0,1=132,2=270.000000
L 3.87208356 5.50606673 3.87458376 5.5058001 2 P 0 ;0,1=132,2=270.000000
L 3.87458376 5.5058001 3.87708396 5.50473327 2 P 0 ;0,1=132,2=270.000000
L 3.87708396 5.50473327 3.87916693 5.50313307 2 P 0 ;0,1=132,2=270.000000
L 3.87916693 5.50313307 3.88 5.50126683 2 P 0 ;0,1=132,2=270.000000
L 3.88 5.50126683 3.87916693 5.49913346 2 P 0 ;0,1=132,2=270.000000
L 3.87916693 5.49913346 3.87666742 5.49726663 2 P 0 ;0,1=132,2=270.000000
L 3.87666742 5.49726663 3.87291673 5.4961998 2 P 0 ;0,1=132,2=270.000000
L 3.87291673 5.4961998 3.8687502 5.49593317 2 P 0 ;0,1=132,2=270.000000
L 3.8687502 5.49593317 3.86333386 5.49646634 2 P 0 ;0,1=132,2=270.000000
L 3.86333386 5.49646634 3.86041634 5.49726663 2 P 0 ;0,1=132,2=270.000000
L 3.86041634 5.49726663 3.8575003 5.4985997 2 P 0 ;0,1=132,2=270.000000
L 3.8575003 5.4985997 3.85541663 5.50046654 2 P 0 ;0,1=132,2=270.000000
L 3.85541663 5.50046654 3.855 5.50233327 2 P 0 ;0,1=132,2=270.000000
L 3.855 5.50233327 3.85583317 5.5042 2 P 0 ;0,1=132,2=270.000000
L 3.85583317 5.5042 3.85791683 5.50553356 2 P 0 ;0,1=132,2=270.000000
L 3.855 5.5249997 3.85583317 5.52286634 2 P 0 ;0,1=132,2=270.000000
L 3.85583317 5.52286634 3.85791683 5.52126663 2 P 0 ;0,1=132,2=270.000000
L 3.85791683 5.52126663 3.86041634 5.5201998 2 P 0 ;0,1=132,2=270.000000
L 3.86041634 5.5201998 3.86375049 5.5193999 2 P 0 ;0,1=132,2=270.000000
L 3.86375049 5.5193999 3.86750039 5.51913327 2 P 0 ;0,1=132,2=270.000000
L 3.86750039 5.51913327 3.87125039 5.5193999 2 P 0 ;0,1=132,2=270.000000
L 3.87125039 5.5193999 3.87458376 5.5201998 2 P 0 ;0,1=132,2=270.000000
L 3.87458376 5.5201998 3.87708396 5.52126663 2 P 0 ;0,1=132,2=270.000000
L 3.87708396 5.52126663 3.87916693 5.52286634 2 P 0 ;0,1=132,2=270.000000
L 3.87916693 5.52286634 3.88 5.5249997 2 P 0 ;0,1=132,2=270.000000
L 3.88 5.5249997 3.87916693 5.52713307 2 P 0 ;0,1=132,2=270.000000
L 3.87916693 5.52713307 3.87708396 5.52873327 2 P 0 ;0,1=132,2=270.000000
L 3.87708396 5.52873327 3.87458376 5.5298001 2 P 0 ;0,1=132,2=270.000000
L 3.87458376 5.5298001 3.87125039 5.5306 2 P 0 ;0,1=132,2=270.000000
L 3.87125039 5.5306 3.86750039 5.53086663 2 P 0 ;0,1=132,2=270.000000
L 3.86750039 5.53086663 3.86375049 5.5306 2 P 0 ;0,1=132,2=270.000000
L 3.86375049 5.5306 3.86041634 5.5298001 2 P 0 ;0,1=132,2=270.000000
L 3.86041634 5.5298001 3.85791683 5.52873327 2 P 0 ;0,1=132,2=270.000000
L 3.85791683 5.52873327 3.85583317 5.52713307 2 P 0 ;0,1=132,2=270.000000
L 3.85583317 5.52713307 3.855 5.5249997 2 P 0 ;0,1=132,2=270.000000
L 3.88 5.5489997 3.855 5.5489997 2 P 0 ;0,1=132,2=270.000000
L 3.855 5.5489997 3.8599997 5.5457999 2 P 0 ;0,1=132,2=270.000000
L 3.88 5.5457999 3.88 5.55219951 2 P 0 ;0,1=132,2=270.000000
L 0.96213002 5.01 0.97786998 5.01 3 P 0 
L 0.98 4.69766654 0.955 4.69766654 2 P 0 ;0,1=133,2=270.000000
L 0.955 4.69766654 0.955 4.70433327 2 P 0 ;0,1=133,2=270.000000
L 0.955 4.70433327 0.95625059 4.70646663 2 P 0 ;0,1=133,2=270.000000
L 0.95625059 4.70646663 0.95791683 4.7078001 2 P 0 ;0,1=133,2=270.000000
L 0.95791683 4.7078001 0.9612502 4.70833337 2 P 0 ;0,1=133,2=270.000000
L 0.9612502 4.70833337 0.96458366 4.7078001 2 P 0 ;0,1=133,2=270.000000
L 0.96458366 4.7078001 0.96666654 4.7062 2 P 0 ;0,1=133,2=270.000000
L 0.96666654 4.7062 0.96791703 4.70433327 2 P 0 ;0,1=133,2=270.000000
L 0.96791703 4.70433327 0.96791703 4.69766654 2 P 0 ;0,1=133,2=270.000000
L 0.96791703 4.70433327 0.98 4.70833337 2 P 0 ;0,1=133,2=270.000000
L 0.98 4.7269997 0.955 4.7269997 2 P 0 ;0,1=133,2=270.000000
L 0.955 4.7269997 0.9599997 4.7237999 2 P 0 ;0,1=133,2=270.000000
L 0.98 4.7237999 0.98 4.73019951 2 P 0 ;0,1=133,2=270.000000
L 0.96958406 4.74593317 0.96666654 4.7477999 2 P 0 ;0,1=133,2=270.000000
L 0.96666654 4.7477999 0.9650002 4.7494 2 P 0 ;0,1=133,2=270.000000
L 0.9650002 4.7494 0.96416703 4.75153337 2 P 0 ;0,1=133,2=270.000000
L 0.96416703 4.75153337 0.9650002 4.7534002 2 P 0 ;0,1=133,2=270.000000
L 0.9650002 4.7534002 0.96666654 4.75473327 2 P 0 ;0,1=133,2=270.000000
L 0.96666654 4.75473327 0.96916673 4.7558001 2 P 0 ;0,1=133,2=270.000000
L 0.96916673 4.7558001 0.97208356 4.75606673 2 P 0 ;0,1=133,2=270.000000
L 0.97208356 4.75606673 0.97458376 4.7558001 2 P 0 ;0,1=133,2=270.000000
L 0.97458376 4.7558001 0.97708396 4.75473327 2 P 0 ;0,1=133,2=270.000000
L 0.97708396 4.75473327 0.97916693 4.75313307 2 P 0 ;0,1=133,2=270.000000
L 0.97916693 4.75313307 0.98 4.75126683 2 P 0 ;0,1=133,2=270.000000
L 0.98 4.75126683 0.97916693 4.74913346 2 P 0 ;0,1=133,2=270.000000
L 0.97916693 4.74913346 0.97666742 4.74726663 2 P 0 ;0,1=133,2=270.000000
L 0.97666742 4.74726663 0.97291673 4.7461998 2 P 0 ;0,1=133,2=270.000000
L 0.97291673 4.7461998 0.9687502 4.74593317 2 P 0 ;0,1=133,2=270.000000
L 0.9687502 4.74593317 0.96333386 4.74646634 2 P 0 ;0,1=133,2=270.000000
L 0.96333386 4.74646634 0.96041634 4.74726663 2 P 0 ;0,1=133,2=270.000000
L 0.96041634 4.74726663 0.9575003 4.7485997 2 P 0 ;0,1=133,2=270.000000
L 0.9575003 4.7485997 0.95541663 4.75046654 2 P 0 ;0,1=133,2=270.000000
L 0.95541663 4.75046654 0.955 4.75233327 2 P 0 ;0,1=133,2=270.000000
L 0.955 4.75233327 0.95583317 4.7542 2 P 0 ;0,1=133,2=270.000000
L 0.95583317 4.7542 0.95791683 4.75553356 2 P 0 ;0,1=133,2=270.000000
L 0.955 4.7749997 0.95583317 4.77286634 2 P 0 ;0,1=133,2=270.000000
L 0.95583317 4.77286634 0.95791683 4.77126663 2 P 0 ;0,1=133,2=270.000000
L 0.95791683 4.77126663 0.96041634 4.7701998 2 P 0 ;0,1=133,2=270.000000
L 0.96041634 4.7701998 0.96375049 4.7693999 2 P 0 ;0,1=133,2=270.000000
L 0.96375049 4.7693999 0.96750039 4.76913327 2 P 0 ;0,1=133,2=270.000000
L 0.96750039 4.76913327 0.97125039 4.7693999 2 P 0 ;0,1=133,2=270.000000
L 0.97125039 4.7693999 0.97458376 4.7701998 2 P 0 ;0,1=133,2=270.000000
L 0.97458376 4.7701998 0.97708396 4.77126663 2 P 0 ;0,1=133,2=270.000000
L 0.97708396 4.77126663 0.97916693 4.77286634 2 P 0 ;0,1=133,2=270.000000
L 0.97916693 4.77286634 0.98 4.7749997 2 P 0 ;0,1=133,2=270.000000
L 0.98 4.7749997 0.97916693 4.77713307 2 P 0 ;0,1=133,2=270.000000
L 0.97916693 4.77713307 0.97708396 4.77873327 2 P 0 ;0,1=133,2=270.000000
L 0.97708396 4.77873327 0.97458376 4.7798001 2 P 0 ;0,1=133,2=270.000000
L 0.97458376 4.7798001 0.97125039 4.7806 2 P 0 ;0,1=133,2=270.000000
L 0.97125039 4.7806 0.96750039 4.78086663 2 P 0 ;0,1=133,2=270.000000
L 0.96750039 4.78086663 0.96375049 4.7806 2 P 0 ;0,1=133,2=270.000000
L 0.96375049 4.7806 0.96041634 4.7798001 2 P 0 ;0,1=133,2=270.000000
L 0.96041634 4.7798001 0.95791683 4.77873327 2 P 0 ;0,1=133,2=270.000000
L 0.95791683 4.77873327 0.95583317 4.77713307 2 P 0 ;0,1=133,2=270.000000
L 0.95583317 4.77713307 0.955 4.7749997 2 P 0 ;0,1=133,2=270.000000
L 0.97708396 4.79446634 0.97916693 4.79633317 2 P 0 ;0,1=133,2=270.000000
L 0.97916693 4.79633317 0.98 4.79846654 2 P 0 ;0,1=133,2=270.000000
L 0.98 4.79846654 0.97916693 4.8005999 2 P 0 ;0,1=133,2=270.000000
L 0.97916693 4.8005999 0.97666742 4.80246663 2 P 0 ;0,1=133,2=270.000000
L 0.97666742 4.80246663 0.97291673 4.8038001 2 P 0 ;0,1=133,2=270.000000
L 0.97291673 4.8038001 0.96916673 4.80433337 2 P 0 ;0,1=133,2=270.000000
L 0.96916673 4.80433337 0.96458366 4.80433337 2 P 0 ;0,1=133,2=270.000000
L 0.96458366 4.80433337 0.96083366 4.8038001 2 P 0 ;0,1=133,2=270.000000
L 0.96083366 4.8038001 0.9575003 4.80246663 2 P 0 ;0,1=133,2=270.000000
L 0.9575003 4.80246663 0.95583317 4.80086644 2 P 0 ;0,1=133,2=270.000000
L 0.95583317 4.80086644 0.955 4.7989997 2 P 0 ;0,1=133,2=270.000000
L 0.955 4.7989997 0.95583317 4.79686634 2 P 0 ;0,1=133,2=270.000000
L 0.95583317 4.79686634 0.9575003 4.79526663 2 P 0 ;0,1=133,2=270.000000
L 0.9575003 4.79526663 0.9599997 4.7941998 2 P 0 ;0,1=133,2=270.000000
L 0.9599997 4.7941998 0.96333386 4.79366654 2 P 0 ;0,1=133,2=270.000000
L 0.96333386 4.79366654 0.9662499 4.7941998 2 P 0 ;0,1=133,2=270.000000
L 0.9662499 4.7941998 0.96916673 4.79553327 2 P 0 ;0,1=133,2=270.000000
L 0.96916673 4.79553327 0.97083386 4.79713346 2 P 0 ;0,1=133,2=270.000000
L 0.97083386 4.79713346 0.97125039 4.7989997 2 P 0 ;0,1=133,2=270.000000
L 0.97125039 4.7989997 0.97041722 4.80113307 2 P 0 ;0,1=133,2=270.000000
L 0.97041722 4.80113307 0.96833356 4.80273327 2 P 0 ;0,1=133,2=270.000000
L 0.96833356 4.80273327 0.96458366 4.80433337 2 P 0 ;0,1=133,2=270.000000
L 0.97786998 5.11 0.96213002 5.11 3 P 0 
L 0.98 4.83266654 0.955 4.83266654 2 P 0 ;0,1=134,2=270.000000
L 0.955 4.83266654 0.955 4.83933327 2 P 0 ;0,1=134,2=270.000000
L 0.955 4.83933327 0.95625059 4.84146663 2 P 0 ;0,1=134,2=270.000000
L 0.95625059 4.84146663 0.95791683 4.8428001 2 P 0 ;0,1=134,2=270.000000
L 0.95791683 4.8428001 0.9612502 4.84333337 2 P 0 ;0,1=134,2=270.000000
L 0.9612502 4.84333337 0.96458366 4.8428001 2 P 0 ;0,1=134,2=270.000000
L 0.96458366 4.8428001 0.96666654 4.8412 2 P 0 ;0,1=134,2=270.000000
L 0.96666654 4.8412 0.96791703 4.83933327 2 P 0 ;0,1=134,2=270.000000
L 0.96791703 4.83933327 0.96791703 4.83266654 2 P 0 ;0,1=134,2=270.000000
L 0.96791703 4.83933327 0.98 4.84333337 2 P 0 ;0,1=134,2=270.000000
L 0.98 4.8619997 0.955 4.8619997 2 P 0 ;0,1=134,2=270.000000
L 0.955 4.8619997 0.9599997 4.8587999 2 P 0 ;0,1=134,2=270.000000
L 0.98 4.8587999 0.98 4.86519951 2 P 0 ;0,1=134,2=270.000000
L 0.96958406 4.88093317 0.96666654 4.8827999 2 P 0 ;0,1=134,2=270.000000
L 0.96666654 4.8827999 0.9650002 4.8844 2 P 0 ;0,1=134,2=270.000000
L 0.9650002 4.8844 0.96416703 4.88653337 2 P 0 ;0,1=134,2=270.000000
L 0.96416703 4.88653337 0.9650002 4.8884002 2 P 0 ;0,1=134,2=270.000000
L 0.9650002 4.8884002 0.96666654 4.88973327 2 P 0 ;0,1=134,2=270.000000
L 0.96666654 4.88973327 0.96916673 4.8908001 2 P 0 ;0,1=134,2=270.000000
L 0.96916673 4.8908001 0.97208356 4.89106673 2 P 0 ;0,1=134,2=270.000000
L 0.97208356 4.89106673 0.97458376 4.8908001 2 P 0 ;0,1=134,2=270.000000
L 0.97458376 4.8908001 0.97708396 4.88973327 2 P 0 ;0,1=134,2=270.000000
L 0.97708396 4.88973327 0.97916693 4.88813307 2 P 0 ;0,1=134,2=270.000000
L 0.97916693 4.88813307 0.98 4.88626683 2 P 0 ;0,1=134,2=270.000000
L 0.98 4.88626683 0.97916693 4.88413346 2 P 0 ;0,1=134,2=270.000000
L 0.97916693 4.88413346 0.97666742 4.88226663 2 P 0 ;0,1=134,2=270.000000
L 0.97666742 4.88226663 0.97291673 4.8811998 2 P 0 ;0,1=134,2=270.000000
L 0.97291673 4.8811998 0.9687502 4.88093317 2 P 0 ;0,1=134,2=270.000000
L 0.9687502 4.88093317 0.96333386 4.88146634 2 P 0 ;0,1=134,2=270.000000
L 0.96333386 4.88146634 0.96041634 4.88226663 2 P 0 ;0,1=134,2=270.000000
L 0.96041634 4.88226663 0.9575003 4.8835997 2 P 0 ;0,1=134,2=270.000000
L 0.9575003 4.8835997 0.95541663 4.88546654 2 P 0 ;0,1=134,2=270.000000
L 0.95541663 4.88546654 0.955 4.88733327 2 P 0 ;0,1=134,2=270.000000
L 0.955 4.88733327 0.95583317 4.8892 2 P 0 ;0,1=134,2=270.000000
L 0.95583317 4.8892 0.95791683 4.89053356 2 P 0 ;0,1=134,2=270.000000
L 0.955 4.9099997 0.95583317 4.90786634 2 P 0 ;0,1=134,2=270.000000
L 0.95583317 4.90786634 0.95791683 4.90626663 2 P 0 ;0,1=134,2=270.000000
L 0.95791683 4.90626663 0.96041634 4.9051998 2 P 0 ;0,1=134,2=270.000000
L 0.96041634 4.9051998 0.96375049 4.9043999 2 P 0 ;0,1=134,2=270.000000
L 0.96375049 4.9043999 0.96750039 4.90413327 2 P 0 ;0,1=134,2=270.000000
L 0.96750039 4.90413327 0.97125039 4.9043999 2 P 0 ;0,1=134,2=270.000000
L 0.97125039 4.9043999 0.97458376 4.9051998 2 P 0 ;0,1=134,2=270.000000
L 0.97458376 4.9051998 0.97708396 4.90626663 2 P 0 ;0,1=134,2=270.000000
L 0.97708396 4.90626663 0.97916693 4.90786634 2 P 0 ;0,1=134,2=270.000000
L 0.97916693 4.90786634 0.98 4.9099997 2 P 0 ;0,1=134,2=270.000000
L 0.98 4.9099997 0.97916693 4.91213307 2 P 0 ;0,1=134,2=270.000000
L 0.97916693 4.91213307 0.97708396 4.91373327 2 P 0 ;0,1=134,2=270.000000
L 0.97708396 4.91373327 0.97458376 4.9148001 2 P 0 ;0,1=134,2=270.000000
L 0.97458376 4.9148001 0.97125039 4.9156 2 P 0 ;0,1=134,2=270.000000
L 0.97125039 4.9156 0.96750039 4.91586663 2 P 0 ;0,1=134,2=270.000000
L 0.96750039 4.91586663 0.96375049 4.9156 2 P 0 ;0,1=134,2=270.000000
L 0.96375049 4.9156 0.96041634 4.9148001 2 P 0 ;0,1=134,2=270.000000
L 0.96041634 4.9148001 0.95791683 4.91373327 2 P 0 ;0,1=134,2=270.000000
L 0.95791683 4.91373327 0.95583317 4.91213307 2 P 0 ;0,1=134,2=270.000000
L 0.95583317 4.91213307 0.955 4.9099997 2 P 0 ;0,1=134,2=270.000000
L 0.98 4.9339997 0.97958346 4.93586644 2 P 0 ;0,1=134,2=270.000000
L 0.97958346 4.93586644 0.97833376 4.9379998 2 P 0 ;0,1=134,2=270.000000
L 0.97833376 4.9379998 0.97625089 4.93933337 2 P 0 ;0,1=134,2=270.000000
L 0.97625089 4.93933337 0.97333327 4.93986663 2 P 0 ;0,1=134,2=270.000000
L 0.97333327 4.93986663 0.97041722 4.93933337 2 P 0 ;0,1=134,2=270.000000
L 0.97041722 4.93933337 0.96791703 4.93773327 2 P 0 ;0,1=134,2=270.000000
L 0.96791703 4.93773327 0.96666654 4.93533327 2 P 0 ;0,1=134,2=270.000000
L 0.96666654 4.93533327 0.96666654 4.93266663 2 P 0 ;0,1=134,2=270.000000
L 0.96666654 4.93266663 0.96583337 4.93106654 2 P 0 ;0,1=134,2=270.000000
L 0.96583337 4.93106654 0.96375049 4.92973297 2 P 0 ;0,1=134,2=270.000000
L 0.96375049 4.92973297 0.96083366 4.9291998 2 P 0 ;0,1=134,2=270.000000
L 0.96083366 4.9291998 0.95791683 4.9300001 2 P 0 ;0,1=134,2=270.000000
L 0.95791683 4.9300001 0.95583317 4.93186634 2 P 0 ;0,1=134,2=270.000000
L 0.95583317 4.93186634 0.955 4.9339997 2 P 0 ;0,1=134,2=270.000000
L 0.955 4.9339997 0.95583317 4.93613307 2 P 0 ;0,1=134,2=270.000000
L 0.95583317 4.93613307 0.95791683 4.9379998 2 P 0 ;0,1=134,2=270.000000
L 0.95791683 4.9379998 0.96083366 4.9388001 2 P 0 ;0,1=134,2=270.000000
L 0.96083366 4.9388001 0.96375049 4.93826644 2 P 0 ;0,1=134,2=270.000000
L 0.96375049 4.93826644 0.96583337 4.93693337 2 P 0 ;0,1=134,2=270.000000
L 0.96583337 4.93693337 0.96666654 4.93533327 2 P 0 ;0,1=134,2=270.000000
L 0.96666654 4.93533327 0.96666654 4.93266663 2 P 0 ;0,1=134,2=270.000000
L 0.96666654 4.93266663 0.96791703 4.93026663 2 P 0 ;0,1=134,2=270.000000
L 0.96791703 4.93026663 0.97041722 4.92866654 2 P 0 ;0,1=134,2=270.000000
L 0.97041722 4.92866654 0.97333327 4.92813327 2 P 0 ;0,1=134,2=270.000000
L 0.97333327 4.92813327 0.97625089 4.92866654 2 P 0 ;0,1=134,2=270.000000
L 0.97625089 4.92866654 0.97833376 4.9300001 2 P 0 ;0,1=134,2=270.000000
L 0.97833376 4.9300001 0.97958346 4.93213346 2 P 0 ;0,1=134,2=270.000000
L 0.97958346 4.93213346 0.98 4.9339997 2 P 0 ;0,1=134,2=270.000000
L 1.00386998 5.4 0.98813002 5.4 3 P 0 
L 1.16 5.33766654 1.135 5.33766654 2 P 0 ;0,1=135,2=270.000000
L 1.135 5.33766654 1.135 5.34433327 2 P 0 ;0,1=135,2=270.000000
L 1.135 5.34433327 1.13625059 5.34646663 2 P 0 ;0,1=135,2=270.000000
L 1.13625059 5.34646663 1.13791683 5.3478001 2 P 0 ;0,1=135,2=270.000000
L 1.13791683 5.3478001 1.1412502 5.34833337 2 P 0 ;0,1=135,2=270.000000
L 1.1412502 5.34833337 1.14458366 5.3478001 2 P 0 ;0,1=135,2=270.000000
L 1.14458366 5.3478001 1.14666654 5.3462 2 P 0 ;0,1=135,2=270.000000
L 1.14666654 5.3462 1.14791703 5.34433327 2 P 0 ;0,1=135,2=270.000000
L 1.14791703 5.34433327 1.14791703 5.33766654 2 P 0 ;0,1=135,2=270.000000
L 1.14791703 5.34433327 1.16 5.34833337 2 P 0 ;0,1=135,2=270.000000
L 1.16 5.3669997 1.135 5.3669997 2 P 0 ;0,1=135,2=270.000000
L 1.135 5.3669997 1.1399997 5.3637999 2 P 0 ;0,1=135,2=270.000000
L 1.16 5.3637999 1.16 5.37019951 2 P 0 ;0,1=135,2=270.000000
L 1.14958406 5.38593317 1.14666654 5.3877999 2 P 0 ;0,1=135,2=270.000000
L 1.14666654 5.3877999 1.1450002 5.3894 2 P 0 ;0,1=135,2=270.000000
L 1.1450002 5.3894 1.14416703 5.39153337 2 P 0 ;0,1=135,2=270.000000
L 1.14416703 5.39153337 1.1450002 5.3934002 2 P 0 ;0,1=135,2=270.000000
L 1.1450002 5.3934002 1.14666654 5.39473327 2 P 0 ;0,1=135,2=270.000000
L 1.14666654 5.39473327 1.14916673 5.3958001 2 P 0 ;0,1=135,2=270.000000
L 1.14916673 5.3958001 1.15208356 5.39606673 2 P 0 ;0,1=135,2=270.000000
L 1.15208356 5.39606673 1.15458376 5.3958001 2 P 0 ;0,1=135,2=270.000000
L 1.15458376 5.3958001 1.15708396 5.39473327 2 P 0 ;0,1=135,2=270.000000
L 1.15708396 5.39473327 1.15916693 5.39313307 2 P 0 ;0,1=135,2=270.000000
L 1.15916693 5.39313307 1.16 5.39126683 2 P 0 ;0,1=135,2=270.000000
L 1.16 5.39126683 1.15916693 5.38913346 2 P 0 ;0,1=135,2=270.000000
L 1.15916693 5.38913346 1.15666742 5.38726663 2 P 0 ;0,1=135,2=270.000000
L 1.15666742 5.38726663 1.15291673 5.3861998 2 P 0 ;0,1=135,2=270.000000
L 1.15291673 5.3861998 1.1487502 5.38593317 2 P 0 ;0,1=135,2=270.000000
L 1.1487502 5.38593317 1.14333386 5.38646634 2 P 0 ;0,1=135,2=270.000000
L 1.14333386 5.38646634 1.14041634 5.38726663 2 P 0 ;0,1=135,2=270.000000
L 1.14041634 5.38726663 1.1375003 5.3885997 2 P 0 ;0,1=135,2=270.000000
L 1.1375003 5.3885997 1.13541663 5.39046654 2 P 0 ;0,1=135,2=270.000000
L 1.13541663 5.39046654 1.135 5.39233327 2 P 0 ;0,1=135,2=270.000000
L 1.135 5.39233327 1.13583317 5.3942 2 P 0 ;0,1=135,2=270.000000
L 1.13583317 5.3942 1.13791683 5.39553356 2 P 0 ;0,1=135,2=270.000000
L 1.135 5.4149997 1.13583317 5.41286634 2 P 0 ;0,1=135,2=270.000000
L 1.13583317 5.41286634 1.13791683 5.41126663 2 P 0 ;0,1=135,2=270.000000
L 1.13791683 5.41126663 1.14041634 5.4101998 2 P 0 ;0,1=135,2=270.000000
L 1.14041634 5.4101998 1.14375049 5.4093999 2 P 0 ;0,1=135,2=270.000000
L 1.14375049 5.4093999 1.14750039 5.40913327 2 P 0 ;0,1=135,2=270.000000
L 1.14750039 5.40913327 1.15125039 5.4093999 2 P 0 ;0,1=135,2=270.000000
L 1.15125039 5.4093999 1.15458376 5.4101998 2 P 0 ;0,1=135,2=270.000000
L 1.15458376 5.4101998 1.15708396 5.41126663 2 P 0 ;0,1=135,2=270.000000
L 1.15708396 5.41126663 1.15916693 5.41286634 2 P 0 ;0,1=135,2=270.000000
L 1.15916693 5.41286634 1.16 5.4149997 2 P 0 ;0,1=135,2=270.000000
L 1.16 5.4149997 1.15916693 5.41713307 2 P 0 ;0,1=135,2=270.000000
L 1.15916693 5.41713307 1.15708396 5.41873327 2 P 0 ;0,1=135,2=270.000000
L 1.15708396 5.41873327 1.15458376 5.4198001 2 P 0 ;0,1=135,2=270.000000
L 1.15458376 5.4198001 1.15125039 5.4206 2 P 0 ;0,1=135,2=270.000000
L 1.15125039 5.4206 1.14750039 5.42086663 2 P 0 ;0,1=135,2=270.000000
L 1.14750039 5.42086663 1.14375049 5.4206 2 P 0 ;0,1=135,2=270.000000
L 1.14375049 5.4206 1.14041634 5.4198001 2 P 0 ;0,1=135,2=270.000000
L 1.14041634 5.4198001 1.13791683 5.41873327 2 P 0 ;0,1=135,2=270.000000
L 1.13791683 5.41873327 1.13583317 5.41713307 2 P 0 ;0,1=135,2=270.000000
L 1.13583317 5.41713307 1.135 5.4149997 2 P 0 ;0,1=135,2=270.000000
L 1.14958406 5.43393317 1.14666654 5.4357999 2 P 0 ;0,1=135,2=270.000000
L 1.14666654 5.4357999 1.1450002 5.4374 2 P 0 ;0,1=135,2=270.000000
L 1.1450002 5.4374 1.14416703 5.43953337 2 P 0 ;0,1=135,2=270.000000
L 1.14416703 5.43953337 1.1450002 5.4414002 2 P 0 ;0,1=135,2=270.000000
L 1.1450002 5.4414002 1.14666654 5.44273327 2 P 0 ;0,1=135,2=270.000000
L 1.14666654 5.44273327 1.14916673 5.4438001 2 P 0 ;0,1=135,2=270.000000
L 1.14916673 5.4438001 1.15208356 5.44406673 2 P 0 ;0,1=135,2=270.000000
L 1.15208356 5.44406673 1.15458376 5.4438001 2 P 0 ;0,1=135,2=270.000000
L 1.15458376 5.4438001 1.15708396 5.44273327 2 P 0 ;0,1=135,2=270.000000
L 1.15708396 5.44273327 1.15916693 5.44113307 2 P 0 ;0,1=135,2=270.000000
L 1.15916693 5.44113307 1.16 5.43926683 2 P 0 ;0,1=135,2=270.000000
L 1.16 5.43926683 1.15916693 5.43713346 2 P 0 ;0,1=135,2=270.000000
L 1.15916693 5.43713346 1.15666742 5.43526663 2 P 0 ;0,1=135,2=270.000000
L 1.15666742 5.43526663 1.15291673 5.4341998 2 P 0 ;0,1=135,2=270.000000
L 1.15291673 5.4341998 1.1487502 5.43393317 2 P 0 ;0,1=135,2=270.000000
L 1.1487502 5.43393317 1.14333386 5.43446634 2 P 0 ;0,1=135,2=270.000000
L 1.14333386 5.43446634 1.14041634 5.43526663 2 P 0 ;0,1=135,2=270.000000
L 1.14041634 5.43526663 1.1375003 5.4365997 2 P 0 ;0,1=135,2=270.000000
L 1.1375003 5.4365997 1.13541663 5.43846654 2 P 0 ;0,1=135,2=270.000000
L 1.13541663 5.43846654 1.135 5.44033327 2 P 0 ;0,1=135,2=270.000000
L 1.135 5.44033327 1.13583317 5.4422 2 P 0 ;0,1=135,2=270.000000
L 1.13583317 5.4422 1.13791683 5.44353356 2 P 0 ;0,1=135,2=270.000000
L 0.72213002 5.01 0.73786998 5.01 3 P 0 
L 0.705 4.95266654 0.68 4.95266654 2 P 0 ;0,1=136,2=270.000000
L 0.68 4.95266654 0.68 4.95933327 2 P 0 ;0,1=136,2=270.000000
L 0.68 4.95933327 0.68125059 4.96146663 2 P 0 ;0,1=136,2=270.000000
L 0.68125059 4.96146663 0.68291683 4.9628001 2 P 0 ;0,1=136,2=270.000000
L 0.68291683 4.9628001 0.6862502 4.96333337 2 P 0 ;0,1=136,2=270.000000
L 0.6862502 4.96333337 0.68958366 4.9628001 2 P 0 ;0,1=136,2=270.000000
L 0.68958366 4.9628001 0.69166654 4.9612 2 P 0 ;0,1=136,2=270.000000
L 0.69166654 4.9612 0.69291703 4.95933327 2 P 0 ;0,1=136,2=270.000000
L 0.69291703 4.95933327 0.69291703 4.95266654 2 P 0 ;0,1=136,2=270.000000
L 0.69291703 4.95933327 0.705 4.96333337 2 P 0 ;0,1=136,2=270.000000
L 0.705 4.9819997 0.68 4.9819997 2 P 0 ;0,1=136,2=270.000000
L 0.68 4.9819997 0.6849997 4.9787999 2 P 0 ;0,1=136,2=270.000000
L 0.705 4.9787999 0.705 4.98519951 2 P 0 ;0,1=136,2=270.000000
L 0.69458406 5.00093317 0.69166654 5.0027999 2 P 0 ;0,1=136,2=270.000000
L 0.69166654 5.0027999 0.6900002 5.0044 2 P 0 ;0,1=136,2=270.000000
L 0.6900002 5.0044 0.68916703 5.00653337 2 P 0 ;0,1=136,2=270.000000
L 0.68916703 5.00653337 0.6900002 5.0084002 2 P 0 ;0,1=136,2=270.000000
L 0.6900002 5.0084002 0.69166654 5.00973327 2 P 0 ;0,1=136,2=270.000000
L 0.69166654 5.00973327 0.69416673 5.0108001 2 P 0 ;0,1=136,2=270.000000
L 0.69416673 5.0108001 0.69708356 5.01106673 2 P 0 ;0,1=136,2=270.000000
L 0.69708356 5.01106673 0.69958376 5.0108001 2 P 0 ;0,1=136,2=270.000000
L 0.69958376 5.0108001 0.70208396 5.00973327 2 P 0 ;0,1=136,2=270.000000
L 0.70208396 5.00973327 0.70416693 5.00813307 2 P 0 ;0,1=136,2=270.000000
L 0.70416693 5.00813307 0.705 5.00626683 2 P 0 ;0,1=136,2=270.000000
L 0.705 5.00626683 0.70416693 5.00413346 2 P 0 ;0,1=136,2=270.000000
L 0.70416693 5.00413346 0.70166742 5.00226663 2 P 0 ;0,1=136,2=270.000000
L 0.70166742 5.00226663 0.69791673 5.0011998 2 P 0 ;0,1=136,2=270.000000
L 0.69791673 5.0011998 0.6937502 5.00093317 2 P 0 ;0,1=136,2=270.000000
L 0.6937502 5.00093317 0.68833386 5.00146634 2 P 0 ;0,1=136,2=270.000000
L 0.68833386 5.00146634 0.68541634 5.00226663 2 P 0 ;0,1=136,2=270.000000
L 0.68541634 5.00226663 0.6825003 5.0035997 2 P 0 ;0,1=136,2=270.000000
L 0.6825003 5.0035997 0.68041663 5.00546654 2 P 0 ;0,1=136,2=270.000000
L 0.68041663 5.00546654 0.68 5.00733327 2 P 0 ;0,1=136,2=270.000000
L 0.68 5.00733327 0.68083317 5.0092 2 P 0 ;0,1=136,2=270.000000
L 0.68083317 5.0092 0.68291683 5.01053356 2 P 0 ;0,1=136,2=270.000000
L 0.68 5.0299997 0.68083317 5.02786634 2 P 0 ;0,1=136,2=270.000000
L 0.68083317 5.02786634 0.68291683 5.02626663 2 P 0 ;0,1=136,2=270.000000
L 0.68291683 5.02626663 0.68541634 5.0251998 2 P 0 ;0,1=136,2=270.000000
L 0.68541634 5.0251998 0.68875049 5.0243999 2 P 0 ;0,1=136,2=270.000000
L 0.68875049 5.0243999 0.69250039 5.02413327 2 P 0 ;0,1=136,2=270.000000
L 0.69250039 5.02413327 0.69625039 5.0243999 2 P 0 ;0,1=136,2=270.000000
L 0.69625039 5.0243999 0.69958376 5.0251998 2 P 0 ;0,1=136,2=270.000000
L 0.69958376 5.0251998 0.70208396 5.02626663 2 P 0 ;0,1=136,2=270.000000
L 0.70208396 5.02626663 0.70416693 5.02786634 2 P 0 ;0,1=136,2=270.000000
L 0.70416693 5.02786634 0.705 5.0299997 2 P 0 ;0,1=136,2=270.000000
L 0.705 5.0299997 0.70416693 5.03213307 2 P 0 ;0,1=136,2=270.000000
L 0.70416693 5.03213307 0.70208396 5.03373327 2 P 0 ;0,1=136,2=270.000000
L 0.70208396 5.03373327 0.69958376 5.0348001 2 P 0 ;0,1=136,2=270.000000
L 0.69958376 5.0348001 0.69625039 5.0356 2 P 0 ;0,1=136,2=270.000000
L 0.69625039 5.0356 0.69250039 5.03586663 2 P 0 ;0,1=136,2=270.000000
L 0.69250039 5.03586663 0.68875049 5.0356 2 P 0 ;0,1=136,2=270.000000
L 0.68875049 5.0356 0.68541634 5.0348001 2 P 0 ;0,1=136,2=270.000000
L 0.68541634 5.0348001 0.68291683 5.03373327 2 P 0 ;0,1=136,2=270.000000
L 0.68291683 5.03373327 0.68083317 5.03213307 2 P 0 ;0,1=136,2=270.000000
L 0.68083317 5.03213307 0.68 5.0299997 2 P 0 ;0,1=136,2=270.000000
L 0.70125089 5.04813327 0.70333376 5.04973297 2 P 0 ;0,1=136,2=270.000000
L 0.70333376 5.04973297 0.70458346 5.0515997 2 P 0 ;0,1=136,2=270.000000
L 0.70458346 5.0515997 0.705 5.0539997 2 P 0 ;0,1=136,2=270.000000
L 0.705 5.0539997 0.70416693 5.0564002 2 P 0 ;0,1=136,2=270.000000
L 0.70416693 5.0564002 0.70250059 5.05826644 2 P 0 ;0,1=136,2=270.000000
L 0.70250059 5.05826644 0.69958376 5.0596 2 P 0 ;0,1=136,2=270.000000
L 0.69958376 5.0596 0.69625039 5.05986663 2 P 0 ;0,1=136,2=270.000000
L 0.69625039 5.05986663 0.69291703 5.05933337 2 P 0 ;0,1=136,2=270.000000
L 0.69291703 5.05933337 0.69083337 5.0579998 2 P 0 ;0,1=136,2=270.000000
L 0.69083337 5.0579998 0.68916703 5.05613307 2 P 0 ;0,1=136,2=270.000000
L 0.68916703 5.05613307 0.68875049 5.05426683 2 P 0 ;0,1=136,2=270.000000
L 0.68875049 5.05426683 0.68916703 5.0524 2 P 0 ;0,1=136,2=270.000000
L 0.68916703 5.0524 0.69083337 5.0500001 2 P 0 ;0,1=136,2=270.000000
L 0.69083337 5.0500001 0.68 5.0507999 2 P 0 ;0,1=136,2=270.000000
L 0.68 5.0507999 0.68 5.0579998 2 P 0 ;0,1=136,2=270.000000
L 9.91786998 4.56 9.90213002 4.56 3 P 0 
L 9.95 4.36766654 9.925 4.36766654 2 P 0 ;0,1=137,2=270.000000
L 9.925 4.36766654 9.925 4.37433327 2 P 0 ;0,1=137,2=270.000000
L 9.925 4.37433327 9.92625059 4.37646663 2 P 0 ;0,1=137,2=270.000000
L 9.92625059 4.37646663 9.92791683 4.3778001 2 P 0 ;0,1=137,2=270.000000
L 9.92791683 4.3778001 9.9312502 4.37833337 2 P 0 ;0,1=137,2=270.000000
L 9.9312502 4.37833337 9.93458366 4.3778001 2 P 0 ;0,1=137,2=270.000000
L 9.93458366 4.3778001 9.93666654 4.3762 2 P 0 ;0,1=137,2=270.000000
L 9.93666654 4.3762 9.93791703 4.37433327 2 P 0 ;0,1=137,2=270.000000
L 9.93791703 4.37433327 9.93791703 4.36766654 2 P 0 ;0,1=137,2=270.000000
L 9.93791703 4.37433327 9.95 4.37833337 2 P 0 ;0,1=137,2=270.000000
L 9.95 4.3969997 9.925 4.3969997 2 P 0 ;0,1=137,2=270.000000
L 9.925 4.3969997 9.9299997 4.3937999 2 P 0 ;0,1=137,2=270.000000
L 9.95 4.3937999 9.95 4.40019951 2 P 0 ;0,1=137,2=270.000000
L 9.94625089 4.41513327 9.94833376 4.41673297 2 P 0 ;0,1=137,2=270.000000
L 9.94833376 4.41673297 9.94958346 4.4185997 2 P 0 ;0,1=137,2=270.000000
L 9.94958346 4.4185997 9.95 4.4209997 2 P 0 ;0,1=137,2=270.000000
L 9.95 4.4209997 9.94916693 4.4234002 2 P 0 ;0,1=137,2=270.000000
L 9.94916693 4.4234002 9.94750059 4.42526644 2 P 0 ;0,1=137,2=270.000000
L 9.94750059 4.42526644 9.94458376 4.4266 2 P 0 ;0,1=137,2=270.000000
L 9.94458376 4.4266 9.94125039 4.42686663 2 P 0 ;0,1=137,2=270.000000
L 9.94125039 4.42686663 9.93791703 4.42633337 2 P 0 ;0,1=137,2=270.000000
L 9.93791703 4.42633337 9.93583337 4.4249998 2 P 0 ;0,1=137,2=270.000000
L 9.93583337 4.4249998 9.93416703 4.42313307 2 P 0 ;0,1=137,2=270.000000
L 9.93416703 4.42313307 9.93375049 4.42126683 2 P 0 ;0,1=137,2=270.000000
L 9.93375049 4.42126683 9.93416703 4.4194 2 P 0 ;0,1=137,2=270.000000
L 9.93416703 4.4194 9.93583337 4.4170001 2 P 0 ;0,1=137,2=270.000000
L 9.93583337 4.4170001 9.925 4.4177999 2 P 0 ;0,1=137,2=270.000000
L 9.925 4.4177999 9.925 4.4249998 2 P 0 ;0,1=137,2=270.000000
L 9.94708396 4.44046634 9.94916693 4.44233317 2 P 0 ;0,1=137,2=270.000000
L 9.94916693 4.44233317 9.95 4.44446654 2 P 0 ;0,1=137,2=270.000000
L 9.95 4.44446654 9.94916693 4.4465999 2 P 0 ;0,1=137,2=270.000000
L 9.94916693 4.4465999 9.94666742 4.44846663 2 P 0 ;0,1=137,2=270.000000
L 9.94666742 4.44846663 9.94291673 4.4498001 2 P 0 ;0,1=137,2=270.000000
L 9.94291673 4.4498001 9.93916673 4.45033337 2 P 0 ;0,1=137,2=270.000000
L 9.93916673 4.45033337 9.93458366 4.45033337 2 P 0 ;0,1=137,2=270.000000
L 9.93458366 4.45033337 9.93083366 4.4498001 2 P 0 ;0,1=137,2=270.000000
L 9.93083366 4.4498001 9.9275003 4.44846663 2 P 0 ;0,1=137,2=270.000000
L 9.9275003 4.44846663 9.92583317 4.44686644 2 P 0 ;0,1=137,2=270.000000
L 9.92583317 4.44686644 9.925 4.4449997 2 P 0 ;0,1=137,2=270.000000
L 9.925 4.4449997 9.92583317 4.44286634 2 P 0 ;0,1=137,2=270.000000
L 9.92583317 4.44286634 9.9275003 4.44126663 2 P 0 ;0,1=137,2=270.000000
L 9.9275003 4.44126663 9.9299997 4.4401998 2 P 0 ;0,1=137,2=270.000000
L 9.9299997 4.4401998 9.93333386 4.43966654 2 P 0 ;0,1=137,2=270.000000
L 9.93333386 4.43966654 9.9362499 4.4401998 2 P 0 ;0,1=137,2=270.000000
L 9.9362499 4.4401998 9.93916673 4.44153327 2 P 0 ;0,1=137,2=270.000000
L 9.93916673 4.44153327 9.94083386 4.44313346 2 P 0 ;0,1=137,2=270.000000
L 9.94083386 4.44313346 9.94125039 4.4449997 2 P 0 ;0,1=137,2=270.000000
L 9.94125039 4.4449997 9.94041722 4.44713307 2 P 0 ;0,1=137,2=270.000000
L 9.94041722 4.44713307 9.93833356 4.44873327 2 P 0 ;0,1=137,2=270.000000
L 9.93833356 4.44873327 9.93458366 4.45033337 2 P 0 ;0,1=137,2=270.000000
L 9.95 4.4689997 9.94958346 4.47086644 2 P 0 ;0,1=137,2=270.000000
L 9.94958346 4.47086644 9.94833376 4.4729998 2 P 0 ;0,1=137,2=270.000000
L 9.94833376 4.4729998 9.94625089 4.47433337 2 P 0 ;0,1=137,2=270.000000
L 9.94625089 4.47433337 9.94333327 4.47486663 2 P 0 ;0,1=137,2=270.000000
L 9.94333327 4.47486663 9.94041722 4.47433337 2 P 0 ;0,1=137,2=270.000000
L 9.94041722 4.47433337 9.93791703 4.47273327 2 P 0 ;0,1=137,2=270.000000
L 9.93791703 4.47273327 9.93666654 4.47033327 2 P 0 ;0,1=137,2=270.000000
L 9.93666654 4.47033327 9.93666654 4.46766663 2 P 0 ;0,1=137,2=270.000000
L 9.93666654 4.46766663 9.93583337 4.46606654 2 P 0 ;0,1=137,2=270.000000
L 9.93583337 4.46606654 9.93375049 4.46473297 2 P 0 ;0,1=137,2=270.000000
L 9.93375049 4.46473297 9.93083366 4.4641998 2 P 0 ;0,1=137,2=270.000000
L 9.93083366 4.4641998 9.92791683 4.4650001 2 P 0 ;0,1=137,2=270.000000
L 9.92791683 4.4650001 9.92583317 4.46686634 2 P 0 ;0,1=137,2=270.000000
L 9.92583317 4.46686634 9.925 4.4689997 2 P 0 ;0,1=137,2=270.000000
L 9.925 4.4689997 9.92583317 4.47113307 2 P 0 ;0,1=137,2=270.000000
L 9.92583317 4.47113307 9.92791683 4.4729998 2 P 0 ;0,1=137,2=270.000000
L 9.92791683 4.4729998 9.93083366 4.4738001 2 P 0 ;0,1=137,2=270.000000
L 9.93083366 4.4738001 9.93375049 4.47326644 2 P 0 ;0,1=137,2=270.000000
L 9.93375049 4.47326644 9.93583337 4.47193337 2 P 0 ;0,1=137,2=270.000000
L 9.93583337 4.47193337 9.93666654 4.47033327 2 P 0 ;0,1=137,2=270.000000
L 9.93666654 4.47033327 9.93666654 4.46766663 2 P 0 ;0,1=137,2=270.000000
L 9.93666654 4.46766663 9.93791703 4.46526663 2 P 0 ;0,1=137,2=270.000000
L 9.93791703 4.46526663 9.94041722 4.46366654 2 P 0 ;0,1=137,2=270.000000
L 9.94041722 4.46366654 9.94333327 4.46313327 2 P 0 ;0,1=137,2=270.000000
L 9.94333327 4.46313327 9.94625089 4.46366654 2 P 0 ;0,1=137,2=270.000000
L 9.94625089 4.46366654 9.94833376 4.4650001 2 P 0 ;0,1=137,2=270.000000
L 9.94833376 4.4650001 9.94958346 4.46713346 2 P 0 ;0,1=137,2=270.000000
L 9.94958346 4.46713346 9.95 4.4689997 2 P 0 ;0,1=137,2=270.000000
L 3.62786998 4.5 3.61213002 4.5 3 P 0 
L 3.63 4.31766654 3.605 4.31766654 2 P 0 ;0,1=138,2=270.000000
L 3.605 4.31766654 3.605 4.32433327 2 P 0 ;0,1=138,2=270.000000
L 3.605 4.32433327 3.60625059 4.32646663 2 P 0 ;0,1=138,2=270.000000
L 3.60625059 4.32646663 3.60791683 4.3278001 2 P 0 ;0,1=138,2=270.000000
L 3.60791683 4.3278001 3.6112502 4.32833337 2 P 0 ;0,1=138,2=270.000000
L 3.6112502 4.32833337 3.61458366 4.3278001 2 P 0 ;0,1=138,2=270.000000
L 3.61458366 4.3278001 3.61666654 4.3262 2 P 0 ;0,1=138,2=270.000000
L 3.61666654 4.3262 3.61791703 4.32433327 2 P 0 ;0,1=138,2=270.000000
L 3.61791703 4.32433327 3.61791703 4.31766654 2 P 0 ;0,1=138,2=270.000000
L 3.61791703 4.32433327 3.63 4.32833337 2 P 0 ;0,1=138,2=270.000000
L 3.63 4.3469997 3.605 4.3469997 2 P 0 ;0,1=138,2=270.000000
L 3.605 4.3469997 3.6099997 4.3437999 2 P 0 ;0,1=138,2=270.000000
L 3.63 4.3437999 3.63 4.35019951 2 P 0 ;0,1=138,2=270.000000
L 3.62625089 4.36513327 3.62833376 4.36673297 2 P 0 ;0,1=138,2=270.000000
L 3.62833376 4.36673297 3.62958346 4.3685997 2 P 0 ;0,1=138,2=270.000000
L 3.62958346 4.3685997 3.63 4.3709997 2 P 0 ;0,1=138,2=270.000000
L 3.63 4.3709997 3.62916693 4.3734002 2 P 0 ;0,1=138,2=270.000000
L 3.62916693 4.3734002 3.62750059 4.37526644 2 P 0 ;0,1=138,2=270.000000
L 3.62750059 4.37526644 3.62458376 4.3766 2 P 0 ;0,1=138,2=270.000000
L 3.62458376 4.3766 3.62125039 4.37686663 2 P 0 ;0,1=138,2=270.000000
L 3.62125039 4.37686663 3.61791703 4.37633337 2 P 0 ;0,1=138,2=270.000000
L 3.61791703 4.37633337 3.61583337 4.3749998 2 P 0 ;0,1=138,2=270.000000
L 3.61583337 4.3749998 3.61416703 4.37313307 2 P 0 ;0,1=138,2=270.000000
L 3.61416703 4.37313307 3.61375049 4.37126683 2 P 0 ;0,1=138,2=270.000000
L 3.61375049 4.37126683 3.61416703 4.3694 2 P 0 ;0,1=138,2=270.000000
L 3.61416703 4.3694 3.61583337 4.3670001 2 P 0 ;0,1=138,2=270.000000
L 3.61583337 4.3670001 3.605 4.3677999 2 P 0 ;0,1=138,2=270.000000
L 3.605 4.3677999 3.605 4.3749998 2 P 0 ;0,1=138,2=270.000000
L 3.62708396 4.39046634 3.62916693 4.39233317 2 P 0 ;0,1=138,2=270.000000
L 3.62916693 4.39233317 3.63 4.39446654 2 P 0 ;0,1=138,2=270.000000
L 3.63 4.39446654 3.62916693 4.3965999 2 P 0 ;0,1=138,2=270.000000
L 3.62916693 4.3965999 3.62666742 4.39846663 2 P 0 ;0,1=138,2=270.000000
L 3.62666742 4.39846663 3.62291673 4.3998001 2 P 0 ;0,1=138,2=270.000000
L 3.62291673 4.3998001 3.61916673 4.40033337 2 P 0 ;0,1=138,2=270.000000
L 3.61916673 4.40033337 3.61458366 4.40033337 2 P 0 ;0,1=138,2=270.000000
L 3.61458366 4.40033337 3.61083366 4.3998001 2 P 0 ;0,1=138,2=270.000000
L 3.61083366 4.3998001 3.6075003 4.39846663 2 P 0 ;0,1=138,2=270.000000
L 3.6075003 4.39846663 3.60583317 4.39686644 2 P 0 ;0,1=138,2=270.000000
L 3.60583317 4.39686644 3.605 4.3949997 2 P 0 ;0,1=138,2=270.000000
L 3.605 4.3949997 3.60583317 4.39286634 2 P 0 ;0,1=138,2=270.000000
L 3.60583317 4.39286634 3.6075003 4.39126663 2 P 0 ;0,1=138,2=270.000000
L 3.6075003 4.39126663 3.6099997 4.3901998 2 P 0 ;0,1=138,2=270.000000
L 3.6099997 4.3901998 3.61333386 4.38966654 2 P 0 ;0,1=138,2=270.000000
L 3.61333386 4.38966654 3.6162499 4.3901998 2 P 0 ;0,1=138,2=270.000000
L 3.6162499 4.3901998 3.61916673 4.39153327 2 P 0 ;0,1=138,2=270.000000
L 3.61916673 4.39153327 3.62083386 4.39313346 2 P 0 ;0,1=138,2=270.000000
L 3.62083386 4.39313346 3.62125039 4.3949997 2 P 0 ;0,1=138,2=270.000000
L 3.62125039 4.3949997 3.62041722 4.39713307 2 P 0 ;0,1=138,2=270.000000
L 3.62041722 4.39713307 3.61833356 4.39873327 2 P 0 ;0,1=138,2=270.000000
L 3.61833356 4.39873327 3.61458366 4.40033337 2 P 0 ;0,1=138,2=270.000000
L 3.61958406 4.41393317 3.61666654 4.4157999 2 P 0 ;0,1=138,2=270.000000
L 3.61666654 4.4157999 3.6150002 4.4174 2 P 0 ;0,1=138,2=270.000000
L 3.6150002 4.4174 3.61416703 4.41953337 2 P 0 ;0,1=138,2=270.000000
L 3.61416703 4.41953337 3.6150002 4.4214002 2 P 0 ;0,1=138,2=270.000000
L 3.6150002 4.4214002 3.61666654 4.42273327 2 P 0 ;0,1=138,2=270.000000
L 3.61666654 4.42273327 3.61916673 4.4238001 2 P 0 ;0,1=138,2=270.000000
L 3.61916673 4.4238001 3.62208356 4.42406673 2 P 0 ;0,1=138,2=270.000000
L 3.62208356 4.42406673 3.62458376 4.4238001 2 P 0 ;0,1=138,2=270.000000
L 3.62458376 4.4238001 3.62708396 4.42273327 2 P 0 ;0,1=138,2=270.000000
L 3.62708396 4.42273327 3.62916693 4.42113307 2 P 0 ;0,1=138,2=270.000000
L 3.62916693 4.42113307 3.63 4.41926683 2 P 0 ;0,1=138,2=270.000000
L 3.63 4.41926683 3.62916693 4.41713346 2 P 0 ;0,1=138,2=270.000000
L 3.62916693 4.41713346 3.62666742 4.41526663 2 P 0 ;0,1=138,2=270.000000
L 3.62666742 4.41526663 3.62291673 4.4141998 2 P 0 ;0,1=138,2=270.000000
L 3.62291673 4.4141998 3.6187502 4.41393317 2 P 0 ;0,1=138,2=270.000000
L 3.6187502 4.41393317 3.61333386 4.41446634 2 P 0 ;0,1=138,2=270.000000
L 3.61333386 4.41446634 3.61041634 4.41526663 2 P 0 ;0,1=138,2=270.000000
L 3.61041634 4.41526663 3.6075003 4.4165997 2 P 0 ;0,1=138,2=270.000000
L 3.6075003 4.4165997 3.60541663 4.41846654 2 P 0 ;0,1=138,2=270.000000
L 3.60541663 4.41846654 3.605 4.42033327 2 P 0 ;0,1=138,2=270.000000
L 3.605 4.42033327 3.60583317 4.4222 2 P 0 ;0,1=138,2=270.000000
L 3.60583317 4.4222 3.60791683 4.42353356 2 P 0 ;0,1=138,2=270.000000
L 1.12786998 5.84 1.11213002 5.84 3 P 0 
L 1.175 5.86766654 1.15 5.86766654 2 P 0 ;0,1=139,2=270.000000
L 1.15 5.86766654 1.15 5.87433327 2 P 0 ;0,1=139,2=270.000000
L 1.15 5.87433327 1.15125059 5.87646663 2 P 0 ;0,1=139,2=270.000000
L 1.15125059 5.87646663 1.15291683 5.8778001 2 P 0 ;0,1=139,2=270.000000
L 1.15291683 5.8778001 1.1562502 5.87833337 2 P 0 ;0,1=139,2=270.000000
L 1.1562502 5.87833337 1.15958366 5.8778001 2 P 0 ;0,1=139,2=270.000000
L 1.15958366 5.8778001 1.16166654 5.8762 2 P 0 ;0,1=139,2=270.000000
L 1.16166654 5.8762 1.16291703 5.87433327 2 P 0 ;0,1=139,2=270.000000
L 1.16291703 5.87433327 1.16291703 5.86766654 2 P 0 ;0,1=139,2=270.000000
L 1.16291703 5.87433327 1.175 5.87833337 2 P 0 ;0,1=139,2=270.000000
L 1.175 5.8969997 1.15 5.8969997 2 P 0 ;0,1=139,2=270.000000
L 1.15 5.8969997 1.1549997 5.8937999 2 P 0 ;0,1=139,2=270.000000
L 1.175 5.8937999 1.175 5.90019951 2 P 0 ;0,1=139,2=270.000000
L 1.16458406 5.91593317 1.16166654 5.9177999 2 P 0 ;0,1=139,2=270.000000
L 1.16166654 5.9177999 1.1600002 5.9194 2 P 0 ;0,1=139,2=270.000000
L 1.1600002 5.9194 1.15916703 5.92153337 2 P 0 ;0,1=139,2=270.000000
L 1.15916703 5.92153337 1.1600002 5.9234002 2 P 0 ;0,1=139,2=270.000000
L 1.1600002 5.9234002 1.16166654 5.92473327 2 P 0 ;0,1=139,2=270.000000
L 1.16166654 5.92473327 1.16416673 5.9258001 2 P 0 ;0,1=139,2=270.000000
L 1.16416673 5.9258001 1.16708356 5.92606673 2 P 0 ;0,1=139,2=270.000000
L 1.16708356 5.92606673 1.16958376 5.9258001 2 P 0 ;0,1=139,2=270.000000
L 1.16958376 5.9258001 1.17208396 5.92473327 2 P 0 ;0,1=139,2=270.000000
L 1.17208396 5.92473327 1.17416693 5.92313307 2 P 0 ;0,1=139,2=270.000000
L 1.17416693 5.92313307 1.175 5.92126683 2 P 0 ;0,1=139,2=270.000000
L 1.175 5.92126683 1.17416693 5.91913346 2 P 0 ;0,1=139,2=270.000000
L 1.17416693 5.91913346 1.17166742 5.91726663 2 P 0 ;0,1=139,2=270.000000
L 1.17166742 5.91726663 1.16791673 5.9161998 2 P 0 ;0,1=139,2=270.000000
L 1.16791673 5.9161998 1.1637502 5.91593317 2 P 0 ;0,1=139,2=270.000000
L 1.1637502 5.91593317 1.15833386 5.91646634 2 P 0 ;0,1=139,2=270.000000
L 1.15833386 5.91646634 1.15541634 5.91726663 2 P 0 ;0,1=139,2=270.000000
L 1.15541634 5.91726663 1.1525003 5.9185997 2 P 0 ;0,1=139,2=270.000000
L 1.1525003 5.9185997 1.15041663 5.92046654 2 P 0 ;0,1=139,2=270.000000
L 1.15041663 5.92046654 1.15 5.92233327 2 P 0 ;0,1=139,2=270.000000
L 1.15 5.92233327 1.15083317 5.9242 2 P 0 ;0,1=139,2=270.000000
L 1.15083317 5.9242 1.15291683 5.92553356 2 P 0 ;0,1=139,2=270.000000
L 1.15 5.9449997 1.15083317 5.94286634 2 P 0 ;0,1=139,2=270.000000
L 1.15083317 5.94286634 1.15291683 5.94126663 2 P 0 ;0,1=139,2=270.000000
L 1.15291683 5.94126663 1.15541634 5.9401998 2 P 0 ;0,1=139,2=270.000000
L 1.15541634 5.9401998 1.15875049 5.9393999 2 P 0 ;0,1=139,2=270.000000
L 1.15875049 5.9393999 1.16250039 5.93913327 2 P 0 ;0,1=139,2=270.000000
L 1.16250039 5.93913327 1.16625039 5.9393999 2 P 0 ;0,1=139,2=270.000000
L 1.16625039 5.9393999 1.16958376 5.9401998 2 P 0 ;0,1=139,2=270.000000
L 1.16958376 5.9401998 1.17208396 5.94126663 2 P 0 ;0,1=139,2=270.000000
L 1.17208396 5.94126663 1.17416693 5.94286634 2 P 0 ;0,1=139,2=270.000000
L 1.17416693 5.94286634 1.175 5.9449997 2 P 0 ;0,1=139,2=270.000000
L 1.175 5.9449997 1.17416693 5.94713307 2 P 0 ;0,1=139,2=270.000000
L 1.17416693 5.94713307 1.17208396 5.94873327 2 P 0 ;0,1=139,2=270.000000
L 1.17208396 5.94873327 1.16958376 5.9498001 2 P 0 ;0,1=139,2=270.000000
L 1.16958376 5.9498001 1.16625039 5.9506 2 P 0 ;0,1=139,2=270.000000
L 1.16625039 5.9506 1.16250039 5.95086663 2 P 0 ;0,1=139,2=270.000000
L 1.16250039 5.95086663 1.15875049 5.9506 2 P 0 ;0,1=139,2=270.000000
L 1.15875049 5.9506 1.15541634 5.9498001 2 P 0 ;0,1=139,2=270.000000
L 1.15541634 5.9498001 1.15291683 5.94873327 2 P 0 ;0,1=139,2=270.000000
L 1.15291683 5.94873327 1.15083317 5.94713307 2 P 0 ;0,1=139,2=270.000000
L 1.15083317 5.94713307 1.15 5.9449997 2 P 0 ;0,1=139,2=270.000000
L 1.175 5.9722 1.15 5.9722 2 P 0 ;0,1=139,2=270.000000
L 1.15 5.9722 1.16791673 5.96233297 2 P 0 ;0,1=139,2=270.000000
L 1.16791673 5.96233297 1.16791673 5.97566693 2 P 0 ;0,1=139,2=270.000000
L 1.04786998 5.84 1.03213002 5.84 3 P 0 
L 1.09 5.86766654 1.065 5.86766654 2 P 0 ;0,1=140,2=270.000000
L 1.065 5.86766654 1.065 5.87433327 2 P 0 ;0,1=140,2=270.000000
L 1.065 5.87433327 1.06625059 5.87646663 2 P 0 ;0,1=140,2=270.000000
L 1.06625059 5.87646663 1.06791683 5.8778001 2 P 0 ;0,1=140,2=270.000000
L 1.06791683 5.8778001 1.0712502 5.87833337 2 P 0 ;0,1=140,2=270.000000
L 1.0712502 5.87833337 1.07458366 5.8778001 2 P 0 ;0,1=140,2=270.000000
L 1.07458366 5.8778001 1.07666654 5.8762 2 P 0 ;0,1=140,2=270.000000
L 1.07666654 5.8762 1.07791703 5.87433327 2 P 0 ;0,1=140,2=270.000000
L 1.07791703 5.87433327 1.07791703 5.86766654 2 P 0 ;0,1=140,2=270.000000
L 1.07791703 5.87433327 1.09 5.87833337 2 P 0 ;0,1=140,2=270.000000
L 1.09 5.8969997 1.065 5.8969997 2 P 0 ;0,1=140,2=270.000000
L 1.065 5.8969997 1.0699997 5.8937999 2 P 0 ;0,1=140,2=270.000000
L 1.09 5.8937999 1.09 5.90019951 2 P 0 ;0,1=140,2=270.000000
L 1.07958406 5.91593317 1.07666654 5.9177999 2 P 0 ;0,1=140,2=270.000000
L 1.07666654 5.9177999 1.0750002 5.9194 2 P 0 ;0,1=140,2=270.000000
L 1.0750002 5.9194 1.07416703 5.92153337 2 P 0 ;0,1=140,2=270.000000
L 1.07416703 5.92153337 1.0750002 5.9234002 2 P 0 ;0,1=140,2=270.000000
L 1.0750002 5.9234002 1.07666654 5.92473327 2 P 0 ;0,1=140,2=270.000000
L 1.07666654 5.92473327 1.07916673 5.9258001 2 P 0 ;0,1=140,2=270.000000
L 1.07916673 5.9258001 1.08208356 5.92606673 2 P 0 ;0,1=140,2=270.000000
L 1.08208356 5.92606673 1.08458376 5.9258001 2 P 0 ;0,1=140,2=270.000000
L 1.08458376 5.9258001 1.08708396 5.92473327 2 P 0 ;0,1=140,2=270.000000
L 1.08708396 5.92473327 1.08916693 5.92313307 2 P 0 ;0,1=140,2=270.000000
L 1.08916693 5.92313307 1.09 5.92126683 2 P 0 ;0,1=140,2=270.000000
L 1.09 5.92126683 1.08916693 5.91913346 2 P 0 ;0,1=140,2=270.000000
L 1.08916693 5.91913346 1.08666742 5.91726663 2 P 0 ;0,1=140,2=270.000000
L 1.08666742 5.91726663 1.08291673 5.9161998 2 P 0 ;0,1=140,2=270.000000
L 1.08291673 5.9161998 1.0787502 5.91593317 2 P 0 ;0,1=140,2=270.000000
L 1.0787502 5.91593317 1.07333386 5.91646634 2 P 0 ;0,1=140,2=270.000000
L 1.07333386 5.91646634 1.07041634 5.91726663 2 P 0 ;0,1=140,2=270.000000
L 1.07041634 5.91726663 1.0675003 5.9185997 2 P 0 ;0,1=140,2=270.000000
L 1.0675003 5.9185997 1.06541663 5.92046654 2 P 0 ;0,1=140,2=270.000000
L 1.06541663 5.92046654 1.065 5.92233327 2 P 0 ;0,1=140,2=270.000000
L 1.065 5.92233327 1.06583317 5.9242 2 P 0 ;0,1=140,2=270.000000
L 1.06583317 5.9242 1.06791683 5.92553356 2 P 0 ;0,1=140,2=270.000000
L 1.065 5.9449997 1.06583317 5.94286634 2 P 0 ;0,1=140,2=270.000000
L 1.06583317 5.94286634 1.06791683 5.94126663 2 P 0 ;0,1=140,2=270.000000
L 1.06791683 5.94126663 1.07041634 5.9401998 2 P 0 ;0,1=140,2=270.000000
L 1.07041634 5.9401998 1.07375049 5.9393999 2 P 0 ;0,1=140,2=270.000000
L 1.07375049 5.9393999 1.07750039 5.93913327 2 P 0 ;0,1=140,2=270.000000
L 1.07750039 5.93913327 1.08125039 5.9393999 2 P 0 ;0,1=140,2=270.000000
L 1.08125039 5.9393999 1.08458376 5.9401998 2 P 0 ;0,1=140,2=270.000000
L 1.08458376 5.9401998 1.08708396 5.94126663 2 P 0 ;0,1=140,2=270.000000
L 1.08708396 5.94126663 1.08916693 5.94286634 2 P 0 ;0,1=140,2=270.000000
L 1.08916693 5.94286634 1.09 5.9449997 2 P 0 ;0,1=140,2=270.000000
L 1.09 5.9449997 1.08916693 5.94713307 2 P 0 ;0,1=140,2=270.000000
L 1.08916693 5.94713307 1.08708396 5.94873327 2 P 0 ;0,1=140,2=270.000000
L 1.08708396 5.94873327 1.08458376 5.9498001 2 P 0 ;0,1=140,2=270.000000
L 1.08458376 5.9498001 1.08125039 5.9506 2 P 0 ;0,1=140,2=270.000000
L 1.08125039 5.9506 1.07750039 5.95086663 2 P 0 ;0,1=140,2=270.000000
L 1.07750039 5.95086663 1.07375049 5.9506 2 P 0 ;0,1=140,2=270.000000
L 1.07375049 5.9506 1.07041634 5.9498001 2 P 0 ;0,1=140,2=270.000000
L 1.07041634 5.9498001 1.06791683 5.94873327 2 P 0 ;0,1=140,2=270.000000
L 1.06791683 5.94873327 1.06583317 5.94713307 2 P 0 ;0,1=140,2=270.000000
L 1.06583317 5.94713307 1.065 5.9449997 2 P 0 ;0,1=140,2=270.000000
L 1.08500039 5.96313327 1.08791713 5.96473297 2 P 0 ;0,1=140,2=270.000000
L 1.08791713 5.96473297 1.08958346 5.96686634 2 P 0 ;0,1=140,2=270.000000
L 1.08958346 5.96686634 1.09 5.96926683 2 P 0 ;0,1=140,2=270.000000
L 1.09 5.96926683 1.08958346 5.9714002 2 P 0 ;0,1=140,2=270.000000
L 1.08958346 5.9714002 1.08750059 5.97353356 2 P 0 ;0,1=140,2=270.000000
L 1.08750059 5.97353356 1.08500039 5.97486663 2 P 0 ;0,1=140,2=270.000000
L 1.08500039 5.97486663 1.0825001 5.97513317 2 P 0 ;0,1=140,2=270.000000
L 1.0825001 5.97513317 1.07958406 5.9746 2 P 0 ;0,1=140,2=270.000000
L 1.07958406 5.9746 1.07750039 5.97273327 2 P 0 ;0,1=140,2=270.000000
L 1.07750039 5.97273327 1.07666654 5.97086644 2 P 0 ;0,1=140,2=270.000000
L 1.07666654 5.97086644 1.07666654 5.96846654 2 P 0 ;0,1=140,2=270.000000
L 1.07666654 5.97086644 1.07541673 5.97246663 2 P 0 ;0,1=140,2=270.000000
L 1.07541673 5.97246663 1.07333386 5.9738001 2 P 0 ;0,1=140,2=270.000000
L 1.07333386 5.9738001 1.07083366 5.97433337 2 P 0 ;0,1=140,2=270.000000
L 1.07083366 5.97433337 1.06833346 5.9738001 2 P 0 ;0,1=140,2=270.000000
L 1.06833346 5.9738001 1.06625059 5.97246663 2 P 0 ;0,1=140,2=270.000000
L 1.06625059 5.97246663 1.065 5.97006663 2 P 0 ;0,1=140,2=270.000000
L 1.065 5.97006663 1.06541663 5.96766663 2 P 0 ;0,1=140,2=270.000000
L 1.06541663 5.96766663 1.06708366 5.96526663 2 P 0 ;0,1=140,2=270.000000
L 9.97213002 4.56 9.98786998 4.56 3 P 0 
L 9.99 4.36766654 9.965 4.36766654 2 P 0 ;0,1=141,2=270.000000
L 9.965 4.36766654 9.965 4.37433327 2 P 0 ;0,1=141,2=270.000000
L 9.965 4.37433327 9.96625059 4.37646663 2 P 0 ;0,1=141,2=270.000000
L 9.96625059 4.37646663 9.96791683 4.3778001 2 P 0 ;0,1=141,2=270.000000
L 9.96791683 4.3778001 9.9712502 4.37833337 2 P 0 ;0,1=141,2=270.000000
L 9.9712502 4.37833337 9.97458366 4.3778001 2 P 0 ;0,1=141,2=270.000000
L 9.97458366 4.3778001 9.97666654 4.3762 2 P 0 ;0,1=141,2=270.000000
L 9.97666654 4.3762 9.97791703 4.37433327 2 P 0 ;0,1=141,2=270.000000
L 9.97791703 4.37433327 9.97791703 4.36766654 2 P 0 ;0,1=141,2=270.000000
L 9.97791703 4.37433327 9.99 4.37833337 2 P 0 ;0,1=141,2=270.000000
L 9.99 4.3969997 9.965 4.3969997 2 P 0 ;0,1=141,2=270.000000
L 9.965 4.3969997 9.9699997 4.3937999 2 P 0 ;0,1=141,2=270.000000
L 9.99 4.3937999 9.99 4.40019951 2 P 0 ;0,1=141,2=270.000000
L 9.98625089 4.41513327 9.98833376 4.41673297 2 P 0 ;0,1=141,2=270.000000
L 9.98833376 4.41673297 9.98958346 4.4185997 2 P 0 ;0,1=141,2=270.000000
L 9.98958346 4.4185997 9.99 4.4209997 2 P 0 ;0,1=141,2=270.000000
L 9.99 4.4209997 9.98916693 4.4234002 2 P 0 ;0,1=141,2=270.000000
L 9.98916693 4.4234002 9.98750059 4.42526644 2 P 0 ;0,1=141,2=270.000000
L 9.98750059 4.42526644 9.98458376 4.4266 2 P 0 ;0,1=141,2=270.000000
L 9.98458376 4.4266 9.98125039 4.42686663 2 P 0 ;0,1=141,2=270.000000
L 9.98125039 4.42686663 9.97791703 4.42633337 2 P 0 ;0,1=141,2=270.000000
L 9.97791703 4.42633337 9.97583337 4.4249998 2 P 0 ;0,1=141,2=270.000000
L 9.97583337 4.4249998 9.97416703 4.42313307 2 P 0 ;0,1=141,2=270.000000
L 9.97416703 4.42313307 9.97375049 4.42126683 2 P 0 ;0,1=141,2=270.000000
L 9.97375049 4.42126683 9.97416703 4.4194 2 P 0 ;0,1=141,2=270.000000
L 9.97416703 4.4194 9.97583337 4.4170001 2 P 0 ;0,1=141,2=270.000000
L 9.97583337 4.4170001 9.965 4.4177999 2 P 0 ;0,1=141,2=270.000000
L 9.965 4.4177999 9.965 4.4249998 2 P 0 ;0,1=141,2=270.000000
L 9.98708396 4.44046634 9.98916693 4.44233317 2 P 0 ;0,1=141,2=270.000000
L 9.98916693 4.44233317 9.99 4.44446654 2 P 0 ;0,1=141,2=270.000000
L 9.99 4.44446654 9.98916693 4.4465999 2 P 0 ;0,1=141,2=270.000000
L 9.98916693 4.4465999 9.98666742 4.44846663 2 P 0 ;0,1=141,2=270.000000
L 9.98666742 4.44846663 9.98291673 4.4498001 2 P 0 ;0,1=141,2=270.000000
L 9.98291673 4.4498001 9.97916673 4.45033337 2 P 0 ;0,1=141,2=270.000000
L 9.97916673 4.45033337 9.97458366 4.45033337 2 P 0 ;0,1=141,2=270.000000
L 9.97458366 4.45033337 9.97083366 4.4498001 2 P 0 ;0,1=141,2=270.000000
L 9.97083366 4.4498001 9.9675003 4.44846663 2 P 0 ;0,1=141,2=270.000000
L 9.9675003 4.44846663 9.96583317 4.44686644 2 P 0 ;0,1=141,2=270.000000
L 9.96583317 4.44686644 9.965 4.4449997 2 P 0 ;0,1=141,2=270.000000
L 9.965 4.4449997 9.96583317 4.44286634 2 P 0 ;0,1=141,2=270.000000
L 9.96583317 4.44286634 9.9675003 4.44126663 2 P 0 ;0,1=141,2=270.000000
L 9.9675003 4.44126663 9.9699997 4.4401998 2 P 0 ;0,1=141,2=270.000000
L 9.9699997 4.4401998 9.97333386 4.43966654 2 P 0 ;0,1=141,2=270.000000
L 9.97333386 4.43966654 9.9762499 4.4401998 2 P 0 ;0,1=141,2=270.000000
L 9.9762499 4.4401998 9.97916673 4.44153327 2 P 0 ;0,1=141,2=270.000000
L 9.97916673 4.44153327 9.98083386 4.44313346 2 P 0 ;0,1=141,2=270.000000
L 9.98083386 4.44313346 9.98125039 4.4449997 2 P 0 ;0,1=141,2=270.000000
L 9.98125039 4.4449997 9.98041722 4.44713307 2 P 0 ;0,1=141,2=270.000000
L 9.98041722 4.44713307 9.97833356 4.44873327 2 P 0 ;0,1=141,2=270.000000
L 9.97833356 4.44873327 9.97458366 4.45033337 2 P 0 ;0,1=141,2=270.000000
L 9.98708396 4.46446634 9.98916693 4.46633317 2 P 0 ;0,1=141,2=270.000000
L 9.98916693 4.46633317 9.99 4.46846654 2 P 0 ;0,1=141,2=270.000000
L 9.99 4.46846654 9.98916693 4.4705999 2 P 0 ;0,1=141,2=270.000000
L 9.98916693 4.4705999 9.98666742 4.47246663 2 P 0 ;0,1=141,2=270.000000
L 9.98666742 4.47246663 9.98291673 4.4738001 2 P 0 ;0,1=141,2=270.000000
L 9.98291673 4.4738001 9.97916673 4.47433337 2 P 0 ;0,1=141,2=270.000000
L 9.97916673 4.47433337 9.97458366 4.47433337 2 P 0 ;0,1=141,2=270.000000
L 9.97458366 4.47433337 9.97083366 4.4738001 2 P 0 ;0,1=141,2=270.000000
L 9.97083366 4.4738001 9.9675003 4.47246663 2 P 0 ;0,1=141,2=270.000000
L 9.9675003 4.47246663 9.96583317 4.47086644 2 P 0 ;0,1=141,2=270.000000
L 9.96583317 4.47086644 9.965 4.4689997 2 P 0 ;0,1=141,2=270.000000
L 9.965 4.4689997 9.96583317 4.46686634 2 P 0 ;0,1=141,2=270.000000
L 9.96583317 4.46686634 9.9675003 4.46526663 2 P 0 ;0,1=141,2=270.000000
L 9.9675003 4.46526663 9.9699997 4.4641998 2 P 0 ;0,1=141,2=270.000000
L 9.9699997 4.4641998 9.97333386 4.46366654 2 P 0 ;0,1=141,2=270.000000
L 9.97333386 4.46366654 9.9762499 4.4641998 2 P 0 ;0,1=141,2=270.000000
L 9.9762499 4.4641998 9.97916673 4.46553327 2 P 0 ;0,1=141,2=270.000000
L 9.97916673 4.46553327 9.98083386 4.46713346 2 P 0 ;0,1=141,2=270.000000
L 9.98083386 4.46713346 9.98125039 4.4689997 2 P 0 ;0,1=141,2=270.000000
L 9.98125039 4.4689997 9.98041722 4.47113307 2 P 0 ;0,1=141,2=270.000000
L 9.98041722 4.47113307 9.97833356 4.47273327 2 P 0 ;0,1=141,2=270.000000
L 9.97833356 4.47273327 9.97458366 4.47433337 2 P 0 ;0,1=141,2=270.000000
L 3.66213002 4.5 3.67786998 4.5 3 P 0 
L 3.68 4.31766654 3.655 4.31766654 2 P 0 ;0,1=142,2=270.000000
L 3.655 4.31766654 3.655 4.32433327 2 P 0 ;0,1=142,2=270.000000
L 3.655 4.32433327 3.65625059 4.32646663 2 P 0 ;0,1=142,2=270.000000
L 3.65625059 4.32646663 3.65791683 4.3278001 2 P 0 ;0,1=142,2=270.000000
L 3.65791683 4.3278001 3.6612502 4.32833337 2 P 0 ;0,1=142,2=270.000000
L 3.6612502 4.32833337 3.66458366 4.3278001 2 P 0 ;0,1=142,2=270.000000
L 3.66458366 4.3278001 3.66666654 4.3262 2 P 0 ;0,1=142,2=270.000000
L 3.66666654 4.3262 3.66791703 4.32433327 2 P 0 ;0,1=142,2=270.000000
L 3.66791703 4.32433327 3.66791703 4.31766654 2 P 0 ;0,1=142,2=270.000000
L 3.66791703 4.32433327 3.68 4.32833337 2 P 0 ;0,1=142,2=270.000000
L 3.68 4.3469997 3.655 4.3469997 2 P 0 ;0,1=142,2=270.000000
L 3.655 4.3469997 3.6599997 4.3437999 2 P 0 ;0,1=142,2=270.000000
L 3.68 4.3437999 3.68 4.35019951 2 P 0 ;0,1=142,2=270.000000
L 3.67625089 4.36513327 3.67833376 4.36673297 2 P 0 ;0,1=142,2=270.000000
L 3.67833376 4.36673297 3.67958346 4.3685997 2 P 0 ;0,1=142,2=270.000000
L 3.67958346 4.3685997 3.68 4.3709997 2 P 0 ;0,1=142,2=270.000000
L 3.68 4.3709997 3.67916693 4.3734002 2 P 0 ;0,1=142,2=270.000000
L 3.67916693 4.3734002 3.67750059 4.37526644 2 P 0 ;0,1=142,2=270.000000
L 3.67750059 4.37526644 3.67458376 4.3766 2 P 0 ;0,1=142,2=270.000000
L 3.67458376 4.3766 3.67125039 4.37686663 2 P 0 ;0,1=142,2=270.000000
L 3.67125039 4.37686663 3.66791703 4.37633337 2 P 0 ;0,1=142,2=270.000000
L 3.66791703 4.37633337 3.66583337 4.3749998 2 P 0 ;0,1=142,2=270.000000
L 3.66583337 4.3749998 3.66416703 4.37313307 2 P 0 ;0,1=142,2=270.000000
L 3.66416703 4.37313307 3.66375049 4.37126683 2 P 0 ;0,1=142,2=270.000000
L 3.66375049 4.37126683 3.66416703 4.3694 2 P 0 ;0,1=142,2=270.000000
L 3.66416703 4.3694 3.66583337 4.3670001 2 P 0 ;0,1=142,2=270.000000
L 3.66583337 4.3670001 3.655 4.3677999 2 P 0 ;0,1=142,2=270.000000
L 3.655 4.3677999 3.655 4.3749998 2 P 0 ;0,1=142,2=270.000000
L 3.67708396 4.39046634 3.67916693 4.39233317 2 P 0 ;0,1=142,2=270.000000
L 3.67916693 4.39233317 3.68 4.39446654 2 P 0 ;0,1=142,2=270.000000
L 3.68 4.39446654 3.67916693 4.3965999 2 P 0 ;0,1=142,2=270.000000
L 3.67916693 4.3965999 3.67666742 4.39846663 2 P 0 ;0,1=142,2=270.000000
L 3.67666742 4.39846663 3.67291673 4.3998001 2 P 0 ;0,1=142,2=270.000000
L 3.67291673 4.3998001 3.66916673 4.40033337 2 P 0 ;0,1=142,2=270.000000
L 3.66916673 4.40033337 3.66458366 4.40033337 2 P 0 ;0,1=142,2=270.000000
L 3.66458366 4.40033337 3.66083366 4.3998001 2 P 0 ;0,1=142,2=270.000000
L 3.66083366 4.3998001 3.6575003 4.39846663 2 P 0 ;0,1=142,2=270.000000
L 3.6575003 4.39846663 3.65583317 4.39686644 2 P 0 ;0,1=142,2=270.000000
L 3.65583317 4.39686644 3.655 4.3949997 2 P 0 ;0,1=142,2=270.000000
L 3.655 4.3949997 3.65583317 4.39286634 2 P 0 ;0,1=142,2=270.000000
L 3.65583317 4.39286634 3.6575003 4.39126663 2 P 0 ;0,1=142,2=270.000000
L 3.6575003 4.39126663 3.6599997 4.3901998 2 P 0 ;0,1=142,2=270.000000
L 3.6599997 4.3901998 3.66333386 4.38966654 2 P 0 ;0,1=142,2=270.000000
L 3.66333386 4.38966654 3.6662499 4.3901998 2 P 0 ;0,1=142,2=270.000000
L 3.6662499 4.3901998 3.66916673 4.39153327 2 P 0 ;0,1=142,2=270.000000
L 3.66916673 4.39153327 3.67083386 4.39313346 2 P 0 ;0,1=142,2=270.000000
L 3.67083386 4.39313346 3.67125039 4.3949997 2 P 0 ;0,1=142,2=270.000000
L 3.67125039 4.3949997 3.67041722 4.39713307 2 P 0 ;0,1=142,2=270.000000
L 3.67041722 4.39713307 3.66833356 4.39873327 2 P 0 ;0,1=142,2=270.000000
L 3.66833356 4.39873327 3.66458366 4.40033337 2 P 0 ;0,1=142,2=270.000000
L 3.68 4.41846654 3.67458376 4.4189997 2 P 0 ;0,1=142,2=270.000000
L 3.67458376 4.4189997 3.67000069 4.4198 2 P 0 ;0,1=142,2=270.000000
L 3.67000069 4.4198 3.66583337 4.42086644 2 P 0 ;0,1=142,2=270.000000
L 3.66583337 4.42086644 3.6612502 4.4222 2 P 0 ;0,1=142,2=270.000000
L 3.6612502 4.4222 3.655 4.42433337 2 P 0 ;0,1=142,2=270.000000
L 3.655 4.42433337 3.655 4.41366654 2 P 0 ;0,1=142,2=270.000000
L 6.36648996 5.00491998 6.36648996 4.98918002 3 P 0 
L 6.15966654 4.99 6.15966654 5.015 2 P 0 ;0,1=143,2=0.000000
L 6.15966654 5.015 6.16606663 5.015 2 P 0 ;0,1=143,2=0.000000
L 6.16606663 5.015 6.1682 5.01374941 2 P 0 ;0,1=143,2=0.000000
L 6.1682 5.01374941 6.1698001 5.01083337 2 P 0 ;0,1=143,2=0.000000
L 6.1698001 5.01083337 6.17033337 5.0075 2 P 0 ;0,1=143,2=0.000000
L 6.17033337 5.0075 6.1698001 5.00416663 2 P 0 ;0,1=143,2=0.000000
L 6.1698001 5.00416663 6.16846663 5.00166644 2 P 0 ;0,1=143,2=0.000000
L 6.16846663 5.00166644 6.16606663 5.00041594 2 P 0 ;0,1=143,2=0.000000
L 6.16606663 5.00041594 6.15966654 5.00041594 2 P 0 ;0,1=143,2=0.000000
L 6.1833999 4.99333258 6.18553327 4.9912497 2 P 0 ;0,1=143,2=0.000000
L 6.18553327 4.9912497 6.18793327 4.99 2 P 0 ;0,1=143,2=0.000000
L 6.18793327 4.99 6.19006663 4.99 2 P 0 ;0,1=143,2=0.000000
L 6.19006663 4.99 6.1922 4.9912497 2 P 0 ;0,1=143,2=0.000000
L 6.1922 4.9912497 6.1938001 4.99333258 2 P 0 ;0,1=143,2=0.000000
L 6.1938001 4.99333258 6.1946 4.9962501 2 P 0 ;0,1=143,2=0.000000
L 6.1946 4.9962501 6.19406673 4.99916614 2 P 0 ;0,1=143,2=0.000000
L 6.19406673 4.99916614 6.19273327 5.00166644 2 P 0 ;0,1=143,2=0.000000
L 6.19273327 5.00166644 6.19033327 5.00333346 2 P 0 ;0,1=143,2=0.000000
L 6.19033327 5.00333346 6.18713346 5.00416663 2 P 0 ;0,1=143,2=0.000000
L 6.18713346 5.00416663 6.18526663 5.00583297 2 P 0 ;0,1=143,2=0.000000
L 6.18526663 5.00583297 6.18446634 5.0087498 2 P 0 ;0,1=143,2=0.000000
L 6.18446634 5.0087498 6.1850001 5.01166654 2 P 0 ;0,1=143,2=0.000000
L 6.1850001 5.01166654 6.18633317 5.01374941 2 P 0 ;0,1=143,2=0.000000
L 6.18633317 5.01374941 6.1881999 5.015 2 P 0 ;0,1=143,2=0.000000
L 6.1881999 5.015 6.19006663 5.015 2 P 0 ;0,1=143,2=0.000000
L 6.19006663 5.015 6.19193337 5.01416683 2 P 0 ;0,1=143,2=0.000000
L 6.19193337 5.01416683 6.19353356 5.01208317 2 P 0 ;0,1=143,2=0.000000
L 6.2129997 5.015 6.2129997 4.99 2 P 0 ;0,1=143,2=0.000000
L 6.20686673 5.015 6.21913317 5.015 2 P 0 ;0,1=143,2=0.000000
L 6.23166654 4.99 6.23166654 5.015 2 P 0 ;0,1=143,2=0.000000
L 6.23166654 5.015 6.23833327 5.015 2 P 0 ;0,1=143,2=0.000000
L 6.23833327 5.015 6.24046663 5.01374941 2 P 0 ;0,1=143,2=0.000000
L 6.24046663 5.01374941 6.2418001 5.01208317 2 P 0 ;0,1=143,2=0.000000
L 6.2418001 5.01208317 6.24233337 5.0087498 2 P 0 ;0,1=143,2=0.000000
L 6.24233337 5.0087498 6.2418001 5.00541634 2 P 0 ;0,1=143,2=0.000000
L 6.2418001 5.00541634 6.2402 5.00333346 2 P 0 ;0,1=143,2=0.000000
L 6.2402 5.00333346 6.23833327 5.00208297 2 P 0 ;0,1=143,2=0.000000
L 6.23833327 5.00208297 6.23166654 5.00208297 2 P 0 ;0,1=143,2=0.000000
L 6.23833327 5.00208297 6.24233337 4.99 2 P 0 ;0,1=143,2=0.000000
L 6.25513327 4.99499961 6.25673297 4.99208287 2 P 0 ;0,1=143,2=0.000000
L 6.25673297 4.99208287 6.25886634 4.99041654 2 P 0 ;0,1=143,2=0.000000
L 6.25886634 4.99041654 6.26126683 4.99 2 P 0 ;0,1=143,2=0.000000
L 6.26126683 4.99 6.2634002 4.99041654 2 P 0 ;0,1=143,2=0.000000
L 6.2634002 4.99041654 6.26553356 4.99249941 2 P 0 ;0,1=143,2=0.000000
L 6.26553356 4.99249941 6.26686663 4.99499961 2 P 0 ;0,1=143,2=0.000000
L 6.26686663 4.99499961 6.26713317 4.9974999 2 P 0 ;0,1=143,2=0.000000
L 6.26713317 4.9974999 6.2666 5.00041594 2 P 0 ;0,1=143,2=0.000000
L 6.2666 5.00041594 6.26473327 5.00249961 2 P 0 ;0,1=143,2=0.000000
L 6.26473327 5.00249961 6.26286644 5.00333346 2 P 0 ;0,1=143,2=0.000000
L 6.26286644 5.00333346 6.26046654 5.00333346 2 P 0 ;0,1=143,2=0.000000
L 6.26286644 5.00333346 6.26446663 5.00458327 2 P 0 ;0,1=143,2=0.000000
L 6.26446663 5.00458327 6.2658001 5.00666614 2 P 0 ;0,1=143,2=0.000000
L 6.2658001 5.00666614 6.26633337 5.00916634 2 P 0 ;0,1=143,2=0.000000
L 6.26633337 5.00916634 6.2658001 5.01166654 2 P 0 ;0,1=143,2=0.000000
L 6.2658001 5.01166654 6.26446663 5.01374941 2 P 0 ;0,1=143,2=0.000000
L 6.26446663 5.01374941 6.26206663 5.015 2 P 0 ;0,1=143,2=0.000000
L 6.26206663 5.015 6.25966663 5.01458337 2 P 0 ;0,1=143,2=0.000000
L 6.25966663 5.01458337 6.25726663 5.01291634 2 P 0 ;0,1=143,2=0.000000
L 6.27913327 4.99374911 6.28073297 4.99166624 2 P 0 ;0,1=143,2=0.000000
L 6.28073297 4.99166624 6.2825997 4.99041654 2 P 0 ;0,1=143,2=0.000000
L 6.2825997 4.99041654 6.2849997 4.99 2 P 0 ;0,1=143,2=0.000000
L 6.2849997 4.99 6.2874002 4.99083307 2 P 0 ;0,1=143,2=0.000000
L 6.2874002 4.99083307 6.28926644 4.99249941 2 P 0 ;0,1=143,2=0.000000
L 6.28926644 4.99249941 6.2906 4.99541624 2 P 0 ;0,1=143,2=0.000000
L 6.2906 4.99541624 6.29086663 4.99874961 2 P 0 ;0,1=143,2=0.000000
L 6.29086663 4.99874961 6.29033337 5.00208297 2 P 0 ;0,1=143,2=0.000000
L 6.29033337 5.00208297 6.2889998 5.00416663 2 P 0 ;0,1=143,2=0.000000
L 6.2889998 5.00416663 6.28713307 5.00583297 2 P 0 ;0,1=143,2=0.000000
L 6.28713307 5.00583297 6.28526683 5.00624951 2 P 0 ;0,1=143,2=0.000000
L 6.28526683 5.00624951 6.2834 5.00583297 2 P 0 ;0,1=143,2=0.000000
L 6.2834 5.00583297 6.2810001 5.00416663 2 P 0 ;0,1=143,2=0.000000
L 6.2810001 5.00416663 6.2817999 5.015 2 P 0 ;0,1=143,2=0.000000
L 6.2817999 5.015 6.2889998 5.015 2 P 0 ;0,1=143,2=0.000000
L 6.44118996 5.08918002 6.44118996 5.10491998 3 P 0 
L 6.38666654 5.245 6.38666654 5.27 2 P 0 ;0,1=144,2=0.000000
L 6.38666654 5.27 6.39306663 5.27 2 P 0 ;0,1=144,2=0.000000
L 6.39306663 5.27 6.3952 5.26874941 2 P 0 ;0,1=144,2=0.000000
L 6.3952 5.26874941 6.3968001 5.26583337 2 P 0 ;0,1=144,2=0.000000
L 6.3968001 5.26583337 6.39733337 5.2625 2 P 0 ;0,1=144,2=0.000000
L 6.39733337 5.2625 6.3968001 5.25916663 2 P 0 ;0,1=144,2=0.000000
L 6.3968001 5.25916663 6.39546663 5.25666644 2 P 0 ;0,1=144,2=0.000000
L 6.39546663 5.25666644 6.39306663 5.25541594 2 P 0 ;0,1=144,2=0.000000
L 6.39306663 5.25541594 6.38666654 5.25541594 2 P 0 ;0,1=144,2=0.000000
L 6.4103999 5.24833258 6.41253327 5.2462497 2 P 0 ;0,1=144,2=0.000000
L 6.41253327 5.2462497 6.41493327 5.245 2 P 0 ;0,1=144,2=0.000000
L 6.41493327 5.245 6.41706663 5.245 2 P 0 ;0,1=144,2=0.000000
L 6.41706663 5.245 6.4192 5.2462497 2 P 0 ;0,1=144,2=0.000000
L 6.4192 5.2462497 6.4208001 5.24833258 2 P 0 ;0,1=144,2=0.000000
L 6.4208001 5.24833258 6.4216 5.2512501 2 P 0 ;0,1=144,2=0.000000
L 6.4216 5.2512501 6.42106673 5.25416614 2 P 0 ;0,1=144,2=0.000000
L 6.42106673 5.25416614 6.41973327 5.25666644 2 P 0 ;0,1=144,2=0.000000
L 6.41973327 5.25666644 6.41733327 5.25833346 2 P 0 ;0,1=144,2=0.000000
L 6.41733327 5.25833346 6.41413346 5.25916663 2 P 0 ;0,1=144,2=0.000000
L 6.41413346 5.25916663 6.41226663 5.26083297 2 P 0 ;0,1=144,2=0.000000
L 6.41226663 5.26083297 6.41146634 5.2637498 2 P 0 ;0,1=144,2=0.000000
L 6.41146634 5.2637498 6.4120001 5.26666654 2 P 0 ;0,1=144,2=0.000000
L 6.4120001 5.26666654 6.41333317 5.26874941 2 P 0 ;0,1=144,2=0.000000
L 6.41333317 5.26874941 6.4151999 5.27 2 P 0 ;0,1=144,2=0.000000
L 6.4151999 5.27 6.41706663 5.27 2 P 0 ;0,1=144,2=0.000000
L 6.41706663 5.27 6.41893337 5.26916683 2 P 0 ;0,1=144,2=0.000000
L 6.41893337 5.26916683 6.42053356 5.26708317 2 P 0 ;0,1=144,2=0.000000
L 6.4399997 5.27 6.4399997 5.245 2 P 0 ;0,1=144,2=0.000000
L 6.43386673 5.27 6.44613317 5.27 2 P 0 ;0,1=144,2=0.000000
L 6.45866654 5.245 6.45866654 5.27 2 P 0 ;0,1=144,2=0.000000
L 6.45866654 5.27 6.46533327 5.27 2 P 0 ;0,1=144,2=0.000000
L 6.46533327 5.27 6.46746663 5.26874941 2 P 0 ;0,1=144,2=0.000000
L 6.46746663 5.26874941 6.4688001 5.26708317 2 P 0 ;0,1=144,2=0.000000
L 6.4688001 5.26708317 6.46933337 5.2637498 2 P 0 ;0,1=144,2=0.000000
L 6.46933337 5.2637498 6.4688001 5.26041634 2 P 0 ;0,1=144,2=0.000000
L 6.4688001 5.26041634 6.4672 5.25833346 2 P 0 ;0,1=144,2=0.000000
L 6.4672 5.25833346 6.46533327 5.25708297 2 P 0 ;0,1=144,2=0.000000
L 6.46533327 5.25708297 6.45866654 5.25708297 2 P 0 ;0,1=144,2=0.000000
L 6.46533327 5.25708297 6.46933337 5.245 2 P 0 ;0,1=144,2=0.000000
L 6.48293317 5.25541594 6.4847999 5.25833346 2 P 0 ;0,1=144,2=0.000000
L 6.4847999 5.25833346 6.4864 5.2599998 2 P 0 ;0,1=144,2=0.000000
L 6.4864 5.2599998 6.48853337 5.26083297 2 P 0 ;0,1=144,2=0.000000
L 6.48853337 5.26083297 6.4904002 5.2599998 2 P 0 ;0,1=144,2=0.000000
L 6.4904002 5.2599998 6.49173327 5.25833346 2 P 0 ;0,1=144,2=0.000000
L 6.49173327 5.25833346 6.4928001 5.25583327 2 P 0 ;0,1=144,2=0.000000
L 6.4928001 5.25583327 6.49306673 5.25291644 2 P 0 ;0,1=144,2=0.000000
L 6.49306673 5.25291644 6.4928001 5.25041624 2 P 0 ;0,1=144,2=0.000000
L 6.4928001 5.25041624 6.49173327 5.24791604 2 P 0 ;0,1=144,2=0.000000
L 6.49173327 5.24791604 6.49013307 5.24583307 2 P 0 ;0,1=144,2=0.000000
L 6.49013307 5.24583307 6.48826683 5.245 2 P 0 ;0,1=144,2=0.000000
L 6.48826683 5.245 6.48613346 5.24583307 2 P 0 ;0,1=144,2=0.000000
L 6.48613346 5.24583307 6.48426663 5.24833258 2 P 0 ;0,1=144,2=0.000000
L 6.48426663 5.24833258 6.4831998 5.25208327 2 P 0 ;0,1=144,2=0.000000
L 6.4831998 5.25208327 6.48293317 5.2562498 2 P 0 ;0,1=144,2=0.000000
L 6.48293317 5.2562498 6.48346634 5.26166614 2 P 0 ;0,1=144,2=0.000000
L 6.48346634 5.26166614 6.48426663 5.26458366 2 P 0 ;0,1=144,2=0.000000
L 6.48426663 5.26458366 6.4855997 5.2674997 2 P 0 ;0,1=144,2=0.000000
L 6.4855997 5.2674997 6.48746654 5.26958337 2 P 0 ;0,1=144,2=0.000000
L 6.48746654 5.26958337 6.48933327 5.27 2 P 0 ;0,1=144,2=0.000000
L 6.48933327 5.27 6.4912 5.26916683 2 P 0 ;0,1=144,2=0.000000
L 6.4912 5.26916683 6.49253356 5.26708317 2 P 0 ;0,1=144,2=0.000000
L 6.44118996 4.95491998 6.44118996 4.93918002 3 P 0 
L 6.38666654 5.125 6.38666654 5.15 2 P 0 ;0,1=145,2=0.000000
L 6.38666654 5.15 6.39306663 5.15 2 P 0 ;0,1=145,2=0.000000
L 6.39306663 5.15 6.3952 5.14874941 2 P 0 ;0,1=145,2=0.000000
L 6.3952 5.14874941 6.3968001 5.14583337 2 P 0 ;0,1=145,2=0.000000
L 6.3968001 5.14583337 6.39733337 5.1425 2 P 0 ;0,1=145,2=0.000000
L 6.39733337 5.1425 6.3968001 5.13916663 2 P 0 ;0,1=145,2=0.000000
L 6.3968001 5.13916663 6.39546663 5.13666644 2 P 0 ;0,1=145,2=0.000000
L 6.39546663 5.13666644 6.39306663 5.13541594 2 P 0 ;0,1=145,2=0.000000
L 6.39306663 5.13541594 6.38666654 5.13541594 2 P 0 ;0,1=145,2=0.000000
L 6.4103999 5.12833258 6.41253327 5.1262497 2 P 0 ;0,1=145,2=0.000000
L 6.41253327 5.1262497 6.41493327 5.125 2 P 0 ;0,1=145,2=0.000000
L 6.41493327 5.125 6.41706663 5.125 2 P 0 ;0,1=145,2=0.000000
L 6.41706663 5.125 6.4192 5.1262497 2 P 0 ;0,1=145,2=0.000000
L 6.4192 5.1262497 6.4208001 5.12833258 2 P 0 ;0,1=145,2=0.000000
L 6.4208001 5.12833258 6.4216 5.1312501 2 P 0 ;0,1=145,2=0.000000
L 6.4216 5.1312501 6.42106673 5.13416614 2 P 0 ;0,1=145,2=0.000000
L 6.42106673 5.13416614 6.41973327 5.13666644 2 P 0 ;0,1=145,2=0.000000
L 6.41973327 5.13666644 6.41733327 5.13833346 2 P 0 ;0,1=145,2=0.000000
L 6.41733327 5.13833346 6.41413346 5.13916663 2 P 0 ;0,1=145,2=0.000000
L 6.41413346 5.13916663 6.41226663 5.14083297 2 P 0 ;0,1=145,2=0.000000
L 6.41226663 5.14083297 6.41146634 5.1437498 2 P 0 ;0,1=145,2=0.000000
L 6.41146634 5.1437498 6.4120001 5.14666654 2 P 0 ;0,1=145,2=0.000000
L 6.4120001 5.14666654 6.41333317 5.14874941 2 P 0 ;0,1=145,2=0.000000
L 6.41333317 5.14874941 6.4151999 5.15 2 P 0 ;0,1=145,2=0.000000
L 6.4151999 5.15 6.41706663 5.15 2 P 0 ;0,1=145,2=0.000000
L 6.41706663 5.15 6.41893337 5.14916683 2 P 0 ;0,1=145,2=0.000000
L 6.41893337 5.14916683 6.42053356 5.14708317 2 P 0 ;0,1=145,2=0.000000
L 6.4399997 5.15 6.4399997 5.125 2 P 0 ;0,1=145,2=0.000000
L 6.43386673 5.15 6.44613317 5.15 2 P 0 ;0,1=145,2=0.000000
L 6.45866654 5.125 6.45866654 5.15 2 P 0 ;0,1=145,2=0.000000
L 6.45866654 5.15 6.46533327 5.15 2 P 0 ;0,1=145,2=0.000000
L 6.46533327 5.15 6.46746663 5.14874941 2 P 0 ;0,1=145,2=0.000000
L 6.46746663 5.14874941 6.4688001 5.14708317 2 P 0 ;0,1=145,2=0.000000
L 6.4688001 5.14708317 6.46933337 5.1437498 2 P 0 ;0,1=145,2=0.000000
L 6.46933337 5.1437498 6.4688001 5.14041634 2 P 0 ;0,1=145,2=0.000000
L 6.4688001 5.14041634 6.4672 5.13833346 2 P 0 ;0,1=145,2=0.000000
L 6.4672 5.13833346 6.46533327 5.13708297 2 P 0 ;0,1=145,2=0.000000
L 6.46533327 5.13708297 6.45866654 5.13708297 2 P 0 ;0,1=145,2=0.000000
L 6.46533327 5.13708297 6.46933337 5.125 2 P 0 ;0,1=145,2=0.000000
L 6.48346634 5.12791604 6.48533317 5.12583307 2 P 0 ;0,1=145,2=0.000000
L 6.48533317 5.12583307 6.48746654 5.125 2 P 0 ;0,1=145,2=0.000000
L 6.48746654 5.125 6.4895999 5.12583307 2 P 0 ;0,1=145,2=0.000000
L 6.4895999 5.12583307 6.49146663 5.12833258 2 P 0 ;0,1=145,2=0.000000
L 6.49146663 5.12833258 6.4928001 5.13208327 2 P 0 ;0,1=145,2=0.000000
L 6.4928001 5.13208327 6.49333337 5.13583327 2 P 0 ;0,1=145,2=0.000000
L 6.49333337 5.13583327 6.49333337 5.14041634 2 P 0 ;0,1=145,2=0.000000
L 6.49333337 5.14041634 6.4928001 5.14416634 2 P 0 ;0,1=145,2=0.000000
L 6.4928001 5.14416634 6.49146663 5.1474997 2 P 0 ;0,1=145,2=0.000000
L 6.49146663 5.1474997 6.48986644 5.14916683 2 P 0 ;0,1=145,2=0.000000
L 6.48986644 5.14916683 6.4879997 5.15 2 P 0 ;0,1=145,2=0.000000
L 6.4879997 5.15 6.48586634 5.14916683 2 P 0 ;0,1=145,2=0.000000
L 6.48586634 5.14916683 6.48426663 5.1474997 2 P 0 ;0,1=145,2=0.000000
L 6.48426663 5.1474997 6.4831998 5.1450003 2 P 0 ;0,1=145,2=0.000000
L 6.4831998 5.1450003 6.48266654 5.14166614 2 P 0 ;0,1=145,2=0.000000
L 6.48266654 5.14166614 6.4831998 5.1387501 2 P 0 ;0,1=145,2=0.000000
L 6.4831998 5.1387501 6.48453327 5.13583327 2 P 0 ;0,1=145,2=0.000000
L 6.48453327 5.13583327 6.48613346 5.13416614 2 P 0 ;0,1=145,2=0.000000
L 6.48613346 5.13416614 6.4879997 5.13374961 2 P 0 ;0,1=145,2=0.000000
L 6.4879997 5.13374961 6.49013307 5.13458278 2 P 0 ;0,1=145,2=0.000000
L 6.49013307 5.13458278 6.49173327 5.13666644 2 P 0 ;0,1=145,2=0.000000
L 6.49173327 5.13666644 6.49333337 5.14041634 2 P 0 ;0,1=145,2=0.000000
L 6.64118996 5.08918002 6.64118996 5.10491998 3 P 0 
L 6.655 5.18466654 6.63 5.18466654 2 P 0 ;0,1=146,2=270.000000
L 6.63 5.18466654 6.63 5.19106663 2 P 0 ;0,1=146,2=270.000000
L 6.63 5.19106663 6.63125059 5.1932 2 P 0 ;0,1=146,2=270.000000
L 6.63125059 5.1932 6.63416663 5.1948001 2 P 0 ;0,1=146,2=270.000000
L 6.63416663 5.1948001 6.6375 5.19533337 2 P 0 ;0,1=146,2=270.000000
L 6.6375 5.19533337 6.64083337 5.1948001 2 P 0 ;0,1=146,2=270.000000
L 6.64083337 5.1948001 6.64333356 5.19346663 2 P 0 ;0,1=146,2=270.000000
L 6.64333356 5.19346663 6.64458406 5.19106663 2 P 0 ;0,1=146,2=270.000000
L 6.64458406 5.19106663 6.64458406 5.18466654 2 P 0 ;0,1=146,2=270.000000
L 6.65166742 5.2083999 6.6537503 5.21053327 2 P 0 ;0,1=146,2=270.000000
L 6.6537503 5.21053327 6.655 5.21293327 2 P 0 ;0,1=146,2=270.000000
L 6.655 5.21293327 6.655 5.21506663 2 P 0 ;0,1=146,2=270.000000
L 6.655 5.21506663 6.6537503 5.2172 2 P 0 ;0,1=146,2=270.000000
L 6.6537503 5.2172 6.65166742 5.2188001 2 P 0 ;0,1=146,2=270.000000
L 6.65166742 5.2188001 6.6487499 5.2196 2 P 0 ;0,1=146,2=270.000000
L 6.6487499 5.2196 6.64583386 5.21906673 2 P 0 ;0,1=146,2=270.000000
L 6.64583386 5.21906673 6.64333356 5.21773327 2 P 0 ;0,1=146,2=270.000000
L 6.64333356 5.21773327 6.64166654 5.21533327 2 P 0 ;0,1=146,2=270.000000
L 6.64166654 5.21533327 6.64083337 5.21213346 2 P 0 ;0,1=146,2=270.000000
L 6.64083337 5.21213346 6.63916703 5.21026663 2 P 0 ;0,1=146,2=270.000000
L 6.63916703 5.21026663 6.6362502 5.20946634 2 P 0 ;0,1=146,2=270.000000
L 6.6362502 5.20946634 6.63333346 5.2100001 2 P 0 ;0,1=146,2=270.000000
L 6.63333346 5.2100001 6.63125059 5.21133317 2 P 0 ;0,1=146,2=270.000000
L 6.63125059 5.21133317 6.63 5.2131999 2 P 0 ;0,1=146,2=270.000000
L 6.63 5.2131999 6.63 5.21506663 2 P 0 ;0,1=146,2=270.000000
L 6.63 5.21506663 6.63083317 5.21693337 2 P 0 ;0,1=146,2=270.000000
L 6.63083317 5.21693337 6.63291683 5.21853356 2 P 0 ;0,1=146,2=270.000000
L 6.63 5.2379997 6.655 5.2379997 2 P 0 ;0,1=146,2=270.000000
L 6.63 5.23186673 6.63 5.24413317 2 P 0 ;0,1=146,2=270.000000
L 6.655 5.25666654 6.63 5.25666654 2 P 0 ;0,1=146,2=270.000000
L 6.63 5.25666654 6.63 5.26333327 2 P 0 ;0,1=146,2=270.000000
L 6.63 5.26333327 6.63125059 5.26546663 2 P 0 ;0,1=146,2=270.000000
L 6.63125059 5.26546663 6.63291683 5.2668001 2 P 0 ;0,1=146,2=270.000000
L 6.63291683 5.2668001 6.6362502 5.26733337 2 P 0 ;0,1=146,2=270.000000
L 6.6362502 5.26733337 6.63958366 5.2668001 2 P 0 ;0,1=146,2=270.000000
L 6.63958366 5.2668001 6.64166654 5.2652 2 P 0 ;0,1=146,2=270.000000
L 6.64166654 5.2652 6.64291703 5.26333327 2 P 0 ;0,1=146,2=270.000000
L 6.64291703 5.26333327 6.64291703 5.25666654 2 P 0 ;0,1=146,2=270.000000
L 6.64291703 5.26333327 6.655 5.26733337 2 P 0 ;0,1=146,2=270.000000
L 6.655 5.2859997 6.63 5.2859997 2 P 0 ;0,1=146,2=270.000000
L 6.63 5.2859997 6.6349997 5.2827999 2 P 0 ;0,1=146,2=270.000000
L 6.655 5.2827999 6.655 5.28919951 2 P 0 ;0,1=146,2=270.000000
L 6.65000039 5.30413327 6.65291713 5.30573297 2 P 0 ;0,1=146,2=270.000000
L 6.65291713 5.30573297 6.65458346 5.30786634 2 P 0 ;0,1=146,2=270.000000
L 6.65458346 5.30786634 6.655 5.31026683 2 P 0 ;0,1=146,2=270.000000
L 6.655 5.31026683 6.65458346 5.3124002 2 P 0 ;0,1=146,2=270.000000
L 6.65458346 5.3124002 6.65250059 5.31453356 2 P 0 ;0,1=146,2=270.000000
L 6.65250059 5.31453356 6.65000039 5.31586663 2 P 0 ;0,1=146,2=270.000000
L 6.65000039 5.31586663 6.6475001 5.31613317 2 P 0 ;0,1=146,2=270.000000
L 6.6475001 5.31613317 6.64458406 5.3156 2 P 0 ;0,1=146,2=270.000000
L 6.64458406 5.3156 6.64250039 5.31373327 2 P 0 ;0,1=146,2=270.000000
L 6.64250039 5.31373327 6.64166654 5.31186644 2 P 0 ;0,1=146,2=270.000000
L 6.64166654 5.31186644 6.64166654 5.30946654 2 P 0 ;0,1=146,2=270.000000
L 6.64166654 5.31186644 6.64041673 5.31346663 2 P 0 ;0,1=146,2=270.000000
L 6.64041673 5.31346663 6.63833386 5.3148001 2 P 0 ;0,1=146,2=270.000000
L 6.63833386 5.3148001 6.63583366 5.31533337 2 P 0 ;0,1=146,2=270.000000
L 6.63583366 5.31533337 6.63333346 5.3148001 2 P 0 ;0,1=146,2=270.000000
L 6.63333346 5.3148001 6.63125059 5.31346663 2 P 0 ;0,1=146,2=270.000000
L 6.63125059 5.31346663 6.63 5.31106663 2 P 0 ;0,1=146,2=270.000000
L 6.63 5.31106663 6.63041663 5.30866663 2 P 0 ;0,1=146,2=270.000000
L 6.63041663 5.30866663 6.63208366 5.30626663 2 P 0 ;0,1=146,2=270.000000
L 6.55618996 5.10491998 6.55618996 5.08918002 3 P 0 
L 6.58 5.18466654 6.555 5.18466654 2 P 0 ;0,1=147,2=270.000000
L 6.555 5.18466654 6.555 5.19106663 2 P 0 ;0,1=147,2=270.000000
L 6.555 5.19106663 6.55625059 5.1932 2 P 0 ;0,1=147,2=270.000000
L 6.55625059 5.1932 6.55916663 5.1948001 2 P 0 ;0,1=147,2=270.000000
L 6.55916663 5.1948001 6.5625 5.19533337 2 P 0 ;0,1=147,2=270.000000
L 6.5625 5.19533337 6.56583337 5.1948001 2 P 0 ;0,1=147,2=270.000000
L 6.56583337 5.1948001 6.56833356 5.19346663 2 P 0 ;0,1=147,2=270.000000
L 6.56833356 5.19346663 6.56958406 5.19106663 2 P 0 ;0,1=147,2=270.000000
L 6.56958406 5.19106663 6.56958406 5.18466654 2 P 0 ;0,1=147,2=270.000000
L 6.57666742 5.2083999 6.5787503 5.21053327 2 P 0 ;0,1=147,2=270.000000
L 6.5787503 5.21053327 6.58 5.21293327 2 P 0 ;0,1=147,2=270.000000
L 6.58 5.21293327 6.58 5.21506663 2 P 0 ;0,1=147,2=270.000000
L 6.58 5.21506663 6.5787503 5.2172 2 P 0 ;0,1=147,2=270.000000
L 6.5787503 5.2172 6.57666742 5.2188001 2 P 0 ;0,1=147,2=270.000000
L 6.57666742 5.2188001 6.5737499 5.2196 2 P 0 ;0,1=147,2=270.000000
L 6.5737499 5.2196 6.57083386 5.21906673 2 P 0 ;0,1=147,2=270.000000
L 6.57083386 5.21906673 6.56833356 5.21773327 2 P 0 ;0,1=147,2=270.000000
L 6.56833356 5.21773327 6.56666654 5.21533327 2 P 0 ;0,1=147,2=270.000000
L 6.56666654 5.21533327 6.56583337 5.21213346 2 P 0 ;0,1=147,2=270.000000
L 6.56583337 5.21213346 6.56416703 5.21026663 2 P 0 ;0,1=147,2=270.000000
L 6.56416703 5.21026663 6.5612502 5.20946634 2 P 0 ;0,1=147,2=270.000000
L 6.5612502 5.20946634 6.55833346 5.2100001 2 P 0 ;0,1=147,2=270.000000
L 6.55833346 5.2100001 6.55625059 5.21133317 2 P 0 ;0,1=147,2=270.000000
L 6.55625059 5.21133317 6.555 5.2131999 2 P 0 ;0,1=147,2=270.000000
L 6.555 5.2131999 6.555 5.21506663 2 P 0 ;0,1=147,2=270.000000
L 6.555 5.21506663 6.55583317 5.21693337 2 P 0 ;0,1=147,2=270.000000
L 6.55583317 5.21693337 6.55791683 5.21853356 2 P 0 ;0,1=147,2=270.000000
L 6.555 5.2379997 6.58 5.2379997 2 P 0 ;0,1=147,2=270.000000
L 6.555 5.23186673 6.555 5.24413317 2 P 0 ;0,1=147,2=270.000000
L 6.58 5.25666654 6.555 5.25666654 2 P 0 ;0,1=147,2=270.000000
L 6.555 5.25666654 6.555 5.26333327 2 P 0 ;0,1=147,2=270.000000
L 6.555 5.26333327 6.55625059 5.26546663 2 P 0 ;0,1=147,2=270.000000
L 6.55625059 5.26546663 6.55791683 5.2668001 2 P 0 ;0,1=147,2=270.000000
L 6.55791683 5.2668001 6.5612502 5.26733337 2 P 0 ;0,1=147,2=270.000000
L 6.5612502 5.26733337 6.56458366 5.2668001 2 P 0 ;0,1=147,2=270.000000
L 6.56458366 5.2668001 6.56666654 5.2652 2 P 0 ;0,1=147,2=270.000000
L 6.56666654 5.2652 6.56791703 5.26333327 2 P 0 ;0,1=147,2=270.000000
L 6.56791703 5.26333327 6.56791703 5.25666654 2 P 0 ;0,1=147,2=270.000000
L 6.56791703 5.26333327 6.58 5.26733337 2 P 0 ;0,1=147,2=270.000000
L 6.58 5.2859997 6.555 5.2859997 2 P 0 ;0,1=147,2=270.000000
L 6.555 5.2859997 6.5599997 5.2827999 2 P 0 ;0,1=147,2=270.000000
L 6.58 5.2827999 6.58 5.28919951 2 P 0 ;0,1=147,2=270.000000
L 6.56958406 5.30493317 6.56666654 5.3067999 2 P 0 ;0,1=147,2=270.000000
L 6.56666654 5.3067999 6.5650002 5.3084 2 P 0 ;0,1=147,2=270.000000
L 6.5650002 5.3084 6.56416703 5.31053337 2 P 0 ;0,1=147,2=270.000000
L 6.56416703 5.31053337 6.5650002 5.3124002 2 P 0 ;0,1=147,2=270.000000
L 6.5650002 5.3124002 6.56666654 5.31373327 2 P 0 ;0,1=147,2=270.000000
L 6.56666654 5.31373327 6.56916673 5.3148001 2 P 0 ;0,1=147,2=270.000000
L 6.56916673 5.3148001 6.57208356 5.31506673 2 P 0 ;0,1=147,2=270.000000
L 6.57208356 5.31506673 6.57458376 5.3148001 2 P 0 ;0,1=147,2=270.000000
L 6.57458376 5.3148001 6.57708396 5.31373327 2 P 0 ;0,1=147,2=270.000000
L 6.57708396 5.31373327 6.57916693 5.31213307 2 P 0 ;0,1=147,2=270.000000
L 6.57916693 5.31213307 6.58 5.31026683 2 P 0 ;0,1=147,2=270.000000
L 6.58 5.31026683 6.57916693 5.30813346 2 P 0 ;0,1=147,2=270.000000
L 6.57916693 5.30813346 6.57666742 5.30626663 2 P 0 ;0,1=147,2=270.000000
L 6.57666742 5.30626663 6.57291673 5.3051998 2 P 0 ;0,1=147,2=270.000000
L 6.57291673 5.3051998 6.5687502 5.30493317 2 P 0 ;0,1=147,2=270.000000
L 6.5687502 5.30493317 6.56333386 5.30546634 2 P 0 ;0,1=147,2=270.000000
L 6.56333386 5.30546634 6.56041634 5.30626663 2 P 0 ;0,1=147,2=270.000000
L 6.56041634 5.30626663 6.5575003 5.3075997 2 P 0 ;0,1=147,2=270.000000
L 6.5575003 5.3075997 6.55541663 5.30946654 2 P 0 ;0,1=147,2=270.000000
L 6.55541663 5.30946654 6.555 5.31133327 2 P 0 ;0,1=147,2=270.000000
L 6.555 5.31133327 6.55583317 5.3132 2 P 0 ;0,1=147,2=270.000000
L 6.55583317 5.3132 6.55791683 5.31453356 2 P 0 ;0,1=147,2=270.000000
L 6.82 4.99213002 6.82 5.00786998 3 P 0 
L 6.90166654 4.99 6.90166654 5.015 2 P 0 ;0,1=148,2=0.000000
L 6.90166654 5.015 6.90806663 5.015 2 P 0 ;0,1=148,2=0.000000
L 6.90806663 5.015 6.9102 5.01374941 2 P 0 ;0,1=148,2=0.000000
L 6.9102 5.01374941 6.9118001 5.01083337 2 P 0 ;0,1=148,2=0.000000
L 6.9118001 5.01083337 6.91233337 5.0075 2 P 0 ;0,1=148,2=0.000000
L 6.91233337 5.0075 6.9118001 5.00416663 2 P 0 ;0,1=148,2=0.000000
L 6.9118001 5.00416663 6.91046663 5.00166644 2 P 0 ;0,1=148,2=0.000000
L 6.91046663 5.00166644 6.90806663 5.00041594 2 P 0 ;0,1=148,2=0.000000
L 6.90806663 5.00041594 6.90166654 5.00041594 2 P 0 ;0,1=148,2=0.000000
L 6.9253999 4.99333258 6.92753327 4.9912497 2 P 0 ;0,1=148,2=0.000000
L 6.92753327 4.9912497 6.92993327 4.99 2 P 0 ;0,1=148,2=0.000000
L 6.92993327 4.99 6.93206663 4.99 2 P 0 ;0,1=148,2=0.000000
L 6.93206663 4.99 6.9342 4.9912497 2 P 0 ;0,1=148,2=0.000000
L 6.9342 4.9912497 6.9358001 4.99333258 2 P 0 ;0,1=148,2=0.000000
L 6.9358001 4.99333258 6.9366 4.9962501 2 P 0 ;0,1=148,2=0.000000
L 6.9366 4.9962501 6.93606673 4.99916614 2 P 0 ;0,1=148,2=0.000000
L 6.93606673 4.99916614 6.93473327 5.00166644 2 P 0 ;0,1=148,2=0.000000
L 6.93473327 5.00166644 6.93233327 5.00333346 2 P 0 ;0,1=148,2=0.000000
L 6.93233327 5.00333346 6.92913346 5.00416663 2 P 0 ;0,1=148,2=0.000000
L 6.92913346 5.00416663 6.92726663 5.00583297 2 P 0 ;0,1=148,2=0.000000
L 6.92726663 5.00583297 6.92646634 5.0087498 2 P 0 ;0,1=148,2=0.000000
L 6.92646634 5.0087498 6.9270001 5.01166654 2 P 0 ;0,1=148,2=0.000000
L 6.9270001 5.01166654 6.92833317 5.01374941 2 P 0 ;0,1=148,2=0.000000
L 6.92833317 5.01374941 6.9301999 5.015 2 P 0 ;0,1=148,2=0.000000
L 6.9301999 5.015 6.93206663 5.015 2 P 0 ;0,1=148,2=0.000000
L 6.93206663 5.015 6.93393337 5.01416683 2 P 0 ;0,1=148,2=0.000000
L 6.93393337 5.01416683 6.93553356 5.01208317 2 P 0 ;0,1=148,2=0.000000
L 6.9549997 5.015 6.9549997 4.99 2 P 0 ;0,1=148,2=0.000000
L 6.94886673 5.015 6.96113317 5.015 2 P 0 ;0,1=148,2=0.000000
L 6.97366654 4.99 6.97366654 5.015 2 P 0 ;0,1=148,2=0.000000
L 6.97366654 5.015 6.98033327 5.015 2 P 0 ;0,1=148,2=0.000000
L 6.98033327 5.015 6.98246663 5.01374941 2 P 0 ;0,1=148,2=0.000000
L 6.98246663 5.01374941 6.9838001 5.01208317 2 P 0 ;0,1=148,2=0.000000
L 6.9838001 5.01208317 6.98433337 5.0087498 2 P 0 ;0,1=148,2=0.000000
L 6.98433337 5.0087498 6.9838001 5.00541634 2 P 0 ;0,1=148,2=0.000000
L 6.9838001 5.00541634 6.9822 5.00333346 2 P 0 ;0,1=148,2=0.000000
L 6.9822 5.00333346 6.98033327 5.00208297 2 P 0 ;0,1=148,2=0.000000
L 6.98033327 5.00208297 6.97366654 5.00208297 2 P 0 ;0,1=148,2=0.000000
L 6.98033327 5.00208297 6.98433337 4.99 2 P 0 ;0,1=148,2=0.000000
L 6.99713327 4.99499961 6.99873297 4.99208287 2 P 0 ;0,1=148,2=0.000000
L 6.99873297 4.99208287 7.00086634 4.99041654 2 P 0 ;0,1=148,2=0.000000
L 7.00086634 4.99041654 7.00326683 4.99 2 P 0 ;0,1=148,2=0.000000
L 7.00326683 4.99 7.0054002 4.99041654 2 P 0 ;0,1=148,2=0.000000
L 7.0054002 4.99041654 7.00753356 4.99249941 2 P 0 ;0,1=148,2=0.000000
L 7.00753356 4.99249941 7.00886663 4.99499961 2 P 0 ;0,1=148,2=0.000000
L 7.00886663 4.99499961 7.00913317 4.9974999 2 P 0 ;0,1=148,2=0.000000
L 7.00913317 4.9974999 7.0086 5.00041594 2 P 0 ;0,1=148,2=0.000000
L 7.0086 5.00041594 7.00673327 5.00249961 2 P 0 ;0,1=148,2=0.000000
L 7.00673327 5.00249961 7.00486644 5.00333346 2 P 0 ;0,1=148,2=0.000000
L 7.00486644 5.00333346 7.00246654 5.00333346 2 P 0 ;0,1=148,2=0.000000
L 7.00486644 5.00333346 7.00646663 5.00458327 2 P 0 ;0,1=148,2=0.000000
L 7.00646663 5.00458327 7.0078001 5.00666614 2 P 0 ;0,1=148,2=0.000000
L 7.0078001 5.00666614 7.00833337 5.00916634 2 P 0 ;0,1=148,2=0.000000
L 7.00833337 5.00916634 7.0078001 5.01166654 2 P 0 ;0,1=148,2=0.000000
L 7.0078001 5.01166654 7.00646663 5.01374941 2 P 0 ;0,1=148,2=0.000000
L 7.00646663 5.01374941 7.00406663 5.015 2 P 0 ;0,1=148,2=0.000000
L 7.00406663 5.015 7.00166663 5.01458337 2 P 0 ;0,1=148,2=0.000000
L 7.00166663 5.01458337 6.99926663 5.01291634 2 P 0 ;0,1=148,2=0.000000
L 6.74713002 5.07 6.76286998 5.07 3 P 0 
L 6.77 5.16166654 6.745 5.16166654 2 P 0 ;0,1=149,2=270.000000
L 6.745 5.16166654 6.745 5.16806663 2 P 0 ;0,1=149,2=270.000000
L 6.745 5.16806663 6.74625059 5.1702 2 P 0 ;0,1=149,2=270.000000
L 6.74625059 5.1702 6.74916663 5.1718001 2 P 0 ;0,1=149,2=270.000000
L 6.74916663 5.1718001 6.7525 5.17233337 2 P 0 ;0,1=149,2=270.000000
L 6.7525 5.17233337 6.75583337 5.1718001 2 P 0 ;0,1=149,2=270.000000
L 6.75583337 5.1718001 6.75833356 5.17046663 2 P 0 ;0,1=149,2=270.000000
L 6.75833356 5.17046663 6.75958406 5.16806663 2 P 0 ;0,1=149,2=270.000000
L 6.75958406 5.16806663 6.75958406 5.16166654 2 P 0 ;0,1=149,2=270.000000
L 6.76666742 5.1853999 6.7687503 5.18753327 2 P 0 ;0,1=149,2=270.000000
L 6.7687503 5.18753327 6.77 5.18993327 2 P 0 ;0,1=149,2=270.000000
L 6.77 5.18993327 6.77 5.19206663 2 P 0 ;0,1=149,2=270.000000
L 6.77 5.19206663 6.7687503 5.1942 2 P 0 ;0,1=149,2=270.000000
L 6.7687503 5.1942 6.76666742 5.1958001 2 P 0 ;0,1=149,2=270.000000
L 6.76666742 5.1958001 6.7637499 5.1966 2 P 0 ;0,1=149,2=270.000000
L 6.7637499 5.1966 6.76083386 5.19606673 2 P 0 ;0,1=149,2=270.000000
L 6.76083386 5.19606673 6.75833356 5.19473327 2 P 0 ;0,1=149,2=270.000000
L 6.75833356 5.19473327 6.75666654 5.19233327 2 P 0 ;0,1=149,2=270.000000
L 6.75666654 5.19233327 6.75583337 5.18913346 2 P 0 ;0,1=149,2=270.000000
L 6.75583337 5.18913346 6.75416703 5.18726663 2 P 0 ;0,1=149,2=270.000000
L 6.75416703 5.18726663 6.7512502 5.18646634 2 P 0 ;0,1=149,2=270.000000
L 6.7512502 5.18646634 6.74833346 5.1870001 2 P 0 ;0,1=149,2=270.000000
L 6.74833346 5.1870001 6.74625059 5.18833317 2 P 0 ;0,1=149,2=270.000000
L 6.74625059 5.18833317 6.745 5.1901999 2 P 0 ;0,1=149,2=270.000000
L 6.745 5.1901999 6.745 5.19206663 2 P 0 ;0,1=149,2=270.000000
L 6.745 5.19206663 6.74583317 5.19393337 2 P 0 ;0,1=149,2=270.000000
L 6.74583317 5.19393337 6.74791683 5.19553356 2 P 0 ;0,1=149,2=270.000000
L 6.745 5.2149997 6.77 5.2149997 2 P 0 ;0,1=149,2=270.000000
L 6.745 5.20886673 6.745 5.22113317 2 P 0 ;0,1=149,2=270.000000
L 6.77 5.23366654 6.745 5.23366654 2 P 0 ;0,1=149,2=270.000000
L 6.745 5.23366654 6.745 5.24033327 2 P 0 ;0,1=149,2=270.000000
L 6.745 5.24033327 6.74625059 5.24246663 2 P 0 ;0,1=149,2=270.000000
L 6.74625059 5.24246663 6.74791683 5.2438001 2 P 0 ;0,1=149,2=270.000000
L 6.74791683 5.2438001 6.7512502 5.24433337 2 P 0 ;0,1=149,2=270.000000
L 6.7512502 5.24433337 6.75458366 5.2438001 2 P 0 ;0,1=149,2=270.000000
L 6.75458366 5.2438001 6.75666654 5.2422 2 P 0 ;0,1=149,2=270.000000
L 6.75666654 5.2422 6.75791703 5.24033327 2 P 0 ;0,1=149,2=270.000000
L 6.75791703 5.24033327 6.75791703 5.23366654 2 P 0 ;0,1=149,2=270.000000
L 6.75791703 5.24033327 6.77 5.24433337 2 P 0 ;0,1=149,2=270.000000
L 6.77 5.2662 6.745 5.2662 2 P 0 ;0,1=149,2=270.000000
L 6.745 5.2662 6.76291673 5.25633297 2 P 0 ;0,1=149,2=270.000000
L 6.76291673 5.25633297 6.76291673 5.26966693 2 P 0 ;0,1=149,2=270.000000
L 5.48306998 4.6031 5.49881004 4.6031 3 P 0 
L 5.505 4.66166654 5.48 4.66166654 2 P 0 ;0,1=150,2=270.000000
L 5.48 4.66166654 5.48 4.66806663 2 P 0 ;0,1=150,2=270.000000
L 5.48 4.66806663 5.48125059 4.6702 2 P 0 ;0,1=150,2=270.000000
L 5.48125059 4.6702 5.48416663 4.6718001 2 P 0 ;0,1=150,2=270.000000
L 5.48416663 4.6718001 5.4875 4.67233337 2 P 0 ;0,1=150,2=270.000000
L 5.4875 4.67233337 5.49083337 4.6718001 2 P 0 ;0,1=150,2=270.000000
L 5.49083337 4.6718001 5.49333356 4.67046663 2 P 0 ;0,1=150,2=270.000000
L 5.49333356 4.67046663 5.49458406 4.66806663 2 P 0 ;0,1=150,2=270.000000
L 5.49458406 4.66806663 5.49458406 4.66166654 2 P 0 ;0,1=150,2=270.000000
L 5.50166742 4.6853999 5.5037503 4.68753327 2 P 0 ;0,1=150,2=270.000000
L 5.5037503 4.68753327 5.505 4.68993327 2 P 0 ;0,1=150,2=270.000000
L 5.505 4.68993327 5.505 4.69206663 2 P 0 ;0,1=150,2=270.000000
L 5.505 4.69206663 5.5037503 4.6942 2 P 0 ;0,1=150,2=270.000000
L 5.5037503 4.6942 5.50166742 4.6958001 2 P 0 ;0,1=150,2=270.000000
L 5.50166742 4.6958001 5.4987499 4.6966 2 P 0 ;0,1=150,2=270.000000
L 5.4987499 4.6966 5.49583386 4.69606673 2 P 0 ;0,1=150,2=270.000000
L 5.49583386 4.69606673 5.49333356 4.69473327 2 P 0 ;0,1=150,2=270.000000
L 5.49333356 4.69473327 5.49166654 4.69233327 2 P 0 ;0,1=150,2=270.000000
L 5.49166654 4.69233327 5.49083337 4.68913346 2 P 0 ;0,1=150,2=270.000000
L 5.49083337 4.68913346 5.48916703 4.68726663 2 P 0 ;0,1=150,2=270.000000
L 5.48916703 4.68726663 5.4862502 4.68646634 2 P 0 ;0,1=150,2=270.000000
L 5.4862502 4.68646634 5.48333346 4.6870001 2 P 0 ;0,1=150,2=270.000000
L 5.48333346 4.6870001 5.48125059 4.68833317 2 P 0 ;0,1=150,2=270.000000
L 5.48125059 4.68833317 5.48 4.6901999 2 P 0 ;0,1=150,2=270.000000
L 5.48 4.6901999 5.48 4.69206663 2 P 0 ;0,1=150,2=270.000000
L 5.48 4.69206663 5.48083317 4.69393337 2 P 0 ;0,1=150,2=270.000000
L 5.48083317 4.69393337 5.48291683 4.69553356 2 P 0 ;0,1=150,2=270.000000
L 5.48 4.7149997 5.505 4.7149997 2 P 0 ;0,1=150,2=270.000000
L 5.48 4.70886673 5.48 4.72113317 2 P 0 ;0,1=150,2=270.000000
L 5.505 4.73366654 5.48 4.73366654 2 P 0 ;0,1=150,2=270.000000
L 5.48 4.73366654 5.48 4.74033327 2 P 0 ;0,1=150,2=270.000000
L 5.48 4.74033327 5.48125059 4.74246663 2 P 0 ;0,1=150,2=270.000000
L 5.48125059 4.74246663 5.48291683 4.7438001 2 P 0 ;0,1=150,2=270.000000
L 5.48291683 4.7438001 5.4862502 4.74433337 2 P 0 ;0,1=150,2=270.000000
L 5.4862502 4.74433337 5.48958366 4.7438001 2 P 0 ;0,1=150,2=270.000000
L 5.48958366 4.7438001 5.49166654 4.7422 2 P 0 ;0,1=150,2=270.000000
L 5.49166654 4.7422 5.49291703 4.74033327 2 P 0 ;0,1=150,2=270.000000
L 5.49291703 4.74033327 5.49291703 4.73366654 2 P 0 ;0,1=150,2=270.000000
L 5.49291703 4.74033327 5.505 4.74433337 2 P 0 ;0,1=150,2=270.000000
L 5.48416663 4.75793317 5.48166713 4.75953327 2 P 0 ;0,1=150,2=270.000000
L 5.48166713 4.75953327 5.48041663 4.7614 2 P 0 ;0,1=150,2=270.000000
L 5.48041663 4.7614 5.48 4.76353337 2 P 0 ;0,1=150,2=270.000000
L 5.48 4.76353337 5.48083317 4.7662 2 P 0 ;0,1=150,2=270.000000
L 5.48083317 4.7662 5.48291683 4.76806673 2 P 0 ;0,1=150,2=270.000000
L 5.48291683 4.76806673 5.48541634 4.7686 2 P 0 ;0,1=150,2=270.000000
L 5.48541634 4.7686 5.48791732 4.76833337 2 P 0 ;0,1=150,2=270.000000
L 5.48791732 4.76833337 5.4900002 4.76726644 2 P 0 ;0,1=150,2=270.000000
L 5.4900002 4.76726644 5.49416673 4.76193327 2 P 0 ;0,1=150,2=270.000000
L 5.49416673 4.76193327 5.49708356 4.75953327 2 P 0 ;0,1=150,2=270.000000
L 5.49708356 4.75953327 5.50125089 4.75793317 2 P 0 ;0,1=150,2=270.000000
L 5.50125089 4.75793317 5.505 4.7573999 2 P 0 ;0,1=150,2=270.000000
L 5.505 4.7573999 5.505 4.7686 2 P 0 ;0,1=150,2=270.000000
L 3.94776998 4.81198996 3.93203002 4.81198996 3 P 0 
L 3.925 4.38266654 3.9 4.38266654 2 P 0 ;0,1=151,2=270.000000
L 3.9 4.38266654 3.9 4.38933327 2 P 0 ;0,1=151,2=270.000000
L 3.9 4.38933327 3.90125059 4.39146663 2 P 0 ;0,1=151,2=270.000000
L 3.90125059 4.39146663 3.90291683 4.3928001 2 P 0 ;0,1=151,2=270.000000
L 3.90291683 4.3928001 3.9062502 4.39333337 2 P 0 ;0,1=151,2=270.000000
L 3.9062502 4.39333337 3.90958366 4.3928001 2 P 0 ;0,1=151,2=270.000000
L 3.90958366 4.3928001 3.91166654 4.3912 2 P 0 ;0,1=151,2=270.000000
L 3.91166654 4.3912 3.91291703 4.38933327 2 P 0 ;0,1=151,2=270.000000
L 3.91291703 4.38933327 3.91291703 4.38266654 2 P 0 ;0,1=151,2=270.000000
L 3.91291703 4.38933327 3.925 4.39333337 2 P 0 ;0,1=151,2=270.000000
L 3.925 4.4119997 3.9 4.4119997 2 P 0 ;0,1=151,2=270.000000
L 3.9 4.4119997 3.9049997 4.4087999 2 P 0 ;0,1=151,2=270.000000
L 3.925 4.4087999 3.925 4.41519951 2 P 0 ;0,1=151,2=270.000000
L 3.92125089 4.43013327 3.92333376 4.43173297 2 P 0 ;0,1=151,2=270.000000
L 3.92333376 4.43173297 3.92458346 4.4335997 2 P 0 ;0,1=151,2=270.000000
L 3.92458346 4.4335997 3.925 4.4359997 2 P 0 ;0,1=151,2=270.000000
L 3.925 4.4359997 3.92416693 4.4384002 2 P 0 ;0,1=151,2=270.000000
L 3.92416693 4.4384002 3.92250059 4.44026644 2 P 0 ;0,1=151,2=270.000000
L 3.92250059 4.44026644 3.91958376 4.4416 2 P 0 ;0,1=151,2=270.000000
L 3.91958376 4.4416 3.91625039 4.44186663 2 P 0 ;0,1=151,2=270.000000
L 3.91625039 4.44186663 3.91291703 4.44133337 2 P 0 ;0,1=151,2=270.000000
L 3.91291703 4.44133337 3.91083337 4.4399998 2 P 0 ;0,1=151,2=270.000000
L 3.91083337 4.4399998 3.90916703 4.43813307 2 P 0 ;0,1=151,2=270.000000
L 3.90916703 4.43813307 3.90875049 4.43626683 2 P 0 ;0,1=151,2=270.000000
L 3.90875049 4.43626683 3.90916703 4.4344 2 P 0 ;0,1=151,2=270.000000
L 3.90916703 4.4344 3.91083337 4.4320001 2 P 0 ;0,1=151,2=270.000000
L 3.91083337 4.4320001 3.9 4.4327999 2 P 0 ;0,1=151,2=270.000000
L 3.9 4.4327999 3.9 4.4399998 2 P 0 ;0,1=151,2=270.000000
L 3.925 4.45946654 3.91958376 4.4599997 2 P 0 ;0,1=151,2=270.000000
L 3.91958376 4.4599997 3.91500069 4.4608 2 P 0 ;0,1=151,2=270.000000
L 3.91500069 4.4608 3.91083337 4.46186644 2 P 0 ;0,1=151,2=270.000000
L 3.91083337 4.46186644 3.9062502 4.4632 2 P 0 ;0,1=151,2=270.000000
L 3.9062502 4.4632 3.9 4.46533337 2 P 0 ;0,1=151,2=270.000000
L 3.9 4.46533337 3.9 4.45466654 2 P 0 ;0,1=151,2=270.000000
L 3.92208396 4.47946634 3.92416693 4.48133317 2 P 0 ;0,1=151,2=270.000000
L 3.92416693 4.48133317 3.925 4.48346654 2 P 0 ;0,1=151,2=270.000000
L 3.925 4.48346654 3.92416693 4.4855999 2 P 0 ;0,1=151,2=270.000000
L 3.92416693 4.4855999 3.92166742 4.48746663 2 P 0 ;0,1=151,2=270.000000
L 3.92166742 4.48746663 3.91791673 4.4888001 2 P 0 ;0,1=151,2=270.000000
L 3.91791673 4.4888001 3.91416673 4.48933337 2 P 0 ;0,1=151,2=270.000000
L 3.91416673 4.48933337 3.90958366 4.48933337 2 P 0 ;0,1=151,2=270.000000
L 3.90958366 4.48933337 3.90583366 4.4888001 2 P 0 ;0,1=151,2=270.000000
L 3.90583366 4.4888001 3.9025003 4.48746663 2 P 0 ;0,1=151,2=270.000000
L 3.9025003 4.48746663 3.90083317 4.48586644 2 P 0 ;0,1=151,2=270.000000
L 3.90083317 4.48586644 3.9 4.4839997 2 P 0 ;0,1=151,2=270.000000
L 3.9 4.4839997 3.90083317 4.48186634 2 P 0 ;0,1=151,2=270.000000
L 3.90083317 4.48186634 3.9025003 4.48026663 2 P 0 ;0,1=151,2=270.000000
L 3.9025003 4.48026663 3.9049997 4.4791998 2 P 0 ;0,1=151,2=270.000000
L 3.9049997 4.4791998 3.90833386 4.47866654 2 P 0 ;0,1=151,2=270.000000
L 3.90833386 4.47866654 3.9112499 4.4791998 2 P 0 ;0,1=151,2=270.000000
L 3.9112499 4.4791998 3.91416673 4.48053327 2 P 0 ;0,1=151,2=270.000000
L 3.91416673 4.48053327 3.91583386 4.48213346 2 P 0 ;0,1=151,2=270.000000
L 3.91583386 4.48213346 3.91625039 4.4839997 2 P 0 ;0,1=151,2=270.000000
L 3.91625039 4.4839997 3.91541722 4.48613307 2 P 0 ;0,1=151,2=270.000000
L 3.91541722 4.48613307 3.91333356 4.48773327 2 P 0 ;0,1=151,2=270.000000
L 3.91333356 4.48773327 3.90958366 4.48933337 2 P 0 ;0,1=151,2=270.000000
L 7.35046998 5.10851004 7.33473002 5.10851004 3 P 0 
L 7.355 5.17766654 7.33 5.17766654 2 P 0 ;0,1=152,2=270.000000
L 7.33 5.17766654 7.33 5.18433327 2 P 0 ;0,1=152,2=270.000000
L 7.33 5.18433327 7.33125059 5.18646663 2 P 0 ;0,1=152,2=270.000000
L 7.33125059 5.18646663 7.33291683 5.1878001 2 P 0 ;0,1=152,2=270.000000
L 7.33291683 5.1878001 7.3362502 5.18833337 2 P 0 ;0,1=152,2=270.000000
L 7.3362502 5.18833337 7.33958366 5.1878001 2 P 0 ;0,1=152,2=270.000000
L 7.33958366 5.1878001 7.34166654 5.1862 2 P 0 ;0,1=152,2=270.000000
L 7.34166654 5.1862 7.34291703 5.18433327 2 P 0 ;0,1=152,2=270.000000
L 7.34291703 5.18433327 7.34291703 5.17766654 2 P 0 ;0,1=152,2=270.000000
L 7.34291703 5.18433327 7.355 5.18833337 2 P 0 ;0,1=152,2=270.000000
L 7.355 5.2069997 7.33 5.2069997 2 P 0 ;0,1=152,2=270.000000
L 7.33 5.2069997 7.3349997 5.2037999 2 P 0 ;0,1=152,2=270.000000
L 7.355 5.2037999 7.355 5.21019951 2 P 0 ;0,1=152,2=270.000000
L 7.35125089 5.22513327 7.35333376 5.22673297 2 P 0 ;0,1=152,2=270.000000
L 7.35333376 5.22673297 7.35458346 5.2285997 2 P 0 ;0,1=152,2=270.000000
L 7.35458346 5.2285997 7.355 5.2309997 2 P 0 ;0,1=152,2=270.000000
L 7.355 5.2309997 7.35416693 5.2334002 2 P 0 ;0,1=152,2=270.000000
L 7.35416693 5.2334002 7.35250059 5.23526644 2 P 0 ;0,1=152,2=270.000000
L 7.35250059 5.23526644 7.34958376 5.2366 2 P 0 ;0,1=152,2=270.000000
L 7.34958376 5.2366 7.34625039 5.23686663 2 P 0 ;0,1=152,2=270.000000
L 7.34625039 5.23686663 7.34291703 5.23633337 2 P 0 ;0,1=152,2=270.000000
L 7.34291703 5.23633337 7.34083337 5.2349998 2 P 0 ;0,1=152,2=270.000000
L 7.34083337 5.2349998 7.33916703 5.23313307 2 P 0 ;0,1=152,2=270.000000
L 7.33916703 5.23313307 7.33875049 5.23126683 2 P 0 ;0,1=152,2=270.000000
L 7.33875049 5.23126683 7.33916703 5.2294 2 P 0 ;0,1=152,2=270.000000
L 7.33916703 5.2294 7.34083337 5.2270001 2 P 0 ;0,1=152,2=270.000000
L 7.34083337 5.2270001 7.33 5.2277999 2 P 0 ;0,1=152,2=270.000000
L 7.33 5.2277999 7.33 5.2349998 2 P 0 ;0,1=152,2=270.000000
L 7.355 5.25446654 7.34958376 5.2549997 2 P 0 ;0,1=152,2=270.000000
L 7.34958376 5.2549997 7.34500069 5.2558 2 P 0 ;0,1=152,2=270.000000
L 7.34500069 5.2558 7.34083337 5.25686644 2 P 0 ;0,1=152,2=270.000000
L 7.34083337 5.25686644 7.3362502 5.2582 2 P 0 ;0,1=152,2=270.000000
L 7.3362502 5.2582 7.33 5.26033337 2 P 0 ;0,1=152,2=270.000000
L 7.33 5.26033337 7.33 5.24966654 2 P 0 ;0,1=152,2=270.000000
L 7.355 5.2789997 7.35458346 5.28086644 2 P 0 ;0,1=152,2=270.000000
L 7.35458346 5.28086644 7.35333376 5.2829998 2 P 0 ;0,1=152,2=270.000000
L 7.35333376 5.2829998 7.35125089 5.28433337 2 P 0 ;0,1=152,2=270.000000
L 7.35125089 5.28433337 7.34833327 5.28486663 2 P 0 ;0,1=152,2=270.000000
L 7.34833327 5.28486663 7.34541722 5.28433337 2 P 0 ;0,1=152,2=270.000000
L 7.34541722 5.28433337 7.34291703 5.28273327 2 P 0 ;0,1=152,2=270.000000
L 7.34291703 5.28273327 7.34166654 5.28033327 2 P 0 ;0,1=152,2=270.000000
L 7.34166654 5.28033327 7.34166654 5.27766663 2 P 0 ;0,1=152,2=270.000000
L 7.34166654 5.27766663 7.34083337 5.27606654 2 P 0 ;0,1=152,2=270.000000
L 7.34083337 5.27606654 7.33875049 5.27473297 2 P 0 ;0,1=152,2=270.000000
L 7.33875049 5.27473297 7.33583366 5.2741998 2 P 0 ;0,1=152,2=270.000000
L 7.33583366 5.2741998 7.33291683 5.2750001 2 P 0 ;0,1=152,2=270.000000
L 7.33291683 5.2750001 7.33083317 5.27686634 2 P 0 ;0,1=152,2=270.000000
L 7.33083317 5.27686634 7.33 5.2789997 2 P 0 ;0,1=152,2=270.000000
L 7.33 5.2789997 7.33083317 5.28113307 2 P 0 ;0,1=152,2=270.000000
L 7.33083317 5.28113307 7.33291683 5.2829998 2 P 0 ;0,1=152,2=270.000000
L 7.33291683 5.2829998 7.33583366 5.2838001 2 P 0 ;0,1=152,2=270.000000
L 7.33583366 5.2838001 7.33875049 5.28326644 2 P 0 ;0,1=152,2=270.000000
L 7.33875049 5.28326644 7.34083337 5.28193337 2 P 0 ;0,1=152,2=270.000000
L 7.34083337 5.28193337 7.34166654 5.28033327 2 P 0 ;0,1=152,2=270.000000
L 7.34166654 5.28033327 7.34166654 5.27766663 2 P 0 ;0,1=152,2=270.000000
L 7.34166654 5.27766663 7.34291703 5.27526663 2 P 0 ;0,1=152,2=270.000000
L 7.34291703 5.27526663 7.34541722 5.27366654 2 P 0 ;0,1=152,2=270.000000
L 7.34541722 5.27366654 7.34833327 5.27313327 2 P 0 ;0,1=152,2=270.000000
L 7.34833327 5.27313327 7.35125089 5.27366654 2 P 0 ;0,1=152,2=270.000000
L 7.35125089 5.27366654 7.35333376 5.2750001 2 P 0 ;0,1=152,2=270.000000
L 7.35333376 5.2750001 7.35458346 5.27713346 2 P 0 ;0,1=152,2=270.000000
L 7.35458346 5.27713346 7.355 5.2789997 2 P 0 ;0,1=152,2=270.000000
L 7.20046998 5.10851004 7.18473002 5.10851004 3 P 0 
L 7.205 5.17766654 7.18 5.17766654 2 P 0 ;0,1=153,2=270.000000
L 7.18 5.17766654 7.18 5.18433327 2 P 0 ;0,1=153,2=270.000000
L 7.18 5.18433327 7.18125059 5.18646663 2 P 0 ;0,1=153,2=270.000000
L 7.18125059 5.18646663 7.18291683 5.1878001 2 P 0 ;0,1=153,2=270.000000
L 7.18291683 5.1878001 7.1862502 5.18833337 2 P 0 ;0,1=153,2=270.000000
L 7.1862502 5.18833337 7.18958366 5.1878001 2 P 0 ;0,1=153,2=270.000000
L 7.18958366 5.1878001 7.19166654 5.1862 2 P 0 ;0,1=153,2=270.000000
L 7.19166654 5.1862 7.19291703 5.18433327 2 P 0 ;0,1=153,2=270.000000
L 7.19291703 5.18433327 7.19291703 5.17766654 2 P 0 ;0,1=153,2=270.000000
L 7.19291703 5.18433327 7.205 5.18833337 2 P 0 ;0,1=153,2=270.000000
L 7.205 5.2069997 7.18 5.2069997 2 P 0 ;0,1=153,2=270.000000
L 7.18 5.2069997 7.1849997 5.2037999 2 P 0 ;0,1=153,2=270.000000
L 7.205 5.2037999 7.205 5.21019951 2 P 0 ;0,1=153,2=270.000000
L 7.20125089 5.22513327 7.20333376 5.22673297 2 P 0 ;0,1=153,2=270.000000
L 7.20333376 5.22673297 7.20458346 5.2285997 2 P 0 ;0,1=153,2=270.000000
L 7.20458346 5.2285997 7.205 5.2309997 2 P 0 ;0,1=153,2=270.000000
L 7.205 5.2309997 7.20416693 5.2334002 2 P 0 ;0,1=153,2=270.000000
L 7.20416693 5.2334002 7.20250059 5.23526644 2 P 0 ;0,1=153,2=270.000000
L 7.20250059 5.23526644 7.19958376 5.2366 2 P 0 ;0,1=153,2=270.000000
L 7.19958376 5.2366 7.19625039 5.23686663 2 P 0 ;0,1=153,2=270.000000
L 7.19625039 5.23686663 7.19291703 5.23633337 2 P 0 ;0,1=153,2=270.000000
L 7.19291703 5.23633337 7.19083337 5.2349998 2 P 0 ;0,1=153,2=270.000000
L 7.19083337 5.2349998 7.18916703 5.23313307 2 P 0 ;0,1=153,2=270.000000
L 7.18916703 5.23313307 7.18875049 5.23126683 2 P 0 ;0,1=153,2=270.000000
L 7.18875049 5.23126683 7.18916703 5.2294 2 P 0 ;0,1=153,2=270.000000
L 7.18916703 5.2294 7.19083337 5.2270001 2 P 0 ;0,1=153,2=270.000000
L 7.19083337 5.2270001 7.18 5.2277999 2 P 0 ;0,1=153,2=270.000000
L 7.18 5.2277999 7.18 5.2349998 2 P 0 ;0,1=153,2=270.000000
L 7.205 5.25446654 7.19958376 5.2549997 2 P 0 ;0,1=153,2=270.000000
L 7.19958376 5.2549997 7.19500069 5.2558 2 P 0 ;0,1=153,2=270.000000
L 7.19500069 5.2558 7.19083337 5.25686644 2 P 0 ;0,1=153,2=270.000000
L 7.19083337 5.25686644 7.1862502 5.2582 2 P 0 ;0,1=153,2=270.000000
L 7.1862502 5.2582 7.18 5.26033337 2 P 0 ;0,1=153,2=270.000000
L 7.18 5.26033337 7.18 5.24966654 2 P 0 ;0,1=153,2=270.000000
L 7.205 5.27846654 7.19958376 5.2789997 2 P 0 ;0,1=153,2=270.000000
L 7.19958376 5.2789997 7.19500069 5.2798 2 P 0 ;0,1=153,2=270.000000
L 7.19500069 5.2798 7.19083337 5.28086644 2 P 0 ;0,1=153,2=270.000000
L 7.19083337 5.28086644 7.1862502 5.2822 2 P 0 ;0,1=153,2=270.000000
L 7.1862502 5.2822 7.18 5.28433337 2 P 0 ;0,1=153,2=270.000000
L 7.18 5.28433337 7.18 5.27366654 2 P 0 ;0,1=153,2=270.000000
L 1.08613002 5.4 1.10186998 5.4 3 P 0 
L 1.24 5.33766654 1.215 5.33766654 2 P 0 ;0,1=154,2=270.000000
L 1.215 5.33766654 1.215 5.34433327 2 P 0 ;0,1=154,2=270.000000
L 1.215 5.34433327 1.21625059 5.34646663 2 P 0 ;0,1=154,2=270.000000
L 1.21625059 5.34646663 1.21791683 5.3478001 2 P 0 ;0,1=154,2=270.000000
L 1.21791683 5.3478001 1.2212502 5.34833337 2 P 0 ;0,1=154,2=270.000000
L 1.2212502 5.34833337 1.22458366 5.3478001 2 P 0 ;0,1=154,2=270.000000
L 1.22458366 5.3478001 1.22666654 5.3462 2 P 0 ;0,1=154,2=270.000000
L 1.22666654 5.3462 1.22791703 5.34433327 2 P 0 ;0,1=154,2=270.000000
L 1.22791703 5.34433327 1.22791703 5.33766654 2 P 0 ;0,1=154,2=270.000000
L 1.22791703 5.34433327 1.24 5.34833337 2 P 0 ;0,1=154,2=270.000000
L 1.24 5.3669997 1.215 5.3669997 2 P 0 ;0,1=154,2=270.000000
L 1.215 5.3669997 1.2199997 5.3637999 2 P 0 ;0,1=154,2=270.000000
L 1.24 5.3637999 1.24 5.37019951 2 P 0 ;0,1=154,2=270.000000
L 1.23625089 5.38513327 1.23833376 5.38673297 2 P 0 ;0,1=154,2=270.000000
L 1.23833376 5.38673297 1.23958346 5.3885997 2 P 0 ;0,1=154,2=270.000000
L 1.23958346 5.3885997 1.24 5.3909997 2 P 0 ;0,1=154,2=270.000000
L 1.24 5.3909997 1.23916693 5.3934002 2 P 0 ;0,1=154,2=270.000000
L 1.23916693 5.3934002 1.23750059 5.39526644 2 P 0 ;0,1=154,2=270.000000
L 1.23750059 5.39526644 1.23458376 5.3966 2 P 0 ;0,1=154,2=270.000000
L 1.23458376 5.3966 1.23125039 5.39686663 2 P 0 ;0,1=154,2=270.000000
L 1.23125039 5.39686663 1.22791703 5.39633337 2 P 0 ;0,1=154,2=270.000000
L 1.22791703 5.39633337 1.22583337 5.3949998 2 P 0 ;0,1=154,2=270.000000
L 1.22583337 5.3949998 1.22416703 5.39313307 2 P 0 ;0,1=154,2=270.000000
L 1.22416703 5.39313307 1.22375049 5.39126683 2 P 0 ;0,1=154,2=270.000000
L 1.22375049 5.39126683 1.22416703 5.3894 2 P 0 ;0,1=154,2=270.000000
L 1.22416703 5.3894 1.22583337 5.3870001 2 P 0 ;0,1=154,2=270.000000
L 1.22583337 5.3870001 1.215 5.3877999 2 P 0 ;0,1=154,2=270.000000
L 1.215 5.3877999 1.215 5.3949998 2 P 0 ;0,1=154,2=270.000000
L 1.23708396 5.41046634 1.23916693 5.41233317 2 P 0 ;0,1=154,2=270.000000
L 1.23916693 5.41233317 1.24 5.41446654 2 P 0 ;0,1=154,2=270.000000
L 1.24 5.41446654 1.23916693 5.4165999 2 P 0 ;0,1=154,2=270.000000
L 1.23916693 5.4165999 1.23666742 5.41846663 2 P 0 ;0,1=154,2=270.000000
L 1.23666742 5.41846663 1.23291673 5.4198001 2 P 0 ;0,1=154,2=270.000000
L 1.23291673 5.4198001 1.22916673 5.42033337 2 P 0 ;0,1=154,2=270.000000
L 1.22916673 5.42033337 1.22458366 5.42033337 2 P 0 ;0,1=154,2=270.000000
L 1.22458366 5.42033337 1.22083366 5.4198001 2 P 0 ;0,1=154,2=270.000000
L 1.22083366 5.4198001 1.2175003 5.41846663 2 P 0 ;0,1=154,2=270.000000
L 1.2175003 5.41846663 1.21583317 5.41686644 2 P 0 ;0,1=154,2=270.000000
L 1.21583317 5.41686644 1.215 5.4149997 2 P 0 ;0,1=154,2=270.000000
L 1.215 5.4149997 1.21583317 5.41286634 2 P 0 ;0,1=154,2=270.000000
L 1.21583317 5.41286634 1.2175003 5.41126663 2 P 0 ;0,1=154,2=270.000000
L 1.2175003 5.41126663 1.2199997 5.4101998 2 P 0 ;0,1=154,2=270.000000
L 1.2199997 5.4101998 1.22333386 5.40966654 2 P 0 ;0,1=154,2=270.000000
L 1.22333386 5.40966654 1.2262499 5.4101998 2 P 0 ;0,1=154,2=270.000000
L 1.2262499 5.4101998 1.22916673 5.41153327 2 P 0 ;0,1=154,2=270.000000
L 1.22916673 5.41153327 1.23083386 5.41313346 2 P 0 ;0,1=154,2=270.000000
L 1.23083386 5.41313346 1.23125039 5.4149997 2 P 0 ;0,1=154,2=270.000000
L 1.23125039 5.4149997 1.23041722 5.41713307 2 P 0 ;0,1=154,2=270.000000
L 1.23041722 5.41713307 1.22833356 5.41873327 2 P 0 ;0,1=154,2=270.000000
L 1.22833356 5.41873327 1.22458366 5.42033337 2 P 0 ;0,1=154,2=270.000000
L 1.24 5.4389997 1.215 5.4389997 2 P 0 ;0,1=154,2=270.000000
L 1.215 5.4389997 1.2199997 5.4357999 2 P 0 ;0,1=154,2=270.000000
L 1.24 5.4357999 1.24 5.44219951 2 P 0 ;0,1=154,2=270.000000
L 0.94013002 5.4 0.95586998 5.4 3 P 0 
L 0.62 5.43266654 0.595 5.43266654 2 P 0 ;0,1=155,2=270.000000
L 0.595 5.43266654 0.595 5.43933327 2 P 0 ;0,1=155,2=270.000000
L 0.595 5.43933327 0.59625059 5.44146663 2 P 0 ;0,1=155,2=270.000000
L 0.59625059 5.44146663 0.59791683 5.4428001 2 P 0 ;0,1=155,2=270.000000
L 0.59791683 5.4428001 0.6012502 5.44333337 2 P 0 ;0,1=155,2=270.000000
L 0.6012502 5.44333337 0.60458366 5.4428001 2 P 0 ;0,1=155,2=270.000000
L 0.60458366 5.4428001 0.60666654 5.4412 2 P 0 ;0,1=155,2=270.000000
L 0.60666654 5.4412 0.60791703 5.43933327 2 P 0 ;0,1=155,2=270.000000
L 0.60791703 5.43933327 0.60791703 5.43266654 2 P 0 ;0,1=155,2=270.000000
L 0.60791703 5.43933327 0.62 5.44333337 2 P 0 ;0,1=155,2=270.000000
L 0.62 5.4619997 0.595 5.4619997 2 P 0 ;0,1=155,2=270.000000
L 0.595 5.4619997 0.5999997 5.4587999 2 P 0 ;0,1=155,2=270.000000
L 0.62 5.4587999 0.62 5.46519951 2 P 0 ;0,1=155,2=270.000000
L 0.61625089 5.48013327 0.61833376 5.48173297 2 P 0 ;0,1=155,2=270.000000
L 0.61833376 5.48173297 0.61958346 5.4835997 2 P 0 ;0,1=155,2=270.000000
L 0.61958346 5.4835997 0.62 5.4859997 2 P 0 ;0,1=155,2=270.000000
L 0.62 5.4859997 0.61916693 5.4884002 2 P 0 ;0,1=155,2=270.000000
L 0.61916693 5.4884002 0.61750059 5.49026644 2 P 0 ;0,1=155,2=270.000000
L 0.61750059 5.49026644 0.61458376 5.4916 2 P 0 ;0,1=155,2=270.000000
L 0.61458376 5.4916 0.61125039 5.49186663 2 P 0 ;0,1=155,2=270.000000
L 0.61125039 5.49186663 0.60791703 5.49133337 2 P 0 ;0,1=155,2=270.000000
L 0.60791703 5.49133337 0.60583337 5.4899998 2 P 0 ;0,1=155,2=270.000000
L 0.60583337 5.4899998 0.60416703 5.48813307 2 P 0 ;0,1=155,2=270.000000
L 0.60416703 5.48813307 0.60375049 5.48626683 2 P 0 ;0,1=155,2=270.000000
L 0.60375049 5.48626683 0.60416703 5.4844 2 P 0 ;0,1=155,2=270.000000
L 0.60416703 5.4844 0.60583337 5.4820001 2 P 0 ;0,1=155,2=270.000000
L 0.60583337 5.4820001 0.595 5.4827999 2 P 0 ;0,1=155,2=270.000000
L 0.595 5.4827999 0.595 5.4899998 2 P 0 ;0,1=155,2=270.000000
L 0.61708396 5.50546634 0.61916693 5.50733317 2 P 0 ;0,1=155,2=270.000000
L 0.61916693 5.50733317 0.62 5.50946654 2 P 0 ;0,1=155,2=270.000000
L 0.62 5.50946654 0.61916693 5.5115999 2 P 0 ;0,1=155,2=270.000000
L 0.61916693 5.5115999 0.61666742 5.51346663 2 P 0 ;0,1=155,2=270.000000
L 0.61666742 5.51346663 0.61291673 5.5148001 2 P 0 ;0,1=155,2=270.000000
L 0.61291673 5.5148001 0.60916673 5.51533337 2 P 0 ;0,1=155,2=270.000000
L 0.60916673 5.51533337 0.60458366 5.51533337 2 P 0 ;0,1=155,2=270.000000
L 0.60458366 5.51533337 0.60083366 5.5148001 2 P 0 ;0,1=155,2=270.000000
L 0.60083366 5.5148001 0.5975003 5.51346663 2 P 0 ;0,1=155,2=270.000000
L 0.5975003 5.51346663 0.59583317 5.51186644 2 P 0 ;0,1=155,2=270.000000
L 0.59583317 5.51186644 0.595 5.5099997 2 P 0 ;0,1=155,2=270.000000
L 0.595 5.5099997 0.59583317 5.50786634 2 P 0 ;0,1=155,2=270.000000
L 0.59583317 5.50786634 0.5975003 5.50626663 2 P 0 ;0,1=155,2=270.000000
L 0.5975003 5.50626663 0.5999997 5.5051998 2 P 0 ;0,1=155,2=270.000000
L 0.5999997 5.5051998 0.60333386 5.50466654 2 P 0 ;0,1=155,2=270.000000
L 0.60333386 5.50466654 0.6062499 5.5051998 2 P 0 ;0,1=155,2=270.000000
L 0.6062499 5.5051998 0.60916673 5.50653327 2 P 0 ;0,1=155,2=270.000000
L 0.60916673 5.50653327 0.61083386 5.50813346 2 P 0 ;0,1=155,2=270.000000
L 0.61083386 5.50813346 0.61125039 5.5099997 2 P 0 ;0,1=155,2=270.000000
L 0.61125039 5.5099997 0.61041722 5.51213307 2 P 0 ;0,1=155,2=270.000000
L 0.61041722 5.51213307 0.60833356 5.51373327 2 P 0 ;0,1=155,2=270.000000
L 0.60833356 5.51373327 0.60458366 5.51533337 2 P 0 ;0,1=155,2=270.000000
L 0.595 5.5339997 0.59583317 5.53186634 2 P 0 ;0,1=155,2=270.000000
L 0.59583317 5.53186634 0.59791683 5.53026663 2 P 0 ;0,1=155,2=270.000000
L 0.59791683 5.53026663 0.60041634 5.5291998 2 P 0 ;0,1=155,2=270.000000
L 0.60041634 5.5291998 0.60375049 5.5283999 2 P 0 ;0,1=155,2=270.000000
L 0.60375049 5.5283999 0.60750039 5.52813327 2 P 0 ;0,1=155,2=270.000000
L 0.60750039 5.52813327 0.61125039 5.5283999 2 P 0 ;0,1=155,2=270.000000
L 0.61125039 5.5283999 0.61458376 5.5291998 2 P 0 ;0,1=155,2=270.000000
L 0.61458376 5.5291998 0.61708396 5.53026663 2 P 0 ;0,1=155,2=270.000000
L 0.61708396 5.53026663 0.61916693 5.53186634 2 P 0 ;0,1=155,2=270.000000
L 0.61916693 5.53186634 0.62 5.5339997 2 P 0 ;0,1=155,2=270.000000
L 0.62 5.5339997 0.61916693 5.53613307 2 P 0 ;0,1=155,2=270.000000
L 0.61916693 5.53613307 0.61708396 5.53773327 2 P 0 ;0,1=155,2=270.000000
L 0.61708396 5.53773327 0.61458376 5.5388001 2 P 0 ;0,1=155,2=270.000000
L 0.61458376 5.5388001 0.61125039 5.5396 2 P 0 ;0,1=155,2=270.000000
L 0.61125039 5.5396 0.60750039 5.53986663 2 P 0 ;0,1=155,2=270.000000
L 0.60750039 5.53986663 0.60375049 5.5396 2 P 0 ;0,1=155,2=270.000000
L 0.60375049 5.5396 0.60041634 5.5388001 2 P 0 ;0,1=155,2=270.000000
L 0.60041634 5.5388001 0.59791683 5.53773327 2 P 0 ;0,1=155,2=270.000000
L 0.59791683 5.53773327 0.59583317 5.53613307 2 P 0 ;0,1=155,2=270.000000
L 0.59583317 5.53613307 0.595 5.5339997 2 P 0 ;0,1=155,2=270.000000
L 0.89213002 5.4 0.90786998 5.4 3 P 0 
L 0.58 5.43266654 0.555 5.43266654 2 P 0 ;0,1=156,2=270.000000
L 0.555 5.43266654 0.555 5.43933327 2 P 0 ;0,1=156,2=270.000000
L 0.555 5.43933327 0.55625059 5.44146663 2 P 0 ;0,1=156,2=270.000000
L 0.55625059 5.44146663 0.55791683 5.4428001 2 P 0 ;0,1=156,2=270.000000
L 0.55791683 5.4428001 0.5612502 5.44333337 2 P 0 ;0,1=156,2=270.000000
L 0.5612502 5.44333337 0.56458366 5.4428001 2 P 0 ;0,1=156,2=270.000000
L 0.56458366 5.4428001 0.56666654 5.4412 2 P 0 ;0,1=156,2=270.000000
L 0.56666654 5.4412 0.56791703 5.43933327 2 P 0 ;0,1=156,2=270.000000
L 0.56791703 5.43933327 0.56791703 5.43266654 2 P 0 ;0,1=156,2=270.000000
L 0.56791703 5.43933327 0.58 5.44333337 2 P 0 ;0,1=156,2=270.000000
L 0.58 5.4619997 0.555 5.4619997 2 P 0 ;0,1=156,2=270.000000
L 0.555 5.4619997 0.5599997 5.4587999 2 P 0 ;0,1=156,2=270.000000
L 0.58 5.4587999 0.58 5.46519951 2 P 0 ;0,1=156,2=270.000000
L 0.57625089 5.48013327 0.57833376 5.48173297 2 P 0 ;0,1=156,2=270.000000
L 0.57833376 5.48173297 0.57958346 5.4835997 2 P 0 ;0,1=156,2=270.000000
L 0.57958346 5.4835997 0.58 5.4859997 2 P 0 ;0,1=156,2=270.000000
L 0.58 5.4859997 0.57916693 5.4884002 2 P 0 ;0,1=156,2=270.000000
L 0.57916693 5.4884002 0.57750059 5.49026644 2 P 0 ;0,1=156,2=270.000000
L 0.57750059 5.49026644 0.57458376 5.4916 2 P 0 ;0,1=156,2=270.000000
L 0.57458376 5.4916 0.57125039 5.49186663 2 P 0 ;0,1=156,2=270.000000
L 0.57125039 5.49186663 0.56791703 5.49133337 2 P 0 ;0,1=156,2=270.000000
L 0.56791703 5.49133337 0.56583337 5.4899998 2 P 0 ;0,1=156,2=270.000000
L 0.56583337 5.4899998 0.56416703 5.48813307 2 P 0 ;0,1=156,2=270.000000
L 0.56416703 5.48813307 0.56375049 5.48626683 2 P 0 ;0,1=156,2=270.000000
L 0.56375049 5.48626683 0.56416703 5.4844 2 P 0 ;0,1=156,2=270.000000
L 0.56416703 5.4844 0.56583337 5.4820001 2 P 0 ;0,1=156,2=270.000000
L 0.56583337 5.4820001 0.555 5.4827999 2 P 0 ;0,1=156,2=270.000000
L 0.555 5.4827999 0.555 5.4899998 2 P 0 ;0,1=156,2=270.000000
L 0.58 5.5099997 0.57958346 5.51186644 2 P 0 ;0,1=156,2=270.000000
L 0.57958346 5.51186644 0.57833376 5.5139998 2 P 0 ;0,1=156,2=270.000000
L 0.57833376 5.5139998 0.57625089 5.51533337 2 P 0 ;0,1=156,2=270.000000
L 0.57625089 5.51533337 0.57333327 5.51586663 2 P 0 ;0,1=156,2=270.000000
L 0.57333327 5.51586663 0.57041722 5.51533337 2 P 0 ;0,1=156,2=270.000000
L 0.57041722 5.51533337 0.56791703 5.51373327 2 P 0 ;0,1=156,2=270.000000
L 0.56791703 5.51373327 0.56666654 5.51133327 2 P 0 ;0,1=156,2=270.000000
L 0.56666654 5.51133327 0.56666654 5.50866663 2 P 0 ;0,1=156,2=270.000000
L 0.56666654 5.50866663 0.56583337 5.50706654 2 P 0 ;0,1=156,2=270.000000
L 0.56583337 5.50706654 0.56375049 5.50573297 2 P 0 ;0,1=156,2=270.000000
L 0.56375049 5.50573297 0.56083366 5.5051998 2 P 0 ;0,1=156,2=270.000000
L 0.56083366 5.5051998 0.55791683 5.5060001 2 P 0 ;0,1=156,2=270.000000
L 0.55791683 5.5060001 0.55583317 5.50786634 2 P 0 ;0,1=156,2=270.000000
L 0.55583317 5.50786634 0.555 5.5099997 2 P 0 ;0,1=156,2=270.000000
L 0.555 5.5099997 0.55583317 5.51213307 2 P 0 ;0,1=156,2=270.000000
L 0.55583317 5.51213307 0.55791683 5.5139998 2 P 0 ;0,1=156,2=270.000000
L 0.55791683 5.5139998 0.56083366 5.5148001 2 P 0 ;0,1=156,2=270.000000
L 0.56083366 5.5148001 0.56375049 5.51426644 2 P 0 ;0,1=156,2=270.000000
L 0.56375049 5.51426644 0.56583337 5.51293337 2 P 0 ;0,1=156,2=270.000000
L 0.56583337 5.51293337 0.56666654 5.51133327 2 P 0 ;0,1=156,2=270.000000
L 0.56666654 5.51133327 0.56666654 5.50866663 2 P 0 ;0,1=156,2=270.000000
L 0.56666654 5.50866663 0.56791703 5.50626663 2 P 0 ;0,1=156,2=270.000000
L 0.56791703 5.50626663 0.57041722 5.50466654 2 P 0 ;0,1=156,2=270.000000
L 0.57041722 5.50466654 0.57333327 5.50413327 2 P 0 ;0,1=156,2=270.000000
L 0.57333327 5.50413327 0.57625089 5.50466654 2 P 0 ;0,1=156,2=270.000000
L 0.57625089 5.50466654 0.57833376 5.5060001 2 P 0 ;0,1=156,2=270.000000
L 0.57833376 5.5060001 0.57958346 5.50813346 2 P 0 ;0,1=156,2=270.000000
L 0.57958346 5.50813346 0.58 5.5099997 2 P 0 ;0,1=156,2=270.000000
L 0.57708396 5.52946634 0.57916693 5.53133317 2 P 0 ;0,1=156,2=270.000000
L 0.57916693 5.53133317 0.58 5.53346654 2 P 0 ;0,1=156,2=270.000000
L 0.58 5.53346654 0.57916693 5.5355999 2 P 0 ;0,1=156,2=270.000000
L 0.57916693 5.5355999 0.57666742 5.53746663 2 P 0 ;0,1=156,2=270.000000
L 0.57666742 5.53746663 0.57291673 5.5388001 2 P 0 ;0,1=156,2=270.000000
L 0.57291673 5.5388001 0.56916673 5.53933337 2 P 0 ;0,1=156,2=270.000000
L 0.56916673 5.53933337 0.56458366 5.53933337 2 P 0 ;0,1=156,2=270.000000
L 0.56458366 5.53933337 0.56083366 5.5388001 2 P 0 ;0,1=156,2=270.000000
L 0.56083366 5.5388001 0.5575003 5.53746663 2 P 0 ;0,1=156,2=270.000000
L 0.5575003 5.53746663 0.55583317 5.53586644 2 P 0 ;0,1=156,2=270.000000
L 0.55583317 5.53586644 0.555 5.5339997 2 P 0 ;0,1=156,2=270.000000
L 0.555 5.5339997 0.55583317 5.53186634 2 P 0 ;0,1=156,2=270.000000
L 0.55583317 5.53186634 0.5575003 5.53026663 2 P 0 ;0,1=156,2=270.000000
L 0.5575003 5.53026663 0.5599997 5.5291998 2 P 0 ;0,1=156,2=270.000000
L 0.5599997 5.5291998 0.56333386 5.52866654 2 P 0 ;0,1=156,2=270.000000
L 0.56333386 5.52866654 0.5662499 5.5291998 2 P 0 ;0,1=156,2=270.000000
L 0.5662499 5.5291998 0.56916673 5.53053327 2 P 0 ;0,1=156,2=270.000000
L 0.56916673 5.53053327 0.57083386 5.53213346 2 P 0 ;0,1=156,2=270.000000
L 0.57083386 5.53213346 0.57125039 5.5339997 2 P 0 ;0,1=156,2=270.000000
L 0.57125039 5.5339997 0.57041722 5.53613307 2 P 0 ;0,1=156,2=270.000000
L 0.57041722 5.53613307 0.56833356 5.53773327 2 P 0 ;0,1=156,2=270.000000
L 0.56833356 5.53773327 0.56458366 5.53933337 2 P 0 ;0,1=156,2=270.000000
L 0.82213002 5.4 0.83786998 5.4 3 P 0 
L 0.54 5.43266654 0.515 5.43266654 2 P 0 ;0,1=157,2=270.000000
L 0.515 5.43266654 0.515 5.43933327 2 P 0 ;0,1=157,2=270.000000
L 0.515 5.43933327 0.51625059 5.44146663 2 P 0 ;0,1=157,2=270.000000
L 0.51625059 5.44146663 0.51791683 5.4428001 2 P 0 ;0,1=157,2=270.000000
L 0.51791683 5.4428001 0.5212502 5.44333337 2 P 0 ;0,1=157,2=270.000000
L 0.5212502 5.44333337 0.52458366 5.4428001 2 P 0 ;0,1=157,2=270.000000
L 0.52458366 5.4428001 0.52666654 5.4412 2 P 0 ;0,1=157,2=270.000000
L 0.52666654 5.4412 0.52791703 5.43933327 2 P 0 ;0,1=157,2=270.000000
L 0.52791703 5.43933327 0.52791703 5.43266654 2 P 0 ;0,1=157,2=270.000000
L 0.52791703 5.43933327 0.54 5.44333337 2 P 0 ;0,1=157,2=270.000000
L 0.54 5.4619997 0.515 5.4619997 2 P 0 ;0,1=157,2=270.000000
L 0.515 5.4619997 0.5199997 5.4587999 2 P 0 ;0,1=157,2=270.000000
L 0.54 5.4587999 0.54 5.46519951 2 P 0 ;0,1=157,2=270.000000
L 0.53625089 5.48013327 0.53833376 5.48173297 2 P 0 ;0,1=157,2=270.000000
L 0.53833376 5.48173297 0.53958346 5.4835997 2 P 0 ;0,1=157,2=270.000000
L 0.53958346 5.4835997 0.54 5.4859997 2 P 0 ;0,1=157,2=270.000000
L 0.54 5.4859997 0.53916693 5.4884002 2 P 0 ;0,1=157,2=270.000000
L 0.53916693 5.4884002 0.53750059 5.49026644 2 P 0 ;0,1=157,2=270.000000
L 0.53750059 5.49026644 0.53458376 5.4916 2 P 0 ;0,1=157,2=270.000000
L 0.53458376 5.4916 0.53125039 5.49186663 2 P 0 ;0,1=157,2=270.000000
L 0.53125039 5.49186663 0.52791703 5.49133337 2 P 0 ;0,1=157,2=270.000000
L 0.52791703 5.49133337 0.52583337 5.4899998 2 P 0 ;0,1=157,2=270.000000
L 0.52583337 5.4899998 0.52416703 5.48813307 2 P 0 ;0,1=157,2=270.000000
L 0.52416703 5.48813307 0.52375049 5.48626683 2 P 0 ;0,1=157,2=270.000000
L 0.52375049 5.48626683 0.52416703 5.4844 2 P 0 ;0,1=157,2=270.000000
L 0.52416703 5.4844 0.52583337 5.4820001 2 P 0 ;0,1=157,2=270.000000
L 0.52583337 5.4820001 0.515 5.4827999 2 P 0 ;0,1=157,2=270.000000
L 0.515 5.4827999 0.515 5.4899998 2 P 0 ;0,1=157,2=270.000000
L 0.54 5.5099997 0.53958346 5.51186644 2 P 0 ;0,1=157,2=270.000000
L 0.53958346 5.51186644 0.53833376 5.5139998 2 P 0 ;0,1=157,2=270.000000
L 0.53833376 5.5139998 0.53625089 5.51533337 2 P 0 ;0,1=157,2=270.000000
L 0.53625089 5.51533337 0.53333327 5.51586663 2 P 0 ;0,1=157,2=270.000000
L 0.53333327 5.51586663 0.53041722 5.51533337 2 P 0 ;0,1=157,2=270.000000
L 0.53041722 5.51533337 0.52791703 5.51373327 2 P 0 ;0,1=157,2=270.000000
L 0.52791703 5.51373327 0.52666654 5.51133327 2 P 0 ;0,1=157,2=270.000000
L 0.52666654 5.51133327 0.52666654 5.50866663 2 P 0 ;0,1=157,2=270.000000
L 0.52666654 5.50866663 0.52583337 5.50706654 2 P 0 ;0,1=157,2=270.000000
L 0.52583337 5.50706654 0.52375049 5.50573297 2 P 0 ;0,1=157,2=270.000000
L 0.52375049 5.50573297 0.52083366 5.5051998 2 P 0 ;0,1=157,2=270.000000
L 0.52083366 5.5051998 0.51791683 5.5060001 2 P 0 ;0,1=157,2=270.000000
L 0.51791683 5.5060001 0.51583317 5.50786634 2 P 0 ;0,1=157,2=270.000000
L 0.51583317 5.50786634 0.515 5.5099997 2 P 0 ;0,1=157,2=270.000000
L 0.515 5.5099997 0.51583317 5.51213307 2 P 0 ;0,1=157,2=270.000000
L 0.51583317 5.51213307 0.51791683 5.5139998 2 P 0 ;0,1=157,2=270.000000
L 0.51791683 5.5139998 0.52083366 5.5148001 2 P 0 ;0,1=157,2=270.000000
L 0.52083366 5.5148001 0.52375049 5.51426644 2 P 0 ;0,1=157,2=270.000000
L 0.52375049 5.51426644 0.52583337 5.51293337 2 P 0 ;0,1=157,2=270.000000
L 0.52583337 5.51293337 0.52666654 5.51133327 2 P 0 ;0,1=157,2=270.000000
L 0.52666654 5.51133327 0.52666654 5.50866663 2 P 0 ;0,1=157,2=270.000000
L 0.52666654 5.50866663 0.52791703 5.50626663 2 P 0 ;0,1=157,2=270.000000
L 0.52791703 5.50626663 0.53041722 5.50466654 2 P 0 ;0,1=157,2=270.000000
L 0.53041722 5.50466654 0.53333327 5.50413327 2 P 0 ;0,1=157,2=270.000000
L 0.53333327 5.50413327 0.53625089 5.50466654 2 P 0 ;0,1=157,2=270.000000
L 0.53625089 5.50466654 0.53833376 5.5060001 2 P 0 ;0,1=157,2=270.000000
L 0.53833376 5.5060001 0.53958346 5.50813346 2 P 0 ;0,1=157,2=270.000000
L 0.53958346 5.50813346 0.54 5.5099997 2 P 0 ;0,1=157,2=270.000000
L 0.54 5.5339997 0.53958346 5.53586644 2 P 0 ;0,1=157,2=270.000000
L 0.53958346 5.53586644 0.53833376 5.5379998 2 P 0 ;0,1=157,2=270.000000
L 0.53833376 5.5379998 0.53625089 5.53933337 2 P 0 ;0,1=157,2=270.000000
L 0.53625089 5.53933337 0.53333327 5.53986663 2 P 0 ;0,1=157,2=270.000000
L 0.53333327 5.53986663 0.53041722 5.53933337 2 P 0 ;0,1=157,2=270.000000
L 0.53041722 5.53933337 0.52791703 5.53773327 2 P 0 ;0,1=157,2=270.000000
L 0.52791703 5.53773327 0.52666654 5.53533327 2 P 0 ;0,1=157,2=270.000000
L 0.52666654 5.53533327 0.52666654 5.53266663 2 P 0 ;0,1=157,2=270.000000
L 0.52666654 5.53266663 0.52583337 5.53106654 2 P 0 ;0,1=157,2=270.000000
L 0.52583337 5.53106654 0.52375049 5.52973297 2 P 0 ;0,1=157,2=270.000000
L 0.52375049 5.52973297 0.52083366 5.5291998 2 P 0 ;0,1=157,2=270.000000
L 0.52083366 5.5291998 0.51791683 5.5300001 2 P 0 ;0,1=157,2=270.000000
L 0.51791683 5.5300001 0.51583317 5.53186634 2 P 0 ;0,1=157,2=270.000000
L 0.51583317 5.53186634 0.515 5.5339997 2 P 0 ;0,1=157,2=270.000000
L 0.515 5.5339997 0.51583317 5.53613307 2 P 0 ;0,1=157,2=270.000000
L 0.51583317 5.53613307 0.51791683 5.5379998 2 P 0 ;0,1=157,2=270.000000
L 0.51791683 5.5379998 0.52083366 5.5388001 2 P 0 ;0,1=157,2=270.000000
L 0.52083366 5.5388001 0.52375049 5.53826644 2 P 0 ;0,1=157,2=270.000000
L 0.52375049 5.53826644 0.52583337 5.53693337 2 P 0 ;0,1=157,2=270.000000
L 0.52583337 5.53693337 0.52666654 5.53533327 2 P 0 ;0,1=157,2=270.000000
L 0.52666654 5.53533327 0.52666654 5.53266663 2 P 0 ;0,1=157,2=270.000000
L 0.52666654 5.53266663 0.52791703 5.53026663 2 P 0 ;0,1=157,2=270.000000
L 0.52791703 5.53026663 0.53041722 5.52866654 2 P 0 ;0,1=157,2=270.000000
L 0.53041722 5.52866654 0.53333327 5.52813327 2 P 0 ;0,1=157,2=270.000000
L 0.53333327 5.52813327 0.53625089 5.52866654 2 P 0 ;0,1=157,2=270.000000
L 0.53625089 5.52866654 0.53833376 5.5300001 2 P 0 ;0,1=157,2=270.000000
L 0.53833376 5.5300001 0.53958346 5.53213346 2 P 0 ;0,1=157,2=270.000000
L 0.53958346 5.53213346 0.54 5.5339997 2 P 0 ;0,1=157,2=270.000000
L 3.93213002 4.7 3.94786998 4.7 3 P 0 
L 3.925 4.24266654 3.9 4.24266654 2 P 0 ;0,1=158,2=270.000000
L 3.9 4.24266654 3.9 4.24933327 2 P 0 ;0,1=158,2=270.000000
L 3.9 4.24933327 3.90125059 4.25146663 2 P 0 ;0,1=158,2=270.000000
L 3.90125059 4.25146663 3.90291683 4.2528001 2 P 0 ;0,1=158,2=270.000000
L 3.90291683 4.2528001 3.9062502 4.25333337 2 P 0 ;0,1=158,2=270.000000
L 3.9062502 4.25333337 3.90958366 4.2528001 2 P 0 ;0,1=158,2=270.000000
L 3.90958366 4.2528001 3.91166654 4.2512 2 P 0 ;0,1=158,2=270.000000
L 3.91166654 4.2512 3.91291703 4.24933327 2 P 0 ;0,1=158,2=270.000000
L 3.91291703 4.24933327 3.91291703 4.24266654 2 P 0 ;0,1=158,2=270.000000
L 3.91291703 4.24933327 3.925 4.25333337 2 P 0 ;0,1=158,2=270.000000
L 3.925 4.2719997 3.9 4.2719997 2 P 0 ;0,1=158,2=270.000000
L 3.9 4.2719997 3.9049997 4.2687999 2 P 0 ;0,1=158,2=270.000000
L 3.925 4.2687999 3.925 4.27519951 2 P 0 ;0,1=158,2=270.000000
L 3.92125089 4.29013327 3.92333376 4.29173297 2 P 0 ;0,1=158,2=270.000000
L 3.92333376 4.29173297 3.92458346 4.2935997 2 P 0 ;0,1=158,2=270.000000
L 3.92458346 4.2935997 3.925 4.2959997 2 P 0 ;0,1=158,2=270.000000
L 3.925 4.2959997 3.92416693 4.2984002 2 P 0 ;0,1=158,2=270.000000
L 3.92416693 4.2984002 3.92250059 4.30026644 2 P 0 ;0,1=158,2=270.000000
L 3.92250059 4.30026644 3.91958376 4.3016 2 P 0 ;0,1=158,2=270.000000
L 3.91958376 4.3016 3.91625039 4.30186663 2 P 0 ;0,1=158,2=270.000000
L 3.91625039 4.30186663 3.91291703 4.30133337 2 P 0 ;0,1=158,2=270.000000
L 3.91291703 4.30133337 3.91083337 4.2999998 2 P 0 ;0,1=158,2=270.000000
L 3.91083337 4.2999998 3.90916703 4.29813307 2 P 0 ;0,1=158,2=270.000000
L 3.90916703 4.29813307 3.90875049 4.29626683 2 P 0 ;0,1=158,2=270.000000
L 3.90875049 4.29626683 3.90916703 4.2944 2 P 0 ;0,1=158,2=270.000000
L 3.90916703 4.2944 3.91083337 4.2920001 2 P 0 ;0,1=158,2=270.000000
L 3.91083337 4.2920001 3.9 4.2927999 2 P 0 ;0,1=158,2=270.000000
L 3.9 4.2927999 3.9 4.2999998 2 P 0 ;0,1=158,2=270.000000
L 3.925 4.3199997 3.92458346 4.32186644 2 P 0 ;0,1=158,2=270.000000
L 3.92458346 4.32186644 3.92333376 4.3239998 2 P 0 ;0,1=158,2=270.000000
L 3.92333376 4.3239998 3.92125089 4.32533337 2 P 0 ;0,1=158,2=270.000000
L 3.92125089 4.32533337 3.91833327 4.32586663 2 P 0 ;0,1=158,2=270.000000
L 3.91833327 4.32586663 3.91541722 4.32533337 2 P 0 ;0,1=158,2=270.000000
L 3.91541722 4.32533337 3.91291703 4.32373327 2 P 0 ;0,1=158,2=270.000000
L 3.91291703 4.32373327 3.91166654 4.32133327 2 P 0 ;0,1=158,2=270.000000
L 3.91166654 4.32133327 3.91166654 4.31866663 2 P 0 ;0,1=158,2=270.000000
L 3.91166654 4.31866663 3.91083337 4.31706654 2 P 0 ;0,1=158,2=270.000000
L 3.91083337 4.31706654 3.90875049 4.31573297 2 P 0 ;0,1=158,2=270.000000
L 3.90875049 4.31573297 3.90583366 4.3151998 2 P 0 ;0,1=158,2=270.000000
L 3.90583366 4.3151998 3.90291683 4.3160001 2 P 0 ;0,1=158,2=270.000000
L 3.90291683 4.3160001 3.90083317 4.31786634 2 P 0 ;0,1=158,2=270.000000
L 3.90083317 4.31786634 3.9 4.3199997 2 P 0 ;0,1=158,2=270.000000
L 3.9 4.3199997 3.90083317 4.32213307 2 P 0 ;0,1=158,2=270.000000
L 3.90083317 4.32213307 3.90291683 4.3239998 2 P 0 ;0,1=158,2=270.000000
L 3.90291683 4.3239998 3.90583366 4.3248001 2 P 0 ;0,1=158,2=270.000000
L 3.90583366 4.3248001 3.90875049 4.32426644 2 P 0 ;0,1=158,2=270.000000
L 3.90875049 4.32426644 3.91083337 4.32293337 2 P 0 ;0,1=158,2=270.000000
L 3.91083337 4.32293337 3.91166654 4.32133327 2 P 0 ;0,1=158,2=270.000000
L 3.91166654 4.32133327 3.91166654 4.31866663 2 P 0 ;0,1=158,2=270.000000
L 3.91166654 4.31866663 3.91291703 4.31626663 2 P 0 ;0,1=158,2=270.000000
L 3.91291703 4.31626663 3.91541722 4.31466654 2 P 0 ;0,1=158,2=270.000000
L 3.91541722 4.31466654 3.91833327 4.31413327 2 P 0 ;0,1=158,2=270.000000
L 3.91833327 4.31413327 3.92125089 4.31466654 2 P 0 ;0,1=158,2=270.000000
L 3.92125089 4.31466654 3.92333376 4.3160001 2 P 0 ;0,1=158,2=270.000000
L 3.92333376 4.3160001 3.92458346 4.31813346 2 P 0 ;0,1=158,2=270.000000
L 3.92458346 4.31813346 3.925 4.3199997 2 P 0 ;0,1=158,2=270.000000
L 3.92125089 4.33813327 3.92333376 4.33973297 2 P 0 ;0,1=158,2=270.000000
L 3.92333376 4.33973297 3.92458346 4.3415997 2 P 0 ;0,1=158,2=270.000000
L 3.92458346 4.3415997 3.925 4.3439997 2 P 0 ;0,1=158,2=270.000000
L 3.925 4.3439997 3.92416693 4.3464002 2 P 0 ;0,1=158,2=270.000000
L 3.92416693 4.3464002 3.92250059 4.34826644 2 P 0 ;0,1=158,2=270.000000
L 3.92250059 4.34826644 3.91958376 4.3496 2 P 0 ;0,1=158,2=270.000000
L 3.91958376 4.3496 3.91625039 4.34986663 2 P 0 ;0,1=158,2=270.000000
L 3.91625039 4.34986663 3.91291703 4.34933337 2 P 0 ;0,1=158,2=270.000000
L 3.91291703 4.34933337 3.91083337 4.3479998 2 P 0 ;0,1=158,2=270.000000
L 3.91083337 4.3479998 3.90916703 4.34613307 2 P 0 ;0,1=158,2=270.000000
L 3.90916703 4.34613307 3.90875049 4.34426683 2 P 0 ;0,1=158,2=270.000000
L 3.90875049 4.34426683 3.90916703 4.3424 2 P 0 ;0,1=158,2=270.000000
L 3.90916703 4.3424 3.91083337 4.3400001 2 P 0 ;0,1=158,2=270.000000
L 3.91083337 4.3400001 3.9 4.3407999 2 P 0 ;0,1=158,2=270.000000
L 3.9 4.3407999 3.9 4.3479998 2 P 0 ;0,1=158,2=270.000000
L 0.97786998 5.84 0.96213002 5.84 3 P 0 
L 1.02 5.86766654 0.995 5.86766654 2 P 0 ;0,1=159,2=270.000000
L 0.995 5.86766654 0.995 5.87433327 2 P 0 ;0,1=159,2=270.000000
L 0.995 5.87433327 0.99625059 5.87646663 2 P 0 ;0,1=159,2=270.000000
L 0.99625059 5.87646663 0.99791683 5.8778001 2 P 0 ;0,1=159,2=270.000000
L 0.99791683 5.8778001 1.0012502 5.87833337 2 P 0 ;0,1=159,2=270.000000
L 1.0012502 5.87833337 1.00458366 5.8778001 2 P 0 ;0,1=159,2=270.000000
L 1.00458366 5.8778001 1.00666654 5.8762 2 P 0 ;0,1=159,2=270.000000
L 1.00666654 5.8762 1.00791703 5.87433327 2 P 0 ;0,1=159,2=270.000000
L 1.00791703 5.87433327 1.00791703 5.86766654 2 P 0 ;0,1=159,2=270.000000
L 1.00791703 5.87433327 1.02 5.87833337 2 P 0 ;0,1=159,2=270.000000
L 1.02 5.8969997 0.995 5.8969997 2 P 0 ;0,1=159,2=270.000000
L 0.995 5.8969997 0.9999997 5.8937999 2 P 0 ;0,1=159,2=270.000000
L 1.02 5.8937999 1.02 5.90019951 2 P 0 ;0,1=159,2=270.000000
L 1.01625089 5.91513327 1.01833376 5.91673297 2 P 0 ;0,1=159,2=270.000000
L 1.01833376 5.91673297 1.01958346 5.9185997 2 P 0 ;0,1=159,2=270.000000
L 1.01958346 5.9185997 1.02 5.9209997 2 P 0 ;0,1=159,2=270.000000
L 1.02 5.9209997 1.01916693 5.9234002 2 P 0 ;0,1=159,2=270.000000
L 1.01916693 5.9234002 1.01750059 5.92526644 2 P 0 ;0,1=159,2=270.000000
L 1.01750059 5.92526644 1.01458376 5.9266 2 P 0 ;0,1=159,2=270.000000
L 1.01458376 5.9266 1.01125039 5.92686663 2 P 0 ;0,1=159,2=270.000000
L 1.01125039 5.92686663 1.00791703 5.92633337 2 P 0 ;0,1=159,2=270.000000
L 1.00791703 5.92633337 1.00583337 5.9249998 2 P 0 ;0,1=159,2=270.000000
L 1.00583337 5.9249998 1.00416703 5.92313307 2 P 0 ;0,1=159,2=270.000000
L 1.00416703 5.92313307 1.00375049 5.92126683 2 P 0 ;0,1=159,2=270.000000
L 1.00375049 5.92126683 1.00416703 5.9194 2 P 0 ;0,1=159,2=270.000000
L 1.00416703 5.9194 1.00583337 5.9170001 2 P 0 ;0,1=159,2=270.000000
L 1.00583337 5.9170001 0.995 5.9177999 2 P 0 ;0,1=159,2=270.000000
L 0.995 5.9177999 0.995 5.9249998 2 P 0 ;0,1=159,2=270.000000
L 1.02 5.9449997 1.01958346 5.94686644 2 P 0 ;0,1=159,2=270.000000
L 1.01958346 5.94686644 1.01833376 5.9489998 2 P 0 ;0,1=159,2=270.000000
L 1.01833376 5.9489998 1.01625089 5.95033337 2 P 0 ;0,1=159,2=270.000000
L 1.01625089 5.95033337 1.01333327 5.95086663 2 P 0 ;0,1=159,2=270.000000
L 1.01333327 5.95086663 1.01041722 5.95033337 2 P 0 ;0,1=159,2=270.000000
L 1.01041722 5.95033337 1.00791703 5.94873327 2 P 0 ;0,1=159,2=270.000000
L 1.00791703 5.94873327 1.00666654 5.94633327 2 P 0 ;0,1=159,2=270.000000
L 1.00666654 5.94633327 1.00666654 5.94366663 2 P 0 ;0,1=159,2=270.000000
L 1.00666654 5.94366663 1.00583337 5.94206654 2 P 0 ;0,1=159,2=270.000000
L 1.00583337 5.94206654 1.00375049 5.94073297 2 P 0 ;0,1=159,2=270.000000
L 1.00375049 5.94073297 1.00083366 5.9401998 2 P 0 ;0,1=159,2=270.000000
L 1.00083366 5.9401998 0.99791683 5.9410001 2 P 0 ;0,1=159,2=270.000000
L 0.99791683 5.9410001 0.99583317 5.94286634 2 P 0 ;0,1=159,2=270.000000
L 0.99583317 5.94286634 0.995 5.9449997 2 P 0 ;0,1=159,2=270.000000
L 0.995 5.9449997 0.99583317 5.94713307 2 P 0 ;0,1=159,2=270.000000
L 0.99583317 5.94713307 0.99791683 5.9489998 2 P 0 ;0,1=159,2=270.000000
L 0.99791683 5.9489998 1.00083366 5.9498001 2 P 0 ;0,1=159,2=270.000000
L 1.00083366 5.9498001 1.00375049 5.94926644 2 P 0 ;0,1=159,2=270.000000
L 1.00375049 5.94926644 1.00583337 5.94793337 2 P 0 ;0,1=159,2=270.000000
L 1.00583337 5.94793337 1.00666654 5.94633327 2 P 0 ;0,1=159,2=270.000000
L 1.00666654 5.94633327 1.00666654 5.94366663 2 P 0 ;0,1=159,2=270.000000
L 1.00666654 5.94366663 1.00791703 5.94126663 2 P 0 ;0,1=159,2=270.000000
L 1.00791703 5.94126663 1.01041722 5.93966654 2 P 0 ;0,1=159,2=270.000000
L 1.01041722 5.93966654 1.01333327 5.93913327 2 P 0 ;0,1=159,2=270.000000
L 1.01333327 5.93913327 1.01625089 5.93966654 2 P 0 ;0,1=159,2=270.000000
L 1.01625089 5.93966654 1.01833376 5.9410001 2 P 0 ;0,1=159,2=270.000000
L 1.01833376 5.9410001 1.01958346 5.94313346 2 P 0 ;0,1=159,2=270.000000
L 1.01958346 5.94313346 1.02 5.9449997 2 P 0 ;0,1=159,2=270.000000
L 1.02 5.9722 0.995 5.9722 2 P 0 ;0,1=159,2=270.000000
L 0.995 5.9722 1.01291673 5.96233297 2 P 0 ;0,1=159,2=270.000000
L 1.01291673 5.96233297 1.01291673 5.97566693 2 P 0 ;0,1=159,2=270.000000
L 0.89786998 5.84 0.88213002 5.84 3 P 0 
L 0.94 5.86766654 0.915 5.86766654 2 P 0 ;0,1=160,2=270.000000
L 0.915 5.86766654 0.915 5.87433327 2 P 0 ;0,1=160,2=270.000000
L 0.915 5.87433327 0.91625059 5.87646663 2 P 0 ;0,1=160,2=270.000000
L 0.91625059 5.87646663 0.91791683 5.8778001 2 P 0 ;0,1=160,2=270.000000
L 0.91791683 5.8778001 0.9212502 5.87833337 2 P 0 ;0,1=160,2=270.000000
L 0.9212502 5.87833337 0.92458366 5.8778001 2 P 0 ;0,1=160,2=270.000000
L 0.92458366 5.8778001 0.92666654 5.8762 2 P 0 ;0,1=160,2=270.000000
L 0.92666654 5.8762 0.92791703 5.87433327 2 P 0 ;0,1=160,2=270.000000
L 0.92791703 5.87433327 0.92791703 5.86766654 2 P 0 ;0,1=160,2=270.000000
L 0.92791703 5.87433327 0.94 5.87833337 2 P 0 ;0,1=160,2=270.000000
L 0.94 5.8969997 0.915 5.8969997 2 P 0 ;0,1=160,2=270.000000
L 0.915 5.8969997 0.9199997 5.8937999 2 P 0 ;0,1=160,2=270.000000
L 0.94 5.8937999 0.94 5.90019951 2 P 0 ;0,1=160,2=270.000000
L 0.93625089 5.91513327 0.93833376 5.91673297 2 P 0 ;0,1=160,2=270.000000
L 0.93833376 5.91673297 0.93958346 5.9185997 2 P 0 ;0,1=160,2=270.000000
L 0.93958346 5.9185997 0.94 5.9209997 2 P 0 ;0,1=160,2=270.000000
L 0.94 5.9209997 0.93916693 5.9234002 2 P 0 ;0,1=160,2=270.000000
L 0.93916693 5.9234002 0.93750059 5.92526644 2 P 0 ;0,1=160,2=270.000000
L 0.93750059 5.92526644 0.93458376 5.9266 2 P 0 ;0,1=160,2=270.000000
L 0.93458376 5.9266 0.93125039 5.92686663 2 P 0 ;0,1=160,2=270.000000
L 0.93125039 5.92686663 0.92791703 5.92633337 2 P 0 ;0,1=160,2=270.000000
L 0.92791703 5.92633337 0.92583337 5.9249998 2 P 0 ;0,1=160,2=270.000000
L 0.92583337 5.9249998 0.92416703 5.92313307 2 P 0 ;0,1=160,2=270.000000
L 0.92416703 5.92313307 0.92375049 5.92126683 2 P 0 ;0,1=160,2=270.000000
L 0.92375049 5.92126683 0.92416703 5.9194 2 P 0 ;0,1=160,2=270.000000
L 0.92416703 5.9194 0.92583337 5.9170001 2 P 0 ;0,1=160,2=270.000000
L 0.92583337 5.9170001 0.915 5.9177999 2 P 0 ;0,1=160,2=270.000000
L 0.915 5.9177999 0.915 5.9249998 2 P 0 ;0,1=160,2=270.000000
L 0.94 5.9449997 0.93958346 5.94686644 2 P 0 ;0,1=160,2=270.000000
L 0.93958346 5.94686644 0.93833376 5.9489998 2 P 0 ;0,1=160,2=270.000000
L 0.93833376 5.9489998 0.93625089 5.95033337 2 P 0 ;0,1=160,2=270.000000
L 0.93625089 5.95033337 0.93333327 5.95086663 2 P 0 ;0,1=160,2=270.000000
L 0.93333327 5.95086663 0.93041722 5.95033337 2 P 0 ;0,1=160,2=270.000000
L 0.93041722 5.95033337 0.92791703 5.94873327 2 P 0 ;0,1=160,2=270.000000
L 0.92791703 5.94873327 0.92666654 5.94633327 2 P 0 ;0,1=160,2=270.000000
L 0.92666654 5.94633327 0.92666654 5.94366663 2 P 0 ;0,1=160,2=270.000000
L 0.92666654 5.94366663 0.92583337 5.94206654 2 P 0 ;0,1=160,2=270.000000
L 0.92583337 5.94206654 0.92375049 5.94073297 2 P 0 ;0,1=160,2=270.000000
L 0.92375049 5.94073297 0.92083366 5.9401998 2 P 0 ;0,1=160,2=270.000000
L 0.92083366 5.9401998 0.91791683 5.9410001 2 P 0 ;0,1=160,2=270.000000
L 0.91791683 5.9410001 0.91583317 5.94286634 2 P 0 ;0,1=160,2=270.000000
L 0.91583317 5.94286634 0.915 5.9449997 2 P 0 ;0,1=160,2=270.000000
L 0.915 5.9449997 0.91583317 5.94713307 2 P 0 ;0,1=160,2=270.000000
L 0.91583317 5.94713307 0.91791683 5.9489998 2 P 0 ;0,1=160,2=270.000000
L 0.91791683 5.9489998 0.92083366 5.9498001 2 P 0 ;0,1=160,2=270.000000
L 0.92083366 5.9498001 0.92375049 5.94926644 2 P 0 ;0,1=160,2=270.000000
L 0.92375049 5.94926644 0.92583337 5.94793337 2 P 0 ;0,1=160,2=270.000000
L 0.92583337 5.94793337 0.92666654 5.94633327 2 P 0 ;0,1=160,2=270.000000
L 0.92666654 5.94633327 0.92666654 5.94366663 2 P 0 ;0,1=160,2=270.000000
L 0.92666654 5.94366663 0.92791703 5.94126663 2 P 0 ;0,1=160,2=270.000000
L 0.92791703 5.94126663 0.93041722 5.93966654 2 P 0 ;0,1=160,2=270.000000
L 0.93041722 5.93966654 0.93333327 5.93913327 2 P 0 ;0,1=160,2=270.000000
L 0.93333327 5.93913327 0.93625089 5.93966654 2 P 0 ;0,1=160,2=270.000000
L 0.93625089 5.93966654 0.93833376 5.9410001 2 P 0 ;0,1=160,2=270.000000
L 0.93833376 5.9410001 0.93958346 5.94313346 2 P 0 ;0,1=160,2=270.000000
L 0.93958346 5.94313346 0.94 5.9449997 2 P 0 ;0,1=160,2=270.000000
L 0.93500039 5.96313327 0.93791713 5.96473297 2 P 0 ;0,1=160,2=270.000000
L 0.93791713 5.96473297 0.93958346 5.96686634 2 P 0 ;0,1=160,2=270.000000
L 0.93958346 5.96686634 0.94 5.96926683 2 P 0 ;0,1=160,2=270.000000
L 0.94 5.96926683 0.93958346 5.9714002 2 P 0 ;0,1=160,2=270.000000
L 0.93958346 5.9714002 0.93750059 5.97353356 2 P 0 ;0,1=160,2=270.000000
L 0.93750059 5.97353356 0.93500039 5.97486663 2 P 0 ;0,1=160,2=270.000000
L 0.93500039 5.97486663 0.9325001 5.97513317 2 P 0 ;0,1=160,2=270.000000
L 0.9325001 5.97513317 0.92958406 5.9746 2 P 0 ;0,1=160,2=270.000000
L 0.92958406 5.9746 0.92750039 5.97273327 2 P 0 ;0,1=160,2=270.000000
L 0.92750039 5.97273327 0.92666654 5.97086644 2 P 0 ;0,1=160,2=270.000000
L 0.92666654 5.97086644 0.92666654 5.96846654 2 P 0 ;0,1=160,2=270.000000
L 0.92666654 5.97086644 0.92541673 5.97246663 2 P 0 ;0,1=160,2=270.000000
L 0.92541673 5.97246663 0.92333386 5.9738001 2 P 0 ;0,1=160,2=270.000000
L 0.92333386 5.9738001 0.92083366 5.97433337 2 P 0 ;0,1=160,2=270.000000
L 0.92083366 5.97433337 0.91833346 5.9738001 2 P 0 ;0,1=160,2=270.000000
L 0.91833346 5.9738001 0.91625059 5.97246663 2 P 0 ;0,1=160,2=270.000000
L 0.91625059 5.97246663 0.915 5.97006663 2 P 0 ;0,1=160,2=270.000000
L 0.915 5.97006663 0.91541663 5.96766663 2 P 0 ;0,1=160,2=270.000000
L 0.91541663 5.96766663 0.91708366 5.96526663 2 P 0 ;0,1=160,2=270.000000
L 0.81786998 5.84 0.80213002 5.84 3 P 0 
L 0.86 5.86766654 0.835 5.86766654 2 P 0 ;0,1=161,2=270.000000
L 0.835 5.86766654 0.835 5.87433327 2 P 0 ;0,1=161,2=270.000000
L 0.835 5.87433327 0.83625059 5.87646663 2 P 0 ;0,1=161,2=270.000000
L 0.83625059 5.87646663 0.83791683 5.8778001 2 P 0 ;0,1=161,2=270.000000
L 0.83791683 5.8778001 0.8412502 5.87833337 2 P 0 ;0,1=161,2=270.000000
L 0.8412502 5.87833337 0.84458366 5.8778001 2 P 0 ;0,1=161,2=270.000000
L 0.84458366 5.8778001 0.84666654 5.8762 2 P 0 ;0,1=161,2=270.000000
L 0.84666654 5.8762 0.84791703 5.87433327 2 P 0 ;0,1=161,2=270.000000
L 0.84791703 5.87433327 0.84791703 5.86766654 2 P 0 ;0,1=161,2=270.000000
L 0.84791703 5.87433327 0.86 5.87833337 2 P 0 ;0,1=161,2=270.000000
L 0.86 5.8969997 0.835 5.8969997 2 P 0 ;0,1=161,2=270.000000
L 0.835 5.8969997 0.8399997 5.8937999 2 P 0 ;0,1=161,2=270.000000
L 0.86 5.8937999 0.86 5.90019951 2 P 0 ;0,1=161,2=270.000000
L 0.85625089 5.91513327 0.85833376 5.91673297 2 P 0 ;0,1=161,2=270.000000
L 0.85833376 5.91673297 0.85958346 5.9185997 2 P 0 ;0,1=161,2=270.000000
L 0.85958346 5.9185997 0.86 5.9209997 2 P 0 ;0,1=161,2=270.000000
L 0.86 5.9209997 0.85916693 5.9234002 2 P 0 ;0,1=161,2=270.000000
L 0.85916693 5.9234002 0.85750059 5.92526644 2 P 0 ;0,1=161,2=270.000000
L 0.85750059 5.92526644 0.85458376 5.9266 2 P 0 ;0,1=161,2=270.000000
L 0.85458376 5.9266 0.85125039 5.92686663 2 P 0 ;0,1=161,2=270.000000
L 0.85125039 5.92686663 0.84791703 5.92633337 2 P 0 ;0,1=161,2=270.000000
L 0.84791703 5.92633337 0.84583337 5.9249998 2 P 0 ;0,1=161,2=270.000000
L 0.84583337 5.9249998 0.84416703 5.92313307 2 P 0 ;0,1=161,2=270.000000
L 0.84416703 5.92313307 0.84375049 5.92126683 2 P 0 ;0,1=161,2=270.000000
L 0.84375049 5.92126683 0.84416703 5.9194 2 P 0 ;0,1=161,2=270.000000
L 0.84416703 5.9194 0.84583337 5.9170001 2 P 0 ;0,1=161,2=270.000000
L 0.84583337 5.9170001 0.835 5.9177999 2 P 0 ;0,1=161,2=270.000000
L 0.835 5.9177999 0.835 5.9249998 2 P 0 ;0,1=161,2=270.000000
L 0.86 5.9449997 0.85958346 5.94686644 2 P 0 ;0,1=161,2=270.000000
L 0.85958346 5.94686644 0.85833376 5.9489998 2 P 0 ;0,1=161,2=270.000000
L 0.85833376 5.9489998 0.85625089 5.95033337 2 P 0 ;0,1=161,2=270.000000
L 0.85625089 5.95033337 0.85333327 5.95086663 2 P 0 ;0,1=161,2=270.000000
L 0.85333327 5.95086663 0.85041722 5.95033337 2 P 0 ;0,1=161,2=270.000000
L 0.85041722 5.95033337 0.84791703 5.94873327 2 P 0 ;0,1=161,2=270.000000
L 0.84791703 5.94873327 0.84666654 5.94633327 2 P 0 ;0,1=161,2=270.000000
L 0.84666654 5.94633327 0.84666654 5.94366663 2 P 0 ;0,1=161,2=270.000000
L 0.84666654 5.94366663 0.84583337 5.94206654 2 P 0 ;0,1=161,2=270.000000
L 0.84583337 5.94206654 0.84375049 5.94073297 2 P 0 ;0,1=161,2=270.000000
L 0.84375049 5.94073297 0.84083366 5.9401998 2 P 0 ;0,1=161,2=270.000000
L 0.84083366 5.9401998 0.83791683 5.9410001 2 P 0 ;0,1=161,2=270.000000
L 0.83791683 5.9410001 0.83583317 5.94286634 2 P 0 ;0,1=161,2=270.000000
L 0.83583317 5.94286634 0.835 5.9449997 2 P 0 ;0,1=161,2=270.000000
L 0.835 5.9449997 0.83583317 5.94713307 2 P 0 ;0,1=161,2=270.000000
L 0.83583317 5.94713307 0.83791683 5.9489998 2 P 0 ;0,1=161,2=270.000000
L 0.83791683 5.9489998 0.84083366 5.9498001 2 P 0 ;0,1=161,2=270.000000
L 0.84083366 5.9498001 0.84375049 5.94926644 2 P 0 ;0,1=161,2=270.000000
L 0.84375049 5.94926644 0.84583337 5.94793337 2 P 0 ;0,1=161,2=270.000000
L 0.84583337 5.94793337 0.84666654 5.94633327 2 P 0 ;0,1=161,2=270.000000
L 0.84666654 5.94633327 0.84666654 5.94366663 2 P 0 ;0,1=161,2=270.000000
L 0.84666654 5.94366663 0.84791703 5.94126663 2 P 0 ;0,1=161,2=270.000000
L 0.84791703 5.94126663 0.85041722 5.93966654 2 P 0 ;0,1=161,2=270.000000
L 0.85041722 5.93966654 0.85333327 5.93913327 2 P 0 ;0,1=161,2=270.000000
L 0.85333327 5.93913327 0.85625089 5.93966654 2 P 0 ;0,1=161,2=270.000000
L 0.85625089 5.93966654 0.85833376 5.9410001 2 P 0 ;0,1=161,2=270.000000
L 0.85833376 5.9410001 0.85958346 5.94313346 2 P 0 ;0,1=161,2=270.000000
L 0.85958346 5.94313346 0.86 5.9449997 2 P 0 ;0,1=161,2=270.000000
L 0.83916663 5.96393317 0.83666713 5.96553327 2 P 0 ;0,1=161,2=270.000000
L 0.83666713 5.96553327 0.83541663 5.9674 2 P 0 ;0,1=161,2=270.000000
L 0.83541663 5.9674 0.835 5.96953337 2 P 0 ;0,1=161,2=270.000000
L 0.835 5.96953337 0.83583317 5.9722 2 P 0 ;0,1=161,2=270.000000
L 0.83583317 5.9722 0.83791683 5.97406673 2 P 0 ;0,1=161,2=270.000000
L 0.83791683 5.97406673 0.84041634 5.9746 2 P 0 ;0,1=161,2=270.000000
L 0.84041634 5.9746 0.84291732 5.97433337 2 P 0 ;0,1=161,2=270.000000
L 0.84291732 5.97433337 0.8450002 5.97326644 2 P 0 ;0,1=161,2=270.000000
L 0.8450002 5.97326644 0.84916673 5.96793327 2 P 0 ;0,1=161,2=270.000000
L 0.84916673 5.96793327 0.85208356 5.96553327 2 P 0 ;0,1=161,2=270.000000
L 0.85208356 5.96553327 0.85625089 5.96393317 2 P 0 ;0,1=161,2=270.000000
L 0.85625089 5.96393317 0.86 5.9633999 2 P 0 ;0,1=161,2=270.000000
L 0.86 5.9633999 0.86 5.9746 2 P 0 ;0,1=161,2=270.000000
L 0.73786998 5.84 0.72213002 5.84 3 P 0 
L 0.78 5.86766654 0.755 5.86766654 2 P 0 ;0,1=162,2=270.000000
L 0.755 5.86766654 0.755 5.87433327 2 P 0 ;0,1=162,2=270.000000
L 0.755 5.87433327 0.75625059 5.87646663 2 P 0 ;0,1=162,2=270.000000
L 0.75625059 5.87646663 0.75791683 5.8778001 2 P 0 ;0,1=162,2=270.000000
L 0.75791683 5.8778001 0.7612502 5.87833337 2 P 0 ;0,1=162,2=270.000000
L 0.7612502 5.87833337 0.76458366 5.8778001 2 P 0 ;0,1=162,2=270.000000
L 0.76458366 5.8778001 0.76666654 5.8762 2 P 0 ;0,1=162,2=270.000000
L 0.76666654 5.8762 0.76791703 5.87433327 2 P 0 ;0,1=162,2=270.000000
L 0.76791703 5.87433327 0.76791703 5.86766654 2 P 0 ;0,1=162,2=270.000000
L 0.76791703 5.87433327 0.78 5.87833337 2 P 0 ;0,1=162,2=270.000000
L 0.78 5.8969997 0.755 5.8969997 2 P 0 ;0,1=162,2=270.000000
L 0.755 5.8969997 0.7599997 5.8937999 2 P 0 ;0,1=162,2=270.000000
L 0.78 5.8937999 0.78 5.90019951 2 P 0 ;0,1=162,2=270.000000
L 0.77625089 5.91513327 0.77833376 5.91673297 2 P 0 ;0,1=162,2=270.000000
L 0.77833376 5.91673297 0.77958346 5.9185997 2 P 0 ;0,1=162,2=270.000000
L 0.77958346 5.9185997 0.78 5.9209997 2 P 0 ;0,1=162,2=270.000000
L 0.78 5.9209997 0.77916693 5.9234002 2 P 0 ;0,1=162,2=270.000000
L 0.77916693 5.9234002 0.77750059 5.92526644 2 P 0 ;0,1=162,2=270.000000
L 0.77750059 5.92526644 0.77458376 5.9266 2 P 0 ;0,1=162,2=270.000000
L 0.77458376 5.9266 0.77125039 5.92686663 2 P 0 ;0,1=162,2=270.000000
L 0.77125039 5.92686663 0.76791703 5.92633337 2 P 0 ;0,1=162,2=270.000000
L 0.76791703 5.92633337 0.76583337 5.9249998 2 P 0 ;0,1=162,2=270.000000
L 0.76583337 5.9249998 0.76416703 5.92313307 2 P 0 ;0,1=162,2=270.000000
L 0.76416703 5.92313307 0.76375049 5.92126683 2 P 0 ;0,1=162,2=270.000000
L 0.76375049 5.92126683 0.76416703 5.9194 2 P 0 ;0,1=162,2=270.000000
L 0.76416703 5.9194 0.76583337 5.9170001 2 P 0 ;0,1=162,2=270.000000
L 0.76583337 5.9170001 0.755 5.9177999 2 P 0 ;0,1=162,2=270.000000
L 0.755 5.9177999 0.755 5.9249998 2 P 0 ;0,1=162,2=270.000000
L 0.78 5.9449997 0.77958346 5.94686644 2 P 0 ;0,1=162,2=270.000000
L 0.77958346 5.94686644 0.77833376 5.9489998 2 P 0 ;0,1=162,2=270.000000
L 0.77833376 5.9489998 0.77625089 5.95033337 2 P 0 ;0,1=162,2=270.000000
L 0.77625089 5.95033337 0.77333327 5.95086663 2 P 0 ;0,1=162,2=270.000000
L 0.77333327 5.95086663 0.77041722 5.95033337 2 P 0 ;0,1=162,2=270.000000
L 0.77041722 5.95033337 0.76791703 5.94873327 2 P 0 ;0,1=162,2=270.000000
L 0.76791703 5.94873327 0.76666654 5.94633327 2 P 0 ;0,1=162,2=270.000000
L 0.76666654 5.94633327 0.76666654 5.94366663 2 P 0 ;0,1=162,2=270.000000
L 0.76666654 5.94366663 0.76583337 5.94206654 2 P 0 ;0,1=162,2=270.000000
L 0.76583337 5.94206654 0.76375049 5.94073297 2 P 0 ;0,1=162,2=270.000000
L 0.76375049 5.94073297 0.76083366 5.9401998 2 P 0 ;0,1=162,2=270.000000
L 0.76083366 5.9401998 0.75791683 5.9410001 2 P 0 ;0,1=162,2=270.000000
L 0.75791683 5.9410001 0.75583317 5.94286634 2 P 0 ;0,1=162,2=270.000000
L 0.75583317 5.94286634 0.755 5.9449997 2 P 0 ;0,1=162,2=270.000000
L 0.755 5.9449997 0.75583317 5.94713307 2 P 0 ;0,1=162,2=270.000000
L 0.75583317 5.94713307 0.75791683 5.9489998 2 P 0 ;0,1=162,2=270.000000
L 0.75791683 5.9489998 0.76083366 5.9498001 2 P 0 ;0,1=162,2=270.000000
L 0.76083366 5.9498001 0.76375049 5.94926644 2 P 0 ;0,1=162,2=270.000000
L 0.76375049 5.94926644 0.76583337 5.94793337 2 P 0 ;0,1=162,2=270.000000
L 0.76583337 5.94793337 0.76666654 5.94633327 2 P 0 ;0,1=162,2=270.000000
L 0.76666654 5.94633327 0.76666654 5.94366663 2 P 0 ;0,1=162,2=270.000000
L 0.76666654 5.94366663 0.76791703 5.94126663 2 P 0 ;0,1=162,2=270.000000
L 0.76791703 5.94126663 0.77041722 5.93966654 2 P 0 ;0,1=162,2=270.000000
L 0.77041722 5.93966654 0.77333327 5.93913327 2 P 0 ;0,1=162,2=270.000000
L 0.77333327 5.93913327 0.77625089 5.93966654 2 P 0 ;0,1=162,2=270.000000
L 0.77625089 5.93966654 0.77833376 5.9410001 2 P 0 ;0,1=162,2=270.000000
L 0.77833376 5.9410001 0.77958346 5.94313346 2 P 0 ;0,1=162,2=270.000000
L 0.77958346 5.94313346 0.78 5.9449997 2 P 0 ;0,1=162,2=270.000000
L 0.78 5.9689997 0.755 5.9689997 2 P 0 ;0,1=162,2=270.000000
L 0.755 5.9689997 0.7599997 5.9657999 2 P 0 ;0,1=162,2=270.000000
L 0.78 5.9657999 0.78 5.97219951 2 P 0 ;0,1=162,2=270.000000
L 1.34693002 5.10851004 1.33118996 5.10851004 3 P 0 
L 1.355 5.17266654 1.33 5.17266654 2 P 0 ;0,1=163,2=270.000000
L 1.33 5.17266654 1.33 5.17933327 2 P 0 ;0,1=163,2=270.000000
L 1.33 5.17933327 1.33125059 5.18146663 2 P 0 ;0,1=163,2=270.000000
L 1.33125059 5.18146663 1.33291683 5.1828001 2 P 0 ;0,1=163,2=270.000000
L 1.33291683 5.1828001 1.3362502 5.18333337 2 P 0 ;0,1=163,2=270.000000
L 1.3362502 5.18333337 1.33958366 5.1828001 2 P 0 ;0,1=163,2=270.000000
L 1.33958366 5.1828001 1.34166654 5.1812 2 P 0 ;0,1=163,2=270.000000
L 1.34166654 5.1812 1.34291703 5.17933327 2 P 0 ;0,1=163,2=270.000000
L 1.34291703 5.17933327 1.34291703 5.17266654 2 P 0 ;0,1=163,2=270.000000
L 1.34291703 5.17933327 1.355 5.18333337 2 P 0 ;0,1=163,2=270.000000
L 1.355 5.2019997 1.33 5.2019997 2 P 0 ;0,1=163,2=270.000000
L 1.33 5.2019997 1.3349997 5.1987999 2 P 0 ;0,1=163,2=270.000000
L 1.355 5.1987999 1.355 5.20519951 2 P 0 ;0,1=163,2=270.000000
L 1.35125089 5.22013327 1.35333376 5.22173297 2 P 0 ;0,1=163,2=270.000000
L 1.35333376 5.22173297 1.35458346 5.2235997 2 P 0 ;0,1=163,2=270.000000
L 1.35458346 5.2235997 1.355 5.2259997 2 P 0 ;0,1=163,2=270.000000
L 1.355 5.2259997 1.35416693 5.2284002 2 P 0 ;0,1=163,2=270.000000
L 1.35416693 5.2284002 1.35250059 5.23026644 2 P 0 ;0,1=163,2=270.000000
L 1.35250059 5.23026644 1.34958376 5.2316 2 P 0 ;0,1=163,2=270.000000
L 1.34958376 5.2316 1.34625039 5.23186663 2 P 0 ;0,1=163,2=270.000000
L 1.34625039 5.23186663 1.34291703 5.23133337 2 P 0 ;0,1=163,2=270.000000
L 1.34291703 5.23133337 1.34083337 5.2299998 2 P 0 ;0,1=163,2=270.000000
L 1.34083337 5.2299998 1.33916703 5.22813307 2 P 0 ;0,1=163,2=270.000000
L 1.33916703 5.22813307 1.33875049 5.22626683 2 P 0 ;0,1=163,2=270.000000
L 1.33875049 5.22626683 1.33916703 5.2244 2 P 0 ;0,1=163,2=270.000000
L 1.33916703 5.2244 1.34083337 5.2220001 2 P 0 ;0,1=163,2=270.000000
L 1.34083337 5.2220001 1.33 5.2227999 2 P 0 ;0,1=163,2=270.000000
L 1.33 5.2227999 1.33 5.2299998 2 P 0 ;0,1=163,2=270.000000
L 1.355 5.24946654 1.34958376 5.2499997 2 P 0 ;0,1=163,2=270.000000
L 1.34958376 5.2499997 1.34500069 5.2508 2 P 0 ;0,1=163,2=270.000000
L 1.34500069 5.2508 1.34083337 5.25186644 2 P 0 ;0,1=163,2=270.000000
L 1.34083337 5.25186644 1.3362502 5.2532 2 P 0 ;0,1=163,2=270.000000
L 1.3362502 5.2532 1.33 5.25533337 2 P 0 ;0,1=163,2=270.000000
L 1.33 5.25533337 1.33 5.24466654 2 P 0 ;0,1=163,2=270.000000
L 1.34458406 5.26893317 1.34166654 5.2707999 2 P 0 ;0,1=163,2=270.000000
L 1.34166654 5.2707999 1.3400002 5.2724 2 P 0 ;0,1=163,2=270.000000
L 1.3400002 5.2724 1.33916703 5.27453337 2 P 0 ;0,1=163,2=270.000000
L 1.33916703 5.27453337 1.3400002 5.2764002 2 P 0 ;0,1=163,2=270.000000
L 1.3400002 5.2764002 1.34166654 5.27773327 2 P 0 ;0,1=163,2=270.000000
L 1.34166654 5.27773327 1.34416673 5.2788001 2 P 0 ;0,1=163,2=270.000000
L 1.34416673 5.2788001 1.34708356 5.27906673 2 P 0 ;0,1=163,2=270.000000
L 1.34708356 5.27906673 1.34958376 5.2788001 2 P 0 ;0,1=163,2=270.000000
L 1.34958376 5.2788001 1.35208396 5.27773327 2 P 0 ;0,1=163,2=270.000000
L 1.35208396 5.27773327 1.35416693 5.27613307 2 P 0 ;0,1=163,2=270.000000
L 1.35416693 5.27613307 1.355 5.27426683 2 P 0 ;0,1=163,2=270.000000
L 1.355 5.27426683 1.35416693 5.27213346 2 P 0 ;0,1=163,2=270.000000
L 1.35416693 5.27213346 1.35166742 5.27026663 2 P 0 ;0,1=163,2=270.000000
L 1.35166742 5.27026663 1.34791673 5.2691998 2 P 0 ;0,1=163,2=270.000000
L 1.34791673 5.2691998 1.3437502 5.26893317 2 P 0 ;0,1=163,2=270.000000
L 1.3437502 5.26893317 1.33833386 5.26946634 2 P 0 ;0,1=163,2=270.000000
L 1.33833386 5.26946634 1.33541634 5.27026663 2 P 0 ;0,1=163,2=270.000000
L 1.33541634 5.27026663 1.3325003 5.2715997 2 P 0 ;0,1=163,2=270.000000
L 1.3325003 5.2715997 1.33041663 5.27346654 2 P 0 ;0,1=163,2=270.000000
L 1.33041663 5.27346654 1.33 5.27533327 2 P 0 ;0,1=163,2=270.000000
L 1.33 5.27533327 1.33083317 5.2772 2 P 0 ;0,1=163,2=270.000000
L 1.33083317 5.2772 1.33291683 5.27853356 2 P 0 ;0,1=163,2=270.000000
L 1.19693002 5.10851004 1.18118996 5.10851004 3 P 0 
L 1.2 5.17266654 1.175 5.17266654 2 P 0 ;0,1=164,2=270.000000
L 1.175 5.17266654 1.175 5.17933327 2 P 0 ;0,1=164,2=270.000000
L 1.175 5.17933327 1.17625059 5.18146663 2 P 0 ;0,1=164,2=270.000000
L 1.17625059 5.18146663 1.17791683 5.1828001 2 P 0 ;0,1=164,2=270.000000
L 1.17791683 5.1828001 1.1812502 5.18333337 2 P 0 ;0,1=164,2=270.000000
L 1.1812502 5.18333337 1.18458366 5.1828001 2 P 0 ;0,1=164,2=270.000000
L 1.18458366 5.1828001 1.18666654 5.1812 2 P 0 ;0,1=164,2=270.000000
L 1.18666654 5.1812 1.18791703 5.17933327 2 P 0 ;0,1=164,2=270.000000
L 1.18791703 5.17933327 1.18791703 5.17266654 2 P 0 ;0,1=164,2=270.000000
L 1.18791703 5.17933327 1.2 5.18333337 2 P 0 ;0,1=164,2=270.000000
L 1.2 5.2019997 1.175 5.2019997 2 P 0 ;0,1=164,2=270.000000
L 1.175 5.2019997 1.1799997 5.1987999 2 P 0 ;0,1=164,2=270.000000
L 1.2 5.1987999 1.2 5.20519951 2 P 0 ;0,1=164,2=270.000000
L 1.19625089 5.22013327 1.19833376 5.22173297 2 P 0 ;0,1=164,2=270.000000
L 1.19833376 5.22173297 1.19958346 5.2235997 2 P 0 ;0,1=164,2=270.000000
L 1.19958346 5.2235997 1.2 5.2259997 2 P 0 ;0,1=164,2=270.000000
L 1.2 5.2259997 1.19916693 5.2284002 2 P 0 ;0,1=164,2=270.000000
L 1.19916693 5.2284002 1.19750059 5.23026644 2 P 0 ;0,1=164,2=270.000000
L 1.19750059 5.23026644 1.19458376 5.2316 2 P 0 ;0,1=164,2=270.000000
L 1.19458376 5.2316 1.19125039 5.23186663 2 P 0 ;0,1=164,2=270.000000
L 1.19125039 5.23186663 1.18791703 5.23133337 2 P 0 ;0,1=164,2=270.000000
L 1.18791703 5.23133337 1.18583337 5.2299998 2 P 0 ;0,1=164,2=270.000000
L 1.18583337 5.2299998 1.18416703 5.22813307 2 P 0 ;0,1=164,2=270.000000
L 1.18416703 5.22813307 1.18375049 5.22626683 2 P 0 ;0,1=164,2=270.000000
L 1.18375049 5.22626683 1.18416703 5.2244 2 P 0 ;0,1=164,2=270.000000
L 1.18416703 5.2244 1.18583337 5.2220001 2 P 0 ;0,1=164,2=270.000000
L 1.18583337 5.2220001 1.175 5.2227999 2 P 0 ;0,1=164,2=270.000000
L 1.175 5.2227999 1.175 5.2299998 2 P 0 ;0,1=164,2=270.000000
L 1.2 5.24946654 1.19458376 5.2499997 2 P 0 ;0,1=164,2=270.000000
L 1.19458376 5.2499997 1.19000069 5.2508 2 P 0 ;0,1=164,2=270.000000
L 1.19000069 5.2508 1.18583337 5.25186644 2 P 0 ;0,1=164,2=270.000000
L 1.18583337 5.25186644 1.1812502 5.2532 2 P 0 ;0,1=164,2=270.000000
L 1.1812502 5.2532 1.175 5.25533337 2 P 0 ;0,1=164,2=270.000000
L 1.175 5.25533337 1.175 5.24466654 2 P 0 ;0,1=164,2=270.000000
L 1.19625089 5.26813327 1.19833376 5.26973297 2 P 0 ;0,1=164,2=270.000000
L 1.19833376 5.26973297 1.19958346 5.2715997 2 P 0 ;0,1=164,2=270.000000
L 1.19958346 5.2715997 1.2 5.2739997 2 P 0 ;0,1=164,2=270.000000
L 1.2 5.2739997 1.19916693 5.2764002 2 P 0 ;0,1=164,2=270.000000
L 1.19916693 5.2764002 1.19750059 5.27826644 2 P 0 ;0,1=164,2=270.000000
L 1.19750059 5.27826644 1.19458376 5.2796 2 P 0 ;0,1=164,2=270.000000
L 1.19458376 5.2796 1.19125039 5.27986663 2 P 0 ;0,1=164,2=270.000000
L 1.19125039 5.27986663 1.18791703 5.27933337 2 P 0 ;0,1=164,2=270.000000
L 1.18791703 5.27933337 1.18583337 5.2779998 2 P 0 ;0,1=164,2=270.000000
L 1.18583337 5.2779998 1.18416703 5.27613307 2 P 0 ;0,1=164,2=270.000000
L 1.18416703 5.27613307 1.18375049 5.27426683 2 P 0 ;0,1=164,2=270.000000
L 1.18375049 5.27426683 1.18416703 5.2724 2 P 0 ;0,1=164,2=270.000000
L 1.18416703 5.2724 1.18583337 5.2700001 2 P 0 ;0,1=164,2=270.000000
L 1.18583337 5.2700001 1.175 5.2707999 2 P 0 ;0,1=164,2=270.000000
L 1.175 5.2707999 1.175 5.2779998 2 P 0 ;0,1=164,2=270.000000
L 0.52 5.69213002 0.52 5.70786998 3 P 0 
L 0.56266654 5.69 0.56266654 5.715 2 P 0 ;0,1=165,2=0.000000
L 0.56266654 5.715 0.56933327 5.715 2 P 0 ;0,1=165,2=0.000000
L 0.56933327 5.715 0.57146663 5.71374941 2 P 0 ;0,1=165,2=0.000000
L 0.57146663 5.71374941 0.5728001 5.71208317 2 P 0 ;0,1=165,2=0.000000
L 0.5728001 5.71208317 0.57333337 5.7087498 2 P 0 ;0,1=165,2=0.000000
L 0.57333337 5.7087498 0.5728001 5.70541634 2 P 0 ;0,1=165,2=0.000000
L 0.5728001 5.70541634 0.5712 5.70333346 2 P 0 ;0,1=165,2=0.000000
L 0.5712 5.70333346 0.56933327 5.70208297 2 P 0 ;0,1=165,2=0.000000
L 0.56933327 5.70208297 0.56266654 5.70208297 2 P 0 ;0,1=165,2=0.000000
L 0.56933327 5.70208297 0.57333337 5.69 2 P 0 ;0,1=165,2=0.000000
L 0.59146654 5.69 0.5919997 5.69541624 2 P 0 ;0,1=165,2=0.000000
L 0.5919997 5.69541624 0.5928 5.69999931 2 P 0 ;0,1=165,2=0.000000
L 0.5928 5.69999931 0.59386644 5.70416663 2 P 0 ;0,1=165,2=0.000000
L 0.59386644 5.70416663 0.5952 5.7087498 2 P 0 ;0,1=165,2=0.000000
L 0.5952 5.7087498 0.59733337 5.715 2 P 0 ;0,1=165,2=0.000000
L 0.59733337 5.715 0.58666654 5.715 2 P 0 ;0,1=165,2=0.000000
L 0.61013327 5.69499961 0.61173297 5.69208287 2 P 0 ;0,1=165,2=0.000000
L 0.61173297 5.69208287 0.61386634 5.69041654 2 P 0 ;0,1=165,2=0.000000
L 0.61386634 5.69041654 0.61626683 5.69 2 P 0 ;0,1=165,2=0.000000
L 0.61626683 5.69 0.6184002 5.69041654 2 P 0 ;0,1=165,2=0.000000
L 0.6184002 5.69041654 0.62053356 5.69249941 2 P 0 ;0,1=165,2=0.000000
L 0.62053356 5.69249941 0.62186663 5.69499961 2 P 0 ;0,1=165,2=0.000000
L 0.62186663 5.69499961 0.62213317 5.6974999 2 P 0 ;0,1=165,2=0.000000
L 0.62213317 5.6974999 0.6216 5.70041594 2 P 0 ;0,1=165,2=0.000000
L 0.6216 5.70041594 0.61973327 5.70249961 2 P 0 ;0,1=165,2=0.000000
L 0.61973327 5.70249961 0.61786644 5.70333346 2 P 0 ;0,1=165,2=0.000000
L 0.61786644 5.70333346 0.61546654 5.70333346 2 P 0 ;0,1=165,2=0.000000
L 0.61786644 5.70333346 0.61946663 5.70458327 2 P 0 ;0,1=165,2=0.000000
L 0.61946663 5.70458327 0.6208001 5.70666614 2 P 0 ;0,1=165,2=0.000000
L 0.6208001 5.70666614 0.62133337 5.70916634 2 P 0 ;0,1=165,2=0.000000
L 0.62133337 5.70916634 0.6208001 5.71166654 2 P 0 ;0,1=165,2=0.000000
L 0.6208001 5.71166654 0.61946663 5.71374941 2 P 0 ;0,1=165,2=0.000000
L 0.61946663 5.71374941 0.61706663 5.715 2 P 0 ;0,1=165,2=0.000000
L 0.61706663 5.715 0.61466663 5.71458337 2 P 0 ;0,1=165,2=0.000000
L 0.61466663 5.71458337 0.61226663 5.71291634 2 P 0 ;0,1=165,2=0.000000
L 0.90213002 5.13 0.91786998 5.13 3 P 0 
L 0.895 4.95266654 0.87 4.95266654 2 P 0 ;0,1=166,2=270.000000
L 0.87 4.95266654 0.87 4.95933327 2 P 0 ;0,1=166,2=270.000000
L 0.87 4.95933327 0.87125059 4.96146663 2 P 0 ;0,1=166,2=270.000000
L 0.87125059 4.96146663 0.87291683 4.9628001 2 P 0 ;0,1=166,2=270.000000
L 0.87291683 4.9628001 0.8762502 4.96333337 2 P 0 ;0,1=166,2=270.000000
L 0.8762502 4.96333337 0.87958366 4.9628001 2 P 0 ;0,1=166,2=270.000000
L 0.87958366 4.9628001 0.88166654 4.9612 2 P 0 ;0,1=166,2=270.000000
L 0.88166654 4.9612 0.88291703 4.95933327 2 P 0 ;0,1=166,2=270.000000
L 0.88291703 4.95933327 0.88291703 4.95266654 2 P 0 ;0,1=166,2=270.000000
L 0.88291703 4.95933327 0.895 4.96333337 2 P 0 ;0,1=166,2=270.000000
L 0.895 4.9819997 0.87 4.9819997 2 P 0 ;0,1=166,2=270.000000
L 0.87 4.9819997 0.8749997 4.9787999 2 P 0 ;0,1=166,2=270.000000
L 0.895 4.9787999 0.895 4.98519951 2 P 0 ;0,1=166,2=270.000000
L 0.895 5.0092 0.87 5.0092 2 P 0 ;0,1=166,2=270.000000
L 0.87 5.0092 0.88791673 4.99933297 2 P 0 ;0,1=166,2=270.000000
L 0.88791673 4.99933297 0.88791673 5.01266693 2 P 0 ;0,1=166,2=270.000000
L 0.895 5.0299997 0.89458346 5.03186644 2 P 0 ;0,1=166,2=270.000000
L 0.89458346 5.03186644 0.89333376 5.0339998 2 P 0 ;0,1=166,2=270.000000
L 0.89333376 5.0339998 0.89125089 5.03533337 2 P 0 ;0,1=166,2=270.000000
L 0.89125089 5.03533337 0.88833327 5.03586663 2 P 0 ;0,1=166,2=270.000000
L 0.88833327 5.03586663 0.88541722 5.03533337 2 P 0 ;0,1=166,2=270.000000
L 0.88541722 5.03533337 0.88291703 5.03373327 2 P 0 ;0,1=166,2=270.000000
L 0.88291703 5.03373327 0.88166654 5.03133327 2 P 0 ;0,1=166,2=270.000000
L 0.88166654 5.03133327 0.88166654 5.02866663 2 P 0 ;0,1=166,2=270.000000
L 0.88166654 5.02866663 0.88083337 5.02706654 2 P 0 ;0,1=166,2=270.000000
L 0.88083337 5.02706654 0.87875049 5.02573297 2 P 0 ;0,1=166,2=270.000000
L 0.87875049 5.02573297 0.87583366 5.0251998 2 P 0 ;0,1=166,2=270.000000
L 0.87583366 5.0251998 0.87291683 5.0260001 2 P 0 ;0,1=166,2=270.000000
L 0.87291683 5.0260001 0.87083317 5.02786634 2 P 0 ;0,1=166,2=270.000000
L 0.87083317 5.02786634 0.87 5.0299997 2 P 0 ;0,1=166,2=270.000000
L 0.87 5.0299997 0.87083317 5.03213307 2 P 0 ;0,1=166,2=270.000000
L 0.87083317 5.03213307 0.87291683 5.0339998 2 P 0 ;0,1=166,2=270.000000
L 0.87291683 5.0339998 0.87583366 5.0348001 2 P 0 ;0,1=166,2=270.000000
L 0.87583366 5.0348001 0.87875049 5.03426644 2 P 0 ;0,1=166,2=270.000000
L 0.87875049 5.03426644 0.88083337 5.03293337 2 P 0 ;0,1=166,2=270.000000
L 0.88083337 5.03293337 0.88166654 5.03133327 2 P 0 ;0,1=166,2=270.000000
L 0.88166654 5.03133327 0.88166654 5.02866663 2 P 0 ;0,1=166,2=270.000000
L 0.88166654 5.02866663 0.88291703 5.02626663 2 P 0 ;0,1=166,2=270.000000
L 0.88291703 5.02626663 0.88541722 5.02466654 2 P 0 ;0,1=166,2=270.000000
L 0.88541722 5.02466654 0.88833327 5.02413327 2 P 0 ;0,1=166,2=270.000000
L 0.88833327 5.02413327 0.89125089 5.02466654 2 P 0 ;0,1=166,2=270.000000
L 0.89125089 5.02466654 0.89333376 5.0260001 2 P 0 ;0,1=166,2=270.000000
L 0.89333376 5.0260001 0.89458346 5.02813346 2 P 0 ;0,1=166,2=270.000000
L 0.89458346 5.02813346 0.895 5.0299997 2 P 0 ;0,1=166,2=270.000000
L 0.89208396 5.04946634 0.89416693 5.05133317 2 P 0 ;0,1=166,2=270.000000
L 0.89416693 5.05133317 0.895 5.05346654 2 P 0 ;0,1=166,2=270.000000
L 0.895 5.05346654 0.89416693 5.0555999 2 P 0 ;0,1=166,2=270.000000
L 0.89416693 5.0555999 0.89166742 5.05746663 2 P 0 ;0,1=166,2=270.000000
L 0.89166742 5.05746663 0.88791673 5.0588001 2 P 0 ;0,1=166,2=270.000000
L 0.88791673 5.0588001 0.88416673 5.05933337 2 P 0 ;0,1=166,2=270.000000
L 0.88416673 5.05933337 0.87958366 5.05933337 2 P 0 ;0,1=166,2=270.000000
L 0.87958366 5.05933337 0.87583366 5.0588001 2 P 0 ;0,1=166,2=270.000000
L 0.87583366 5.0588001 0.8725003 5.05746663 2 P 0 ;0,1=166,2=270.000000
L 0.8725003 5.05746663 0.87083317 5.05586644 2 P 0 ;0,1=166,2=270.000000
L 0.87083317 5.05586644 0.87 5.0539997 2 P 0 ;0,1=166,2=270.000000
L 0.87 5.0539997 0.87083317 5.05186634 2 P 0 ;0,1=166,2=270.000000
L 0.87083317 5.05186634 0.8725003 5.05026663 2 P 0 ;0,1=166,2=270.000000
L 0.8725003 5.05026663 0.8749997 5.0491998 2 P 0 ;0,1=166,2=270.000000
L 0.8749997 5.0491998 0.87833386 5.04866654 2 P 0 ;0,1=166,2=270.000000
L 0.87833386 5.04866654 0.8812499 5.0491998 2 P 0 ;0,1=166,2=270.000000
L 0.8812499 5.0491998 0.88416673 5.05053327 2 P 0 ;0,1=166,2=270.000000
L 0.88416673 5.05053327 0.88583386 5.05213346 2 P 0 ;0,1=166,2=270.000000
L 0.88583386 5.05213346 0.88625039 5.0539997 2 P 0 ;0,1=166,2=270.000000
L 0.88625039 5.0539997 0.88541722 5.05613307 2 P 0 ;0,1=166,2=270.000000
L 0.88541722 5.05613307 0.88333356 5.05773327 2 P 0 ;0,1=166,2=270.000000
L 0.88333356 5.05773327 0.87958366 5.05933337 2 P 0 ;0,1=166,2=270.000000
L 3.81211998 0.7581 3.82786004 0.7581 3 P 0 
L 3.83 0.80766654 3.805 0.80766654 2 P 0 ;0,1=167,2=270.000000
L 3.805 0.80766654 3.805 0.81433327 2 P 0 ;0,1=167,2=270.000000
L 3.805 0.81433327 3.80625059 0.81646663 2 P 0 ;0,1=167,2=270.000000
L 3.80625059 0.81646663 3.80791683 0.8178001 2 P 0 ;0,1=167,2=270.000000
L 3.80791683 0.8178001 3.8112502 0.81833337 2 P 0 ;0,1=167,2=270.000000
L 3.8112502 0.81833337 3.81458366 0.8178001 2 P 0 ;0,1=167,2=270.000000
L 3.81458366 0.8178001 3.81666654 0.8162 2 P 0 ;0,1=167,2=270.000000
L 3.81666654 0.8162 3.81791703 0.81433327 2 P 0 ;0,1=167,2=270.000000
L 3.81791703 0.81433327 3.81791703 0.80766654 2 P 0 ;0,1=167,2=270.000000
L 3.81791703 0.81433327 3.83 0.81833337 2 P 0 ;0,1=167,2=270.000000
L 3.83 0.8369997 3.82958346 0.83886644 2 P 0 ;0,1=167,2=270.000000
L 3.82958346 0.83886644 3.82833376 0.8409998 2 P 0 ;0,1=167,2=270.000000
L 3.82833376 0.8409998 3.82625089 0.84233337 2 P 0 ;0,1=167,2=270.000000
L 3.82625089 0.84233337 3.82333327 0.84286663 2 P 0 ;0,1=167,2=270.000000
L 3.82333327 0.84286663 3.82041722 0.84233337 2 P 0 ;0,1=167,2=270.000000
L 3.82041722 0.84233337 3.81791703 0.84073327 2 P 0 ;0,1=167,2=270.000000
L 3.81791703 0.84073327 3.81666654 0.83833327 2 P 0 ;0,1=167,2=270.000000
L 3.81666654 0.83833327 3.81666654 0.83566663 2 P 0 ;0,1=167,2=270.000000
L 3.81666654 0.83566663 3.81583337 0.83406654 2 P 0 ;0,1=167,2=270.000000
L 3.81583337 0.83406654 3.81375049 0.83273297 2 P 0 ;0,1=167,2=270.000000
L 3.81375049 0.83273297 3.81083366 0.8321998 2 P 0 ;0,1=167,2=270.000000
L 3.81083366 0.8321998 3.80791683 0.8330001 2 P 0 ;0,1=167,2=270.000000
L 3.80791683 0.8330001 3.80583317 0.83486634 2 P 0 ;0,1=167,2=270.000000
L 3.80583317 0.83486634 3.805 0.8369997 2 P 0 ;0,1=167,2=270.000000
L 3.805 0.8369997 3.80583317 0.83913307 2 P 0 ;0,1=167,2=270.000000
L 3.80583317 0.83913307 3.80791683 0.8409998 2 P 0 ;0,1=167,2=270.000000
L 3.80791683 0.8409998 3.81083366 0.8418001 2 P 0 ;0,1=167,2=270.000000
L 3.81083366 0.8418001 3.81375049 0.84126644 2 P 0 ;0,1=167,2=270.000000
L 3.81375049 0.84126644 3.81583337 0.83993337 2 P 0 ;0,1=167,2=270.000000
L 3.81583337 0.83993337 3.81666654 0.83833327 2 P 0 ;0,1=167,2=270.000000
L 3.81666654 0.83833327 3.81666654 0.83566663 2 P 0 ;0,1=167,2=270.000000
L 3.81666654 0.83566663 3.81791703 0.83326663 2 P 0 ;0,1=167,2=270.000000
L 3.81791703 0.83326663 3.82041722 0.83166654 2 P 0 ;0,1=167,2=270.000000
L 3.82041722 0.83166654 3.82333327 0.83113327 2 P 0 ;0,1=167,2=270.000000
L 3.82333327 0.83113327 3.82625089 0.83166654 2 P 0 ;0,1=167,2=270.000000
L 3.82625089 0.83166654 3.82833376 0.8330001 2 P 0 ;0,1=167,2=270.000000
L 3.82833376 0.8330001 3.82958346 0.83513346 2 P 0 ;0,1=167,2=270.000000
L 3.82958346 0.83513346 3.83 0.8369997 2 P 0 ;0,1=167,2=270.000000
L 3.805 0.8609997 3.80583317 0.85886634 2 P 0 ;0,1=167,2=270.000000
L 3.80583317 0.85886634 3.80791683 0.85726663 2 P 0 ;0,1=167,2=270.000000
L 3.80791683 0.85726663 3.81041634 0.8561998 2 P 0 ;0,1=167,2=270.000000
L 3.81041634 0.8561998 3.81375049 0.8553999 2 P 0 ;0,1=167,2=270.000000
L 3.81375049 0.8553999 3.81750039 0.85513327 2 P 0 ;0,1=167,2=270.000000
L 3.81750039 0.85513327 3.82125039 0.8553999 2 P 0 ;0,1=167,2=270.000000
L 3.82125039 0.8553999 3.82458376 0.8561998 2 P 0 ;0,1=167,2=270.000000
L 3.82458376 0.8561998 3.82708396 0.85726663 2 P 0 ;0,1=167,2=270.000000
L 3.82708396 0.85726663 3.82916693 0.85886634 2 P 0 ;0,1=167,2=270.000000
L 3.82916693 0.85886634 3.83 0.8609997 2 P 0 ;0,1=167,2=270.000000
L 3.83 0.8609997 3.82916693 0.86313307 2 P 0 ;0,1=167,2=270.000000
L 3.82916693 0.86313307 3.82708396 0.86473327 2 P 0 ;0,1=167,2=270.000000
L 3.82708396 0.86473327 3.82458376 0.8658001 2 P 0 ;0,1=167,2=270.000000
L 3.82458376 0.8658001 3.82125039 0.8666 2 P 0 ;0,1=167,2=270.000000
L 3.82125039 0.8666 3.81750039 0.86686663 2 P 0 ;0,1=167,2=270.000000
L 3.81750039 0.86686663 3.81375049 0.8666 2 P 0 ;0,1=167,2=270.000000
L 3.81375049 0.8666 3.81041634 0.8658001 2 P 0 ;0,1=167,2=270.000000
L 3.81041634 0.8658001 3.80791683 0.86473327 2 P 0 ;0,1=167,2=270.000000
L 3.80791683 0.86473327 3.80583317 0.86313307 2 P 0 ;0,1=167,2=270.000000
L 3.80583317 0.86313307 3.805 0.8609997 2 P 0 ;0,1=167,2=270.000000
L 3.83 0.8882 3.805 0.8882 2 P 0 ;0,1=167,2=270.000000
L 3.805 0.8882 3.82291673 0.87833297 2 P 0 ;0,1=167,2=270.000000
L 3.82291673 0.87833297 3.82291673 0.89166693 2 P 0 ;0,1=167,2=270.000000
L 3.61786004 0.2881 3.60211998 0.2881 3 P 0 
L 3.62 0.13766654 3.595 0.13766654 2 P 0 ;0,1=168,2=270.000000
L 3.595 0.13766654 3.595 0.14433327 2 P 0 ;0,1=168,2=270.000000
L 3.595 0.14433327 3.59625059 0.14646663 2 P 0 ;0,1=168,2=270.000000
L 3.59625059 0.14646663 3.59791683 0.1478001 2 P 0 ;0,1=168,2=270.000000
L 3.59791683 0.1478001 3.6012502 0.14833337 2 P 0 ;0,1=168,2=270.000000
L 3.6012502 0.14833337 3.60458366 0.1478001 2 P 0 ;0,1=168,2=270.000000
L 3.60458366 0.1478001 3.60666654 0.1462 2 P 0 ;0,1=168,2=270.000000
L 3.60666654 0.1462 3.60791703 0.14433327 2 P 0 ;0,1=168,2=270.000000
L 3.60791703 0.14433327 3.60791703 0.13766654 2 P 0 ;0,1=168,2=270.000000
L 3.60791703 0.14433327 3.62 0.14833337 2 P 0 ;0,1=168,2=270.000000
L 3.62 0.16646654 3.61458376 0.1669997 2 P 0 ;0,1=168,2=270.000000
L 3.61458376 0.1669997 3.61000069 0.1678 2 P 0 ;0,1=168,2=270.000000
L 3.61000069 0.1678 3.60583337 0.16886644 2 P 0 ;0,1=168,2=270.000000
L 3.60583337 0.16886644 3.6012502 0.1702 2 P 0 ;0,1=168,2=270.000000
L 3.6012502 0.1702 3.595 0.17233337 2 P 0 ;0,1=168,2=270.000000
L 3.595 0.17233337 3.595 0.16166654 2 P 0 ;0,1=168,2=270.000000
L 3.59916663 0.18593317 3.59666713 0.18753327 2 P 0 ;0,1=168,2=270.000000
L 3.59666713 0.18753327 3.59541663 0.1894 2 P 0 ;0,1=168,2=270.000000
L 3.59541663 0.1894 3.595 0.19153337 2 P 0 ;0,1=168,2=270.000000
L 3.595 0.19153337 3.59583317 0.1942 2 P 0 ;0,1=168,2=270.000000
L 3.59583317 0.1942 3.59791683 0.19606673 2 P 0 ;0,1=168,2=270.000000
L 3.59791683 0.19606673 3.60041634 0.1966 2 P 0 ;0,1=168,2=270.000000
L 3.60041634 0.1966 3.60291732 0.19633337 2 P 0 ;0,1=168,2=270.000000
L 3.60291732 0.19633337 3.6050002 0.19526644 2 P 0 ;0,1=168,2=270.000000
L 3.6050002 0.19526644 3.60916673 0.18993327 2 P 0 ;0,1=168,2=270.000000
L 3.60916673 0.18993327 3.61208356 0.18753327 2 P 0 ;0,1=168,2=270.000000
L 3.61208356 0.18753327 3.61625089 0.18593317 2 P 0 ;0,1=168,2=270.000000
L 3.61625089 0.18593317 3.62 0.1853999 2 P 0 ;0,1=168,2=270.000000
L 3.62 0.1853999 3.62 0.1966 2 P 0 ;0,1=168,2=270.000000
L 3.62 0.2149997 3.595 0.2149997 2 P 0 ;0,1=168,2=270.000000
L 3.595 0.2149997 3.5999997 0.2117999 2 P 0 ;0,1=168,2=270.000000
L 3.62 0.2117999 3.62 0.21819951 2 P 0 ;0,1=168,2=270.000000
L 9.41581998 0.30943002 9.40008002 0.30943002 3 P 0 
L 9.42 0.13266654 9.395 0.13266654 2 P 0 ;0,1=169,2=270.000000
L 9.395 0.13266654 9.395 0.13933327 2 P 0 ;0,1=169,2=270.000000
L 9.395 0.13933327 9.39625059 0.14146663 2 P 0 ;0,1=169,2=270.000000
L 9.39625059 0.14146663 9.39791683 0.1428001 2 P 0 ;0,1=169,2=270.000000
L 9.39791683 0.1428001 9.4012502 0.14333337 2 P 0 ;0,1=169,2=270.000000
L 9.4012502 0.14333337 9.40458366 0.1428001 2 P 0 ;0,1=169,2=270.000000
L 9.40458366 0.1428001 9.40666654 0.1412 2 P 0 ;0,1=169,2=270.000000
L 9.40666654 0.1412 9.40791703 0.13933327 2 P 0 ;0,1=169,2=270.000000
L 9.40791703 0.13933327 9.40791703 0.13266654 2 P 0 ;0,1=169,2=270.000000
L 9.40791703 0.13933327 9.42 0.14333337 2 P 0 ;0,1=169,2=270.000000
L 9.42 0.1619997 9.395 0.1619997 2 P 0 ;0,1=169,2=270.000000
L 9.395 0.1619997 9.3999997 0.1587999 2 P 0 ;0,1=169,2=270.000000
L 9.42 0.1587999 9.42 0.16519951 2 P 0 ;0,1=169,2=270.000000
L 9.41625089 0.18013327 9.41833376 0.18173297 2 P 0 ;0,1=169,2=270.000000
L 9.41833376 0.18173297 9.41958346 0.1835997 2 P 0 ;0,1=169,2=270.000000
L 9.41958346 0.1835997 9.42 0.1859997 2 P 0 ;0,1=169,2=270.000000
L 9.42 0.1859997 9.41916693 0.1884002 2 P 0 ;0,1=169,2=270.000000
L 9.41916693 0.1884002 9.41750059 0.19026644 2 P 0 ;0,1=169,2=270.000000
L 9.41750059 0.19026644 9.41458376 0.1916 2 P 0 ;0,1=169,2=270.000000
L 9.41458376 0.1916 9.41125039 0.19186663 2 P 0 ;0,1=169,2=270.000000
L 9.41125039 0.19186663 9.40791703 0.19133337 2 P 0 ;0,1=169,2=270.000000
L 9.40791703 0.19133337 9.40583337 0.1899998 2 P 0 ;0,1=169,2=270.000000
L 9.40583337 0.1899998 9.40416703 0.18813307 2 P 0 ;0,1=169,2=270.000000
L 9.40416703 0.18813307 9.40375049 0.18626683 2 P 0 ;0,1=169,2=270.000000
L 9.40375049 0.18626683 9.40416703 0.1844 2 P 0 ;0,1=169,2=270.000000
L 9.40416703 0.1844 9.40583337 0.1820001 2 P 0 ;0,1=169,2=270.000000
L 9.40583337 0.1820001 9.395 0.1827999 2 P 0 ;0,1=169,2=270.000000
L 9.395 0.1827999 9.395 0.1899998 2 P 0 ;0,1=169,2=270.000000
L 9.39916663 0.20493317 9.39666713 0.20653327 2 P 0 ;0,1=169,2=270.000000
L 9.39666713 0.20653327 9.39541663 0.2084 2 P 0 ;0,1=169,2=270.000000
L 9.39541663 0.2084 9.395 0.21053337 2 P 0 ;0,1=169,2=270.000000
L 9.395 0.21053337 9.39583317 0.2132 2 P 0 ;0,1=169,2=270.000000
L 9.39583317 0.2132 9.39791683 0.21506673 2 P 0 ;0,1=169,2=270.000000
L 9.39791683 0.21506673 9.40041634 0.2156 2 P 0 ;0,1=169,2=270.000000
L 9.40041634 0.2156 9.40291732 0.21533337 2 P 0 ;0,1=169,2=270.000000
L 9.40291732 0.21533337 9.4050002 0.21426644 2 P 0 ;0,1=169,2=270.000000
L 9.4050002 0.21426644 9.40916673 0.20893327 2 P 0 ;0,1=169,2=270.000000
L 9.40916673 0.20893327 9.41208356 0.20653327 2 P 0 ;0,1=169,2=270.000000
L 9.41208356 0.20653327 9.41625089 0.20493317 2 P 0 ;0,1=169,2=270.000000
L 9.41625089 0.20493317 9.42 0.2043999 2 P 0 ;0,1=169,2=270.000000
L 9.42 0.2043999 9.42 0.2156 2 P 0 ;0,1=169,2=270.000000
L 9.42 0.2372 9.395 0.2372 2 P 0 ;0,1=169,2=270.000000
L 9.395 0.2372 9.41291673 0.22733297 2 P 0 ;0,1=169,2=270.000000
L 9.41291673 0.22733297 9.41291673 0.24066693 2 P 0 ;0,1=169,2=270.000000
L 9.61008002 0.77943002 9.62581998 0.77943002 3 P 0 
L 9.63 0.84266654 9.605 0.84266654 2 P 0 ;0,1=170,2=270.000000
L 9.605 0.84266654 9.605 0.84933327 2 P 0 ;0,1=170,2=270.000000
L 9.605 0.84933327 9.60625059 0.85146663 2 P 0 ;0,1=170,2=270.000000
L 9.60625059 0.85146663 9.60791683 0.8528001 2 P 0 ;0,1=170,2=270.000000
L 9.60791683 0.8528001 9.6112502 0.85333337 2 P 0 ;0,1=170,2=270.000000
L 9.6112502 0.85333337 9.61458366 0.8528001 2 P 0 ;0,1=170,2=270.000000
L 9.61458366 0.8528001 9.61666654 0.8512 2 P 0 ;0,1=170,2=270.000000
L 9.61666654 0.8512 9.61791703 0.84933327 2 P 0 ;0,1=170,2=270.000000
L 9.61791703 0.84933327 9.61791703 0.84266654 2 P 0 ;0,1=170,2=270.000000
L 9.61791703 0.84933327 9.63 0.85333337 2 P 0 ;0,1=170,2=270.000000
L 9.63 0.8719997 9.605 0.8719997 2 P 0 ;0,1=170,2=270.000000
L 9.605 0.8719997 9.6099997 0.8687999 2 P 0 ;0,1=170,2=270.000000
L 9.63 0.8687999 9.63 0.87519951 2 P 0 ;0,1=170,2=270.000000
L 9.62625089 0.89013327 9.62833376 0.89173297 2 P 0 ;0,1=170,2=270.000000
L 9.62833376 0.89173297 9.62958346 0.8935997 2 P 0 ;0,1=170,2=270.000000
L 9.62958346 0.8935997 9.63 0.8959997 2 P 0 ;0,1=170,2=270.000000
L 9.63 0.8959997 9.62916693 0.8984002 2 P 0 ;0,1=170,2=270.000000
L 9.62916693 0.8984002 9.62750059 0.90026644 2 P 0 ;0,1=170,2=270.000000
L 9.62750059 0.90026644 9.62458376 0.9016 2 P 0 ;0,1=170,2=270.000000
L 9.62458376 0.9016 9.62125039 0.90186663 2 P 0 ;0,1=170,2=270.000000
L 9.62125039 0.90186663 9.61791703 0.90133337 2 P 0 ;0,1=170,2=270.000000
L 9.61791703 0.90133337 9.61583337 0.8999998 2 P 0 ;0,1=170,2=270.000000
L 9.61583337 0.8999998 9.61416703 0.89813307 2 P 0 ;0,1=170,2=270.000000
L 9.61416703 0.89813307 9.61375049 0.89626683 2 P 0 ;0,1=170,2=270.000000
L 9.61375049 0.89626683 9.61416703 0.8944 2 P 0 ;0,1=170,2=270.000000
L 9.61416703 0.8944 9.61583337 0.8920001 2 P 0 ;0,1=170,2=270.000000
L 9.61583337 0.8920001 9.605 0.8927999 2 P 0 ;0,1=170,2=270.000000
L 9.605 0.8927999 9.605 0.8999998 2 P 0 ;0,1=170,2=270.000000
L 9.60916663 0.91493317 9.60666713 0.91653327 2 P 0 ;0,1=170,2=270.000000
L 9.60666713 0.91653327 9.60541663 0.9184 2 P 0 ;0,1=170,2=270.000000
L 9.60541663 0.9184 9.605 0.92053337 2 P 0 ;0,1=170,2=270.000000
L 9.605 0.92053337 9.60583317 0.9232 2 P 0 ;0,1=170,2=270.000000
L 9.60583317 0.9232 9.60791683 0.92506673 2 P 0 ;0,1=170,2=270.000000
L 9.60791683 0.92506673 9.61041634 0.9256 2 P 0 ;0,1=170,2=270.000000
L 9.61041634 0.9256 9.61291732 0.92533337 2 P 0 ;0,1=170,2=270.000000
L 9.61291732 0.92533337 9.6150002 0.92426644 2 P 0 ;0,1=170,2=270.000000
L 9.6150002 0.92426644 9.61916673 0.91893327 2 P 0 ;0,1=170,2=270.000000
L 9.61916673 0.91893327 9.62208356 0.91653327 2 P 0 ;0,1=170,2=270.000000
L 9.62208356 0.91653327 9.62625089 0.91493317 2 P 0 ;0,1=170,2=270.000000
L 9.62625089 0.91493317 9.63 0.9143999 2 P 0 ;0,1=170,2=270.000000
L 9.63 0.9143999 9.63 0.9256 2 P 0 ;0,1=170,2=270.000000
L 9.62500039 0.93813327 9.62791713 0.93973297 2 P 0 ;0,1=170,2=270.000000
L 9.62791713 0.93973297 9.62958346 0.94186634 2 P 0 ;0,1=170,2=270.000000
L 9.62958346 0.94186634 9.63 0.94426683 2 P 0 ;0,1=170,2=270.000000
L 9.63 0.94426683 9.62958346 0.9464002 2 P 0 ;0,1=170,2=270.000000
L 9.62958346 0.9464002 9.62750059 0.94853356 2 P 0 ;0,1=170,2=270.000000
L 9.62750059 0.94853356 9.62500039 0.94986663 2 P 0 ;0,1=170,2=270.000000
L 9.62500039 0.94986663 9.6225001 0.95013317 2 P 0 ;0,1=170,2=270.000000
L 9.6225001 0.95013317 9.61958406 0.9496 2 P 0 ;0,1=170,2=270.000000
L 9.61958406 0.9496 9.61750039 0.94773327 2 P 0 ;0,1=170,2=270.000000
L 9.61750039 0.94773327 9.61666654 0.94586644 2 P 0 ;0,1=170,2=270.000000
L 9.61666654 0.94586644 9.61666654 0.94346654 2 P 0 ;0,1=170,2=270.000000
L 9.61666654 0.94586644 9.61541673 0.94746663 2 P 0 ;0,1=170,2=270.000000
L 9.61541673 0.94746663 9.61333386 0.9488001 2 P 0 ;0,1=170,2=270.000000
L 9.61333386 0.9488001 9.61083366 0.94933337 2 P 0 ;0,1=170,2=270.000000
L 9.61083366 0.94933337 9.60833346 0.9488001 2 P 0 ;0,1=170,2=270.000000
L 9.60833346 0.9488001 9.60625059 0.94746663 2 P 0 ;0,1=170,2=270.000000
L 9.60625059 0.94746663 9.605 0.94506663 2 P 0 ;0,1=170,2=270.000000
L 9.605 0.94506663 9.60541663 0.94266663 2 P 0 ;0,1=170,2=270.000000
L 9.60541663 0.94266663 9.60708366 0.94026663 2 P 0 ;0,1=170,2=270.000000
L 7.25046998 5.10851004 7.23473002 5.10851004 3 P 0 
L 7.255 5.17766654 7.23 5.17766654 2 P 0 ;0,1=171,2=270.000000
L 7.23 5.17766654 7.23 5.18433327 2 P 0 ;0,1=171,2=270.000000
L 7.23 5.18433327 7.23125059 5.18646663 2 P 0 ;0,1=171,2=270.000000
L 7.23125059 5.18646663 7.23291683 5.1878001 2 P 0 ;0,1=171,2=270.000000
L 7.23291683 5.1878001 7.2362502 5.18833337 2 P 0 ;0,1=171,2=270.000000
L 7.2362502 5.18833337 7.23958366 5.1878001 2 P 0 ;0,1=171,2=270.000000
L 7.23958366 5.1878001 7.24166654 5.1862 2 P 0 ;0,1=171,2=270.000000
L 7.24166654 5.1862 7.24291703 5.18433327 2 P 0 ;0,1=171,2=270.000000
L 7.24291703 5.18433327 7.24291703 5.17766654 2 P 0 ;0,1=171,2=270.000000
L 7.24291703 5.18433327 7.255 5.18833337 2 P 0 ;0,1=171,2=270.000000
L 7.255 5.2069997 7.23 5.2069997 2 P 0 ;0,1=171,2=270.000000
L 7.23 5.2069997 7.2349997 5.2037999 2 P 0 ;0,1=171,2=270.000000
L 7.255 5.2037999 7.255 5.21019951 2 P 0 ;0,1=171,2=270.000000
L 7.25125089 5.22513327 7.25333376 5.22673297 2 P 0 ;0,1=171,2=270.000000
L 7.25333376 5.22673297 7.25458346 5.2285997 2 P 0 ;0,1=171,2=270.000000
L 7.25458346 5.2285997 7.255 5.2309997 2 P 0 ;0,1=171,2=270.000000
L 7.255 5.2309997 7.25416693 5.2334002 2 P 0 ;0,1=171,2=270.000000
L 7.25416693 5.2334002 7.25250059 5.23526644 2 P 0 ;0,1=171,2=270.000000
L 7.25250059 5.23526644 7.24958376 5.2366 2 P 0 ;0,1=171,2=270.000000
L 7.24958376 5.2366 7.24625039 5.23686663 2 P 0 ;0,1=171,2=270.000000
L 7.24625039 5.23686663 7.24291703 5.23633337 2 P 0 ;0,1=171,2=270.000000
L 7.24291703 5.23633337 7.24083337 5.2349998 2 P 0 ;0,1=171,2=270.000000
L 7.24083337 5.2349998 7.23916703 5.23313307 2 P 0 ;0,1=171,2=270.000000
L 7.23916703 5.23313307 7.23875049 5.23126683 2 P 0 ;0,1=171,2=270.000000
L 7.23875049 5.23126683 7.23916703 5.2294 2 P 0 ;0,1=171,2=270.000000
L 7.23916703 5.2294 7.24083337 5.2270001 2 P 0 ;0,1=171,2=270.000000
L 7.24083337 5.2270001 7.23 5.2277999 2 P 0 ;0,1=171,2=270.000000
L 7.23 5.2277999 7.23 5.2349998 2 P 0 ;0,1=171,2=270.000000
L 7.255 5.2549997 7.23 5.2549997 2 P 0 ;0,1=171,2=270.000000
L 7.23 5.2549997 7.2349997 5.2517999 2 P 0 ;0,1=171,2=270.000000
L 7.255 5.2517999 7.255 5.25819951 2 P 0 ;0,1=171,2=270.000000
L 7.23 5.2789997 7.23083317 5.27686634 2 P 0 ;0,1=171,2=270.000000
L 7.23083317 5.27686634 7.23291683 5.27526663 2 P 0 ;0,1=171,2=270.000000
L 7.23291683 5.27526663 7.23541634 5.2741998 2 P 0 ;0,1=171,2=270.000000
L 7.23541634 5.2741998 7.23875049 5.2733999 2 P 0 ;0,1=171,2=270.000000
L 7.23875049 5.2733999 7.24250039 5.27313327 2 P 0 ;0,1=171,2=270.000000
L 7.24250039 5.27313327 7.24625039 5.2733999 2 P 0 ;0,1=171,2=270.000000
L 7.24625039 5.2733999 7.24958376 5.2741998 2 P 0 ;0,1=171,2=270.000000
L 7.24958376 5.2741998 7.25208396 5.27526663 2 P 0 ;0,1=171,2=270.000000
L 7.25208396 5.27526663 7.25416693 5.27686634 2 P 0 ;0,1=171,2=270.000000
L 7.25416693 5.27686634 7.255 5.2789997 2 P 0 ;0,1=171,2=270.000000
L 7.255 5.2789997 7.25416693 5.28113307 2 P 0 ;0,1=171,2=270.000000
L 7.25416693 5.28113307 7.25208396 5.28273327 2 P 0 ;0,1=171,2=270.000000
L 7.25208396 5.28273327 7.24958376 5.2838001 2 P 0 ;0,1=171,2=270.000000
L 7.24958376 5.2838001 7.24625039 5.2846 2 P 0 ;0,1=171,2=270.000000
L 7.24625039 5.2846 7.24250039 5.28486663 2 P 0 ;0,1=171,2=270.000000
L 7.24250039 5.28486663 7.23875049 5.2846 2 P 0 ;0,1=171,2=270.000000
L 7.23875049 5.2846 7.23541634 5.2838001 2 P 0 ;0,1=171,2=270.000000
L 7.23541634 5.2838001 7.23291683 5.28273327 2 P 0 ;0,1=171,2=270.000000
L 7.23291683 5.28273327 7.23083317 5.28113307 2 P 0 ;0,1=171,2=270.000000
L 7.23083317 5.28113307 7.23 5.2789997 2 P 0 ;0,1=171,2=270.000000
L 7.30046998 5.10851004 7.28473002 5.10851004 3 P 0 
L 7.305 5.17766654 7.28 5.17766654 2 P 0 ;0,1=172,2=270.000000
L 7.28 5.17766654 7.28 5.18433327 2 P 0 ;0,1=172,2=270.000000
L 7.28 5.18433327 7.28125059 5.18646663 2 P 0 ;0,1=172,2=270.000000
L 7.28125059 5.18646663 7.28291683 5.1878001 2 P 0 ;0,1=172,2=270.000000
L 7.28291683 5.1878001 7.2862502 5.18833337 2 P 0 ;0,1=172,2=270.000000
L 7.2862502 5.18833337 7.28958366 5.1878001 2 P 0 ;0,1=172,2=270.000000
L 7.28958366 5.1878001 7.29166654 5.1862 2 P 0 ;0,1=172,2=270.000000
L 7.29166654 5.1862 7.29291703 5.18433327 2 P 0 ;0,1=172,2=270.000000
L 7.29291703 5.18433327 7.29291703 5.17766654 2 P 0 ;0,1=172,2=270.000000
L 7.29291703 5.18433327 7.305 5.18833337 2 P 0 ;0,1=172,2=270.000000
L 7.305 5.2069997 7.28 5.2069997 2 P 0 ;0,1=172,2=270.000000
L 7.28 5.2069997 7.2849997 5.2037999 2 P 0 ;0,1=172,2=270.000000
L 7.305 5.2037999 7.305 5.21019951 2 P 0 ;0,1=172,2=270.000000
L 7.30125089 5.22513327 7.30333376 5.22673297 2 P 0 ;0,1=172,2=270.000000
L 7.30333376 5.22673297 7.30458346 5.2285997 2 P 0 ;0,1=172,2=270.000000
L 7.30458346 5.2285997 7.305 5.2309997 2 P 0 ;0,1=172,2=270.000000
L 7.305 5.2309997 7.30416693 5.2334002 2 P 0 ;0,1=172,2=270.000000
L 7.30416693 5.2334002 7.30250059 5.23526644 2 P 0 ;0,1=172,2=270.000000
L 7.30250059 5.23526644 7.29958376 5.2366 2 P 0 ;0,1=172,2=270.000000
L 7.29958376 5.2366 7.29625039 5.23686663 2 P 0 ;0,1=172,2=270.000000
L 7.29625039 5.23686663 7.29291703 5.23633337 2 P 0 ;0,1=172,2=270.000000
L 7.29291703 5.23633337 7.29083337 5.2349998 2 P 0 ;0,1=172,2=270.000000
L 7.29083337 5.2349998 7.28916703 5.23313307 2 P 0 ;0,1=172,2=270.000000
L 7.28916703 5.23313307 7.28875049 5.23126683 2 P 0 ;0,1=172,2=270.000000
L 7.28875049 5.23126683 7.28916703 5.2294 2 P 0 ;0,1=172,2=270.000000
L 7.28916703 5.2294 7.29083337 5.2270001 2 P 0 ;0,1=172,2=270.000000
L 7.29083337 5.2270001 7.28 5.2277999 2 P 0 ;0,1=172,2=270.000000
L 7.28 5.2277999 7.28 5.2349998 2 P 0 ;0,1=172,2=270.000000
L 7.28 5.2549997 7.28083317 5.25286634 2 P 0 ;0,1=172,2=270.000000
L 7.28083317 5.25286634 7.28291683 5.25126663 2 P 0 ;0,1=172,2=270.000000
L 7.28291683 5.25126663 7.28541634 5.2501998 2 P 0 ;0,1=172,2=270.000000
L 7.28541634 5.2501998 7.28875049 5.2493999 2 P 0 ;0,1=172,2=270.000000
L 7.28875049 5.2493999 7.29250039 5.24913327 2 P 0 ;0,1=172,2=270.000000
L 7.29250039 5.24913327 7.29625039 5.2493999 2 P 0 ;0,1=172,2=270.000000
L 7.29625039 5.2493999 7.29958376 5.2501998 2 P 0 ;0,1=172,2=270.000000
L 7.29958376 5.2501998 7.30208396 5.25126663 2 P 0 ;0,1=172,2=270.000000
L 7.30208396 5.25126663 7.30416693 5.25286634 2 P 0 ;0,1=172,2=270.000000
L 7.30416693 5.25286634 7.305 5.2549997 2 P 0 ;0,1=172,2=270.000000
L 7.305 5.2549997 7.30416693 5.25713307 2 P 0 ;0,1=172,2=270.000000
L 7.30416693 5.25713307 7.30208396 5.25873327 2 P 0 ;0,1=172,2=270.000000
L 7.30208396 5.25873327 7.29958376 5.2598001 2 P 0 ;0,1=172,2=270.000000
L 7.29958376 5.2598001 7.29625039 5.2606 2 P 0 ;0,1=172,2=270.000000
L 7.29625039 5.2606 7.29250039 5.26086663 2 P 0 ;0,1=172,2=270.000000
L 7.29250039 5.26086663 7.28875049 5.2606 2 P 0 ;0,1=172,2=270.000000
L 7.28875049 5.2606 7.28541634 5.2598001 2 P 0 ;0,1=172,2=270.000000
L 7.28541634 5.2598001 7.28291683 5.25873327 2 P 0 ;0,1=172,2=270.000000
L 7.28291683 5.25873327 7.28083317 5.25713307 2 P 0 ;0,1=172,2=270.000000
L 7.28083317 5.25713307 7.28 5.2549997 2 P 0 ;0,1=172,2=270.000000
L 7.30208396 5.27446634 7.30416693 5.27633317 2 P 0 ;0,1=172,2=270.000000
L 7.30416693 5.27633317 7.305 5.27846654 2 P 0 ;0,1=172,2=270.000000
L 7.305 5.27846654 7.30416693 5.2805999 2 P 0 ;0,1=172,2=270.000000
L 7.30416693 5.2805999 7.30166742 5.28246663 2 P 0 ;0,1=172,2=270.000000
L 7.30166742 5.28246663 7.29791673 5.2838001 2 P 0 ;0,1=172,2=270.000000
L 7.29791673 5.2838001 7.29416673 5.28433337 2 P 0 ;0,1=172,2=270.000000
L 7.29416673 5.28433337 7.28958366 5.28433337 2 P 0 ;0,1=172,2=270.000000
L 7.28958366 5.28433337 7.28583366 5.2838001 2 P 0 ;0,1=172,2=270.000000
L 7.28583366 5.2838001 7.2825003 5.28246663 2 P 0 ;0,1=172,2=270.000000
L 7.2825003 5.28246663 7.28083317 5.28086644 2 P 0 ;0,1=172,2=270.000000
L 7.28083317 5.28086644 7.28 5.2789997 2 P 0 ;0,1=172,2=270.000000
L 7.28 5.2789997 7.28083317 5.27686634 2 P 0 ;0,1=172,2=270.000000
L 7.28083317 5.27686634 7.2825003 5.27526663 2 P 0 ;0,1=172,2=270.000000
L 7.2825003 5.27526663 7.2849997 5.2741998 2 P 0 ;0,1=172,2=270.000000
L 7.2849997 5.2741998 7.28833386 5.27366654 2 P 0 ;0,1=172,2=270.000000
L 7.28833386 5.27366654 7.2912499 5.2741998 2 P 0 ;0,1=172,2=270.000000
L 7.2912499 5.2741998 7.29416673 5.27553327 2 P 0 ;0,1=172,2=270.000000
L 7.29416673 5.27553327 7.29583386 5.27713346 2 P 0 ;0,1=172,2=270.000000
L 7.29583386 5.27713346 7.29625039 5.2789997 2 P 0 ;0,1=172,2=270.000000
L 7.29625039 5.2789997 7.29541722 5.28113307 2 P 0 ;0,1=172,2=270.000000
L 7.29541722 5.28113307 7.29333356 5.28273327 2 P 0 ;0,1=172,2=270.000000
L 7.29333356 5.28273327 7.28958366 5.28433337 2 P 0 ;0,1=172,2=270.000000
L 7.40046998 5.10851004 7.38473002 5.10851004 3 P 0 
L 7.405 5.17766654 7.38 5.17766654 2 P 0 ;0,1=173,2=270.000000
L 7.38 5.17766654 7.38 5.18433327 2 P 0 ;0,1=173,2=270.000000
L 7.38 5.18433327 7.38125059 5.18646663 2 P 0 ;0,1=173,2=270.000000
L 7.38125059 5.18646663 7.38291683 5.1878001 2 P 0 ;0,1=173,2=270.000000
L 7.38291683 5.1878001 7.3862502 5.18833337 2 P 0 ;0,1=173,2=270.000000
L 7.3862502 5.18833337 7.38958366 5.1878001 2 P 0 ;0,1=173,2=270.000000
L 7.38958366 5.1878001 7.39166654 5.1862 2 P 0 ;0,1=173,2=270.000000
L 7.39166654 5.1862 7.39291703 5.18433327 2 P 0 ;0,1=173,2=270.000000
L 7.39291703 5.18433327 7.39291703 5.17766654 2 P 0 ;0,1=173,2=270.000000
L 7.39291703 5.18433327 7.405 5.18833337 2 P 0 ;0,1=173,2=270.000000
L 7.405 5.2069997 7.38 5.2069997 2 P 0 ;0,1=173,2=270.000000
L 7.38 5.2069997 7.3849997 5.2037999 2 P 0 ;0,1=173,2=270.000000
L 7.405 5.2037999 7.405 5.21019951 2 P 0 ;0,1=173,2=270.000000
L 7.40125089 5.22513327 7.40333376 5.22673297 2 P 0 ;0,1=173,2=270.000000
L 7.40333376 5.22673297 7.40458346 5.2285997 2 P 0 ;0,1=173,2=270.000000
L 7.40458346 5.2285997 7.405 5.2309997 2 P 0 ;0,1=173,2=270.000000
L 7.405 5.2309997 7.40416693 5.2334002 2 P 0 ;0,1=173,2=270.000000
L 7.40416693 5.2334002 7.40250059 5.23526644 2 P 0 ;0,1=173,2=270.000000
L 7.40250059 5.23526644 7.39958376 5.2366 2 P 0 ;0,1=173,2=270.000000
L 7.39958376 5.2366 7.39625039 5.23686663 2 P 0 ;0,1=173,2=270.000000
L 7.39625039 5.23686663 7.39291703 5.23633337 2 P 0 ;0,1=173,2=270.000000
L 7.39291703 5.23633337 7.39083337 5.2349998 2 P 0 ;0,1=173,2=270.000000
L 7.39083337 5.2349998 7.38916703 5.23313307 2 P 0 ;0,1=173,2=270.000000
L 7.38916703 5.23313307 7.38875049 5.23126683 2 P 0 ;0,1=173,2=270.000000
L 7.38875049 5.23126683 7.38916703 5.2294 2 P 0 ;0,1=173,2=270.000000
L 7.38916703 5.2294 7.39083337 5.2270001 2 P 0 ;0,1=173,2=270.000000
L 7.39083337 5.2270001 7.38 5.2277999 2 P 0 ;0,1=173,2=270.000000
L 7.38 5.2277999 7.38 5.2349998 2 P 0 ;0,1=173,2=270.000000
L 7.38 5.2549997 7.38083317 5.25286634 2 P 0 ;0,1=173,2=270.000000
L 7.38083317 5.25286634 7.38291683 5.25126663 2 P 0 ;0,1=173,2=270.000000
L 7.38291683 5.25126663 7.38541634 5.2501998 2 P 0 ;0,1=173,2=270.000000
L 7.38541634 5.2501998 7.38875049 5.2493999 2 P 0 ;0,1=173,2=270.000000
L 7.38875049 5.2493999 7.39250039 5.24913327 2 P 0 ;0,1=173,2=270.000000
L 7.39250039 5.24913327 7.39625039 5.2493999 2 P 0 ;0,1=173,2=270.000000
L 7.39625039 5.2493999 7.39958376 5.2501998 2 P 0 ;0,1=173,2=270.000000
L 7.39958376 5.2501998 7.40208396 5.25126663 2 P 0 ;0,1=173,2=270.000000
L 7.40208396 5.25126663 7.40416693 5.25286634 2 P 0 ;0,1=173,2=270.000000
L 7.40416693 5.25286634 7.405 5.2549997 2 P 0 ;0,1=173,2=270.000000
L 7.405 5.2549997 7.40416693 5.25713307 2 P 0 ;0,1=173,2=270.000000
L 7.40416693 5.25713307 7.40208396 5.25873327 2 P 0 ;0,1=173,2=270.000000
L 7.40208396 5.25873327 7.39958376 5.2598001 2 P 0 ;0,1=173,2=270.000000
L 7.39958376 5.2598001 7.39625039 5.2606 2 P 0 ;0,1=173,2=270.000000
L 7.39625039 5.2606 7.39250039 5.26086663 2 P 0 ;0,1=173,2=270.000000
L 7.39250039 5.26086663 7.38875049 5.2606 2 P 0 ;0,1=173,2=270.000000
L 7.38875049 5.2606 7.38541634 5.2598001 2 P 0 ;0,1=173,2=270.000000
L 7.38541634 5.2598001 7.38291683 5.25873327 2 P 0 ;0,1=173,2=270.000000
L 7.38291683 5.25873327 7.38083317 5.25713307 2 P 0 ;0,1=173,2=270.000000
L 7.38083317 5.25713307 7.38 5.2549997 2 P 0 ;0,1=173,2=270.000000
L 7.405 5.2789997 7.40458346 5.28086644 2 P 0 ;0,1=173,2=270.000000
L 7.40458346 5.28086644 7.40333376 5.2829998 2 P 0 ;0,1=173,2=270.000000
L 7.40333376 5.2829998 7.40125089 5.28433337 2 P 0 ;0,1=173,2=270.000000
L 7.40125089 5.28433337 7.39833327 5.28486663 2 P 0 ;0,1=173,2=270.000000
L 7.39833327 5.28486663 7.39541722 5.28433337 2 P 0 ;0,1=173,2=270.000000
L 7.39541722 5.28433337 7.39291703 5.28273327 2 P 0 ;0,1=173,2=270.000000
L 7.39291703 5.28273327 7.39166654 5.28033327 2 P 0 ;0,1=173,2=270.000000
L 7.39166654 5.28033327 7.39166654 5.27766663 2 P 0 ;0,1=173,2=270.000000
L 7.39166654 5.27766663 7.39083337 5.27606654 2 P 0 ;0,1=173,2=270.000000
L 7.39083337 5.27606654 7.38875049 5.27473297 2 P 0 ;0,1=173,2=270.000000
L 7.38875049 5.27473297 7.38583366 5.2741998 2 P 0 ;0,1=173,2=270.000000
L 7.38583366 5.2741998 7.38291683 5.2750001 2 P 0 ;0,1=173,2=270.000000
L 7.38291683 5.2750001 7.38083317 5.27686634 2 P 0 ;0,1=173,2=270.000000
L 7.38083317 5.27686634 7.38 5.2789997 2 P 0 ;0,1=173,2=270.000000
L 7.38 5.2789997 7.38083317 5.28113307 2 P 0 ;0,1=173,2=270.000000
L 7.38083317 5.28113307 7.38291683 5.2829998 2 P 0 ;0,1=173,2=270.000000
L 7.38291683 5.2829998 7.38583366 5.2838001 2 P 0 ;0,1=173,2=270.000000
L 7.38583366 5.2838001 7.38875049 5.28326644 2 P 0 ;0,1=173,2=270.000000
L 7.38875049 5.28326644 7.39083337 5.28193337 2 P 0 ;0,1=173,2=270.000000
L 7.39083337 5.28193337 7.39166654 5.28033327 2 P 0 ;0,1=173,2=270.000000
L 7.39166654 5.28033327 7.39166654 5.27766663 2 P 0 ;0,1=173,2=270.000000
L 7.39166654 5.27766663 7.39291703 5.27526663 2 P 0 ;0,1=173,2=270.000000
L 7.39291703 5.27526663 7.39541722 5.27366654 2 P 0 ;0,1=173,2=270.000000
L 7.39541722 5.27366654 7.39833327 5.27313327 2 P 0 ;0,1=173,2=270.000000
L 7.39833327 5.27313327 7.40125089 5.27366654 2 P 0 ;0,1=173,2=270.000000
L 7.40125089 5.27366654 7.40333376 5.2750001 2 P 0 ;0,1=173,2=270.000000
L 7.40333376 5.2750001 7.40458346 5.27713346 2 P 0 ;0,1=173,2=270.000000
L 7.40458346 5.27713346 7.405 5.2789997 2 P 0 ;0,1=173,2=270.000000
L 1.24693002 5.10851004 1.23118996 5.10851004 3 P 0 
L 1.25 5.17266654 1.225 5.17266654 2 P 0 ;0,1=174,2=270.000000
L 1.225 5.17266654 1.225 5.17933327 2 P 0 ;0,1=174,2=270.000000
L 1.225 5.17933327 1.22625059 5.18146663 2 P 0 ;0,1=174,2=270.000000
L 1.22625059 5.18146663 1.22791683 5.1828001 2 P 0 ;0,1=174,2=270.000000
L 1.22791683 5.1828001 1.2312502 5.18333337 2 P 0 ;0,1=174,2=270.000000
L 1.2312502 5.18333337 1.23458366 5.1828001 2 P 0 ;0,1=174,2=270.000000
L 1.23458366 5.1828001 1.23666654 5.1812 2 P 0 ;0,1=174,2=270.000000
L 1.23666654 5.1812 1.23791703 5.17933327 2 P 0 ;0,1=174,2=270.000000
L 1.23791703 5.17933327 1.23791703 5.17266654 2 P 0 ;0,1=174,2=270.000000
L 1.23791703 5.17933327 1.25 5.18333337 2 P 0 ;0,1=174,2=270.000000
L 1.25 5.2019997 1.225 5.2019997 2 P 0 ;0,1=174,2=270.000000
L 1.225 5.2019997 1.2299997 5.1987999 2 P 0 ;0,1=174,2=270.000000
L 1.25 5.1987999 1.25 5.20519951 2 P 0 ;0,1=174,2=270.000000
L 1.24625089 5.22013327 1.24833376 5.22173297 2 P 0 ;0,1=174,2=270.000000
L 1.24833376 5.22173297 1.24958346 5.2235997 2 P 0 ;0,1=174,2=270.000000
L 1.24958346 5.2235997 1.25 5.2259997 2 P 0 ;0,1=174,2=270.000000
L 1.25 5.2259997 1.24916693 5.2284002 2 P 0 ;0,1=174,2=270.000000
L 1.24916693 5.2284002 1.24750059 5.23026644 2 P 0 ;0,1=174,2=270.000000
L 1.24750059 5.23026644 1.24458376 5.2316 2 P 0 ;0,1=174,2=270.000000
L 1.24458376 5.2316 1.24125039 5.23186663 2 P 0 ;0,1=174,2=270.000000
L 1.24125039 5.23186663 1.23791703 5.23133337 2 P 0 ;0,1=174,2=270.000000
L 1.23791703 5.23133337 1.23583337 5.2299998 2 P 0 ;0,1=174,2=270.000000
L 1.23583337 5.2299998 1.23416703 5.22813307 2 P 0 ;0,1=174,2=270.000000
L 1.23416703 5.22813307 1.23375049 5.22626683 2 P 0 ;0,1=174,2=270.000000
L 1.23375049 5.22626683 1.23416703 5.2244 2 P 0 ;0,1=174,2=270.000000
L 1.23416703 5.2244 1.23583337 5.2220001 2 P 0 ;0,1=174,2=270.000000
L 1.23583337 5.2220001 1.225 5.2227999 2 P 0 ;0,1=174,2=270.000000
L 1.225 5.2227999 1.225 5.2299998 2 P 0 ;0,1=174,2=270.000000
L 1.225 5.2499997 1.22583317 5.24786634 2 P 0 ;0,1=174,2=270.000000
L 1.22583317 5.24786634 1.22791683 5.24626663 2 P 0 ;0,1=174,2=270.000000
L 1.22791683 5.24626663 1.23041634 5.2451998 2 P 0 ;0,1=174,2=270.000000
L 1.23041634 5.2451998 1.23375049 5.2443999 2 P 0 ;0,1=174,2=270.000000
L 1.23375049 5.2443999 1.23750039 5.24413327 2 P 0 ;0,1=174,2=270.000000
L 1.23750039 5.24413327 1.24125039 5.2443999 2 P 0 ;0,1=174,2=270.000000
L 1.24125039 5.2443999 1.24458376 5.2451998 2 P 0 ;0,1=174,2=270.000000
L 1.24458376 5.2451998 1.24708396 5.24626663 2 P 0 ;0,1=174,2=270.000000
L 1.24708396 5.24626663 1.24916693 5.24786634 2 P 0 ;0,1=174,2=270.000000
L 1.24916693 5.24786634 1.25 5.2499997 2 P 0 ;0,1=174,2=270.000000
L 1.25 5.2499997 1.24916693 5.25213307 2 P 0 ;0,1=174,2=270.000000
L 1.24916693 5.25213307 1.24708396 5.25373327 2 P 0 ;0,1=174,2=270.000000
L 1.24708396 5.25373327 1.24458376 5.2548001 2 P 0 ;0,1=174,2=270.000000
L 1.24458376 5.2548001 1.24125039 5.2556 2 P 0 ;0,1=174,2=270.000000
L 1.24125039 5.2556 1.23750039 5.25586663 2 P 0 ;0,1=174,2=270.000000
L 1.23750039 5.25586663 1.23375049 5.2556 2 P 0 ;0,1=174,2=270.000000
L 1.23375049 5.2556 1.23041634 5.2548001 2 P 0 ;0,1=174,2=270.000000
L 1.23041634 5.2548001 1.22791683 5.25373327 2 P 0 ;0,1=174,2=270.000000
L 1.22791683 5.25373327 1.22583317 5.25213307 2 P 0 ;0,1=174,2=270.000000
L 1.22583317 5.25213307 1.225 5.2499997 2 P 0 ;0,1=174,2=270.000000
L 1.225 5.2739997 1.22583317 5.27186634 2 P 0 ;0,1=174,2=270.000000
L 1.22583317 5.27186634 1.22791683 5.27026663 2 P 0 ;0,1=174,2=270.000000
L 1.22791683 5.27026663 1.23041634 5.2691998 2 P 0 ;0,1=174,2=270.000000
L 1.23041634 5.2691998 1.23375049 5.2683999 2 P 0 ;0,1=174,2=270.000000
L 1.23375049 5.2683999 1.23750039 5.26813327 2 P 0 ;0,1=174,2=270.000000
L 1.23750039 5.26813327 1.24125039 5.2683999 2 P 0 ;0,1=174,2=270.000000
L 1.24125039 5.2683999 1.24458376 5.2691998 2 P 0 ;0,1=174,2=270.000000
L 1.24458376 5.2691998 1.24708396 5.27026663 2 P 0 ;0,1=174,2=270.000000
L 1.24708396 5.27026663 1.24916693 5.27186634 2 P 0 ;0,1=174,2=270.000000
L 1.24916693 5.27186634 1.25 5.2739997 2 P 0 ;0,1=174,2=270.000000
L 1.25 5.2739997 1.24916693 5.27613307 2 P 0 ;0,1=174,2=270.000000
L 1.24916693 5.27613307 1.24708396 5.27773327 2 P 0 ;0,1=174,2=270.000000
L 1.24708396 5.27773327 1.24458376 5.2788001 2 P 0 ;0,1=174,2=270.000000
L 1.24458376 5.2788001 1.24125039 5.2796 2 P 0 ;0,1=174,2=270.000000
L 1.24125039 5.2796 1.23750039 5.27986663 2 P 0 ;0,1=174,2=270.000000
L 1.23750039 5.27986663 1.23375049 5.2796 2 P 0 ;0,1=174,2=270.000000
L 1.23375049 5.2796 1.23041634 5.2788001 2 P 0 ;0,1=174,2=270.000000
L 1.23041634 5.2788001 1.22791683 5.27773327 2 P 0 ;0,1=174,2=270.000000
L 1.22791683 5.27773327 1.22583317 5.27613307 2 P 0 ;0,1=174,2=270.000000
L 1.22583317 5.27613307 1.225 5.2739997 2 P 0 ;0,1=174,2=270.000000
L 1.29693002 5.10851004 1.28118996 5.10851004 3 P 0 
L 1.3 5.17266654 1.275 5.17266654 2 P 0 ;0,1=175,2=270.000000
L 1.275 5.17266654 1.275 5.17933327 2 P 0 ;0,1=175,2=270.000000
L 1.275 5.17933327 1.27625059 5.18146663 2 P 0 ;0,1=175,2=270.000000
L 1.27625059 5.18146663 1.27791683 5.1828001 2 P 0 ;0,1=175,2=270.000000
L 1.27791683 5.1828001 1.2812502 5.18333337 2 P 0 ;0,1=175,2=270.000000
L 1.2812502 5.18333337 1.28458366 5.1828001 2 P 0 ;0,1=175,2=270.000000
L 1.28458366 5.1828001 1.28666654 5.1812 2 P 0 ;0,1=175,2=270.000000
L 1.28666654 5.1812 1.28791703 5.17933327 2 P 0 ;0,1=175,2=270.000000
L 1.28791703 5.17933327 1.28791703 5.17266654 2 P 0 ;0,1=175,2=270.000000
L 1.28791703 5.17933327 1.3 5.18333337 2 P 0 ;0,1=175,2=270.000000
L 1.3 5.2019997 1.275 5.2019997 2 P 0 ;0,1=175,2=270.000000
L 1.275 5.2019997 1.2799997 5.1987999 2 P 0 ;0,1=175,2=270.000000
L 1.3 5.1987999 1.3 5.20519951 2 P 0 ;0,1=175,2=270.000000
L 1.3 5.2292 1.275 5.2292 2 P 0 ;0,1=175,2=270.000000
L 1.275 5.2292 1.29291673 5.21933297 2 P 0 ;0,1=175,2=270.000000
L 1.29291673 5.21933297 1.29291673 5.23266693 2 P 0 ;0,1=175,2=270.000000
L 1.29708396 5.24546634 1.29916693 5.24733317 2 P 0 ;0,1=175,2=270.000000
L 1.29916693 5.24733317 1.3 5.24946654 2 P 0 ;0,1=175,2=270.000000
L 1.3 5.24946654 1.29916693 5.2515999 2 P 0 ;0,1=175,2=270.000000
L 1.29916693 5.2515999 1.29666742 5.25346663 2 P 0 ;0,1=175,2=270.000000
L 1.29666742 5.25346663 1.29291673 5.2548001 2 P 0 ;0,1=175,2=270.000000
L 1.29291673 5.2548001 1.28916673 5.25533337 2 P 0 ;0,1=175,2=270.000000
L 1.28916673 5.25533337 1.28458366 5.25533337 2 P 0 ;0,1=175,2=270.000000
L 1.28458366 5.25533337 1.28083366 5.2548001 2 P 0 ;0,1=175,2=270.000000
L 1.28083366 5.2548001 1.2775003 5.25346663 2 P 0 ;0,1=175,2=270.000000
L 1.2775003 5.25346663 1.27583317 5.25186644 2 P 0 ;0,1=175,2=270.000000
L 1.27583317 5.25186644 1.275 5.2499997 2 P 0 ;0,1=175,2=270.000000
L 1.275 5.2499997 1.27583317 5.24786634 2 P 0 ;0,1=175,2=270.000000
L 1.27583317 5.24786634 1.2775003 5.24626663 2 P 0 ;0,1=175,2=270.000000
L 1.2775003 5.24626663 1.2799997 5.2451998 2 P 0 ;0,1=175,2=270.000000
L 1.2799997 5.2451998 1.28333386 5.24466654 2 P 0 ;0,1=175,2=270.000000
L 1.28333386 5.24466654 1.2862499 5.2451998 2 P 0 ;0,1=175,2=270.000000
L 1.2862499 5.2451998 1.28916673 5.24653327 2 P 0 ;0,1=175,2=270.000000
L 1.28916673 5.24653327 1.29083386 5.24813346 2 P 0 ;0,1=175,2=270.000000
L 1.29083386 5.24813346 1.29125039 5.2499997 2 P 0 ;0,1=175,2=270.000000
L 1.29125039 5.2499997 1.29041722 5.25213307 2 P 0 ;0,1=175,2=270.000000
L 1.29041722 5.25213307 1.28833356 5.25373327 2 P 0 ;0,1=175,2=270.000000
L 1.28833356 5.25373327 1.28458366 5.25533337 2 P 0 ;0,1=175,2=270.000000
L 1.29708396 5.26946634 1.29916693 5.27133317 2 P 0 ;0,1=175,2=270.000000
L 1.29916693 5.27133317 1.3 5.27346654 2 P 0 ;0,1=175,2=270.000000
L 1.3 5.27346654 1.29916693 5.2755999 2 P 0 ;0,1=175,2=270.000000
L 1.29916693 5.2755999 1.29666742 5.27746663 2 P 0 ;0,1=175,2=270.000000
L 1.29666742 5.27746663 1.29291673 5.2788001 2 P 0 ;0,1=175,2=270.000000
L 1.29291673 5.2788001 1.28916673 5.27933337 2 P 0 ;0,1=175,2=270.000000
L 1.28916673 5.27933337 1.28458366 5.27933337 2 P 0 ;0,1=175,2=270.000000
L 1.28458366 5.27933337 1.28083366 5.2788001 2 P 0 ;0,1=175,2=270.000000
L 1.28083366 5.2788001 1.2775003 5.27746663 2 P 0 ;0,1=175,2=270.000000
L 1.2775003 5.27746663 1.27583317 5.27586644 2 P 0 ;0,1=175,2=270.000000
L 1.27583317 5.27586644 1.275 5.2739997 2 P 0 ;0,1=175,2=270.000000
L 1.275 5.2739997 1.27583317 5.27186634 2 P 0 ;0,1=175,2=270.000000
L 1.27583317 5.27186634 1.2775003 5.27026663 2 P 0 ;0,1=175,2=270.000000
L 1.2775003 5.27026663 1.2799997 5.2691998 2 P 0 ;0,1=175,2=270.000000
L 1.2799997 5.2691998 1.28333386 5.26866654 2 P 0 ;0,1=175,2=270.000000
L 1.28333386 5.26866654 1.2862499 5.2691998 2 P 0 ;0,1=175,2=270.000000
L 1.2862499 5.2691998 1.28916673 5.27053327 2 P 0 ;0,1=175,2=270.000000
L 1.28916673 5.27053327 1.29083386 5.27213346 2 P 0 ;0,1=175,2=270.000000
L 1.29083386 5.27213346 1.29125039 5.2739997 2 P 0 ;0,1=175,2=270.000000
L 1.29125039 5.2739997 1.29041722 5.27613307 2 P 0 ;0,1=175,2=270.000000
L 1.29041722 5.27613307 1.28833356 5.27773327 2 P 0 ;0,1=175,2=270.000000
L 1.28833356 5.27773327 1.28458366 5.27933337 2 P 0 ;0,1=175,2=270.000000
L 1.39693002 5.10851004 1.38118996 5.10851004 3 P 0 
L 1.405 5.17266654 1.38 5.17266654 2 P 0 ;0,1=176,2=270.000000
L 1.38 5.17266654 1.38 5.17933327 2 P 0 ;0,1=176,2=270.000000
L 1.38 5.17933327 1.38125059 5.18146663 2 P 0 ;0,1=176,2=270.000000
L 1.38125059 5.18146663 1.38291683 5.1828001 2 P 0 ;0,1=176,2=270.000000
L 1.38291683 5.1828001 1.3862502 5.18333337 2 P 0 ;0,1=176,2=270.000000
L 1.3862502 5.18333337 1.38958366 5.1828001 2 P 0 ;0,1=176,2=270.000000
L 1.38958366 5.1828001 1.39166654 5.1812 2 P 0 ;0,1=176,2=270.000000
L 1.39166654 5.1812 1.39291703 5.17933327 2 P 0 ;0,1=176,2=270.000000
L 1.39291703 5.17933327 1.39291703 5.17266654 2 P 0 ;0,1=176,2=270.000000
L 1.39291703 5.17933327 1.405 5.18333337 2 P 0 ;0,1=176,2=270.000000
L 1.405 5.2019997 1.38 5.2019997 2 P 0 ;0,1=176,2=270.000000
L 1.38 5.2019997 1.3849997 5.1987999 2 P 0 ;0,1=176,2=270.000000
L 1.405 5.1987999 1.405 5.20519951 2 P 0 ;0,1=176,2=270.000000
L 1.405 5.2292 1.38 5.2292 2 P 0 ;0,1=176,2=270.000000
L 1.38 5.2292 1.39791673 5.21933297 2 P 0 ;0,1=176,2=270.000000
L 1.39791673 5.21933297 1.39791673 5.23266693 2 P 0 ;0,1=176,2=270.000000
L 1.40208396 5.24546634 1.40416693 5.24733317 2 P 0 ;0,1=176,2=270.000000
L 1.40416693 5.24733317 1.405 5.24946654 2 P 0 ;0,1=176,2=270.000000
L 1.405 5.24946654 1.40416693 5.2515999 2 P 0 ;0,1=176,2=270.000000
L 1.40416693 5.2515999 1.40166742 5.25346663 2 P 0 ;0,1=176,2=270.000000
L 1.40166742 5.25346663 1.39791673 5.2548001 2 P 0 ;0,1=176,2=270.000000
L 1.39791673 5.2548001 1.39416673 5.25533337 2 P 0 ;0,1=176,2=270.000000
L 1.39416673 5.25533337 1.38958366 5.25533337 2 P 0 ;0,1=176,2=270.000000
L 1.38958366 5.25533337 1.38583366 5.2548001 2 P 0 ;0,1=176,2=270.000000
L 1.38583366 5.2548001 1.3825003 5.25346663 2 P 0 ;0,1=176,2=270.000000
L 1.3825003 5.25346663 1.38083317 5.25186644 2 P 0 ;0,1=176,2=270.000000
L 1.38083317 5.25186644 1.38 5.2499997 2 P 0 ;0,1=176,2=270.000000
L 1.38 5.2499997 1.38083317 5.24786634 2 P 0 ;0,1=176,2=270.000000
L 1.38083317 5.24786634 1.3825003 5.24626663 2 P 0 ;0,1=176,2=270.000000
L 1.3825003 5.24626663 1.3849997 5.2451998 2 P 0 ;0,1=176,2=270.000000
L 1.3849997 5.2451998 1.38833386 5.24466654 2 P 0 ;0,1=176,2=270.000000
L 1.38833386 5.24466654 1.3912499 5.2451998 2 P 0 ;0,1=176,2=270.000000
L 1.3912499 5.2451998 1.39416673 5.24653327 2 P 0 ;0,1=176,2=270.000000
L 1.39416673 5.24653327 1.39583386 5.24813346 2 P 0 ;0,1=176,2=270.000000
L 1.39583386 5.24813346 1.39625039 5.2499997 2 P 0 ;0,1=176,2=270.000000
L 1.39625039 5.2499997 1.39541722 5.25213307 2 P 0 ;0,1=176,2=270.000000
L 1.39541722 5.25213307 1.39333356 5.25373327 2 P 0 ;0,1=176,2=270.000000
L 1.39333356 5.25373327 1.38958366 5.25533337 2 P 0 ;0,1=176,2=270.000000
L 1.405 5.2739997 1.40458346 5.27586644 2 P 0 ;0,1=176,2=270.000000
L 1.40458346 5.27586644 1.40333376 5.2779998 2 P 0 ;0,1=176,2=270.000000
L 1.40333376 5.2779998 1.40125089 5.27933337 2 P 0 ;0,1=176,2=270.000000
L 1.40125089 5.27933337 1.39833327 5.27986663 2 P 0 ;0,1=176,2=270.000000
L 1.39833327 5.27986663 1.39541722 5.27933337 2 P 0 ;0,1=176,2=270.000000
L 1.39541722 5.27933337 1.39291703 5.27773327 2 P 0 ;0,1=176,2=270.000000
L 1.39291703 5.27773327 1.39166654 5.27533327 2 P 0 ;0,1=176,2=270.000000
L 1.39166654 5.27533327 1.39166654 5.27266663 2 P 0 ;0,1=176,2=270.000000
L 1.39166654 5.27266663 1.39083337 5.27106654 2 P 0 ;0,1=176,2=270.000000
L 1.39083337 5.27106654 1.38875049 5.26973297 2 P 0 ;0,1=176,2=270.000000
L 1.38875049 5.26973297 1.38583366 5.2691998 2 P 0 ;0,1=176,2=270.000000
L 1.38583366 5.2691998 1.38291683 5.2700001 2 P 0 ;0,1=176,2=270.000000
L 1.38291683 5.2700001 1.38083317 5.27186634 2 P 0 ;0,1=176,2=270.000000
L 1.38083317 5.27186634 1.38 5.2739997 2 P 0 ;0,1=176,2=270.000000
L 1.38 5.2739997 1.38083317 5.27613307 2 P 0 ;0,1=176,2=270.000000
L 1.38083317 5.27613307 1.38291683 5.2779998 2 P 0 ;0,1=176,2=270.000000
L 1.38291683 5.2779998 1.38583366 5.2788001 2 P 0 ;0,1=176,2=270.000000
L 1.38583366 5.2788001 1.38875049 5.27826644 2 P 0 ;0,1=176,2=270.000000
L 1.38875049 5.27826644 1.39083337 5.27693337 2 P 0 ;0,1=176,2=270.000000
L 1.39083337 5.27693337 1.39166654 5.27533327 2 P 0 ;0,1=176,2=270.000000
L 1.39166654 5.27533327 1.39166654 5.27266663 2 P 0 ;0,1=176,2=270.000000
L 1.39166654 5.27266663 1.39291703 5.27026663 2 P 0 ;0,1=176,2=270.000000
L 1.39291703 5.27026663 1.39541722 5.26866654 2 P 0 ;0,1=176,2=270.000000
L 1.39541722 5.26866654 1.39833327 5.26813327 2 P 0 ;0,1=176,2=270.000000
L 1.39833327 5.26813327 1.40125089 5.26866654 2 P 0 ;0,1=176,2=270.000000
L 1.40125089 5.26866654 1.40333376 5.2700001 2 P 0 ;0,1=176,2=270.000000
L 1.40333376 5.2700001 1.40458346 5.27213346 2 P 0 ;0,1=176,2=270.000000
L 1.40458346 5.27213346 1.405 5.2739997 2 P 0 ;0,1=176,2=270.000000
L 4.04776998 4.81198996 4.03203002 4.81198996 3 P 0 
L 4.06 4.38266654 4.035 4.38266654 2 P 0 ;0,1=177,2=270.000000
L 4.035 4.38266654 4.035 4.38933327 2 P 0 ;0,1=177,2=270.000000
L 4.035 4.38933327 4.03625059 4.39146663 2 P 0 ;0,1=177,2=270.000000
L 4.03625059 4.39146663 4.03791683 4.3928001 2 P 0 ;0,1=177,2=270.000000
L 4.03791683 4.3928001 4.0412502 4.39333337 2 P 0 ;0,1=177,2=270.000000
L 4.0412502 4.39333337 4.04458366 4.3928001 2 P 0 ;0,1=177,2=270.000000
L 4.04458366 4.3928001 4.04666654 4.3912 2 P 0 ;0,1=177,2=270.000000
L 4.04666654 4.3912 4.04791703 4.38933327 2 P 0 ;0,1=177,2=270.000000
L 4.04791703 4.38933327 4.04791703 4.38266654 2 P 0 ;0,1=177,2=270.000000
L 4.04791703 4.38933327 4.06 4.39333337 2 P 0 ;0,1=177,2=270.000000
L 4.06 4.4119997 4.035 4.4119997 2 P 0 ;0,1=177,2=270.000000
L 4.035 4.4119997 4.0399997 4.4087999 2 P 0 ;0,1=177,2=270.000000
L 4.06 4.4087999 4.06 4.41519951 2 P 0 ;0,1=177,2=270.000000
L 4.06 4.4392 4.035 4.4392 2 P 0 ;0,1=177,2=270.000000
L 4.035 4.4392 4.05291673 4.42933297 2 P 0 ;0,1=177,2=270.000000
L 4.05291673 4.42933297 4.05291673 4.44266693 2 P 0 ;0,1=177,2=270.000000
L 4.06 4.4599997 4.05958346 4.46186644 2 P 0 ;0,1=177,2=270.000000
L 4.05958346 4.46186644 4.05833376 4.4639998 2 P 0 ;0,1=177,2=270.000000
L 4.05833376 4.4639998 4.05625089 4.46533337 2 P 0 ;0,1=177,2=270.000000
L 4.05625089 4.46533337 4.05333327 4.46586663 2 P 0 ;0,1=177,2=270.000000
L 4.05333327 4.46586663 4.05041722 4.46533337 2 P 0 ;0,1=177,2=270.000000
L 4.05041722 4.46533337 4.04791703 4.46373327 2 P 0 ;0,1=177,2=270.000000
L 4.04791703 4.46373327 4.04666654 4.46133327 2 P 0 ;0,1=177,2=270.000000
L 4.04666654 4.46133327 4.04666654 4.45866663 2 P 0 ;0,1=177,2=270.000000
L 4.04666654 4.45866663 4.04583337 4.45706654 2 P 0 ;0,1=177,2=270.000000
L 4.04583337 4.45706654 4.04375049 4.45573297 2 P 0 ;0,1=177,2=270.000000
L 4.04375049 4.45573297 4.04083366 4.4551998 2 P 0 ;0,1=177,2=270.000000
L 4.04083366 4.4551998 4.03791683 4.4560001 2 P 0 ;0,1=177,2=270.000000
L 4.03791683 4.4560001 4.03583317 4.45786634 2 P 0 ;0,1=177,2=270.000000
L 4.03583317 4.45786634 4.035 4.4599997 2 P 0 ;0,1=177,2=270.000000
L 4.035 4.4599997 4.03583317 4.46213307 2 P 0 ;0,1=177,2=270.000000
L 4.03583317 4.46213307 4.03791683 4.4639998 2 P 0 ;0,1=177,2=270.000000
L 4.03791683 4.4639998 4.04083366 4.4648001 2 P 0 ;0,1=177,2=270.000000
L 4.04083366 4.4648001 4.04375049 4.46426644 2 P 0 ;0,1=177,2=270.000000
L 4.04375049 4.46426644 4.04583337 4.46293337 2 P 0 ;0,1=177,2=270.000000
L 4.04583337 4.46293337 4.04666654 4.46133327 2 P 0 ;0,1=177,2=270.000000
L 4.04666654 4.46133327 4.04666654 4.45866663 2 P 0 ;0,1=177,2=270.000000
L 4.04666654 4.45866663 4.04791703 4.45626663 2 P 0 ;0,1=177,2=270.000000
L 4.04791703 4.45626663 4.05041722 4.45466654 2 P 0 ;0,1=177,2=270.000000
L 4.05041722 4.45466654 4.05333327 4.45413327 2 P 0 ;0,1=177,2=270.000000
L 4.05333327 4.45413327 4.05625089 4.45466654 2 P 0 ;0,1=177,2=270.000000
L 4.05625089 4.45466654 4.05833376 4.4560001 2 P 0 ;0,1=177,2=270.000000
L 4.05833376 4.4560001 4.05958346 4.45813346 2 P 0 ;0,1=177,2=270.000000
L 4.05958346 4.45813346 4.06 4.4599997 2 P 0 ;0,1=177,2=270.000000
L 4.035 4.4839997 4.03583317 4.48186634 2 P 0 ;0,1=177,2=270.000000
L 4.03583317 4.48186634 4.03791683 4.48026663 2 P 0 ;0,1=177,2=270.000000
L 4.03791683 4.48026663 4.04041634 4.4791998 2 P 0 ;0,1=177,2=270.000000
L 4.04041634 4.4791998 4.04375049 4.4783999 2 P 0 ;0,1=177,2=270.000000
L 4.04375049 4.4783999 4.04750039 4.47813327 2 P 0 ;0,1=177,2=270.000000
L 4.04750039 4.47813327 4.05125039 4.4783999 2 P 0 ;0,1=177,2=270.000000
L 4.05125039 4.4783999 4.05458376 4.4791998 2 P 0 ;0,1=177,2=270.000000
L 4.05458376 4.4791998 4.05708396 4.48026663 2 P 0 ;0,1=177,2=270.000000
L 4.05708396 4.48026663 4.05916693 4.48186634 2 P 0 ;0,1=177,2=270.000000
L 4.05916693 4.48186634 4.06 4.4839997 2 P 0 ;0,1=177,2=270.000000
L 4.06 4.4839997 4.05916693 4.48613307 2 P 0 ;0,1=177,2=270.000000
L 4.05916693 4.48613307 4.05708396 4.48773327 2 P 0 ;0,1=177,2=270.000000
L 4.05708396 4.48773327 4.05458376 4.4888001 2 P 0 ;0,1=177,2=270.000000
L 4.05458376 4.4888001 4.05125039 4.4896 2 P 0 ;0,1=177,2=270.000000
L 4.05125039 4.4896 4.04750039 4.48986663 2 P 0 ;0,1=177,2=270.000000
L 4.04750039 4.48986663 4.04375049 4.4896 2 P 0 ;0,1=177,2=270.000000
L 4.04375049 4.4896 4.04041634 4.4888001 2 P 0 ;0,1=177,2=270.000000
L 4.04041634 4.4888001 4.03791683 4.48773327 2 P 0 ;0,1=177,2=270.000000
L 4.03791683 4.48773327 4.03583317 4.48613307 2 P 0 ;0,1=177,2=270.000000
L 4.03583317 4.48613307 4.035 4.4839997 2 P 0 ;0,1=177,2=270.000000
L 3.99776998 4.81198996 3.98203002 4.81198996 3 P 0 
L 4.005 4.38266654 3.98 4.38266654 2 P 0 ;0,1=178,2=270.000000
L 3.98 4.38266654 3.98 4.38933327 2 P 0 ;0,1=178,2=270.000000
L 3.98 4.38933327 3.98125059 4.39146663 2 P 0 ;0,1=178,2=270.000000
L 3.98125059 4.39146663 3.98291683 4.3928001 2 P 0 ;0,1=178,2=270.000000
L 3.98291683 4.3928001 3.9862502 4.39333337 2 P 0 ;0,1=178,2=270.000000
L 3.9862502 4.39333337 3.98958366 4.3928001 2 P 0 ;0,1=178,2=270.000000
L 3.98958366 4.3928001 3.99166654 4.3912 2 P 0 ;0,1=178,2=270.000000
L 3.99166654 4.3912 3.99291703 4.38933327 2 P 0 ;0,1=178,2=270.000000
L 3.99291703 4.38933327 3.99291703 4.38266654 2 P 0 ;0,1=178,2=270.000000
L 3.99291703 4.38933327 4.005 4.39333337 2 P 0 ;0,1=178,2=270.000000
L 4.005 4.4119997 3.98 4.4119997 2 P 0 ;0,1=178,2=270.000000
L 3.98 4.4119997 3.9849997 4.4087999 2 P 0 ;0,1=178,2=270.000000
L 4.005 4.4087999 4.005 4.41519951 2 P 0 ;0,1=178,2=270.000000
L 4.005 4.4392 3.98 4.4392 2 P 0 ;0,1=178,2=270.000000
L 3.98 4.4392 3.99791673 4.42933297 2 P 0 ;0,1=178,2=270.000000
L 3.99791673 4.42933297 3.99791673 4.44266693 2 P 0 ;0,1=178,2=270.000000
L 4.005 4.45946654 3.99958376 4.4599997 2 P 0 ;0,1=178,2=270.000000
L 3.99958376 4.4599997 3.99500069 4.4608 2 P 0 ;0,1=178,2=270.000000
L 3.99500069 4.4608 3.99083337 4.46186644 2 P 0 ;0,1=178,2=270.000000
L 3.99083337 4.46186644 3.9862502 4.4632 2 P 0 ;0,1=178,2=270.000000
L 3.9862502 4.4632 3.98 4.46533337 2 P 0 ;0,1=178,2=270.000000
L 3.98 4.46533337 3.98 4.45466654 2 P 0 ;0,1=178,2=270.000000
L 4.00208396 4.47946634 4.00416693 4.48133317 2 P 0 ;0,1=178,2=270.000000
L 4.00416693 4.48133317 4.005 4.48346654 2 P 0 ;0,1=178,2=270.000000
L 4.005 4.48346654 4.00416693 4.4855999 2 P 0 ;0,1=178,2=270.000000
L 4.00416693 4.4855999 4.00166742 4.48746663 2 P 0 ;0,1=178,2=270.000000
L 4.00166742 4.48746663 3.99791673 4.4888001 2 P 0 ;0,1=178,2=270.000000
L 3.99791673 4.4888001 3.99416673 4.48933337 2 P 0 ;0,1=178,2=270.000000
L 3.99416673 4.48933337 3.98958366 4.48933337 2 P 0 ;0,1=178,2=270.000000
L 3.98958366 4.48933337 3.98583366 4.4888001 2 P 0 ;0,1=178,2=270.000000
L 3.98583366 4.4888001 3.9825003 4.48746663 2 P 0 ;0,1=178,2=270.000000
L 3.9825003 4.48746663 3.98083317 4.48586644 2 P 0 ;0,1=178,2=270.000000
L 3.98083317 4.48586644 3.98 4.4839997 2 P 0 ;0,1=178,2=270.000000
L 3.98 4.4839997 3.98083317 4.48186634 2 P 0 ;0,1=178,2=270.000000
L 3.98083317 4.48186634 3.9825003 4.48026663 2 P 0 ;0,1=178,2=270.000000
L 3.9825003 4.48026663 3.9849997 4.4791998 2 P 0 ;0,1=178,2=270.000000
L 3.9849997 4.4791998 3.98833386 4.47866654 2 P 0 ;0,1=178,2=270.000000
L 3.98833386 4.47866654 3.9912499 4.4791998 2 P 0 ;0,1=178,2=270.000000
L 3.9912499 4.4791998 3.99416673 4.48053327 2 P 0 ;0,1=178,2=270.000000
L 3.99416673 4.48053327 3.99583386 4.48213346 2 P 0 ;0,1=178,2=270.000000
L 3.99583386 4.48213346 3.99625039 4.4839997 2 P 0 ;0,1=178,2=270.000000
L 3.99625039 4.4839997 3.99541722 4.48613307 2 P 0 ;0,1=178,2=270.000000
L 3.99541722 4.48613307 3.99333356 4.48773327 2 P 0 ;0,1=178,2=270.000000
L 3.99333356 4.48773327 3.98958366 4.48933337 2 P 0 ;0,1=178,2=270.000000
L 4.00203002 5.34198996 4.01776998 5.34198996 3 P 0 
L 4.15 5.28766654 4.125 5.28766654 2 P 0 ;0,1=179,2=270.000000
L 4.125 5.28766654 4.125 5.29433327 2 P 0 ;0,1=179,2=270.000000
L 4.125 5.29433327 4.12625059 5.29646663 2 P 0 ;0,1=179,2=270.000000
L 4.12625059 5.29646663 4.12791683 5.2978001 2 P 0 ;0,1=179,2=270.000000
L 4.12791683 5.2978001 4.1312502 5.29833337 2 P 0 ;0,1=179,2=270.000000
L 4.1312502 5.29833337 4.13458366 5.2978001 2 P 0 ;0,1=179,2=270.000000
L 4.13458366 5.2978001 4.13666654 5.2962 2 P 0 ;0,1=179,2=270.000000
L 4.13666654 5.2962 4.13791703 5.29433327 2 P 0 ;0,1=179,2=270.000000
L 4.13791703 5.29433327 4.13791703 5.28766654 2 P 0 ;0,1=179,2=270.000000
L 4.13791703 5.29433327 4.15 5.29833337 2 P 0 ;0,1=179,2=270.000000
L 4.15 5.3169997 4.125 5.3169997 2 P 0 ;0,1=179,2=270.000000
L 4.125 5.3169997 4.1299997 5.3137999 2 P 0 ;0,1=179,2=270.000000
L 4.15 5.3137999 4.15 5.32019951 2 P 0 ;0,1=179,2=270.000000
L 4.15 5.3442 4.125 5.3442 2 P 0 ;0,1=179,2=270.000000
L 4.125 5.3442 4.14291673 5.33433297 2 P 0 ;0,1=179,2=270.000000
L 4.14291673 5.33433297 4.14291673 5.34766693 2 P 0 ;0,1=179,2=270.000000
L 4.15 5.36446654 4.14458376 5.3649997 2 P 0 ;0,1=179,2=270.000000
L 4.14458376 5.3649997 4.14000069 5.3658 2 P 0 ;0,1=179,2=270.000000
L 4.14000069 5.3658 4.13583337 5.36686644 2 P 0 ;0,1=179,2=270.000000
L 4.13583337 5.36686644 4.1312502 5.3682 2 P 0 ;0,1=179,2=270.000000
L 4.1312502 5.3682 4.125 5.37033337 2 P 0 ;0,1=179,2=270.000000
L 4.125 5.37033337 4.125 5.35966654 2 P 0 ;0,1=179,2=270.000000
L 4.13958406 5.38393317 4.13666654 5.3857999 2 P 0 ;0,1=179,2=270.000000
L 4.13666654 5.3857999 4.1350002 5.3874 2 P 0 ;0,1=179,2=270.000000
L 4.1350002 5.3874 4.13416703 5.38953337 2 P 0 ;0,1=179,2=270.000000
L 4.13416703 5.38953337 4.1350002 5.3914002 2 P 0 ;0,1=179,2=270.000000
L 4.1350002 5.3914002 4.13666654 5.39273327 2 P 0 ;0,1=179,2=270.000000
L 4.13666654 5.39273327 4.13916673 5.3938001 2 P 0 ;0,1=179,2=270.000000
L 4.13916673 5.3938001 4.14208356 5.39406673 2 P 0 ;0,1=179,2=270.000000
L 4.14208356 5.39406673 4.14458376 5.3938001 2 P 0 ;0,1=179,2=270.000000
L 4.14458376 5.3938001 4.14708396 5.39273327 2 P 0 ;0,1=179,2=270.000000
L 4.14708396 5.39273327 4.14916693 5.39113307 2 P 0 ;0,1=179,2=270.000000
L 4.14916693 5.39113307 4.15 5.38926683 2 P 0 ;0,1=179,2=270.000000
L 4.15 5.38926683 4.14916693 5.38713346 2 P 0 ;0,1=179,2=270.000000
L 4.14916693 5.38713346 4.14666742 5.38526663 2 P 0 ;0,1=179,2=270.000000
L 4.14666742 5.38526663 4.14291673 5.3841998 2 P 0 ;0,1=179,2=270.000000
L 4.14291673 5.3841998 4.1387502 5.38393317 2 P 0 ;0,1=179,2=270.000000
L 4.1387502 5.38393317 4.13333386 5.38446634 2 P 0 ;0,1=179,2=270.000000
L 4.13333386 5.38446634 4.13041634 5.38526663 2 P 0 ;0,1=179,2=270.000000
L 4.13041634 5.38526663 4.1275003 5.3865997 2 P 0 ;0,1=179,2=270.000000
L 4.1275003 5.3865997 4.12541663 5.38846654 2 P 0 ;0,1=179,2=270.000000
L 4.12541663 5.38846654 4.125 5.39033327 2 P 0 ;0,1=179,2=270.000000
L 4.125 5.39033327 4.12583317 5.3922 2 P 0 ;0,1=179,2=270.000000
L 4.12583317 5.3922 4.12791683 5.39353356 2 P 0 ;0,1=179,2=270.000000
L 4.05203002 5.34198996 4.06776998 5.34198996 3 P 0 
L 4.19 5.28766654 4.165 5.28766654 2 P 0 ;0,1=180,2=270.000000
L 4.165 5.28766654 4.165 5.29433327 2 P 0 ;0,1=180,2=270.000000
L 4.165 5.29433327 4.16625059 5.29646663 2 P 0 ;0,1=180,2=270.000000
L 4.16625059 5.29646663 4.16791683 5.2978001 2 P 0 ;0,1=180,2=270.000000
L 4.16791683 5.2978001 4.1712502 5.29833337 2 P 0 ;0,1=180,2=270.000000
L 4.1712502 5.29833337 4.17458366 5.2978001 2 P 0 ;0,1=180,2=270.000000
L 4.17458366 5.2978001 4.17666654 5.2962 2 P 0 ;0,1=180,2=270.000000
L 4.17666654 5.2962 4.17791703 5.29433327 2 P 0 ;0,1=180,2=270.000000
L 4.17791703 5.29433327 4.17791703 5.28766654 2 P 0 ;0,1=180,2=270.000000
L 4.17791703 5.29433327 4.19 5.29833337 2 P 0 ;0,1=180,2=270.000000
L 4.19 5.3169997 4.165 5.3169997 2 P 0 ;0,1=180,2=270.000000
L 4.165 5.3169997 4.1699997 5.3137999 2 P 0 ;0,1=180,2=270.000000
L 4.19 5.3137999 4.19 5.32019951 2 P 0 ;0,1=180,2=270.000000
L 4.19 5.3442 4.165 5.3442 2 P 0 ;0,1=180,2=270.000000
L 4.165 5.3442 4.18291673 5.33433297 2 P 0 ;0,1=180,2=270.000000
L 4.18291673 5.33433297 4.18291673 5.34766693 2 P 0 ;0,1=180,2=270.000000
L 4.19 5.36446654 4.18458376 5.3649997 2 P 0 ;0,1=180,2=270.000000
L 4.18458376 5.3649997 4.18000069 5.3658 2 P 0 ;0,1=180,2=270.000000
L 4.18000069 5.3658 4.17583337 5.36686644 2 P 0 ;0,1=180,2=270.000000
L 4.17583337 5.36686644 4.1712502 5.3682 2 P 0 ;0,1=180,2=270.000000
L 4.1712502 5.3682 4.165 5.37033337 2 P 0 ;0,1=180,2=270.000000
L 4.165 5.37033337 4.165 5.35966654 2 P 0 ;0,1=180,2=270.000000
L 4.18625089 5.38313327 4.18833376 5.38473297 2 P 0 ;0,1=180,2=270.000000
L 4.18833376 5.38473297 4.18958346 5.3865997 2 P 0 ;0,1=180,2=270.000000
L 4.18958346 5.3865997 4.19 5.3889997 2 P 0 ;0,1=180,2=270.000000
L 4.19 5.3889997 4.18916693 5.3914002 2 P 0 ;0,1=180,2=270.000000
L 4.18916693 5.3914002 4.18750059 5.39326644 2 P 0 ;0,1=180,2=270.000000
L 4.18750059 5.39326644 4.18458376 5.3946 2 P 0 ;0,1=180,2=270.000000
L 4.18458376 5.3946 4.18125039 5.39486663 2 P 0 ;0,1=180,2=270.000000
L 4.18125039 5.39486663 4.17791703 5.39433337 2 P 0 ;0,1=180,2=270.000000
L 4.17791703 5.39433337 4.17583337 5.3929998 2 P 0 ;0,1=180,2=270.000000
L 4.17583337 5.3929998 4.17416703 5.39113307 2 P 0 ;0,1=180,2=270.000000
L 4.17416703 5.39113307 4.17375049 5.38926683 2 P 0 ;0,1=180,2=270.000000
L 4.17375049 5.38926683 4.17416703 5.3874 2 P 0 ;0,1=180,2=270.000000
L 4.17416703 5.3874 4.17583337 5.3850001 2 P 0 ;0,1=180,2=270.000000
L 4.17583337 5.3850001 4.165 5.3857999 2 P 0 ;0,1=180,2=270.000000
L 4.165 5.3857999 4.165 5.3929998 2 P 0 ;0,1=180,2=270.000000
L 0.71286998 5.4 0.69713002 5.4 3 P 0 
L 0.46 5.43266654 0.435 5.43266654 2 P 0 ;0,1=181,2=270.000000
L 0.435 5.43266654 0.435 5.43933327 2 P 0 ;0,1=181,2=270.000000
L 0.435 5.43933327 0.43625059 5.44146663 2 P 0 ;0,1=181,2=270.000000
L 0.43625059 5.44146663 0.43791683 5.4428001 2 P 0 ;0,1=181,2=270.000000
L 0.43791683 5.4428001 0.4412502 5.44333337 2 P 0 ;0,1=181,2=270.000000
L 0.4412502 5.44333337 0.44458366 5.4428001 2 P 0 ;0,1=181,2=270.000000
L 0.44458366 5.4428001 0.44666654 5.4412 2 P 0 ;0,1=181,2=270.000000
L 0.44666654 5.4412 0.44791703 5.43933327 2 P 0 ;0,1=181,2=270.000000
L 0.44791703 5.43933327 0.44791703 5.43266654 2 P 0 ;0,1=181,2=270.000000
L 0.44791703 5.43933327 0.46 5.44333337 2 P 0 ;0,1=181,2=270.000000
L 0.46 5.4619997 0.435 5.4619997 2 P 0 ;0,1=181,2=270.000000
L 0.435 5.4619997 0.4399997 5.4587999 2 P 0 ;0,1=181,2=270.000000
L 0.46 5.4587999 0.46 5.46519951 2 P 0 ;0,1=181,2=270.000000
L 0.46 5.4892 0.435 5.4892 2 P 0 ;0,1=181,2=270.000000
L 0.435 5.4892 0.45291673 5.47933297 2 P 0 ;0,1=181,2=270.000000
L 0.45291673 5.47933297 0.45291673 5.49266693 2 P 0 ;0,1=181,2=270.000000
L 0.45708396 5.50546634 0.45916693 5.50733317 2 P 0 ;0,1=181,2=270.000000
L 0.45916693 5.50733317 0.46 5.50946654 2 P 0 ;0,1=181,2=270.000000
L 0.46 5.50946654 0.45916693 5.5115999 2 P 0 ;0,1=181,2=270.000000
L 0.45916693 5.5115999 0.45666742 5.51346663 2 P 0 ;0,1=181,2=270.000000
L 0.45666742 5.51346663 0.45291673 5.5148001 2 P 0 ;0,1=181,2=270.000000
L 0.45291673 5.5148001 0.44916673 5.51533337 2 P 0 ;0,1=181,2=270.000000
L 0.44916673 5.51533337 0.44458366 5.51533337 2 P 0 ;0,1=181,2=270.000000
L 0.44458366 5.51533337 0.44083366 5.5148001 2 P 0 ;0,1=181,2=270.000000
L 0.44083366 5.5148001 0.4375003 5.51346663 2 P 0 ;0,1=181,2=270.000000
L 0.4375003 5.51346663 0.43583317 5.51186644 2 P 0 ;0,1=181,2=270.000000
L 0.43583317 5.51186644 0.435 5.5099997 2 P 0 ;0,1=181,2=270.000000
L 0.435 5.5099997 0.43583317 5.50786634 2 P 0 ;0,1=181,2=270.000000
L 0.43583317 5.50786634 0.4375003 5.50626663 2 P 0 ;0,1=181,2=270.000000
L 0.4375003 5.50626663 0.4399997 5.5051998 2 P 0 ;0,1=181,2=270.000000
L 0.4399997 5.5051998 0.44333386 5.50466654 2 P 0 ;0,1=181,2=270.000000
L 0.44333386 5.50466654 0.4462499 5.5051998 2 P 0 ;0,1=181,2=270.000000
L 0.4462499 5.5051998 0.44916673 5.50653327 2 P 0 ;0,1=181,2=270.000000
L 0.44916673 5.50653327 0.45083386 5.50813346 2 P 0 ;0,1=181,2=270.000000
L 0.45083386 5.50813346 0.45125039 5.5099997 2 P 0 ;0,1=181,2=270.000000
L 0.45125039 5.5099997 0.45041722 5.51213307 2 P 0 ;0,1=181,2=270.000000
L 0.45041722 5.51213307 0.44833356 5.51373327 2 P 0 ;0,1=181,2=270.000000
L 0.44833356 5.51373327 0.44458366 5.51533337 2 P 0 ;0,1=181,2=270.000000
L 0.45625089 5.52813327 0.45833376 5.52973297 2 P 0 ;0,1=181,2=270.000000
L 0.45833376 5.52973297 0.45958346 5.5315997 2 P 0 ;0,1=181,2=270.000000
L 0.45958346 5.5315997 0.46 5.5339997 2 P 0 ;0,1=181,2=270.000000
L 0.46 5.5339997 0.45916693 5.5364002 2 P 0 ;0,1=181,2=270.000000
L 0.45916693 5.5364002 0.45750059 5.53826644 2 P 0 ;0,1=181,2=270.000000
L 0.45750059 5.53826644 0.45458376 5.5396 2 P 0 ;0,1=181,2=270.000000
L 0.45458376 5.5396 0.45125039 5.53986663 2 P 0 ;0,1=181,2=270.000000
L 0.45125039 5.53986663 0.44791703 5.53933337 2 P 0 ;0,1=181,2=270.000000
L 0.44791703 5.53933337 0.44583337 5.5379998 2 P 0 ;0,1=181,2=270.000000
L 0.44583337 5.5379998 0.44416703 5.53613307 2 P 0 ;0,1=181,2=270.000000
L 0.44416703 5.53613307 0.44375049 5.53426683 2 P 0 ;0,1=181,2=270.000000
L 0.44375049 5.53426683 0.44416703 5.5324 2 P 0 ;0,1=181,2=270.000000
L 0.44416703 5.5324 0.44583337 5.5300001 2 P 0 ;0,1=181,2=270.000000
L 0.44583337 5.5300001 0.435 5.5307999 2 P 0 ;0,1=181,2=270.000000
L 0.435 5.5307999 0.435 5.5379998 2 P 0 ;0,1=181,2=270.000000
L 0.91786998 5.25 0.90213002 5.25 3 P 0 
L 0.89 5.23766654 0.865 5.23766654 2 P 0 ;0,1=182,2=270.000000
L 0.865 5.23766654 0.865 5.24433327 2 P 0 ;0,1=182,2=270.000000
L 0.865 5.24433327 0.86625059 5.24646663 2 P 0 ;0,1=182,2=270.000000
L 0.86625059 5.24646663 0.86791683 5.2478001 2 P 0 ;0,1=182,2=270.000000
L 0.86791683 5.2478001 0.8712502 5.24833337 2 P 0 ;0,1=182,2=270.000000
L 0.8712502 5.24833337 0.87458366 5.2478001 2 P 0 ;0,1=182,2=270.000000
L 0.87458366 5.2478001 0.87666654 5.2462 2 P 0 ;0,1=182,2=270.000000
L 0.87666654 5.2462 0.87791703 5.24433327 2 P 0 ;0,1=182,2=270.000000
L 0.87791703 5.24433327 0.87791703 5.23766654 2 P 0 ;0,1=182,2=270.000000
L 0.87791703 5.24433327 0.89 5.24833337 2 P 0 ;0,1=182,2=270.000000
L 0.89 5.2669997 0.865 5.2669997 2 P 0 ;0,1=182,2=270.000000
L 0.865 5.2669997 0.8699997 5.2637999 2 P 0 ;0,1=182,2=270.000000
L 0.89 5.2637999 0.89 5.27019951 2 P 0 ;0,1=182,2=270.000000
L 0.89 5.2942 0.865 5.2942 2 P 0 ;0,1=182,2=270.000000
L 0.865 5.2942 0.88291673 5.28433297 2 P 0 ;0,1=182,2=270.000000
L 0.88291673 5.28433297 0.88291673 5.29766693 2 P 0 ;0,1=182,2=270.000000
L 0.89 5.3149997 0.88958346 5.31686644 2 P 0 ;0,1=182,2=270.000000
L 0.88958346 5.31686644 0.88833376 5.3189998 2 P 0 ;0,1=182,2=270.000000
L 0.88833376 5.3189998 0.88625089 5.32033337 2 P 0 ;0,1=182,2=270.000000
L 0.88625089 5.32033337 0.88333327 5.32086663 2 P 0 ;0,1=182,2=270.000000
L 0.88333327 5.32086663 0.88041722 5.32033337 2 P 0 ;0,1=182,2=270.000000
L 0.88041722 5.32033337 0.87791703 5.31873327 2 P 0 ;0,1=182,2=270.000000
L 0.87791703 5.31873327 0.87666654 5.31633327 2 P 0 ;0,1=182,2=270.000000
L 0.87666654 5.31633327 0.87666654 5.31366663 2 P 0 ;0,1=182,2=270.000000
L 0.87666654 5.31366663 0.87583337 5.31206654 2 P 0 ;0,1=182,2=270.000000
L 0.87583337 5.31206654 0.87375049 5.31073297 2 P 0 ;0,1=182,2=270.000000
L 0.87375049 5.31073297 0.87083366 5.3101998 2 P 0 ;0,1=182,2=270.000000
L 0.87083366 5.3101998 0.86791683 5.3110001 2 P 0 ;0,1=182,2=270.000000
L 0.86791683 5.3110001 0.86583317 5.31286634 2 P 0 ;0,1=182,2=270.000000
L 0.86583317 5.31286634 0.865 5.3149997 2 P 0 ;0,1=182,2=270.000000
L 0.865 5.3149997 0.86583317 5.31713307 2 P 0 ;0,1=182,2=270.000000
L 0.86583317 5.31713307 0.86791683 5.3189998 2 P 0 ;0,1=182,2=270.000000
L 0.86791683 5.3189998 0.87083366 5.3198001 2 P 0 ;0,1=182,2=270.000000
L 0.87083366 5.3198001 0.87375049 5.31926644 2 P 0 ;0,1=182,2=270.000000
L 0.87375049 5.31926644 0.87583337 5.31793337 2 P 0 ;0,1=182,2=270.000000
L 0.87583337 5.31793337 0.87666654 5.31633327 2 P 0 ;0,1=182,2=270.000000
L 0.87666654 5.31633327 0.87666654 5.31366663 2 P 0 ;0,1=182,2=270.000000
L 0.87666654 5.31366663 0.87791703 5.31126663 2 P 0 ;0,1=182,2=270.000000
L 0.87791703 5.31126663 0.88041722 5.30966654 2 P 0 ;0,1=182,2=270.000000
L 0.88041722 5.30966654 0.88333327 5.30913327 2 P 0 ;0,1=182,2=270.000000
L 0.88333327 5.30913327 0.88625089 5.30966654 2 P 0 ;0,1=182,2=270.000000
L 0.88625089 5.30966654 0.88833376 5.3110001 2 P 0 ;0,1=182,2=270.000000
L 0.88833376 5.3110001 0.88958346 5.31313346 2 P 0 ;0,1=182,2=270.000000
L 0.88958346 5.31313346 0.89 5.3149997 2 P 0 ;0,1=182,2=270.000000
L 0.89 5.3389997 0.88958346 5.34086644 2 P 0 ;0,1=182,2=270.000000
L 0.88958346 5.34086644 0.88833376 5.3429998 2 P 0 ;0,1=182,2=270.000000
L 0.88833376 5.3429998 0.88625089 5.34433337 2 P 0 ;0,1=182,2=270.000000
L 0.88625089 5.34433337 0.88333327 5.34486663 2 P 0 ;0,1=182,2=270.000000
L 0.88333327 5.34486663 0.88041722 5.34433337 2 P 0 ;0,1=182,2=270.000000
L 0.88041722 5.34433337 0.87791703 5.34273327 2 P 0 ;0,1=182,2=270.000000
L 0.87791703 5.34273327 0.87666654 5.34033327 2 P 0 ;0,1=182,2=270.000000
L 0.87666654 5.34033327 0.87666654 5.33766663 2 P 0 ;0,1=182,2=270.000000
L 0.87666654 5.33766663 0.87583337 5.33606654 2 P 0 ;0,1=182,2=270.000000
L 0.87583337 5.33606654 0.87375049 5.33473297 2 P 0 ;0,1=182,2=270.000000
L 0.87375049 5.33473297 0.87083366 5.3341998 2 P 0 ;0,1=182,2=270.000000
L 0.87083366 5.3341998 0.86791683 5.3350001 2 P 0 ;0,1=182,2=270.000000
L 0.86791683 5.3350001 0.86583317 5.33686634 2 P 0 ;0,1=182,2=270.000000
L 0.86583317 5.33686634 0.865 5.3389997 2 P 0 ;0,1=182,2=270.000000
L 0.865 5.3389997 0.86583317 5.34113307 2 P 0 ;0,1=182,2=270.000000
L 0.86583317 5.34113307 0.86791683 5.3429998 2 P 0 ;0,1=182,2=270.000000
L 0.86791683 5.3429998 0.87083366 5.3438001 2 P 0 ;0,1=182,2=270.000000
L 0.87083366 5.3438001 0.87375049 5.34326644 2 P 0 ;0,1=182,2=270.000000
L 0.87375049 5.34326644 0.87583337 5.34193337 2 P 0 ;0,1=182,2=270.000000
L 0.87583337 5.34193337 0.87666654 5.34033327 2 P 0 ;0,1=182,2=270.000000
L 0.87666654 5.34033327 0.87666654 5.33766663 2 P 0 ;0,1=182,2=270.000000
L 0.87666654 5.33766663 0.87791703 5.33526663 2 P 0 ;0,1=182,2=270.000000
L 0.87791703 5.33526663 0.88041722 5.33366654 2 P 0 ;0,1=182,2=270.000000
L 0.88041722 5.33366654 0.88333327 5.33313327 2 P 0 ;0,1=182,2=270.000000
L 0.88333327 5.33313327 0.88625089 5.33366654 2 P 0 ;0,1=182,2=270.000000
L 0.88625089 5.33366654 0.88833376 5.3350001 2 P 0 ;0,1=182,2=270.000000
L 0.88833376 5.3350001 0.88958346 5.33713346 2 P 0 ;0,1=182,2=270.000000
L 0.88958346 5.33713346 0.89 5.3389997 2 P 0 ;0,1=182,2=270.000000
L 3.84776998 4.81198996 3.83203002 4.81198996 3 P 0 
L 3.835 4.38266654 3.81 4.38266654 2 P 0 ;0,1=183,2=270.000000
L 3.81 4.38266654 3.81 4.38933327 2 P 0 ;0,1=183,2=270.000000
L 3.81 4.38933327 3.81125059 4.39146663 2 P 0 ;0,1=183,2=270.000000
L 3.81125059 4.39146663 3.81291683 4.3928001 2 P 0 ;0,1=183,2=270.000000
L 3.81291683 4.3928001 3.8162502 4.39333337 2 P 0 ;0,1=183,2=270.000000
L 3.8162502 4.39333337 3.81958366 4.3928001 2 P 0 ;0,1=183,2=270.000000
L 3.81958366 4.3928001 3.82166654 4.3912 2 P 0 ;0,1=183,2=270.000000
L 3.82166654 4.3912 3.82291703 4.38933327 2 P 0 ;0,1=183,2=270.000000
L 3.82291703 4.38933327 3.82291703 4.38266654 2 P 0 ;0,1=183,2=270.000000
L 3.82291703 4.38933327 3.835 4.39333337 2 P 0 ;0,1=183,2=270.000000
L 3.835 4.4119997 3.81 4.4119997 2 P 0 ;0,1=183,2=270.000000
L 3.81 4.4119997 3.8149997 4.4087999 2 P 0 ;0,1=183,2=270.000000
L 3.835 4.4087999 3.835 4.41519951 2 P 0 ;0,1=183,2=270.000000
L 3.835 4.4392 3.81 4.4392 2 P 0 ;0,1=183,2=270.000000
L 3.81 4.4392 3.82791673 4.42933297 2 P 0 ;0,1=183,2=270.000000
L 3.82791673 4.42933297 3.82791673 4.44266693 2 P 0 ;0,1=183,2=270.000000
L 3.835 4.4599997 3.83458346 4.46186644 2 P 0 ;0,1=183,2=270.000000
L 3.83458346 4.46186644 3.83333376 4.4639998 2 P 0 ;0,1=183,2=270.000000
L 3.83333376 4.4639998 3.83125089 4.46533337 2 P 0 ;0,1=183,2=270.000000
L 3.83125089 4.46533337 3.82833327 4.46586663 2 P 0 ;0,1=183,2=270.000000
L 3.82833327 4.46586663 3.82541722 4.46533337 2 P 0 ;0,1=183,2=270.000000
L 3.82541722 4.46533337 3.82291703 4.46373327 2 P 0 ;0,1=183,2=270.000000
L 3.82291703 4.46373327 3.82166654 4.46133327 2 P 0 ;0,1=183,2=270.000000
L 3.82166654 4.46133327 3.82166654 4.45866663 2 P 0 ;0,1=183,2=270.000000
L 3.82166654 4.45866663 3.82083337 4.45706654 2 P 0 ;0,1=183,2=270.000000
L 3.82083337 4.45706654 3.81875049 4.45573297 2 P 0 ;0,1=183,2=270.000000
L 3.81875049 4.45573297 3.81583366 4.4551998 2 P 0 ;0,1=183,2=270.000000
L 3.81583366 4.4551998 3.81291683 4.4560001 2 P 0 ;0,1=183,2=270.000000
L 3.81291683 4.4560001 3.81083317 4.45786634 2 P 0 ;0,1=183,2=270.000000
L 3.81083317 4.45786634 3.81 4.4599997 2 P 0 ;0,1=183,2=270.000000
L 3.81 4.4599997 3.81083317 4.46213307 2 P 0 ;0,1=183,2=270.000000
L 3.81083317 4.46213307 3.81291683 4.4639998 2 P 0 ;0,1=183,2=270.000000
L 3.81291683 4.4639998 3.81583366 4.4648001 2 P 0 ;0,1=183,2=270.000000
L 3.81583366 4.4648001 3.81875049 4.46426644 2 P 0 ;0,1=183,2=270.000000
L 3.81875049 4.46426644 3.82083337 4.46293337 2 P 0 ;0,1=183,2=270.000000
L 3.82083337 4.46293337 3.82166654 4.46133327 2 P 0 ;0,1=183,2=270.000000
L 3.82166654 4.46133327 3.82166654 4.45866663 2 P 0 ;0,1=183,2=270.000000
L 3.82166654 4.45866663 3.82291703 4.45626663 2 P 0 ;0,1=183,2=270.000000
L 3.82291703 4.45626663 3.82541722 4.45466654 2 P 0 ;0,1=183,2=270.000000
L 3.82541722 4.45466654 3.82833327 4.45413327 2 P 0 ;0,1=183,2=270.000000
L 3.82833327 4.45413327 3.83125089 4.45466654 2 P 0 ;0,1=183,2=270.000000
L 3.83125089 4.45466654 3.83333376 4.4560001 2 P 0 ;0,1=183,2=270.000000
L 3.83333376 4.4560001 3.83458346 4.45813346 2 P 0 ;0,1=183,2=270.000000
L 3.83458346 4.45813346 3.835 4.4599997 2 P 0 ;0,1=183,2=270.000000
L 3.83125089 4.47813327 3.83333376 4.47973297 2 P 0 ;0,1=183,2=270.000000
L 3.83333376 4.47973297 3.83458346 4.4815997 2 P 0 ;0,1=183,2=270.000000
L 3.83458346 4.4815997 3.835 4.4839997 2 P 0 ;0,1=183,2=270.000000
L 3.835 4.4839997 3.83416693 4.4864002 2 P 0 ;0,1=183,2=270.000000
L 3.83416693 4.4864002 3.83250059 4.48826644 2 P 0 ;0,1=183,2=270.000000
L 3.83250059 4.48826644 3.82958376 4.4896 2 P 0 ;0,1=183,2=270.000000
L 3.82958376 4.4896 3.82625039 4.48986663 2 P 0 ;0,1=183,2=270.000000
L 3.82625039 4.48986663 3.82291703 4.48933337 2 P 0 ;0,1=183,2=270.000000
L 3.82291703 4.48933337 3.82083337 4.4879998 2 P 0 ;0,1=183,2=270.000000
L 3.82083337 4.4879998 3.81916703 4.48613307 2 P 0 ;0,1=183,2=270.000000
L 3.81916703 4.48613307 3.81875049 4.48426683 2 P 0 ;0,1=183,2=270.000000
L 3.81875049 4.48426683 3.81916703 4.4824 2 P 0 ;0,1=183,2=270.000000
L 3.81916703 4.4824 3.82083337 4.4800001 2 P 0 ;0,1=183,2=270.000000
L 3.82083337 4.4800001 3.81 4.4807999 2 P 0 ;0,1=183,2=270.000000
L 3.81 4.4807999 3.81 4.4879998 2 P 0 ;0,1=183,2=270.000000
L 3.89776998 4.81198996 3.88203002 4.81198996 3 P 0 
L 3.88 4.38266654 3.855 4.38266654 2 P 0 ;0,1=184,2=270.000000
L 3.855 4.38266654 3.855 4.38933327 2 P 0 ;0,1=184,2=270.000000
L 3.855 4.38933327 3.85625059 4.39146663 2 P 0 ;0,1=184,2=270.000000
L 3.85625059 4.39146663 3.85791683 4.3928001 2 P 0 ;0,1=184,2=270.000000
L 3.85791683 4.3928001 3.8612502 4.39333337 2 P 0 ;0,1=184,2=270.000000
L 3.8612502 4.39333337 3.86458366 4.3928001 2 P 0 ;0,1=184,2=270.000000
L 3.86458366 4.3928001 3.86666654 4.3912 2 P 0 ;0,1=184,2=270.000000
L 3.86666654 4.3912 3.86791703 4.38933327 2 P 0 ;0,1=184,2=270.000000
L 3.86791703 4.38933327 3.86791703 4.38266654 2 P 0 ;0,1=184,2=270.000000
L 3.86791703 4.38933327 3.88 4.39333337 2 P 0 ;0,1=184,2=270.000000
L 3.88 4.4119997 3.855 4.4119997 2 P 0 ;0,1=184,2=270.000000
L 3.855 4.4119997 3.8599997 4.4087999 2 P 0 ;0,1=184,2=270.000000
L 3.88 4.4087999 3.88 4.41519951 2 P 0 ;0,1=184,2=270.000000
L 3.88 4.4392 3.855 4.4392 2 P 0 ;0,1=184,2=270.000000
L 3.855 4.4392 3.87291673 4.42933297 2 P 0 ;0,1=184,2=270.000000
L 3.87291673 4.42933297 3.87291673 4.44266693 2 P 0 ;0,1=184,2=270.000000
L 3.88 4.4599997 3.87958346 4.46186644 2 P 0 ;0,1=184,2=270.000000
L 3.87958346 4.46186644 3.87833376 4.4639998 2 P 0 ;0,1=184,2=270.000000
L 3.87833376 4.4639998 3.87625089 4.46533337 2 P 0 ;0,1=184,2=270.000000
L 3.87625089 4.46533337 3.87333327 4.46586663 2 P 0 ;0,1=184,2=270.000000
L 3.87333327 4.46586663 3.87041722 4.46533337 2 P 0 ;0,1=184,2=270.000000
L 3.87041722 4.46533337 3.86791703 4.46373327 2 P 0 ;0,1=184,2=270.000000
L 3.86791703 4.46373327 3.86666654 4.46133327 2 P 0 ;0,1=184,2=270.000000
L 3.86666654 4.46133327 3.86666654 4.45866663 2 P 0 ;0,1=184,2=270.000000
L 3.86666654 4.45866663 3.86583337 4.45706654 2 P 0 ;0,1=184,2=270.000000
L 3.86583337 4.45706654 3.86375049 4.45573297 2 P 0 ;0,1=184,2=270.000000
L 3.86375049 4.45573297 3.86083366 4.4551998 2 P 0 ;0,1=184,2=270.000000
L 3.86083366 4.4551998 3.85791683 4.4560001 2 P 0 ;0,1=184,2=270.000000
L 3.85791683 4.4560001 3.85583317 4.45786634 2 P 0 ;0,1=184,2=270.000000
L 3.85583317 4.45786634 3.855 4.4599997 2 P 0 ;0,1=184,2=270.000000
L 3.855 4.4599997 3.85583317 4.46213307 2 P 0 ;0,1=184,2=270.000000
L 3.85583317 4.46213307 3.85791683 4.4639998 2 P 0 ;0,1=184,2=270.000000
L 3.85791683 4.4639998 3.86083366 4.4648001 2 P 0 ;0,1=184,2=270.000000
L 3.86083366 4.4648001 3.86375049 4.46426644 2 P 0 ;0,1=184,2=270.000000
L 3.86375049 4.46426644 3.86583337 4.46293337 2 P 0 ;0,1=184,2=270.000000
L 3.86583337 4.46293337 3.86666654 4.46133327 2 P 0 ;0,1=184,2=270.000000
L 3.86666654 4.46133327 3.86666654 4.45866663 2 P 0 ;0,1=184,2=270.000000
L 3.86666654 4.45866663 3.86791703 4.45626663 2 P 0 ;0,1=184,2=270.000000
L 3.86791703 4.45626663 3.87041722 4.45466654 2 P 0 ;0,1=184,2=270.000000
L 3.87041722 4.45466654 3.87333327 4.45413327 2 P 0 ;0,1=184,2=270.000000
L 3.87333327 4.45413327 3.87625089 4.45466654 2 P 0 ;0,1=184,2=270.000000
L 3.87625089 4.45466654 3.87833376 4.4560001 2 P 0 ;0,1=184,2=270.000000
L 3.87833376 4.4560001 3.87958346 4.45813346 2 P 0 ;0,1=184,2=270.000000
L 3.87958346 4.45813346 3.88 4.4599997 2 P 0 ;0,1=184,2=270.000000
L 3.88 4.4872 3.855 4.4872 2 P 0 ;0,1=184,2=270.000000
L 3.855 4.4872 3.87291673 4.47733297 2 P 0 ;0,1=184,2=270.000000
L 3.87291673 4.47733297 3.87291673 4.49066693 2 P 0 ;0,1=184,2=270.000000
L 3.86776998 5.34198996 3.85203002 5.34198996 3 P 0 
L 3.795 5.31766654 3.77 5.31766654 2 P 0 ;0,1=185,2=270.000000
L 3.77 5.31766654 3.77 5.32433327 2 P 0 ;0,1=185,2=270.000000
L 3.77 5.32433327 3.77125059 5.32646663 2 P 0 ;0,1=185,2=270.000000
L 3.77125059 5.32646663 3.77291683 5.3278001 2 P 0 ;0,1=185,2=270.000000
L 3.77291683 5.3278001 3.7762502 5.32833337 2 P 0 ;0,1=185,2=270.000000
L 3.7762502 5.32833337 3.77958366 5.3278001 2 P 0 ;0,1=185,2=270.000000
L 3.77958366 5.3278001 3.78166654 5.3262 2 P 0 ;0,1=185,2=270.000000
L 3.78166654 5.3262 3.78291703 5.32433327 2 P 0 ;0,1=185,2=270.000000
L 3.78291703 5.32433327 3.78291703 5.31766654 2 P 0 ;0,1=185,2=270.000000
L 3.78291703 5.32433327 3.795 5.32833337 2 P 0 ;0,1=185,2=270.000000
L 3.795 5.3469997 3.77 5.3469997 2 P 0 ;0,1=185,2=270.000000
L 3.77 5.3469997 3.7749997 5.3437999 2 P 0 ;0,1=185,2=270.000000
L 3.795 5.3437999 3.795 5.35019951 2 P 0 ;0,1=185,2=270.000000
L 3.795 5.3742 3.77 5.3742 2 P 0 ;0,1=185,2=270.000000
L 3.77 5.3742 3.78791673 5.36433297 2 P 0 ;0,1=185,2=270.000000
L 3.78791673 5.36433297 3.78791673 5.37766693 2 P 0 ;0,1=185,2=270.000000
L 3.795 5.3949997 3.79458346 5.39686644 2 P 0 ;0,1=185,2=270.000000
L 3.79458346 5.39686644 3.79333376 5.3989998 2 P 0 ;0,1=185,2=270.000000
L 3.79333376 5.3989998 3.79125089 5.40033337 2 P 0 ;0,1=185,2=270.000000
L 3.79125089 5.40033337 3.78833327 5.40086663 2 P 0 ;0,1=185,2=270.000000
L 3.78833327 5.40086663 3.78541722 5.40033337 2 P 0 ;0,1=185,2=270.000000
L 3.78541722 5.40033337 3.78291703 5.39873327 2 P 0 ;0,1=185,2=270.000000
L 3.78291703 5.39873327 3.78166654 5.39633327 2 P 0 ;0,1=185,2=270.000000
L 3.78166654 5.39633327 3.78166654 5.39366663 2 P 0 ;0,1=185,2=270.000000
L 3.78166654 5.39366663 3.78083337 5.39206654 2 P 0 ;0,1=185,2=270.000000
L 3.78083337 5.39206654 3.77875049 5.39073297 2 P 0 ;0,1=185,2=270.000000
L 3.77875049 5.39073297 3.77583366 5.3901998 2 P 0 ;0,1=185,2=270.000000
L 3.77583366 5.3901998 3.77291683 5.3910001 2 P 0 ;0,1=185,2=270.000000
L 3.77291683 5.3910001 3.77083317 5.39286634 2 P 0 ;0,1=185,2=270.000000
L 3.77083317 5.39286634 3.77 5.3949997 2 P 0 ;0,1=185,2=270.000000
L 3.77 5.3949997 3.77083317 5.39713307 2 P 0 ;0,1=185,2=270.000000
L 3.77083317 5.39713307 3.77291683 5.3989998 2 P 0 ;0,1=185,2=270.000000
L 3.77291683 5.3989998 3.77583366 5.3998001 2 P 0 ;0,1=185,2=270.000000
L 3.77583366 5.3998001 3.77875049 5.39926644 2 P 0 ;0,1=185,2=270.000000
L 3.77875049 5.39926644 3.78083337 5.39793337 2 P 0 ;0,1=185,2=270.000000
L 3.78083337 5.39793337 3.78166654 5.39633327 2 P 0 ;0,1=185,2=270.000000
L 3.78166654 5.39633327 3.78166654 5.39366663 2 P 0 ;0,1=185,2=270.000000
L 3.78166654 5.39366663 3.78291703 5.39126663 2 P 0 ;0,1=185,2=270.000000
L 3.78291703 5.39126663 3.78541722 5.38966654 2 P 0 ;0,1=185,2=270.000000
L 3.78541722 5.38966654 3.78833327 5.38913327 2 P 0 ;0,1=185,2=270.000000
L 3.78833327 5.38913327 3.79125089 5.38966654 2 P 0 ;0,1=185,2=270.000000
L 3.79125089 5.38966654 3.79333376 5.3910001 2 P 0 ;0,1=185,2=270.000000
L 3.79333376 5.3910001 3.79458346 5.39313346 2 P 0 ;0,1=185,2=270.000000
L 3.79458346 5.39313346 3.795 5.3949997 2 P 0 ;0,1=185,2=270.000000
L 3.79000039 5.41313327 3.79291713 5.41473297 2 P 0 ;0,1=185,2=270.000000
L 3.79291713 5.41473297 3.79458346 5.41686634 2 P 0 ;0,1=185,2=270.000000
L 3.79458346 5.41686634 3.795 5.41926683 2 P 0 ;0,1=185,2=270.000000
L 3.795 5.41926683 3.79458346 5.4214002 2 P 0 ;0,1=185,2=270.000000
L 3.79458346 5.4214002 3.79250059 5.42353356 2 P 0 ;0,1=185,2=270.000000
L 3.79250059 5.42353356 3.79000039 5.42486663 2 P 0 ;0,1=185,2=270.000000
L 3.79000039 5.42486663 3.7875001 5.42513317 2 P 0 ;0,1=185,2=270.000000
L 3.7875001 5.42513317 3.78458406 5.4246 2 P 0 ;0,1=185,2=270.000000
L 3.78458406 5.4246 3.78250039 5.42273327 2 P 0 ;0,1=185,2=270.000000
L 3.78250039 5.42273327 3.78166654 5.42086644 2 P 0 ;0,1=185,2=270.000000
L 3.78166654 5.42086644 3.78166654 5.41846654 2 P 0 ;0,1=185,2=270.000000
L 3.78166654 5.42086644 3.78041673 5.42246663 2 P 0 ;0,1=185,2=270.000000
L 3.78041673 5.42246663 3.77833386 5.4238001 2 P 0 ;0,1=185,2=270.000000
L 3.77833386 5.4238001 3.77583366 5.42433337 2 P 0 ;0,1=185,2=270.000000
L 3.77583366 5.42433337 3.77333346 5.4238001 2 P 0 ;0,1=185,2=270.000000
L 3.77333346 5.4238001 3.77125059 5.42246663 2 P 0 ;0,1=185,2=270.000000
L 3.77125059 5.42246663 3.77 5.42006663 2 P 0 ;0,1=185,2=270.000000
L 3.77 5.42006663 3.77041663 5.41766663 2 P 0 ;0,1=185,2=270.000000
L 3.77041663 5.41766663 3.77208366 5.41526663 2 P 0 ;0,1=185,2=270.000000
L 3.91776998 5.34198996 3.90203002 5.34198996 3 P 0 
L 3.835 5.31766654 3.81 5.31766654 2 P 0 ;0,1=186,2=270.000000
L 3.81 5.31766654 3.81 5.32433327 2 P 0 ;0,1=186,2=270.000000
L 3.81 5.32433327 3.81125059 5.32646663 2 P 0 ;0,1=186,2=270.000000
L 3.81125059 5.32646663 3.81291683 5.3278001 2 P 0 ;0,1=186,2=270.000000
L 3.81291683 5.3278001 3.8162502 5.32833337 2 P 0 ;0,1=186,2=270.000000
L 3.8162502 5.32833337 3.81958366 5.3278001 2 P 0 ;0,1=186,2=270.000000
L 3.81958366 5.3278001 3.82166654 5.3262 2 P 0 ;0,1=186,2=270.000000
L 3.82166654 5.3262 3.82291703 5.32433327 2 P 0 ;0,1=186,2=270.000000
L 3.82291703 5.32433327 3.82291703 5.31766654 2 P 0 ;0,1=186,2=270.000000
L 3.82291703 5.32433327 3.835 5.32833337 2 P 0 ;0,1=186,2=270.000000
L 3.835 5.3469997 3.81 5.3469997 2 P 0 ;0,1=186,2=270.000000
L 3.81 5.3469997 3.8149997 5.3437999 2 P 0 ;0,1=186,2=270.000000
L 3.835 5.3437999 3.835 5.35019951 2 P 0 ;0,1=186,2=270.000000
L 3.835 5.3742 3.81 5.3742 2 P 0 ;0,1=186,2=270.000000
L 3.81 5.3742 3.82791673 5.36433297 2 P 0 ;0,1=186,2=270.000000
L 3.82791673 5.36433297 3.82791673 5.37766693 2 P 0 ;0,1=186,2=270.000000
L 3.835 5.3949997 3.83458346 5.39686644 2 P 0 ;0,1=186,2=270.000000
L 3.83458346 5.39686644 3.83333376 5.3989998 2 P 0 ;0,1=186,2=270.000000
L 3.83333376 5.3989998 3.83125089 5.40033337 2 P 0 ;0,1=186,2=270.000000
L 3.83125089 5.40033337 3.82833327 5.40086663 2 P 0 ;0,1=186,2=270.000000
L 3.82833327 5.40086663 3.82541722 5.40033337 2 P 0 ;0,1=186,2=270.000000
L 3.82541722 5.40033337 3.82291703 5.39873327 2 P 0 ;0,1=186,2=270.000000
L 3.82291703 5.39873327 3.82166654 5.39633327 2 P 0 ;0,1=186,2=270.000000
L 3.82166654 5.39633327 3.82166654 5.39366663 2 P 0 ;0,1=186,2=270.000000
L 3.82166654 5.39366663 3.82083337 5.39206654 2 P 0 ;0,1=186,2=270.000000
L 3.82083337 5.39206654 3.81875049 5.39073297 2 P 0 ;0,1=186,2=270.000000
L 3.81875049 5.39073297 3.81583366 5.3901998 2 P 0 ;0,1=186,2=270.000000
L 3.81583366 5.3901998 3.81291683 5.3910001 2 P 0 ;0,1=186,2=270.000000
L 3.81291683 5.3910001 3.81083317 5.39286634 2 P 0 ;0,1=186,2=270.000000
L 3.81083317 5.39286634 3.81 5.3949997 2 P 0 ;0,1=186,2=270.000000
L 3.81 5.3949997 3.81083317 5.39713307 2 P 0 ;0,1=186,2=270.000000
L 3.81083317 5.39713307 3.81291683 5.3989998 2 P 0 ;0,1=186,2=270.000000
L 3.81291683 5.3989998 3.81583366 5.3998001 2 P 0 ;0,1=186,2=270.000000
L 3.81583366 5.3998001 3.81875049 5.39926644 2 P 0 ;0,1=186,2=270.000000
L 3.81875049 5.39926644 3.82083337 5.39793337 2 P 0 ;0,1=186,2=270.000000
L 3.82083337 5.39793337 3.82166654 5.39633327 2 P 0 ;0,1=186,2=270.000000
L 3.82166654 5.39633327 3.82166654 5.39366663 2 P 0 ;0,1=186,2=270.000000
L 3.82166654 5.39366663 3.82291703 5.39126663 2 P 0 ;0,1=186,2=270.000000
L 3.82291703 5.39126663 3.82541722 5.38966654 2 P 0 ;0,1=186,2=270.000000
L 3.82541722 5.38966654 3.82833327 5.38913327 2 P 0 ;0,1=186,2=270.000000
L 3.82833327 5.38913327 3.83125089 5.38966654 2 P 0 ;0,1=186,2=270.000000
L 3.83125089 5.38966654 3.83333376 5.3910001 2 P 0 ;0,1=186,2=270.000000
L 3.83333376 5.3910001 3.83458346 5.39313346 2 P 0 ;0,1=186,2=270.000000
L 3.83458346 5.39313346 3.835 5.3949997 2 P 0 ;0,1=186,2=270.000000
L 3.81416663 5.41393317 3.81166713 5.41553327 2 P 0 ;0,1=186,2=270.000000
L 3.81166713 5.41553327 3.81041663 5.4174 2 P 0 ;0,1=186,2=270.000000
L 3.81041663 5.4174 3.81 5.41953337 2 P 0 ;0,1=186,2=270.000000
L 3.81 5.41953337 3.81083317 5.4222 2 P 0 ;0,1=186,2=270.000000
L 3.81083317 5.4222 3.81291683 5.42406673 2 P 0 ;0,1=186,2=270.000000
L 3.81291683 5.42406673 3.81541634 5.4246 2 P 0 ;0,1=186,2=270.000000
L 3.81541634 5.4246 3.81791732 5.42433337 2 P 0 ;0,1=186,2=270.000000
L 3.81791732 5.42433337 3.8200002 5.42326644 2 P 0 ;0,1=186,2=270.000000
L 3.8200002 5.42326644 3.82416673 5.41793327 2 P 0 ;0,1=186,2=270.000000
L 3.82416673 5.41793327 3.82708356 5.41553327 2 P 0 ;0,1=186,2=270.000000
L 3.82708356 5.41553327 3.83125089 5.41393317 2 P 0 ;0,1=186,2=270.000000
L 3.83125089 5.41393317 3.835 5.4133999 2 P 0 ;0,1=186,2=270.000000
L 3.835 5.4133999 3.835 5.4246 2 P 0 ;0,1=186,2=270.000000
L 3.96776998 5.34198996 3.95203002 5.34198996 3 P 0 
L 4.11 5.28766654 4.085 5.28766654 2 P 0 ;0,1=187,2=270.000000
L 4.085 5.28766654 4.085 5.29433327 2 P 0 ;0,1=187,2=270.000000
L 4.085 5.29433327 4.08625059 5.29646663 2 P 0 ;0,1=187,2=270.000000
L 4.08625059 5.29646663 4.08791683 5.2978001 2 P 0 ;0,1=187,2=270.000000
L 4.08791683 5.2978001 4.0912502 5.29833337 2 P 0 ;0,1=187,2=270.000000
L 4.0912502 5.29833337 4.09458366 5.2978001 2 P 0 ;0,1=187,2=270.000000
L 4.09458366 5.2978001 4.09666654 5.2962 2 P 0 ;0,1=187,2=270.000000
L 4.09666654 5.2962 4.09791703 5.29433327 2 P 0 ;0,1=187,2=270.000000
L 4.09791703 5.29433327 4.09791703 5.28766654 2 P 0 ;0,1=187,2=270.000000
L 4.09791703 5.29433327 4.11 5.29833337 2 P 0 ;0,1=187,2=270.000000
L 4.11 5.3169997 4.085 5.3169997 2 P 0 ;0,1=187,2=270.000000
L 4.085 5.3169997 4.0899997 5.3137999 2 P 0 ;0,1=187,2=270.000000
L 4.11 5.3137999 4.11 5.32019951 2 P 0 ;0,1=187,2=270.000000
L 4.11 5.3442 4.085 5.3442 2 P 0 ;0,1=187,2=270.000000
L 4.085 5.3442 4.10291673 5.33433297 2 P 0 ;0,1=187,2=270.000000
L 4.10291673 5.33433297 4.10291673 5.34766693 2 P 0 ;0,1=187,2=270.000000
L 4.11 5.36446654 4.10458376 5.3649997 2 P 0 ;0,1=187,2=270.000000
L 4.10458376 5.3649997 4.10000069 5.3658 2 P 0 ;0,1=187,2=270.000000
L 4.10000069 5.3658 4.09583337 5.36686644 2 P 0 ;0,1=187,2=270.000000
L 4.09583337 5.36686644 4.0912502 5.3682 2 P 0 ;0,1=187,2=270.000000
L 4.0912502 5.3682 4.085 5.37033337 2 P 0 ;0,1=187,2=270.000000
L 4.085 5.37033337 4.085 5.35966654 2 P 0 ;0,1=187,2=270.000000
L 4.10500039 5.38313327 4.10791713 5.38473297 2 P 0 ;0,1=187,2=270.000000
L 4.10791713 5.38473297 4.10958346 5.38686634 2 P 0 ;0,1=187,2=270.000000
L 4.10958346 5.38686634 4.11 5.38926683 2 P 0 ;0,1=187,2=270.000000
L 4.11 5.38926683 4.10958346 5.3914002 2 P 0 ;0,1=187,2=270.000000
L 4.10958346 5.3914002 4.10750059 5.39353356 2 P 0 ;0,1=187,2=270.000000
L 4.10750059 5.39353356 4.10500039 5.39486663 2 P 0 ;0,1=187,2=270.000000
L 4.10500039 5.39486663 4.1025001 5.39513317 2 P 0 ;0,1=187,2=270.000000
L 4.1025001 5.39513317 4.09958406 5.3946 2 P 0 ;0,1=187,2=270.000000
L 4.09958406 5.3946 4.09750039 5.39273327 2 P 0 ;0,1=187,2=270.000000
L 4.09750039 5.39273327 4.09666654 5.39086644 2 P 0 ;0,1=187,2=270.000000
L 4.09666654 5.39086644 4.09666654 5.38846654 2 P 0 ;0,1=187,2=270.000000
L 4.09666654 5.39086644 4.09541673 5.39246663 2 P 0 ;0,1=187,2=270.000000
L 4.09541673 5.39246663 4.09333386 5.3938001 2 P 0 ;0,1=187,2=270.000000
L 4.09333386 5.3938001 4.09083366 5.39433337 2 P 0 ;0,1=187,2=270.000000
L 4.09083366 5.39433337 4.08833346 5.3938001 2 P 0 ;0,1=187,2=270.000000
L 4.08833346 5.3938001 4.08625059 5.39246663 2 P 0 ;0,1=187,2=270.000000
L 4.08625059 5.39246663 4.085 5.39006663 2 P 0 ;0,1=187,2=270.000000
L 4.085 5.39006663 4.08541663 5.38766663 2 P 0 ;0,1=187,2=270.000000
L 4.08541663 5.38766663 4.08708366 5.38526663 2 P 0 ;0,1=187,2=270.000000
L 0.74713002 5.4 0.76286998 5.4 3 P 0 
L 0.5 5.43266654 0.475 5.43266654 2 P 0 ;0,1=188,2=270.000000
L 0.475 5.43266654 0.475 5.43933327 2 P 0 ;0,1=188,2=270.000000
L 0.475 5.43933327 0.47625059 5.44146663 2 P 0 ;0,1=188,2=270.000000
L 0.47625059 5.44146663 0.47791683 5.4428001 2 P 0 ;0,1=188,2=270.000000
L 0.47791683 5.4428001 0.4812502 5.44333337 2 P 0 ;0,1=188,2=270.000000
L 0.4812502 5.44333337 0.48458366 5.4428001 2 P 0 ;0,1=188,2=270.000000
L 0.48458366 5.4428001 0.48666654 5.4412 2 P 0 ;0,1=188,2=270.000000
L 0.48666654 5.4412 0.48791703 5.43933327 2 P 0 ;0,1=188,2=270.000000
L 0.48791703 5.43933327 0.48791703 5.43266654 2 P 0 ;0,1=188,2=270.000000
L 0.48791703 5.43933327 0.5 5.44333337 2 P 0 ;0,1=188,2=270.000000
L 0.5 5.4619997 0.475 5.4619997 2 P 0 ;0,1=188,2=270.000000
L 0.475 5.4619997 0.4799997 5.4587999 2 P 0 ;0,1=188,2=270.000000
L 0.5 5.4587999 0.5 5.46519951 2 P 0 ;0,1=188,2=270.000000
L 0.5 5.4892 0.475 5.4892 2 P 0 ;0,1=188,2=270.000000
L 0.475 5.4892 0.49291673 5.47933297 2 P 0 ;0,1=188,2=270.000000
L 0.49291673 5.47933297 0.49291673 5.49266693 2 P 0 ;0,1=188,2=270.000000
L 0.49708396 5.50546634 0.49916693 5.50733317 2 P 0 ;0,1=188,2=270.000000
L 0.49916693 5.50733317 0.5 5.50946654 2 P 0 ;0,1=188,2=270.000000
L 0.5 5.50946654 0.49916693 5.5115999 2 P 0 ;0,1=188,2=270.000000
L 0.49916693 5.5115999 0.49666742 5.51346663 2 P 0 ;0,1=188,2=270.000000
L 0.49666742 5.51346663 0.49291673 5.5148001 2 P 0 ;0,1=188,2=270.000000
L 0.49291673 5.5148001 0.48916673 5.51533337 2 P 0 ;0,1=188,2=270.000000
L 0.48916673 5.51533337 0.48458366 5.51533337 2 P 0 ;0,1=188,2=270.000000
L 0.48458366 5.51533337 0.48083366 5.5148001 2 P 0 ;0,1=188,2=270.000000
L 0.48083366 5.5148001 0.4775003 5.51346663 2 P 0 ;0,1=188,2=270.000000
L 0.4775003 5.51346663 0.47583317 5.51186644 2 P 0 ;0,1=188,2=270.000000
L 0.47583317 5.51186644 0.475 5.5099997 2 P 0 ;0,1=188,2=270.000000
L 0.475 5.5099997 0.47583317 5.50786634 2 P 0 ;0,1=188,2=270.000000
L 0.47583317 5.50786634 0.4775003 5.50626663 2 P 0 ;0,1=188,2=270.000000
L 0.4775003 5.50626663 0.4799997 5.5051998 2 P 0 ;0,1=188,2=270.000000
L 0.4799997 5.5051998 0.48333386 5.50466654 2 P 0 ;0,1=188,2=270.000000
L 0.48333386 5.50466654 0.4862499 5.5051998 2 P 0 ;0,1=188,2=270.000000
L 0.4862499 5.5051998 0.48916673 5.50653327 2 P 0 ;0,1=188,2=270.000000
L 0.48916673 5.50653327 0.49083386 5.50813346 2 P 0 ;0,1=188,2=270.000000
L 0.49083386 5.50813346 0.49125039 5.5099997 2 P 0 ;0,1=188,2=270.000000
L 0.49125039 5.5099997 0.49041722 5.51213307 2 P 0 ;0,1=188,2=270.000000
L 0.49041722 5.51213307 0.48833356 5.51373327 2 P 0 ;0,1=188,2=270.000000
L 0.48833356 5.51373327 0.48458366 5.51533337 2 P 0 ;0,1=188,2=270.000000
L 0.5 5.5339997 0.475 5.5339997 2 P 0 ;0,1=188,2=270.000000
L 0.475 5.5339997 0.4799997 5.5307999 2 P 0 ;0,1=188,2=270.000000
L 0.5 5.5307999 0.5 5.53719951 2 P 0 ;0,1=188,2=270.000000
L 3.67786004 0.7581 3.66211998 0.7581 3 P 0 
L 3.685 0.80766654 3.66 0.80766654 2 P 0 ;0,1=189,2=270.000000
L 3.66 0.80766654 3.66 0.81433327 2 P 0 ;0,1=189,2=270.000000
L 3.66 0.81433327 3.66125059 0.81646663 2 P 0 ;0,1=189,2=270.000000
L 3.66125059 0.81646663 3.66291683 0.8178001 2 P 0 ;0,1=189,2=270.000000
L 3.66291683 0.8178001 3.6662502 0.81833337 2 P 0 ;0,1=189,2=270.000000
L 3.6662502 0.81833337 3.66958366 0.8178001 2 P 0 ;0,1=189,2=270.000000
L 3.66958366 0.8178001 3.67166654 0.8162 2 P 0 ;0,1=189,2=270.000000
L 3.67166654 0.8162 3.67291703 0.81433327 2 P 0 ;0,1=189,2=270.000000
L 3.67291703 0.81433327 3.67291703 0.80766654 2 P 0 ;0,1=189,2=270.000000
L 3.67291703 0.81433327 3.685 0.81833337 2 P 0 ;0,1=189,2=270.000000
L 3.685 0.83646654 3.67958376 0.8369997 2 P 0 ;0,1=189,2=270.000000
L 3.67958376 0.8369997 3.67500069 0.8378 2 P 0 ;0,1=189,2=270.000000
L 3.67500069 0.8378 3.67083337 0.83886644 2 P 0 ;0,1=189,2=270.000000
L 3.67083337 0.83886644 3.6662502 0.8402 2 P 0 ;0,1=189,2=270.000000
L 3.6662502 0.8402 3.66 0.84233337 2 P 0 ;0,1=189,2=270.000000
L 3.66 0.84233337 3.66 0.83166654 2 P 0 ;0,1=189,2=270.000000
L 3.68000039 0.85513327 3.68291713 0.85673297 2 P 0 ;0,1=189,2=270.000000
L 3.68291713 0.85673297 3.68458346 0.85886634 2 P 0 ;0,1=189,2=270.000000
L 3.68458346 0.85886634 3.685 0.86126683 2 P 0 ;0,1=189,2=270.000000
L 3.685 0.86126683 3.68458346 0.8634002 2 P 0 ;0,1=189,2=270.000000
L 3.68458346 0.8634002 3.68250059 0.86553356 2 P 0 ;0,1=189,2=270.000000
L 3.68250059 0.86553356 3.68000039 0.86686663 2 P 0 ;0,1=189,2=270.000000
L 3.68000039 0.86686663 3.6775001 0.86713317 2 P 0 ;0,1=189,2=270.000000
L 3.6775001 0.86713317 3.67458406 0.8666 2 P 0 ;0,1=189,2=270.000000
L 3.67458406 0.8666 3.67250039 0.86473327 2 P 0 ;0,1=189,2=270.000000
L 3.67250039 0.86473327 3.67166654 0.86286644 2 P 0 ;0,1=189,2=270.000000
L 3.67166654 0.86286644 3.67166654 0.86046654 2 P 0 ;0,1=189,2=270.000000
L 3.67166654 0.86286644 3.67041673 0.86446663 2 P 0 ;0,1=189,2=270.000000
L 3.67041673 0.86446663 3.66833386 0.8658001 2 P 0 ;0,1=189,2=270.000000
L 3.66833386 0.8658001 3.66583366 0.86633337 2 P 0 ;0,1=189,2=270.000000
L 3.66583366 0.86633337 3.66333346 0.8658001 2 P 0 ;0,1=189,2=270.000000
L 3.66333346 0.8658001 3.66125059 0.86446663 2 P 0 ;0,1=189,2=270.000000
L 3.66125059 0.86446663 3.66 0.86206663 2 P 0 ;0,1=189,2=270.000000
L 3.66 0.86206663 3.66041663 0.85966663 2 P 0 ;0,1=189,2=270.000000
L 3.66041663 0.85966663 3.66208366 0.85726663 2 P 0 ;0,1=189,2=270.000000
L 3.685 0.8849997 3.68458346 0.88686644 2 P 0 ;0,1=189,2=270.000000
L 3.68458346 0.88686644 3.68333376 0.8889998 2 P 0 ;0,1=189,2=270.000000
L 3.68333376 0.8889998 3.68125089 0.89033337 2 P 0 ;0,1=189,2=270.000000
L 3.68125089 0.89033337 3.67833327 0.89086663 2 P 0 ;0,1=189,2=270.000000
L 3.67833327 0.89086663 3.67541722 0.89033337 2 P 0 ;0,1=189,2=270.000000
L 3.67541722 0.89033337 3.67291703 0.88873327 2 P 0 ;0,1=189,2=270.000000
L 3.67291703 0.88873327 3.67166654 0.88633327 2 P 0 ;0,1=189,2=270.000000
L 3.67166654 0.88633327 3.67166654 0.88366663 2 P 0 ;0,1=189,2=270.000000
L 3.67166654 0.88366663 3.67083337 0.88206654 2 P 0 ;0,1=189,2=270.000000
L 3.67083337 0.88206654 3.66875049 0.88073297 2 P 0 ;0,1=189,2=270.000000
L 3.66875049 0.88073297 3.66583366 0.8801998 2 P 0 ;0,1=189,2=270.000000
L 3.66583366 0.8801998 3.66291683 0.8810001 2 P 0 ;0,1=189,2=270.000000
L 3.66291683 0.8810001 3.66083317 0.88286634 2 P 0 ;0,1=189,2=270.000000
L 3.66083317 0.88286634 3.66 0.8849997 2 P 0 ;0,1=189,2=270.000000
L 3.66 0.8849997 3.66083317 0.88713307 2 P 0 ;0,1=189,2=270.000000
L 3.66083317 0.88713307 3.66291683 0.8889998 2 P 0 ;0,1=189,2=270.000000
L 3.66291683 0.8889998 3.66583366 0.8898001 2 P 0 ;0,1=189,2=270.000000
L 3.66583366 0.8898001 3.66875049 0.88926644 2 P 0 ;0,1=189,2=270.000000
L 3.66875049 0.88926644 3.67083337 0.88793337 2 P 0 ;0,1=189,2=270.000000
L 3.67083337 0.88793337 3.67166654 0.88633327 2 P 0 ;0,1=189,2=270.000000
L 3.67166654 0.88633327 3.67166654 0.88366663 2 P 0 ;0,1=189,2=270.000000
L 3.67166654 0.88366663 3.67291703 0.88126663 2 P 0 ;0,1=189,2=270.000000
L 3.67291703 0.88126663 3.67541722 0.87966654 2 P 0 ;0,1=189,2=270.000000
L 3.67541722 0.87966654 3.67833327 0.87913327 2 P 0 ;0,1=189,2=270.000000
L 3.67833327 0.87913327 3.68125089 0.87966654 2 P 0 ;0,1=189,2=270.000000
L 3.68125089 0.87966654 3.68333376 0.8810001 2 P 0 ;0,1=189,2=270.000000
L 3.68333376 0.8810001 3.68458346 0.88313346 2 P 0 ;0,1=189,2=270.000000
L 3.68458346 0.88313346 3.685 0.8849997 2 P 0 ;0,1=189,2=270.000000
L 3.61786004 0.7581 3.60211998 0.7581 3 P 0 
L 3.625 0.80766654 3.6 0.80766654 2 P 0 ;0,1=190,2=270.000000
L 3.6 0.80766654 3.6 0.81433327 2 P 0 ;0,1=190,2=270.000000
L 3.6 0.81433327 3.60125059 0.81646663 2 P 0 ;0,1=190,2=270.000000
L 3.60125059 0.81646663 3.60291683 0.8178001 2 P 0 ;0,1=190,2=270.000000
L 3.60291683 0.8178001 3.6062502 0.81833337 2 P 0 ;0,1=190,2=270.000000
L 3.6062502 0.81833337 3.60958366 0.8178001 2 P 0 ;0,1=190,2=270.000000
L 3.60958366 0.8178001 3.61166654 0.8162 2 P 0 ;0,1=190,2=270.000000
L 3.61166654 0.8162 3.61291703 0.81433327 2 P 0 ;0,1=190,2=270.000000
L 3.61291703 0.81433327 3.61291703 0.80766654 2 P 0 ;0,1=190,2=270.000000
L 3.61291703 0.81433327 3.625 0.81833337 2 P 0 ;0,1=190,2=270.000000
L 3.625 0.83646654 3.61958376 0.8369997 2 P 0 ;0,1=190,2=270.000000
L 3.61958376 0.8369997 3.61500069 0.8378 2 P 0 ;0,1=190,2=270.000000
L 3.61500069 0.8378 3.61083337 0.83886644 2 P 0 ;0,1=190,2=270.000000
L 3.61083337 0.83886644 3.6062502 0.8402 2 P 0 ;0,1=190,2=270.000000
L 3.6062502 0.8402 3.6 0.84233337 2 P 0 ;0,1=190,2=270.000000
L 3.6 0.84233337 3.6 0.83166654 2 P 0 ;0,1=190,2=270.000000
L 3.62000039 0.85513327 3.62291713 0.85673297 2 P 0 ;0,1=190,2=270.000000
L 3.62291713 0.85673297 3.62458346 0.85886634 2 P 0 ;0,1=190,2=270.000000
L 3.62458346 0.85886634 3.625 0.86126683 2 P 0 ;0,1=190,2=270.000000
L 3.625 0.86126683 3.62458346 0.8634002 2 P 0 ;0,1=190,2=270.000000
L 3.62458346 0.8634002 3.62250059 0.86553356 2 P 0 ;0,1=190,2=270.000000
L 3.62250059 0.86553356 3.62000039 0.86686663 2 P 0 ;0,1=190,2=270.000000
L 3.62000039 0.86686663 3.6175001 0.86713317 2 P 0 ;0,1=190,2=270.000000
L 3.6175001 0.86713317 3.61458406 0.8666 2 P 0 ;0,1=190,2=270.000000
L 3.61458406 0.8666 3.61250039 0.86473327 2 P 0 ;0,1=190,2=270.000000
L 3.61250039 0.86473327 3.61166654 0.86286644 2 P 0 ;0,1=190,2=270.000000
L 3.61166654 0.86286644 3.61166654 0.86046654 2 P 0 ;0,1=190,2=270.000000
L 3.61166654 0.86286644 3.61041673 0.86446663 2 P 0 ;0,1=190,2=270.000000
L 3.61041673 0.86446663 3.60833386 0.8658001 2 P 0 ;0,1=190,2=270.000000
L 3.60833386 0.8658001 3.60583366 0.86633337 2 P 0 ;0,1=190,2=270.000000
L 3.60583366 0.86633337 3.60333346 0.8658001 2 P 0 ;0,1=190,2=270.000000
L 3.60333346 0.8658001 3.60125059 0.86446663 2 P 0 ;0,1=190,2=270.000000
L 3.60125059 0.86446663 3.6 0.86206663 2 P 0 ;0,1=190,2=270.000000
L 3.6 0.86206663 3.60041663 0.85966663 2 P 0 ;0,1=190,2=270.000000
L 3.60041663 0.85966663 3.60208366 0.85726663 2 P 0 ;0,1=190,2=270.000000
L 3.625 0.88446654 3.61958376 0.8849997 2 P 0 ;0,1=190,2=270.000000
L 3.61958376 0.8849997 3.61500069 0.8858 2 P 0 ;0,1=190,2=270.000000
L 3.61500069 0.8858 3.61083337 0.88686644 2 P 0 ;0,1=190,2=270.000000
L 3.61083337 0.88686644 3.6062502 0.8882 2 P 0 ;0,1=190,2=270.000000
L 3.6062502 0.8882 3.6 0.89033337 2 P 0 ;0,1=190,2=270.000000
L 3.6 0.89033337 3.6 0.87966654 2 P 0 ;0,1=190,2=270.000000
L 3.75211998 0.2881 3.76786004 0.2881 3 P 0 
L 3.77 0.13766654 3.745 0.13766654 2 P 0 ;0,1=191,2=270.000000
L 3.745 0.13766654 3.745 0.14433327 2 P 0 ;0,1=191,2=270.000000
L 3.745 0.14433327 3.74625059 0.14646663 2 P 0 ;0,1=191,2=270.000000
L 3.74625059 0.14646663 3.74791683 0.1478001 2 P 0 ;0,1=191,2=270.000000
L 3.74791683 0.1478001 3.7512502 0.14833337 2 P 0 ;0,1=191,2=270.000000
L 3.7512502 0.14833337 3.75458366 0.1478001 2 P 0 ;0,1=191,2=270.000000
L 3.75458366 0.1478001 3.75666654 0.1462 2 P 0 ;0,1=191,2=270.000000
L 3.75666654 0.1462 3.75791703 0.14433327 2 P 0 ;0,1=191,2=270.000000
L 3.75791703 0.14433327 3.75791703 0.13766654 2 P 0 ;0,1=191,2=270.000000
L 3.75791703 0.14433327 3.77 0.14833337 2 P 0 ;0,1=191,2=270.000000
L 3.77 0.16646654 3.76458376 0.1669997 2 P 0 ;0,1=191,2=270.000000
L 3.76458376 0.1669997 3.76000069 0.1678 2 P 0 ;0,1=191,2=270.000000
L 3.76000069 0.1678 3.75583337 0.16886644 2 P 0 ;0,1=191,2=270.000000
L 3.75583337 0.16886644 3.7512502 0.1702 2 P 0 ;0,1=191,2=270.000000
L 3.7512502 0.1702 3.745 0.17233337 2 P 0 ;0,1=191,2=270.000000
L 3.745 0.17233337 3.745 0.16166654 2 P 0 ;0,1=191,2=270.000000
L 3.74916663 0.18593317 3.74666713 0.18753327 2 P 0 ;0,1=191,2=270.000000
L 3.74666713 0.18753327 3.74541663 0.1894 2 P 0 ;0,1=191,2=270.000000
L 3.74541663 0.1894 3.745 0.19153337 2 P 0 ;0,1=191,2=270.000000
L 3.745 0.19153337 3.74583317 0.1942 2 P 0 ;0,1=191,2=270.000000
L 3.74583317 0.1942 3.74791683 0.19606673 2 P 0 ;0,1=191,2=270.000000
L 3.74791683 0.19606673 3.75041634 0.1966 2 P 0 ;0,1=191,2=270.000000
L 3.75041634 0.1966 3.75291732 0.19633337 2 P 0 ;0,1=191,2=270.000000
L 3.75291732 0.19633337 3.7550002 0.19526644 2 P 0 ;0,1=191,2=270.000000
L 3.7550002 0.19526644 3.75916673 0.18993327 2 P 0 ;0,1=191,2=270.000000
L 3.75916673 0.18993327 3.76208356 0.18753327 2 P 0 ;0,1=191,2=270.000000
L 3.76208356 0.18753327 3.76625089 0.18593317 2 P 0 ;0,1=191,2=270.000000
L 3.76625089 0.18593317 3.77 0.1853999 2 P 0 ;0,1=191,2=270.000000
L 3.77 0.1853999 3.77 0.1966 2 P 0 ;0,1=191,2=270.000000
L 3.74916663 0.20993317 3.74666713 0.21153327 2 P 0 ;0,1=191,2=270.000000
L 3.74666713 0.21153327 3.74541663 0.2134 2 P 0 ;0,1=191,2=270.000000
L 3.74541663 0.2134 3.745 0.21553337 2 P 0 ;0,1=191,2=270.000000
L 3.745 0.21553337 3.74583317 0.2182 2 P 0 ;0,1=191,2=270.000000
L 3.74583317 0.2182 3.74791683 0.22006673 2 P 0 ;0,1=191,2=270.000000
L 3.74791683 0.22006673 3.75041634 0.2206 2 P 0 ;0,1=191,2=270.000000
L 3.75041634 0.2206 3.75291732 0.22033337 2 P 0 ;0,1=191,2=270.000000
L 3.75291732 0.22033337 3.7550002 0.21926644 2 P 0 ;0,1=191,2=270.000000
L 3.7550002 0.21926644 3.75916673 0.21393327 2 P 0 ;0,1=191,2=270.000000
L 3.75916673 0.21393327 3.76208356 0.21153327 2 P 0 ;0,1=191,2=270.000000
L 3.76208356 0.21153327 3.76625089 0.20993317 2 P 0 ;0,1=191,2=270.000000
L 3.76625089 0.20993317 3.77 0.2093999 2 P 0 ;0,1=191,2=270.000000
L 3.77 0.2093999 3.77 0.2206 2 P 0 ;0,1=191,2=270.000000
L 9.55008002 0.30943002 9.56581998 0.30943002 3 P 0 
L 9.57 0.12766654 9.545 0.12766654 2 P 0 ;0,1=192,2=270.000000
L 9.545 0.12766654 9.545 0.13433327 2 P 0 ;0,1=192,2=270.000000
L 9.545 0.13433327 9.54625059 0.13646663 2 P 0 ;0,1=192,2=270.000000
L 9.54625059 0.13646663 9.54791683 0.1378001 2 P 0 ;0,1=192,2=270.000000
L 9.54791683 0.1378001 9.5512502 0.13833337 2 P 0 ;0,1=192,2=270.000000
L 9.5512502 0.13833337 9.55458366 0.1378001 2 P 0 ;0,1=192,2=270.000000
L 9.55458366 0.1378001 9.55666654 0.1362 2 P 0 ;0,1=192,2=270.000000
L 9.55666654 0.1362 9.55791703 0.13433327 2 P 0 ;0,1=192,2=270.000000
L 9.55791703 0.13433327 9.55791703 0.12766654 2 P 0 ;0,1=192,2=270.000000
L 9.55791703 0.13433327 9.57 0.13833337 2 P 0 ;0,1=192,2=270.000000
L 9.57 0.1569997 9.545 0.1569997 2 P 0 ;0,1=192,2=270.000000
L 9.545 0.1569997 9.5499997 0.1537999 2 P 0 ;0,1=192,2=270.000000
L 9.57 0.1537999 9.57 0.16019951 2 P 0 ;0,1=192,2=270.000000
L 9.56625089 0.17513327 9.56833376 0.17673297 2 P 0 ;0,1=192,2=270.000000
L 9.56833376 0.17673297 9.56958346 0.1785997 2 P 0 ;0,1=192,2=270.000000
L 9.56958346 0.1785997 9.57 0.1809997 2 P 0 ;0,1=192,2=270.000000
L 9.57 0.1809997 9.56916693 0.1834002 2 P 0 ;0,1=192,2=270.000000
L 9.56916693 0.1834002 9.56750059 0.18526644 2 P 0 ;0,1=192,2=270.000000
L 9.56750059 0.18526644 9.56458376 0.1866 2 P 0 ;0,1=192,2=270.000000
L 9.56458376 0.1866 9.56125039 0.18686663 2 P 0 ;0,1=192,2=270.000000
L 9.56125039 0.18686663 9.55791703 0.18633337 2 P 0 ;0,1=192,2=270.000000
L 9.55791703 0.18633337 9.55583337 0.1849998 2 P 0 ;0,1=192,2=270.000000
L 9.55583337 0.1849998 9.55416703 0.18313307 2 P 0 ;0,1=192,2=270.000000
L 9.55416703 0.18313307 9.55375049 0.18126683 2 P 0 ;0,1=192,2=270.000000
L 9.55375049 0.18126683 9.55416703 0.1794 2 P 0 ;0,1=192,2=270.000000
L 9.55416703 0.1794 9.55583337 0.1770001 2 P 0 ;0,1=192,2=270.000000
L 9.55583337 0.1770001 9.545 0.1777999 2 P 0 ;0,1=192,2=270.000000
L 9.545 0.1777999 9.545 0.1849998 2 P 0 ;0,1=192,2=270.000000
L 9.54916663 0.19993317 9.54666713 0.20153327 2 P 0 ;0,1=192,2=270.000000
L 9.54666713 0.20153327 9.54541663 0.2034 2 P 0 ;0,1=192,2=270.000000
L 9.54541663 0.2034 9.545 0.20553337 2 P 0 ;0,1=192,2=270.000000
L 9.545 0.20553337 9.54583317 0.2082 2 P 0 ;0,1=192,2=270.000000
L 9.54583317 0.2082 9.54791683 0.21006673 2 P 0 ;0,1=192,2=270.000000
L 9.54791683 0.21006673 9.55041634 0.2106 2 P 0 ;0,1=192,2=270.000000
L 9.55041634 0.2106 9.55291732 0.21033337 2 P 0 ;0,1=192,2=270.000000
L 9.55291732 0.21033337 9.5550002 0.20926644 2 P 0 ;0,1=192,2=270.000000
L 9.5550002 0.20926644 9.55916673 0.20393327 2 P 0 ;0,1=192,2=270.000000
L 9.55916673 0.20393327 9.56208356 0.20153327 2 P 0 ;0,1=192,2=270.000000
L 9.56208356 0.20153327 9.56625089 0.19993317 2 P 0 ;0,1=192,2=270.000000
L 9.56625089 0.19993317 9.57 0.1993999 2 P 0 ;0,1=192,2=270.000000
L 9.57 0.1993999 9.57 0.2106 2 P 0 ;0,1=192,2=270.000000
L 9.545 0.2289997 9.54583317 0.22686634 2 P 0 ;0,1=192,2=270.000000
L 9.54583317 0.22686634 9.54791683 0.22526663 2 P 0 ;0,1=192,2=270.000000
L 9.54791683 0.22526663 9.55041634 0.2241998 2 P 0 ;0,1=192,2=270.000000
L 9.55041634 0.2241998 9.55375049 0.2233999 2 P 0 ;0,1=192,2=270.000000
L 9.55375049 0.2233999 9.55750039 0.22313327 2 P 0 ;0,1=192,2=270.000000
L 9.55750039 0.22313327 9.56125039 0.2233999 2 P 0 ;0,1=192,2=270.000000
L 9.56125039 0.2233999 9.56458376 0.2241998 2 P 0 ;0,1=192,2=270.000000
L 9.56458376 0.2241998 9.56708396 0.22526663 2 P 0 ;0,1=192,2=270.000000
L 9.56708396 0.22526663 9.56916693 0.22686634 2 P 0 ;0,1=192,2=270.000000
L 9.56916693 0.22686634 9.57 0.2289997 2 P 0 ;0,1=192,2=270.000000
L 9.57 0.2289997 9.56916693 0.23113307 2 P 0 ;0,1=192,2=270.000000
L 9.56916693 0.23113307 9.56708396 0.23273327 2 P 0 ;0,1=192,2=270.000000
L 9.56708396 0.23273327 9.56458376 0.2338001 2 P 0 ;0,1=192,2=270.000000
L 9.56458376 0.2338001 9.56125039 0.2346 2 P 0 ;0,1=192,2=270.000000
L 9.56125039 0.2346 9.55750039 0.23486663 2 P 0 ;0,1=192,2=270.000000
L 9.55750039 0.23486663 9.55375049 0.2346 2 P 0 ;0,1=192,2=270.000000
L 9.55375049 0.2346 9.55041634 0.2338001 2 P 0 ;0,1=192,2=270.000000
L 9.55041634 0.2338001 9.54791683 0.23273327 2 P 0 ;0,1=192,2=270.000000
L 9.54791683 0.23273327 9.54583317 0.23113307 2 P 0 ;0,1=192,2=270.000000
L 9.54583317 0.23113307 9.545 0.2289997 2 P 0 ;0,1=192,2=270.000000
L 9.41581998 0.77943002 9.40008002 0.77943002 3 P 0 
L 9.42 0.84266654 9.395 0.84266654 2 P 0 ;0,1=193,2=270.000000
L 9.395 0.84266654 9.395 0.84933327 2 P 0 ;0,1=193,2=270.000000
L 9.395 0.84933327 9.39625059 0.85146663 2 P 0 ;0,1=193,2=270.000000
L 9.39625059 0.85146663 9.39791683 0.8528001 2 P 0 ;0,1=193,2=270.000000
L 9.39791683 0.8528001 9.4012502 0.85333337 2 P 0 ;0,1=193,2=270.000000
L 9.4012502 0.85333337 9.40458366 0.8528001 2 P 0 ;0,1=193,2=270.000000
L 9.40458366 0.8528001 9.40666654 0.8512 2 P 0 ;0,1=193,2=270.000000
L 9.40666654 0.8512 9.40791703 0.84933327 2 P 0 ;0,1=193,2=270.000000
L 9.40791703 0.84933327 9.40791703 0.84266654 2 P 0 ;0,1=193,2=270.000000
L 9.40791703 0.84933327 9.42 0.85333337 2 P 0 ;0,1=193,2=270.000000
L 9.42 0.8719997 9.395 0.8719997 2 P 0 ;0,1=193,2=270.000000
L 9.395 0.8719997 9.3999997 0.8687999 2 P 0 ;0,1=193,2=270.000000
L 9.42 0.8687999 9.42 0.87519951 2 P 0 ;0,1=193,2=270.000000
L 9.41625089 0.89013327 9.41833376 0.89173297 2 P 0 ;0,1=193,2=270.000000
L 9.41833376 0.89173297 9.41958346 0.8935997 2 P 0 ;0,1=193,2=270.000000
L 9.41958346 0.8935997 9.42 0.8959997 2 P 0 ;0,1=193,2=270.000000
L 9.42 0.8959997 9.41916693 0.8984002 2 P 0 ;0,1=193,2=270.000000
L 9.41916693 0.8984002 9.41750059 0.90026644 2 P 0 ;0,1=193,2=270.000000
L 9.41750059 0.90026644 9.41458376 0.9016 2 P 0 ;0,1=193,2=270.000000
L 9.41458376 0.9016 9.41125039 0.90186663 2 P 0 ;0,1=193,2=270.000000
L 9.41125039 0.90186663 9.40791703 0.90133337 2 P 0 ;0,1=193,2=270.000000
L 9.40791703 0.90133337 9.40583337 0.8999998 2 P 0 ;0,1=193,2=270.000000
L 9.40583337 0.8999998 9.40416703 0.89813307 2 P 0 ;0,1=193,2=270.000000
L 9.40416703 0.89813307 9.40375049 0.89626683 2 P 0 ;0,1=193,2=270.000000
L 9.40375049 0.89626683 9.40416703 0.8944 2 P 0 ;0,1=193,2=270.000000
L 9.40416703 0.8944 9.40583337 0.8920001 2 P 0 ;0,1=193,2=270.000000
L 9.40583337 0.8920001 9.395 0.8927999 2 P 0 ;0,1=193,2=270.000000
L 9.395 0.8927999 9.395 0.8999998 2 P 0 ;0,1=193,2=270.000000
L 9.42 0.9199997 9.395 0.9199997 2 P 0 ;0,1=193,2=270.000000
L 9.395 0.9199997 9.3999997 0.9167999 2 P 0 ;0,1=193,2=270.000000
L 9.42 0.9167999 9.42 0.92319951 2 P 0 ;0,1=193,2=270.000000
L 9.41708396 0.93946634 9.41916693 0.94133317 2 P 0 ;0,1=193,2=270.000000
L 9.41916693 0.94133317 9.42 0.94346654 2 P 0 ;0,1=193,2=270.000000
L 9.42 0.94346654 9.41916693 0.9455999 2 P 0 ;0,1=193,2=270.000000
L 9.41916693 0.9455999 9.41666742 0.94746663 2 P 0 ;0,1=193,2=270.000000
L 9.41666742 0.94746663 9.41291673 0.9488001 2 P 0 ;0,1=193,2=270.000000
L 9.41291673 0.9488001 9.40916673 0.94933337 2 P 0 ;0,1=193,2=270.000000
L 9.40916673 0.94933337 9.40458366 0.94933337 2 P 0 ;0,1=193,2=270.000000
L 9.40458366 0.94933337 9.40083366 0.9488001 2 P 0 ;0,1=193,2=270.000000
L 9.40083366 0.9488001 9.3975003 0.94746663 2 P 0 ;0,1=193,2=270.000000
L 9.3975003 0.94746663 9.39583317 0.94586644 2 P 0 ;0,1=193,2=270.000000
L 9.39583317 0.94586644 9.395 0.9439997 2 P 0 ;0,1=193,2=270.000000
L 9.395 0.9439997 9.39583317 0.94186634 2 P 0 ;0,1=193,2=270.000000
L 9.39583317 0.94186634 9.3975003 0.94026663 2 P 0 ;0,1=193,2=270.000000
L 9.3975003 0.94026663 9.3999997 0.9391998 2 P 0 ;0,1=193,2=270.000000
L 9.3999997 0.9391998 9.40333386 0.93866654 2 P 0 ;0,1=193,2=270.000000
L 9.40333386 0.93866654 9.4062499 0.9391998 2 P 0 ;0,1=193,2=270.000000
L 9.4062499 0.9391998 9.40916673 0.94053327 2 P 0 ;0,1=193,2=270.000000
L 9.40916673 0.94053327 9.41083386 0.94213346 2 P 0 ;0,1=193,2=270.000000
L 9.41083386 0.94213346 9.41125039 0.9439997 2 P 0 ;0,1=193,2=270.000000
L 9.41125039 0.9439997 9.41041722 0.94613307 2 P 0 ;0,1=193,2=270.000000
L 9.41041722 0.94613307 9.40833356 0.94773327 2 P 0 ;0,1=193,2=270.000000
L 9.40833356 0.94773327 9.40458366 0.94933337 2 P 0 ;0,1=193,2=270.000000
L 9.47581998 0.77943002 9.46008002 0.77943002 3 P 0 
L 9.48 0.84266654 9.455 0.84266654 2 P 0 ;0,1=194,2=270.000000
L 9.455 0.84266654 9.455 0.84933327 2 P 0 ;0,1=194,2=270.000000
L 9.455 0.84933327 9.45625059 0.85146663 2 P 0 ;0,1=194,2=270.000000
L 9.45625059 0.85146663 9.45791683 0.8528001 2 P 0 ;0,1=194,2=270.000000
L 9.45791683 0.8528001 9.4612502 0.85333337 2 P 0 ;0,1=194,2=270.000000
L 9.4612502 0.85333337 9.46458366 0.8528001 2 P 0 ;0,1=194,2=270.000000
L 9.46458366 0.8528001 9.46666654 0.8512 2 P 0 ;0,1=194,2=270.000000
L 9.46666654 0.8512 9.46791703 0.84933327 2 P 0 ;0,1=194,2=270.000000
L 9.46791703 0.84933327 9.46791703 0.84266654 2 P 0 ;0,1=194,2=270.000000
L 9.46791703 0.84933327 9.48 0.85333337 2 P 0 ;0,1=194,2=270.000000
L 9.48 0.8719997 9.455 0.8719997 2 P 0 ;0,1=194,2=270.000000
L 9.455 0.8719997 9.4599997 0.8687999 2 P 0 ;0,1=194,2=270.000000
L 9.48 0.8687999 9.48 0.87519951 2 P 0 ;0,1=194,2=270.000000
L 9.47625089 0.89013327 9.47833376 0.89173297 2 P 0 ;0,1=194,2=270.000000
L 9.47833376 0.89173297 9.47958346 0.8935997 2 P 0 ;0,1=194,2=270.000000
L 9.47958346 0.8935997 9.48 0.8959997 2 P 0 ;0,1=194,2=270.000000
L 9.48 0.8959997 9.47916693 0.8984002 2 P 0 ;0,1=194,2=270.000000
L 9.47916693 0.8984002 9.47750059 0.90026644 2 P 0 ;0,1=194,2=270.000000
L 9.47750059 0.90026644 9.47458376 0.9016 2 P 0 ;0,1=194,2=270.000000
L 9.47458376 0.9016 9.47125039 0.90186663 2 P 0 ;0,1=194,2=270.000000
L 9.47125039 0.90186663 9.46791703 0.90133337 2 P 0 ;0,1=194,2=270.000000
L 9.46791703 0.90133337 9.46583337 0.8999998 2 P 0 ;0,1=194,2=270.000000
L 9.46583337 0.8999998 9.46416703 0.89813307 2 P 0 ;0,1=194,2=270.000000
L 9.46416703 0.89813307 9.46375049 0.89626683 2 P 0 ;0,1=194,2=270.000000
L 9.46375049 0.89626683 9.46416703 0.8944 2 P 0 ;0,1=194,2=270.000000
L 9.46416703 0.8944 9.46583337 0.8920001 2 P 0 ;0,1=194,2=270.000000
L 9.46583337 0.8920001 9.455 0.8927999 2 P 0 ;0,1=194,2=270.000000
L 9.455 0.8927999 9.455 0.8999998 2 P 0 ;0,1=194,2=270.000000
L 9.48 0.9199997 9.455 0.9199997 2 P 0 ;0,1=194,2=270.000000
L 9.455 0.9199997 9.4599997 0.9167999 2 P 0 ;0,1=194,2=270.000000
L 9.48 0.9167999 9.48 0.92319951 2 P 0 ;0,1=194,2=270.000000
L 9.48 0.9439997 9.47958346 0.94586644 2 P 0 ;0,1=194,2=270.000000
L 9.47958346 0.94586644 9.47833376 0.9479998 2 P 0 ;0,1=194,2=270.000000
L 9.47833376 0.9479998 9.47625089 0.94933337 2 P 0 ;0,1=194,2=270.000000
L 9.47625089 0.94933337 9.47333327 0.94986663 2 P 0 ;0,1=194,2=270.000000
L 9.47333327 0.94986663 9.47041722 0.94933337 2 P 0 ;0,1=194,2=270.000000
L 9.47041722 0.94933337 9.46791703 0.94773327 2 P 0 ;0,1=194,2=270.000000
L 9.46791703 0.94773327 9.46666654 0.94533327 2 P 0 ;0,1=194,2=270.000000
L 9.46666654 0.94533327 9.46666654 0.94266663 2 P 0 ;0,1=194,2=270.000000
L 9.46666654 0.94266663 9.46583337 0.94106654 2 P 0 ;0,1=194,2=270.000000
L 9.46583337 0.94106654 9.46375049 0.93973297 2 P 0 ;0,1=194,2=270.000000
L 9.46375049 0.93973297 9.46083366 0.9391998 2 P 0 ;0,1=194,2=270.000000
L 9.46083366 0.9391998 9.45791683 0.9400001 2 P 0 ;0,1=194,2=270.000000
L 9.45791683 0.9400001 9.45583317 0.94186634 2 P 0 ;0,1=194,2=270.000000
L 9.45583317 0.94186634 9.455 0.9439997 2 P 0 ;0,1=194,2=270.000000
L 9.455 0.9439997 9.45583317 0.94613307 2 P 0 ;0,1=194,2=270.000000
L 9.45583317 0.94613307 9.45791683 0.9479998 2 P 0 ;0,1=194,2=270.000000
L 9.45791683 0.9479998 9.46083366 0.9488001 2 P 0 ;0,1=194,2=270.000000
L 9.46083366 0.9488001 9.46375049 0.94826644 2 P 0 ;0,1=194,2=270.000000
L 9.46375049 0.94826644 9.46583337 0.94693337 2 P 0 ;0,1=194,2=270.000000
L 9.46583337 0.94693337 9.46666654 0.94533327 2 P 0 ;0,1=194,2=270.000000
L 9.46666654 0.94533327 9.46666654 0.94266663 2 P 0 ;0,1=194,2=270.000000
L 9.46666654 0.94266663 9.46791703 0.94026663 2 P 0 ;0,1=194,2=270.000000
L 9.46791703 0.94026663 9.47041722 0.93866654 2 P 0 ;0,1=194,2=270.000000
L 9.47041722 0.93866654 9.47333327 0.93813327 2 P 0 ;0,1=194,2=270.000000
L 9.47333327 0.93813327 9.47625089 0.93866654 2 P 0 ;0,1=194,2=270.000000
L 9.47625089 0.93866654 9.47833376 0.9400001 2 P 0 ;0,1=194,2=270.000000
L 9.47833376 0.9400001 9.47958346 0.94213346 2 P 0 ;0,1=194,2=270.000000
L 9.47958346 0.94213346 9.48 0.9439997 2 P 0 ;0,1=194,2=270.000000
L 7.33473002 4.64851004 7.35046998 4.64851004 3 P 0 
L 7.355 4.47266654 7.33 4.47266654 2 P 0 ;0,1=195,2=270.000000
L 7.33 4.47266654 7.33 4.47933327 2 P 0 ;0,1=195,2=270.000000
L 7.33 4.47933327 7.33125059 4.48146663 2 P 0 ;0,1=195,2=270.000000
L 7.33125059 4.48146663 7.33291683 4.4828001 2 P 0 ;0,1=195,2=270.000000
L 7.33291683 4.4828001 7.3362502 4.48333337 2 P 0 ;0,1=195,2=270.000000
L 7.3362502 4.48333337 7.33958366 4.4828001 2 P 0 ;0,1=195,2=270.000000
L 7.33958366 4.4828001 7.34166654 4.4812 2 P 0 ;0,1=195,2=270.000000
L 7.34166654 4.4812 7.34291703 4.47933327 2 P 0 ;0,1=195,2=270.000000
L 7.34291703 4.47933327 7.34291703 4.47266654 2 P 0 ;0,1=195,2=270.000000
L 7.34291703 4.47933327 7.355 4.48333337 2 P 0 ;0,1=195,2=270.000000
L 7.355 4.5019997 7.33 4.5019997 2 P 0 ;0,1=195,2=270.000000
L 7.33 4.5019997 7.3349997 4.4987999 2 P 0 ;0,1=195,2=270.000000
L 7.355 4.4987999 7.355 4.50519951 2 P 0 ;0,1=195,2=270.000000
L 7.35125089 4.52013327 7.35333376 4.52173297 2 P 0 ;0,1=195,2=270.000000
L 7.35333376 4.52173297 7.35458346 4.5235997 2 P 0 ;0,1=195,2=270.000000
L 7.35458346 4.5235997 7.355 4.5259997 2 P 0 ;0,1=195,2=270.000000
L 7.355 4.5259997 7.35416693 4.5284002 2 P 0 ;0,1=195,2=270.000000
L 7.35416693 4.5284002 7.35250059 4.53026644 2 P 0 ;0,1=195,2=270.000000
L 7.35250059 4.53026644 7.34958376 4.5316 2 P 0 ;0,1=195,2=270.000000
L 7.34958376 4.5316 7.34625039 4.53186663 2 P 0 ;0,1=195,2=270.000000
L 7.34625039 4.53186663 7.34291703 4.53133337 2 P 0 ;0,1=195,2=270.000000
L 7.34291703 4.53133337 7.34083337 4.5299998 2 P 0 ;0,1=195,2=270.000000
L 7.34083337 4.5299998 7.33916703 4.52813307 2 P 0 ;0,1=195,2=270.000000
L 7.33916703 4.52813307 7.33875049 4.52626683 2 P 0 ;0,1=195,2=270.000000
L 7.33875049 4.52626683 7.33916703 4.5244 2 P 0 ;0,1=195,2=270.000000
L 7.33916703 4.5244 7.34083337 4.5220001 2 P 0 ;0,1=195,2=270.000000
L 7.34083337 4.5220001 7.33 4.5227999 2 P 0 ;0,1=195,2=270.000000
L 7.33 4.5227999 7.33 4.5299998 2 P 0 ;0,1=195,2=270.000000
L 7.33 4.5499997 7.33083317 4.54786634 2 P 0 ;0,1=195,2=270.000000
L 7.33083317 4.54786634 7.33291683 4.54626663 2 P 0 ;0,1=195,2=270.000000
L 7.33291683 4.54626663 7.33541634 4.5451998 2 P 0 ;0,1=195,2=270.000000
L 7.33541634 4.5451998 7.33875049 4.5443999 2 P 0 ;0,1=195,2=270.000000
L 7.33875049 4.5443999 7.34250039 4.54413327 2 P 0 ;0,1=195,2=270.000000
L 7.34250039 4.54413327 7.34625039 4.5443999 2 P 0 ;0,1=195,2=270.000000
L 7.34625039 4.5443999 7.34958376 4.5451998 2 P 0 ;0,1=195,2=270.000000
L 7.34958376 4.5451998 7.35208396 4.54626663 2 P 0 ;0,1=195,2=270.000000
L 7.35208396 4.54626663 7.35416693 4.54786634 2 P 0 ;0,1=195,2=270.000000
L 7.35416693 4.54786634 7.355 4.5499997 2 P 0 ;0,1=195,2=270.000000
L 7.355 4.5499997 7.35416693 4.55213307 2 P 0 ;0,1=195,2=270.000000
L 7.35416693 4.55213307 7.35208396 4.55373327 2 P 0 ;0,1=195,2=270.000000
L 7.35208396 4.55373327 7.34958376 4.5548001 2 P 0 ;0,1=195,2=270.000000
L 7.34958376 4.5548001 7.34625039 4.5556 2 P 0 ;0,1=195,2=270.000000
L 7.34625039 4.5556 7.34250039 4.55586663 2 P 0 ;0,1=195,2=270.000000
L 7.34250039 4.55586663 7.33875049 4.5556 2 P 0 ;0,1=195,2=270.000000
L 7.33875049 4.5556 7.33541634 4.5548001 2 P 0 ;0,1=195,2=270.000000
L 7.33541634 4.5548001 7.33291683 4.55373327 2 P 0 ;0,1=195,2=270.000000
L 7.33291683 4.55373327 7.33083317 4.55213307 2 P 0 ;0,1=195,2=270.000000
L 7.33083317 4.55213307 7.33 4.5499997 2 P 0 ;0,1=195,2=270.000000
L 7.355 4.57346654 7.34958376 4.5739997 2 P 0 ;0,1=195,2=270.000000
L 7.34958376 4.5739997 7.34500069 4.5748 2 P 0 ;0,1=195,2=270.000000
L 7.34500069 4.5748 7.34083337 4.57586644 2 P 0 ;0,1=195,2=270.000000
L 7.34083337 4.57586644 7.3362502 4.5772 2 P 0 ;0,1=195,2=270.000000
L 7.3362502 4.5772 7.33 4.57933337 2 P 0 ;0,1=195,2=270.000000
L 7.33 4.57933337 7.33 4.56866654 2 P 0 ;0,1=195,2=270.000000
L 7.28473002 4.64851004 7.30046998 4.64851004 3 P 0 
L 7.305 4.47266654 7.28 4.47266654 2 P 0 ;0,1=196,2=270.000000
L 7.28 4.47266654 7.28 4.47933327 2 P 0 ;0,1=196,2=270.000000
L 7.28 4.47933327 7.28125059 4.48146663 2 P 0 ;0,1=196,2=270.000000
L 7.28125059 4.48146663 7.28291683 4.4828001 2 P 0 ;0,1=196,2=270.000000
L 7.28291683 4.4828001 7.2862502 4.48333337 2 P 0 ;0,1=196,2=270.000000
L 7.2862502 4.48333337 7.28958366 4.4828001 2 P 0 ;0,1=196,2=270.000000
L 7.28958366 4.4828001 7.29166654 4.4812 2 P 0 ;0,1=196,2=270.000000
L 7.29166654 4.4812 7.29291703 4.47933327 2 P 0 ;0,1=196,2=270.000000
L 7.29291703 4.47933327 7.29291703 4.47266654 2 P 0 ;0,1=196,2=270.000000
L 7.29291703 4.47933327 7.305 4.48333337 2 P 0 ;0,1=196,2=270.000000
L 7.305 4.5019997 7.28 4.5019997 2 P 0 ;0,1=196,2=270.000000
L 7.28 4.5019997 7.2849997 4.4987999 2 P 0 ;0,1=196,2=270.000000
L 7.305 4.4987999 7.305 4.50519951 2 P 0 ;0,1=196,2=270.000000
L 7.30125089 4.52013327 7.30333376 4.52173297 2 P 0 ;0,1=196,2=270.000000
L 7.30333376 4.52173297 7.30458346 4.5235997 2 P 0 ;0,1=196,2=270.000000
L 7.30458346 4.5235997 7.305 4.5259997 2 P 0 ;0,1=196,2=270.000000
L 7.305 4.5259997 7.30416693 4.5284002 2 P 0 ;0,1=196,2=270.000000
L 7.30416693 4.5284002 7.30250059 4.53026644 2 P 0 ;0,1=196,2=270.000000
L 7.30250059 4.53026644 7.29958376 4.5316 2 P 0 ;0,1=196,2=270.000000
L 7.29958376 4.5316 7.29625039 4.53186663 2 P 0 ;0,1=196,2=270.000000
L 7.29625039 4.53186663 7.29291703 4.53133337 2 P 0 ;0,1=196,2=270.000000
L 7.29291703 4.53133337 7.29083337 4.5299998 2 P 0 ;0,1=196,2=270.000000
L 7.29083337 4.5299998 7.28916703 4.52813307 2 P 0 ;0,1=196,2=270.000000
L 7.28916703 4.52813307 7.28875049 4.52626683 2 P 0 ;0,1=196,2=270.000000
L 7.28875049 4.52626683 7.28916703 4.5244 2 P 0 ;0,1=196,2=270.000000
L 7.28916703 4.5244 7.29083337 4.5220001 2 P 0 ;0,1=196,2=270.000000
L 7.29083337 4.5220001 7.28 4.5227999 2 P 0 ;0,1=196,2=270.000000
L 7.28 4.5227999 7.28 4.5299998 2 P 0 ;0,1=196,2=270.000000
L 7.28 4.5499997 7.28083317 4.54786634 2 P 0 ;0,1=196,2=270.000000
L 7.28083317 4.54786634 7.28291683 4.54626663 2 P 0 ;0,1=196,2=270.000000
L 7.28291683 4.54626663 7.28541634 4.5451998 2 P 0 ;0,1=196,2=270.000000
L 7.28541634 4.5451998 7.28875049 4.5443999 2 P 0 ;0,1=196,2=270.000000
L 7.28875049 4.5443999 7.29250039 4.54413327 2 P 0 ;0,1=196,2=270.000000
L 7.29250039 4.54413327 7.29625039 4.5443999 2 P 0 ;0,1=196,2=270.000000
L 7.29625039 4.5443999 7.29958376 4.5451998 2 P 0 ;0,1=196,2=270.000000
L 7.29958376 4.5451998 7.30208396 4.54626663 2 P 0 ;0,1=196,2=270.000000
L 7.30208396 4.54626663 7.30416693 4.54786634 2 P 0 ;0,1=196,2=270.000000
L 7.30416693 4.54786634 7.305 4.5499997 2 P 0 ;0,1=196,2=270.000000
L 7.305 4.5499997 7.30416693 4.55213307 2 P 0 ;0,1=196,2=270.000000
L 7.30416693 4.55213307 7.30208396 4.55373327 2 P 0 ;0,1=196,2=270.000000
L 7.30208396 4.55373327 7.29958376 4.5548001 2 P 0 ;0,1=196,2=270.000000
L 7.29958376 4.5548001 7.29625039 4.5556 2 P 0 ;0,1=196,2=270.000000
L 7.29625039 4.5556 7.29250039 4.55586663 2 P 0 ;0,1=196,2=270.000000
L 7.29250039 4.55586663 7.28875049 4.5556 2 P 0 ;0,1=196,2=270.000000
L 7.28875049 4.5556 7.28541634 4.5548001 2 P 0 ;0,1=196,2=270.000000
L 7.28541634 4.5548001 7.28291683 4.55373327 2 P 0 ;0,1=196,2=270.000000
L 7.28291683 4.55373327 7.28083317 4.55213307 2 P 0 ;0,1=196,2=270.000000
L 7.28083317 4.55213307 7.28 4.5499997 2 P 0 ;0,1=196,2=270.000000
L 7.29458406 4.56893317 7.29166654 4.5707999 2 P 0 ;0,1=196,2=270.000000
L 7.29166654 4.5707999 7.2900002 4.5724 2 P 0 ;0,1=196,2=270.000000
L 7.2900002 4.5724 7.28916703 4.57453337 2 P 0 ;0,1=196,2=270.000000
L 7.28916703 4.57453337 7.2900002 4.5764002 2 P 0 ;0,1=196,2=270.000000
L 7.2900002 4.5764002 7.29166654 4.57773327 2 P 0 ;0,1=196,2=270.000000
L 7.29166654 4.57773327 7.29416673 4.5788001 2 P 0 ;0,1=196,2=270.000000
L 7.29416673 4.5788001 7.29708356 4.57906673 2 P 0 ;0,1=196,2=270.000000
L 7.29708356 4.57906673 7.29958376 4.5788001 2 P 0 ;0,1=196,2=270.000000
L 7.29958376 4.5788001 7.30208396 4.57773327 2 P 0 ;0,1=196,2=270.000000
L 7.30208396 4.57773327 7.30416693 4.57613307 2 P 0 ;0,1=196,2=270.000000
L 7.30416693 4.57613307 7.305 4.57426683 2 P 0 ;0,1=196,2=270.000000
L 7.305 4.57426683 7.30416693 4.57213346 2 P 0 ;0,1=196,2=270.000000
L 7.30416693 4.57213346 7.30166742 4.57026663 2 P 0 ;0,1=196,2=270.000000
L 7.30166742 4.57026663 7.29791673 4.5691998 2 P 0 ;0,1=196,2=270.000000
L 7.29791673 4.5691998 7.2937502 4.56893317 2 P 0 ;0,1=196,2=270.000000
L 7.2937502 4.56893317 7.28833386 4.56946634 2 P 0 ;0,1=196,2=270.000000
L 7.28833386 4.56946634 7.28541634 4.57026663 2 P 0 ;0,1=196,2=270.000000
L 7.28541634 4.57026663 7.2825003 4.5715997 2 P 0 ;0,1=196,2=270.000000
L 7.2825003 4.5715997 7.28041663 4.57346654 2 P 0 ;0,1=196,2=270.000000
L 7.28041663 4.57346654 7.28 4.57533327 2 P 0 ;0,1=196,2=270.000000
L 7.28 4.57533327 7.28083317 4.5772 2 P 0 ;0,1=196,2=270.000000
L 7.28083317 4.5772 7.28291683 4.57853356 2 P 0 ;0,1=196,2=270.000000
L 1.33118996 4.64851004 1.34693002 4.64851004 3 P 0 
L 1.35 4.47766654 1.325 4.47766654 2 P 0 ;0,1=197,2=270.000000
L 1.325 4.47766654 1.325 4.48433327 2 P 0 ;0,1=197,2=270.000000
L 1.325 4.48433327 1.32625059 4.48646663 2 P 0 ;0,1=197,2=270.000000
L 1.32625059 4.48646663 1.32791683 4.4878001 2 P 0 ;0,1=197,2=270.000000
L 1.32791683 4.4878001 1.3312502 4.48833337 2 P 0 ;0,1=197,2=270.000000
L 1.3312502 4.48833337 1.33458366 4.4878001 2 P 0 ;0,1=197,2=270.000000
L 1.33458366 4.4878001 1.33666654 4.4862 2 P 0 ;0,1=197,2=270.000000
L 1.33666654 4.4862 1.33791703 4.48433327 2 P 0 ;0,1=197,2=270.000000
L 1.33791703 4.48433327 1.33791703 4.47766654 2 P 0 ;0,1=197,2=270.000000
L 1.33791703 4.48433327 1.35 4.48833337 2 P 0 ;0,1=197,2=270.000000
L 1.35 4.5069997 1.325 4.5069997 2 P 0 ;0,1=197,2=270.000000
L 1.325 4.5069997 1.3299997 4.5037999 2 P 0 ;0,1=197,2=270.000000
L 1.35 4.5037999 1.35 4.51019951 2 P 0 ;0,1=197,2=270.000000
L 1.35 4.5342 1.325 4.5342 2 P 0 ;0,1=197,2=270.000000
L 1.325 4.5342 1.34291673 4.52433297 2 P 0 ;0,1=197,2=270.000000
L 1.34291673 4.52433297 1.34291673 4.53766693 2 P 0 ;0,1=197,2=270.000000
L 1.34708396 4.55046634 1.34916693 4.55233317 2 P 0 ;0,1=197,2=270.000000
L 1.34916693 4.55233317 1.35 4.55446654 2 P 0 ;0,1=197,2=270.000000
L 1.35 4.55446654 1.34916693 4.5565999 2 P 0 ;0,1=197,2=270.000000
L 1.34916693 4.5565999 1.34666742 4.55846663 2 P 0 ;0,1=197,2=270.000000
L 1.34666742 4.55846663 1.34291673 4.5598001 2 P 0 ;0,1=197,2=270.000000
L 1.34291673 4.5598001 1.33916673 4.56033337 2 P 0 ;0,1=197,2=270.000000
L 1.33916673 4.56033337 1.33458366 4.56033337 2 P 0 ;0,1=197,2=270.000000
L 1.33458366 4.56033337 1.33083366 4.5598001 2 P 0 ;0,1=197,2=270.000000
L 1.33083366 4.5598001 1.3275003 4.55846663 2 P 0 ;0,1=197,2=270.000000
L 1.3275003 4.55846663 1.32583317 4.55686644 2 P 0 ;0,1=197,2=270.000000
L 1.32583317 4.55686644 1.325 4.5549997 2 P 0 ;0,1=197,2=270.000000
L 1.325 4.5549997 1.32583317 4.55286634 2 P 0 ;0,1=197,2=270.000000
L 1.32583317 4.55286634 1.3275003 4.55126663 2 P 0 ;0,1=197,2=270.000000
L 1.3275003 4.55126663 1.3299997 4.5501998 2 P 0 ;0,1=197,2=270.000000
L 1.3299997 4.5501998 1.33333386 4.54966654 2 P 0 ;0,1=197,2=270.000000
L 1.33333386 4.54966654 1.3362499 4.5501998 2 P 0 ;0,1=197,2=270.000000
L 1.3362499 4.5501998 1.33916673 4.55153327 2 P 0 ;0,1=197,2=270.000000
L 1.33916673 4.55153327 1.34083386 4.55313346 2 P 0 ;0,1=197,2=270.000000
L 1.34083386 4.55313346 1.34125039 4.5549997 2 P 0 ;0,1=197,2=270.000000
L 1.34125039 4.5549997 1.34041722 4.55713307 2 P 0 ;0,1=197,2=270.000000
L 1.34041722 4.55713307 1.33833356 4.55873327 2 P 0 ;0,1=197,2=270.000000
L 1.33833356 4.55873327 1.33458366 4.56033337 2 P 0 ;0,1=197,2=270.000000
L 1.35 4.57846654 1.34458376 4.5789997 2 P 0 ;0,1=197,2=270.000000
L 1.34458376 4.5789997 1.34000069 4.5798 2 P 0 ;0,1=197,2=270.000000
L 1.34000069 4.5798 1.33583337 4.58086644 2 P 0 ;0,1=197,2=270.000000
L 1.33583337 4.58086644 1.3312502 4.5822 2 P 0 ;0,1=197,2=270.000000
L 1.3312502 4.5822 1.325 4.58433337 2 P 0 ;0,1=197,2=270.000000
L 1.325 4.58433337 1.325 4.57366654 2 P 0 ;0,1=197,2=270.000000
L 1.28118996 4.64851004 1.29693002 4.64851004 3 P 0 
L 1.3 4.47766654 1.275 4.47766654 2 P 0 ;0,1=198,2=270.000000
L 1.275 4.47766654 1.275 4.48433327 2 P 0 ;0,1=198,2=270.000000
L 1.275 4.48433327 1.27625059 4.48646663 2 P 0 ;0,1=198,2=270.000000
L 1.27625059 4.48646663 1.27791683 4.4878001 2 P 0 ;0,1=198,2=270.000000
L 1.27791683 4.4878001 1.2812502 4.48833337 2 P 0 ;0,1=198,2=270.000000
L 1.2812502 4.48833337 1.28458366 4.4878001 2 P 0 ;0,1=198,2=270.000000
L 1.28458366 4.4878001 1.28666654 4.4862 2 P 0 ;0,1=198,2=270.000000
L 1.28666654 4.4862 1.28791703 4.48433327 2 P 0 ;0,1=198,2=270.000000
L 1.28791703 4.48433327 1.28791703 4.47766654 2 P 0 ;0,1=198,2=270.000000
L 1.28791703 4.48433327 1.3 4.48833337 2 P 0 ;0,1=198,2=270.000000
L 1.3 4.5069997 1.275 4.5069997 2 P 0 ;0,1=198,2=270.000000
L 1.275 4.5069997 1.2799997 4.5037999 2 P 0 ;0,1=198,2=270.000000
L 1.3 4.5037999 1.3 4.51019951 2 P 0 ;0,1=198,2=270.000000
L 1.3 4.5342 1.275 4.5342 2 P 0 ;0,1=198,2=270.000000
L 1.275 4.5342 1.29291673 4.52433297 2 P 0 ;0,1=198,2=270.000000
L 1.29291673 4.52433297 1.29291673 4.53766693 2 P 0 ;0,1=198,2=270.000000
L 1.29708396 4.55046634 1.29916693 4.55233317 2 P 0 ;0,1=198,2=270.000000
L 1.29916693 4.55233317 1.3 4.55446654 2 P 0 ;0,1=198,2=270.000000
L 1.3 4.55446654 1.29916693 4.5565999 2 P 0 ;0,1=198,2=270.000000
L 1.29916693 4.5565999 1.29666742 4.55846663 2 P 0 ;0,1=198,2=270.000000
L 1.29666742 4.55846663 1.29291673 4.5598001 2 P 0 ;0,1=198,2=270.000000
L 1.29291673 4.5598001 1.28916673 4.56033337 2 P 0 ;0,1=198,2=270.000000
L 1.28916673 4.56033337 1.28458366 4.56033337 2 P 0 ;0,1=198,2=270.000000
L 1.28458366 4.56033337 1.28083366 4.5598001 2 P 0 ;0,1=198,2=270.000000
L 1.28083366 4.5598001 1.2775003 4.55846663 2 P 0 ;0,1=198,2=270.000000
L 1.2775003 4.55846663 1.27583317 4.55686644 2 P 0 ;0,1=198,2=270.000000
L 1.27583317 4.55686644 1.275 4.5549997 2 P 0 ;0,1=198,2=270.000000
L 1.275 4.5549997 1.27583317 4.55286634 2 P 0 ;0,1=198,2=270.000000
L 1.27583317 4.55286634 1.2775003 4.55126663 2 P 0 ;0,1=198,2=270.000000
L 1.2775003 4.55126663 1.2799997 4.5501998 2 P 0 ;0,1=198,2=270.000000
L 1.2799997 4.5501998 1.28333386 4.54966654 2 P 0 ;0,1=198,2=270.000000
L 1.28333386 4.54966654 1.2862499 4.5501998 2 P 0 ;0,1=198,2=270.000000
L 1.2862499 4.5501998 1.28916673 4.55153327 2 P 0 ;0,1=198,2=270.000000
L 1.28916673 4.55153327 1.29083386 4.55313346 2 P 0 ;0,1=198,2=270.000000
L 1.29083386 4.55313346 1.29125039 4.5549997 2 P 0 ;0,1=198,2=270.000000
L 1.29125039 4.5549997 1.29041722 4.55713307 2 P 0 ;0,1=198,2=270.000000
L 1.29041722 4.55713307 1.28833356 4.55873327 2 P 0 ;0,1=198,2=270.000000
L 1.28833356 4.55873327 1.28458366 4.56033337 2 P 0 ;0,1=198,2=270.000000
L 1.28958406 4.57393317 1.28666654 4.5757999 2 P 0 ;0,1=198,2=270.000000
L 1.28666654 4.5757999 1.2850002 4.5774 2 P 0 ;0,1=198,2=270.000000
L 1.2850002 4.5774 1.28416703 4.57953337 2 P 0 ;0,1=198,2=270.000000
L 1.28416703 4.57953337 1.2850002 4.5814002 2 P 0 ;0,1=198,2=270.000000
L 1.2850002 4.5814002 1.28666654 4.58273327 2 P 0 ;0,1=198,2=270.000000
L 1.28666654 4.58273327 1.28916673 4.5838001 2 P 0 ;0,1=198,2=270.000000
L 1.28916673 4.5838001 1.29208356 4.58406673 2 P 0 ;0,1=198,2=270.000000
L 1.29208356 4.58406673 1.29458376 4.5838001 2 P 0 ;0,1=198,2=270.000000
L 1.29458376 4.5838001 1.29708396 4.58273327 2 P 0 ;0,1=198,2=270.000000
L 1.29708396 4.58273327 1.29916693 4.58113307 2 P 0 ;0,1=198,2=270.000000
L 1.29916693 4.58113307 1.3 4.57926683 2 P 0 ;0,1=198,2=270.000000
L 1.3 4.57926683 1.29916693 4.57713346 2 P 0 ;0,1=198,2=270.000000
L 1.29916693 4.57713346 1.29666742 4.57526663 2 P 0 ;0,1=198,2=270.000000
L 1.29666742 4.57526663 1.29291673 4.5741998 2 P 0 ;0,1=198,2=270.000000
L 1.29291673 4.5741998 1.2887502 4.57393317 2 P 0 ;0,1=198,2=270.000000
L 1.2887502 4.57393317 1.28333386 4.57446634 2 P 0 ;0,1=198,2=270.000000
L 1.28333386 4.57446634 1.28041634 4.57526663 2 P 0 ;0,1=198,2=270.000000
L 1.28041634 4.57526663 1.2775003 4.5765997 2 P 0 ;0,1=198,2=270.000000
L 1.2775003 4.5765997 1.27541663 4.57846654 2 P 0 ;0,1=198,2=270.000000
L 1.27541663 4.57846654 1.275 4.58033327 2 P 0 ;0,1=198,2=270.000000
L 1.275 4.58033327 1.27583317 4.5822 2 P 0 ;0,1=198,2=270.000000
L 1.27583317 4.5822 1.27791683 4.58353356 2 P 0 ;0,1=198,2=270.000000
A 5.1218 4.92566004 5.11603878 4.93451329 5.10605 4.92171191 3 P 0 N
A 5.11603878 4.93451329 5.10605 4.93795 5.10604813 4.92171004 3 P 0 N
L 5.10605 4.93795 5.10605 4.96425 3 P 0 
A 5.1218 4.90203996 5.11029282 4.91393632 5.10575 4.89802854 3 P 0 N
A 5.11029282 4.91393632 5.09423996 4.90991004 5.10575098 4.89803002 3 P 0 N
A 5.09423996 4.90991004 5.11398189 4.90734557 5.10580384 4.92166004 3 P 0 N
A 5.11398189 4.90734557 5.1218 4.92566004 5.1058 4.92166417 3 P 0 N
A 5.09423996 4.88628996 5.11398189 4.88372549 5.10580384 4.89803996 3 P 0 N
A 5.11398189 4.88372549 5.1218 4.90203996 5.1058 4.89804409 3 P 0 N
A 5.1218 4.87841004 5.11029705 4.89030876 5.10575 4.87440335 3 P 0 N
A 5.11029705 4.89030876 5.09423996 4.88628996 5.10574724 4.8744 3 P 0 N
A 5.1218 4.87841004 5.11884144 4.86448819 5.10605 4.87448179 3 P 0 Y
A 5.11884144 4.86448819 5.10605 4.85825 5.10605167 4.87448002 3 P 0 Y
L 5.10605 4.85825 5.10605 4.83195 3 P 0 
L 5.16865 5.09101004 5.23596998 5.09101004 3 P 0 
L 5.23596998 5.09101004 5.23596998 4.70518996 3 P 0 
L 5.23596998 4.70518996 5.16865 4.70518996 3 P 0 
L 5.04345 5.09101004 4.97613002 5.09101004 3 P 0 
L 4.97613002 5.09101004 4.97613002 4.70518996 3 P 0 
L 4.97613002 4.70518996 5.04345 4.70518996 3 P 0 
L 5.07383317 4.632 5.07383317 4.6 2 P 0 ;0,1=199,2=0.000000
L 5.07383317 4.6 5.08916673 4.6 2 P 0 ;0,1=199,2=0.000000
L 5.10598287 4.60373248 5.10866634 4.60106644 2 P 0 ;0,1=199,2=0.000000
L 5.10866634 4.60106644 5.11173307 4.6 2 P 0 ;0,1=199,2=0.000000
L 5.11173307 4.6 5.1147998 4.60106644 2 P 0 ;0,1=199,2=0.000000
L 5.1147998 4.60106644 5.11748327 4.60426575 2 P 0 ;0,1=199,2=0.000000
L 5.11748327 4.60426575 5.1194002 4.60906663 2 P 0 ;0,1=199,2=0.000000
L 5.1194002 4.60906663 5.12016673 4.61386663 2 P 0 ;0,1=199,2=0.000000
L 5.12016673 4.61386663 5.12016673 4.61973297 2 P 0 ;0,1=199,2=0.000000
L 5.12016673 4.61973297 5.1194002 4.62453297 2 P 0 ;0,1=199,2=0.000000
L 5.1194002 4.62453297 5.11748327 4.6287997 2 P 0 ;0,1=199,2=0.000000
L 5.11748327 4.6287997 5.11518307 4.63093346 2 P 0 ;0,1=199,2=0.000000
L 5.11518307 4.63093346 5.11249961 4.632 2 P 0 ;0,1=199,2=0.000000
L 5.11249961 4.632 5.10943287 4.63093346 2 P 0 ;0,1=199,2=0.000000
L 5.10943287 4.63093346 5.10713337 4.6287997 2 P 0 ;0,1=199,2=0.000000
L 5.10713337 4.6287997 5.1055997 4.6256003 2 P 0 ;0,1=199,2=0.000000
L 5.1055997 4.6256003 5.10483317 4.62133268 2 P 0 ;0,1=199,2=0.000000
L 5.10483317 4.62133268 5.1055997 4.6176001 2 P 0 ;0,1=199,2=0.000000
L 5.1055997 4.6176001 5.10751663 4.61386663 2 P 0 ;0,1=199,2=0.000000
L 5.10751663 4.61386663 5.10981683 4.61173278 2 P 0 ;0,1=199,2=0.000000
L 5.10981683 4.61173278 5.11249961 4.61119951 2 P 0 ;0,1=199,2=0.000000
L 5.11249961 4.61119951 5.11556634 4.61226594 2 P 0 ;0,1=199,2=0.000000
L 5.11556634 4.61226594 5.11786654 4.61493307 2 P 0 ;0,1=199,2=0.000000
L 5.11786654 4.61493307 5.12016673 4.61973297 2 P 0 ;0,1=199,2=0.000000
A 11.12573996 4.92566004 11.11997874 4.93451329 11.10998996 4.92171191 3 P 0 N
A 11.11997874 4.93451329 11.10998996 4.93795 11.10998809 4.92171004 3 P 0 N
L 11.10998996 4.93795 11.10998996 4.96425 3 P 0 
A 11.12573996 4.90203996 11.11423278 4.91393622 11.10968996 4.89802835 3 P 0 N
A 11.11423278 4.91393622 11.09818002 4.90991004 11.10969094 4.89803002 3 P 0 N
A 11.09818002 4.90991004 11.11792185 4.90734567 11.1097438 4.92166004 3 P 0 N
A 11.11792185 4.90734567 11.12573996 4.92566004 11.10973996 4.92166427 3 P 0 N
A 11.09818002 4.88628996 11.11792185 4.88372559 11.1097438 4.89803996 3 P 0 N
A 11.11792185 4.88372559 11.12573996 4.90203996 11.10973996 4.89804419 3 P 0 N
A 11.12573996 4.87841004 11.11423701 4.89030876 11.10968996 4.87440335 3 P 0 N
A 11.11423701 4.89030876 11.09818002 4.88628996 11.1096873 4.8744 3 P 0 N
A 11.12573996 4.87841004 11.1227814 4.86448819 11.10998996 4.87448179 3 P 0 Y
A 11.1227814 4.86448819 11.10998996 4.85825 11.10999163 4.87448002 3 P 0 Y
L 11.10998996 4.85825 11.10998996 4.83195 3 P 0 
L 11.17258996 5.09101004 11.23991004 5.09101004 3 P 0 
L 11.23991004 5.09101004 11.23991004 4.70518996 3 P 0 
L 11.23991004 4.70518996 11.17258996 4.70518996 3 P 0 
L 11.04738996 5.09101004 10.98006998 5.09101004 3 P 0 
L 10.98006998 5.09101004 10.98006998 4.70518996 3 P 0 
L 10.98006998 4.70518996 11.04738996 4.70518996 3 P 0 
L 11.03883317 4.652 11.03883317 4.62 2 P 0 ;0,1=200,2=0.000000
L 11.03883317 4.62 11.05416673 4.62 2 P 0 ;0,1=200,2=0.000000
L 11.07749961 4.62 11.07749961 4.652 2 P 0 ;0,1=200,2=0.000000
L 11.07749961 4.652 11.0728999 4.6456003 2 P 0 ;0,1=200,2=0.000000
L 11.0728999 4.62 11.08209931 4.62 2 P 0 ;0,1=200,2=0.000000
L 11.10849961 4.652 11.10543287 4.65093346 2 P 0 ;0,1=200,2=0.000000
L 11.10543287 4.65093346 11.10313337 4.64826644 2 P 0 ;0,1=200,2=0.000000
L 11.10313337 4.64826644 11.1015997 4.64506713 2 P 0 ;0,1=200,2=0.000000
L 11.1015997 4.64506713 11.1004499 4.64079941 2 P 0 ;0,1=200,2=0.000000
L 11.1004499 4.64079941 11.10006663 4.63599951 2 P 0 ;0,1=200,2=0.000000
L 11.10006663 4.63599951 11.1004499 4.63119951 2 P 0 ;0,1=200,2=0.000000
L 11.1004499 4.63119951 11.1015997 4.62693278 2 P 0 ;0,1=200,2=0.000000
L 11.1015997 4.62693278 11.10313337 4.62373248 2 P 0 ;0,1=200,2=0.000000
L 11.10313337 4.62373248 11.10543287 4.62106644 2 P 0 ;0,1=200,2=0.000000
L 11.10543287 4.62106644 11.10849961 4.62 2 P 0 ;0,1=200,2=0.000000
L 11.10849961 4.62 11.11156634 4.62106644 2 P 0 ;0,1=200,2=0.000000
L 11.11156634 4.62106644 11.11386654 4.62373248 2 P 0 ;0,1=200,2=0.000000
L 11.11386654 4.62373248 11.1154002 4.62693278 2 P 0 ;0,1=200,2=0.000000
L 11.1154002 4.62693278 11.11655 4.63119951 2 P 0 ;0,1=200,2=0.000000
L 11.11655 4.63119951 11.11693327 4.63599951 2 P 0 ;0,1=200,2=0.000000
L 11.11693327 4.63599951 11.11655 4.64079941 2 P 0 ;0,1=200,2=0.000000
L 11.11655 4.64079941 11.1154002 4.64506713 2 P 0 ;0,1=200,2=0.000000
L 11.1154002 4.64506713 11.11386654 4.64826644 2 P 0 ;0,1=200,2=0.000000
L 11.11386654 4.64826644 11.11156634 4.65093346 2 P 0 ;0,1=200,2=0.000000
L 11.11156634 4.65093346 11.10849961 4.652 2 P 0 ;0,1=200,2=0.000000
L 10.45526004 4.62676998 10.45521998 4.65278996 3 P 0 
L 10.45521998 4.65278996 10.44733996 4.65278996 3 P 0 
L 10.44733996 4.65278996 10.44733996 4.62681004 3 P 0 
L 10.44733996 4.62681004 10.42136004 4.62681004 3 P 0 
L 10.42136004 4.62681004 10.42136004 4.61893002 3 P 0 
L 10.42136004 4.61893002 10.44733996 4.61893002 3 P 0 
L 10.44733996 4.61893002 10.44733996 4.59295 3 P 0 
L 10.44733996 4.59295 10.45521998 4.59295 3 P 0 
L 10.45521998 4.59295 10.45521998 4.61893002 3 P 0 
L 10.45521998 4.61893002 10.4812 4.61893002 3 P 0 
L 10.4812 4.61893002 10.4812 4.62681004 3 P 0 
L 10.4812 4.62681004 10.45521998 4.62681004 3 P 0 
L 10.31698996 4.70983996 10.25518002 4.70983996 3 P 0 
L 10.25518002 4.70983996 10.19573002 4.76928996 3 P 0 
L 10.19573002 4.76928996 10.19573002 5.05236004 3 P 0 
L 10.19573002 5.05236004 10.31541998 5.05236004 3 P 0 
L 10.41856004 5.05236004 10.53825 5.05236004 3 P 0 
L 10.53825 5.05236004 10.53825 4.76928996 3 P 0 
L 10.53825 4.76928996 10.4788 4.70983996 3 P 0 
L 10.4788 4.70983996 10.41581004 4.70983996 3 P 0 
S P 0
OB 10.554 4.8811 I
OS 10.179980019685 4.8811
OS 10.179980019685 5.06811003937
OS 10.31935 5.06811003937
OS 10.31935 4.93386003937
OS 10.414630019685 4.93386003937
OS 10.414630019685 5.06811003937
OS 10.554 5.06811003937
OS 10.554 4.8811
OE
SE
L 10.33993327 4.58433287 10.33763307 4.58593346 2 P 0 ;0,1=201,2=0.000000
L 10.33763307 4.58593346 10.3349503 4.587 2 P 0 ;0,1=201,2=0.000000
L 10.3349503 4.587 10.33188356 4.587 2 P 0 ;0,1=201,2=0.000000
L 10.33188356 4.587 10.32843287 4.58539931 2 P 0 ;0,1=201,2=0.000000
L 10.32843287 4.58539931 10.3257501 4.58273327 2 P 0 ;0,1=201,2=0.000000
L 10.3257501 4.58273327 10.32383317 4.57953297 2 P 0 ;0,1=201,2=0.000000
L 10.32383317 4.57953297 10.32229951 4.5741998 2 P 0 ;0,1=201,2=0.000000
L 10.32229951 4.5741998 10.32191624 4.5693998 2 P 0 ;0,1=201,2=0.000000
L 10.32191624 4.5693998 10.32268337 4.5645999 2 P 0 ;0,1=201,2=0.000000
L 10.32268337 4.5645999 10.32383317 4.56139961 2 P 0 ;0,1=201,2=0.000000
L 10.32383317 4.56139961 10.32613337 4.55819931 2 P 0 ;0,1=201,2=0.000000
L 10.32613337 4.55819931 10.32881683 4.55606644 2 P 0 ;0,1=201,2=0.000000
L 10.32881683 4.55606644 10.33149961 4.555 2 P 0 ;0,1=201,2=0.000000
L 10.33149961 4.555 10.33418307 4.555 2 P 0 ;0,1=201,2=0.000000
L 10.33418307 4.555 10.33686654 4.55606644 2 P 0 ;0,1=201,2=0.000000
L 10.33686654 4.55606644 10.33916673 4.55766604 2 P 0 ;0,1=201,2=0.000000
L 10.33916673 4.55766604 10.34108366 4.55979892 2 P 0 ;0,1=201,2=0.000000
L 10.37016673 4.555 10.35483317 4.555 2 P 0 ;0,1=201,2=0.000000
L 10.35483317 4.555 10.35483317 4.587 2 P 0 ;0,1=201,2=0.000000
L 10.35483317 4.587 10.37016673 4.587 2 P 0 ;0,1=201,2=0.000000
L 10.36403327 4.57153366 10.35483317 4.57153366 2 P 0 ;0,1=201,2=0.000000
L 10.39349961 4.555 10.39618307 4.55553317 2 P 0 ;0,1=201,2=0.000000
L 10.39618307 4.55553317 10.3992498 4.55713287 2 P 0 ;0,1=201,2=0.000000
L 10.3992498 4.55713287 10.40116673 4.55979892 2 P 0 ;0,1=201,2=0.000000
L 10.40116673 4.55979892 10.40193327 4.56353337 2 P 0 ;0,1=201,2=0.000000
L 10.40193327 4.56353337 10.40116673 4.56726594 2 P 0 ;0,1=201,2=0.000000
L 10.40116673 4.56726594 10.39886654 4.57046624 2 P 0 ;0,1=201,2=0.000000
L 10.39886654 4.57046624 10.39541654 4.57206683 2 P 0 ;0,1=201,2=0.000000
L 10.39541654 4.57206683 10.39158337 4.57206683 2 P 0 ;0,1=201,2=0.000000
L 10.39158337 4.57206683 10.38928317 4.57313327 2 P 0 ;0,1=201,2=0.000000
L 10.38928317 4.57313327 10.38736614 4.57579941 2 P 0 ;0,1=201,2=0.000000
L 10.38736614 4.57579941 10.3865997 4.57953297 2 P 0 ;0,1=201,2=0.000000
L 10.3865997 4.57953297 10.3877501 4.58326644 2 P 0 ;0,1=201,2=0.000000
L 10.3877501 4.58326644 10.39043287 4.58593346 2 P 0 ;0,1=201,2=0.000000
L 10.39043287 4.58593346 10.39349961 4.587 2 P 0 ;0,1=201,2=0.000000
L 10.39349961 4.587 10.39656634 4.58593346 2 P 0 ;0,1=201,2=0.000000
L 10.39656634 4.58593346 10.3992498 4.58326644 2 P 0 ;0,1=201,2=0.000000
L 10.3992498 4.58326644 10.4004002 4.57953297 2 P 0 ;0,1=201,2=0.000000
L 10.4004002 4.57953297 10.39963307 4.57579941 2 P 0 ;0,1=201,2=0.000000
L 10.39963307 4.57579941 10.39771673 4.57313327 2 P 0 ;0,1=201,2=0.000000
L 10.39771673 4.57313327 10.39541654 4.57206683 2 P 0 ;0,1=201,2=0.000000
L 10.39541654 4.57206683 10.39158337 4.57206683 2 P 0 ;0,1=201,2=0.000000
L 10.39158337 4.57206683 10.38813337 4.57046624 2 P 0 ;0,1=201,2=0.000000
L 10.38813337 4.57046624 10.38583317 4.56726594 2 P 0 ;0,1=201,2=0.000000
L 10.38583317 4.56726594 10.38506663 4.56353337 2 P 0 ;0,1=201,2=0.000000
L 10.38506663 4.56353337 10.38583317 4.55979892 2 P 0 ;0,1=201,2=0.000000
L 10.38583317 4.55979892 10.3877501 4.55713287 2 P 0 ;0,1=201,2=0.000000
L 10.3877501 4.55713287 10.39081683 4.55553317 2 P 0 ;0,1=201,2=0.000000
L 10.39081683 4.55553317 10.39349961 4.555 2 P 0 ;0,1=201,2=0.000000
L 10.84526004 4.62176998 10.84521998 4.64778996 3 P 0 
L 10.84521998 4.64778996 10.83733996 4.64778996 3 P 0 
L 10.83733996 4.64778996 10.83733996 4.62181004 3 P 0 
L 10.83733996 4.62181004 10.81136004 4.62181004 3 P 0 
L 10.81136004 4.62181004 10.81136004 4.61393002 3 P 0 
L 10.81136004 4.61393002 10.83733996 4.61393002 3 P 0 
L 10.83733996 4.61393002 10.83733996 4.58795 3 P 0 
L 10.83733996 4.58795 10.84521998 4.58795 3 P 0 
L 10.84521998 4.58795 10.84521998 4.61393002 3 P 0 
L 10.84521998 4.61393002 10.8712 4.61393002 3 P 0 
L 10.8712 4.61393002 10.8712 4.62181004 3 P 0 
L 10.8712 4.62181004 10.84521998 4.62181004 3 P 0 
L 10.70698996 4.70983996 10.64518002 4.70983996 3 P 0 
L 10.64518002 4.70983996 10.58573002 4.76928996 3 P 0 
L 10.58573002 4.76928996 10.58573002 5.05236004 3 P 0 
L 10.58573002 5.05236004 10.70541998 5.05236004 3 P 0 
L 10.80856004 5.05236004 10.92825 5.05236004 3 P 0 
L 10.92825 5.05236004 10.92825 4.76928996 3 P 0 
L 10.92825 4.76928996 10.8688 4.70983996 3 P 0 
L 10.8688 4.70983996 10.80581004 4.70983996 3 P 0 
S P 0
OB 10.944 4.8811 I
OS 10.569980019685 4.8811
OS 10.569980019685 5.06811003937
OS 10.70935 5.06811003937
OS 10.70935 4.93386003937
OS 10.804630019685 4.93386003937
OS 10.804630019685 5.06811003937
OS 10.944 5.06811003937
OS 10.944 4.8811
OE
SE
L 10.73493327 4.58933287 10.73263307 4.59093346 2 P 0 ;0,1=202,2=0.000000
L 10.73263307 4.59093346 10.7299503 4.592 2 P 0 ;0,1=202,2=0.000000
L 10.7299503 4.592 10.72688356 4.592 2 P 0 ;0,1=202,2=0.000000
L 10.72688356 4.592 10.72343287 4.59039931 2 P 0 ;0,1=202,2=0.000000
L 10.72343287 4.59039931 10.7207501 4.58773327 2 P 0 ;0,1=202,2=0.000000
L 10.7207501 4.58773327 10.71883317 4.58453297 2 P 0 ;0,1=202,2=0.000000
L 10.71883317 4.58453297 10.71729951 4.5791998 2 P 0 ;0,1=202,2=0.000000
L 10.71729951 4.5791998 10.71691624 4.5743998 2 P 0 ;0,1=202,2=0.000000
L 10.71691624 4.5743998 10.71768337 4.5695999 2 P 0 ;0,1=202,2=0.000000
L 10.71768337 4.5695999 10.71883317 4.56639961 2 P 0 ;0,1=202,2=0.000000
L 10.71883317 4.56639961 10.72113337 4.56319931 2 P 0 ;0,1=202,2=0.000000
L 10.72113337 4.56319931 10.72381683 4.56106644 2 P 0 ;0,1=202,2=0.000000
L 10.72381683 4.56106644 10.72649961 4.56 2 P 0 ;0,1=202,2=0.000000
L 10.72649961 4.56 10.72918307 4.56 2 P 0 ;0,1=202,2=0.000000
L 10.72918307 4.56 10.73186654 4.56106644 2 P 0 ;0,1=202,2=0.000000
L 10.73186654 4.56106644 10.73416673 4.56266604 2 P 0 ;0,1=202,2=0.000000
L 10.73416673 4.56266604 10.73608366 4.56479892 2 P 0 ;0,1=202,2=0.000000
L 10.76516673 4.56 10.74983317 4.56 2 P 0 ;0,1=202,2=0.000000
L 10.74983317 4.56 10.74983317 4.592 2 P 0 ;0,1=202,2=0.000000
L 10.74983317 4.592 10.76516673 4.592 2 P 0 ;0,1=202,2=0.000000
L 10.75903327 4.57653366 10.74983317 4.57653366 2 P 0 ;0,1=202,2=0.000000
L 10.78773307 4.56 10.78849961 4.56693278 2 P 0 ;0,1=202,2=0.000000
L 10.78849961 4.56693278 10.7896501 4.57279921 2 P 0 ;0,1=202,2=0.000000
L 10.7896501 4.57279921 10.79118307 4.57813327 2 P 0 ;0,1=202,2=0.000000
L 10.79118307 4.57813327 10.7931 4.5839997 2 P 0 ;0,1=202,2=0.000000
L 10.7931 4.5839997 10.79616673 4.592 2 P 0 ;0,1=202,2=0.000000
L 10.79616673 4.592 10.78083317 4.592 2 P 0 ;0,1=202,2=0.000000
L 4.86131998 4.62176998 4.86128002 4.64778996 3 P 0 
L 4.86128002 4.64778996 4.8534 4.64778996 3 P 0 
L 4.8534 4.64778996 4.8534 4.62181004 3 P 0 
L 4.8534 4.62181004 4.82741998 4.62181004 3 P 0 
L 4.82741998 4.62181004 4.82741998 4.61393002 3 P 0 
L 4.82741998 4.61393002 4.8534 4.61393002 3 P 0 
L 4.8534 4.61393002 4.8534 4.58795 3 P 0 
L 4.8534 4.58795 4.86128002 4.58795 3 P 0 
L 4.86128002 4.58795 4.86128002 4.61393002 3 P 0 
L 4.86128002 4.61393002 4.88726004 4.61393002 3 P 0 
L 4.88726004 4.61393002 4.88726004 4.62181004 3 P 0 
L 4.88726004 4.62181004 4.86128002 4.62181004 3 P 0 
L 4.70305 4.70983996 4.64123996 4.70983996 3 P 0 
L 4.64123996 4.70983996 4.58178996 4.76928996 3 P 0 
L 4.58178996 4.76928996 4.58178996 5.05236004 3 P 0 
L 4.58178996 5.05236004 4.70148002 5.05236004 3 P 0 
L 4.80461998 5.05236004 4.92431004 5.05236004 3 P 0 
L 4.92431004 5.05236004 4.92431004 4.76928996 3 P 0 
L 4.92431004 4.76928996 4.86486004 4.70983996 3 P 0 
L 4.86486004 4.70983996 4.80186998 4.70983996 3 P 0 
S P 0
OB 4.94006003937 4.8811 I
OS 4.56603996063 4.8811
OS 4.56603996063 5.06811003937
OS 4.70541003937 5.06811003937
OS 4.70541003937 4.93386003937
OS 4.80068996063 4.93386003937
OS 4.80068996063 5.06811003937
OS 4.94006003937 5.06811003937
OS 4.94006003937 4.8811
OE
SE
L 4.72993327 4.60933287 4.72763307 4.61093346 2 P 0 ;0,1=203,2=0.000000
L 4.72763307 4.61093346 4.7249503 4.612 2 P 0 ;0,1=203,2=0.000000
L 4.7249503 4.612 4.72188356 4.612 2 P 0 ;0,1=203,2=0.000000
L 4.72188356 4.612 4.71843287 4.61039931 2 P 0 ;0,1=203,2=0.000000
L 4.71843287 4.61039931 4.7157501 4.60773327 2 P 0 ;0,1=203,2=0.000000
L 4.7157501 4.60773327 4.71383317 4.60453297 2 P 0 ;0,1=203,2=0.000000
L 4.71383317 4.60453297 4.71229951 4.5991998 2 P 0 ;0,1=203,2=0.000000
L 4.71229951 4.5991998 4.71191624 4.5943998 2 P 0 ;0,1=203,2=0.000000
L 4.71191624 4.5943998 4.71268337 4.5895999 2 P 0 ;0,1=203,2=0.000000
L 4.71268337 4.5895999 4.71383317 4.58639961 2 P 0 ;0,1=203,2=0.000000
L 4.71383317 4.58639961 4.71613337 4.58319931 2 P 0 ;0,1=203,2=0.000000
L 4.71613337 4.58319931 4.71881683 4.58106644 2 P 0 ;0,1=203,2=0.000000
L 4.71881683 4.58106644 4.72149961 4.58 2 P 0 ;0,1=203,2=0.000000
L 4.72149961 4.58 4.72418307 4.58 2 P 0 ;0,1=203,2=0.000000
L 4.72418307 4.58 4.72686654 4.58106644 2 P 0 ;0,1=203,2=0.000000
L 4.72686654 4.58106644 4.72916673 4.58266604 2 P 0 ;0,1=203,2=0.000000
L 4.72916673 4.58266604 4.73108366 4.58479892 2 P 0 ;0,1=203,2=0.000000
L 4.76016673 4.58 4.74483317 4.58 2 P 0 ;0,1=203,2=0.000000
L 4.74483317 4.58 4.74483317 4.612 2 P 0 ;0,1=203,2=0.000000
L 4.74483317 4.612 4.76016673 4.612 2 P 0 ;0,1=203,2=0.000000
L 4.75403327 4.59653366 4.74483317 4.59653366 2 P 0 ;0,1=203,2=0.000000
L 4.77621644 4.59333238 4.7788999 4.59706683 2 P 0 ;0,1=203,2=0.000000
L 4.7788999 4.59706683 4.7812001 4.5991998 2 P 0 ;0,1=203,2=0.000000
L 4.7812001 4.5991998 4.78426683 4.60026624 2 P 0 ;0,1=203,2=0.000000
L 4.78426683 4.60026624 4.7869503 4.5991998 2 P 0 ;0,1=203,2=0.000000
L 4.7869503 4.5991998 4.78886654 4.59706683 2 P 0 ;0,1=203,2=0.000000
L 4.78886654 4.59706683 4.7904002 4.59386663 2 P 0 ;0,1=203,2=0.000000
L 4.7904002 4.59386663 4.79078346 4.59013307 2 P 0 ;0,1=203,2=0.000000
L 4.79078346 4.59013307 4.7904002 4.58693278 2 P 0 ;0,1=203,2=0.000000
L 4.7904002 4.58693278 4.78886654 4.58373248 2 P 0 ;0,1=203,2=0.000000
L 4.78886654 4.58373248 4.78656634 4.58106644 2 P 0 ;0,1=203,2=0.000000
L 4.78656634 4.58106644 4.78388356 4.58 2 P 0 ;0,1=203,2=0.000000
L 4.78388356 4.58 4.78081683 4.58106644 2 P 0 ;0,1=203,2=0.000000
L 4.78081683 4.58106644 4.77813337 4.58426575 2 P 0 ;0,1=203,2=0.000000
L 4.77813337 4.58426575 4.7765997 4.58906663 2 P 0 ;0,1=203,2=0.000000
L 4.7765997 4.58906663 4.77621644 4.5943998 2 P 0 ;0,1=203,2=0.000000
L 4.77621644 4.5943998 4.77698287 4.60133268 2 P 0 ;0,1=203,2=0.000000
L 4.77698287 4.60133268 4.77813337 4.60506713 2 P 0 ;0,1=203,2=0.000000
L 4.77813337 4.60506713 4.78004961 4.6087997 2 P 0 ;0,1=203,2=0.000000
L 4.78004961 4.6087997 4.78273307 4.61146673 2 P 0 ;0,1=203,2=0.000000
L 4.78273307 4.61146673 4.78541654 4.612 2 P 0 ;0,1=203,2=0.000000
L 4.78541654 4.612 4.7881 4.61093346 2 P 0 ;0,1=203,2=0.000000
L 4.7881 4.61093346 4.79001703 4.60826644 2 P 0 ;0,1=203,2=0.000000
L 4.47131998 4.62176998 4.47128002 4.64778996 3 P 0 
L 4.47128002 4.64778996 4.4634 4.64778996 3 P 0 
L 4.4634 4.64778996 4.4634 4.62181004 3 P 0 
L 4.4634 4.62181004 4.43741998 4.62181004 3 P 0 
L 4.43741998 4.62181004 4.43741998 4.61393002 3 P 0 
L 4.43741998 4.61393002 4.4634 4.61393002 3 P 0 
L 4.4634 4.61393002 4.4634 4.58795 3 P 0 
L 4.4634 4.58795 4.47128002 4.58795 3 P 0 
L 4.47128002 4.58795 4.47128002 4.61393002 3 P 0 
L 4.47128002 4.61393002 4.49726004 4.61393002 3 P 0 
L 4.49726004 4.61393002 4.49726004 4.62181004 3 P 0 
L 4.49726004 4.62181004 4.47128002 4.62181004 3 P 0 
L 4.31305 4.70983996 4.25123996 4.70983996 3 P 0 
L 4.25123996 4.70983996 4.19178996 4.76928996 3 P 0 
L 4.19178996 4.76928996 4.19178996 5.05236004 3 P 0 
L 4.19178996 5.05236004 4.31148002 5.05236004 3 P 0 
L 4.41461998 5.05236004 4.53431004 5.05236004 3 P 0 
L 4.53431004 5.05236004 4.53431004 4.76928996 3 P 0 
L 4.53431004 4.76928996 4.47486004 4.70983996 3 P 0 
L 4.47486004 4.70983996 4.41186998 4.70983996 3 P 0 
S P 0
OB 4.55006003937 4.8811 I
OS 4.17603996063 4.8811
OS 4.17603996063 5.06811003937
OS 4.31541003937 5.06811003937
OS 4.31541003937 4.93386003937
OS 4.41068996063 4.93386003937
OS 4.41068996063 5.06811003937
OS 4.55006003937 5.06811003937
OS 4.55006003937 4.8811
OE
SE
L 4.34493327 4.61433287 4.34263307 4.61593346 2 P 0 ;0,1=204,2=0.000000
L 4.34263307 4.61593346 4.3399503 4.617 2 P 0 ;0,1=204,2=0.000000
L 4.3399503 4.617 4.33688356 4.617 2 P 0 ;0,1=204,2=0.000000
L 4.33688356 4.617 4.33343287 4.61539931 2 P 0 ;0,1=204,2=0.000000
L 4.33343287 4.61539931 4.3307501 4.61273327 2 P 0 ;0,1=204,2=0.000000
L 4.3307501 4.61273327 4.32883317 4.60953297 2 P 0 ;0,1=204,2=0.000000
L 4.32883317 4.60953297 4.32729951 4.6041998 2 P 0 ;0,1=204,2=0.000000
L 4.32729951 4.6041998 4.32691624 4.5993998 2 P 0 ;0,1=204,2=0.000000
L 4.32691624 4.5993998 4.32768337 4.5945999 2 P 0 ;0,1=204,2=0.000000
L 4.32768337 4.5945999 4.32883317 4.59139961 2 P 0 ;0,1=204,2=0.000000
L 4.32883317 4.59139961 4.33113337 4.58819931 2 P 0 ;0,1=204,2=0.000000
L 4.33113337 4.58819931 4.33381683 4.58606644 2 P 0 ;0,1=204,2=0.000000
L 4.33381683 4.58606644 4.33649961 4.585 2 P 0 ;0,1=204,2=0.000000
L 4.33649961 4.585 4.33918307 4.585 2 P 0 ;0,1=204,2=0.000000
L 4.33918307 4.585 4.34186654 4.58606644 2 P 0 ;0,1=204,2=0.000000
L 4.34186654 4.58606644 4.34416673 4.58766604 2 P 0 ;0,1=204,2=0.000000
L 4.34416673 4.58766604 4.34608366 4.58979892 2 P 0 ;0,1=204,2=0.000000
L 4.37516673 4.585 4.35983317 4.585 2 P 0 ;0,1=204,2=0.000000
L 4.35983317 4.585 4.35983317 4.617 2 P 0 ;0,1=204,2=0.000000
L 4.35983317 4.617 4.37516673 4.617 2 P 0 ;0,1=204,2=0.000000
L 4.36903327 4.60153366 4.35983317 4.60153366 2 P 0 ;0,1=204,2=0.000000
L 4.39121644 4.61166673 4.39351663 4.61486614 2 P 0 ;0,1=204,2=0.000000
L 4.39351663 4.61486614 4.3962001 4.61646673 2 P 0 ;0,1=204,2=0.000000
L 4.3962001 4.61646673 4.39926683 4.617 2 P 0 ;0,1=204,2=0.000000
L 4.39926683 4.617 4.4031 4.61593346 2 P 0 ;0,1=204,2=0.000000
L 4.4031 4.61593346 4.40578346 4.61326644 2 P 0 ;0,1=204,2=0.000000
L 4.40578346 4.61326644 4.40655 4.61006713 2 P 0 ;0,1=204,2=0.000000
L 4.40655 4.61006713 4.40616673 4.60686585 2 P 0 ;0,1=204,2=0.000000
L 4.40616673 4.60686585 4.40463307 4.6041998 2 P 0 ;0,1=204,2=0.000000
L 4.40463307 4.6041998 4.39696663 4.59886663 2 P 0 ;0,1=204,2=0.000000
L 4.39696663 4.59886663 4.39351663 4.59513307 2 P 0 ;0,1=204,2=0.000000
L 4.39351663 4.59513307 4.39121644 4.58979892 2 P 0 ;0,1=204,2=0.000000
L 4.39121644 4.58979892 4.3904499 4.585 2 P 0 ;0,1=204,2=0.000000
L 4.3904499 4.585 4.40655 4.585 2 P 0 ;0,1=204,2=0.000000
L 11.50315 4.67528002 11.53071004 4.67528002 3 P 0 
L 11.53071004 4.67528002 11.53071004 4.68315 3 P 0 
L 11.53071004 4.68315 11.50315 4.68315 3 P 0 
L 11.50315 4.68315 11.50315 4.71071004 3 P 0 
L 11.50315 4.71071004 11.49528002 4.71071004 3 P 0 
L 11.49528002 4.71071004 11.49528002 4.68315 3 P 0 
L 11.49528002 4.68315 11.46771998 4.68315 3 P 0 
L 11.46771998 4.68315 11.46771998 4.67528002 3 P 0 
L 11.46771998 4.67528002 11.49528002 4.67528002 3 P 0 
L 11.49528002 4.67528002 11.49528002 4.64771998 3 P 0 
L 11.49528002 4.64771998 11.50315 4.64771998 3 P 0 
L 11.50315 4.64771998 11.50315 4.67528002 3 P 0 
L 11.91141998 4.93591004 11.91141998 5.09156998 3 P 0 
L 11.91141998 5.09156998 11.56826998 5.09156998 3 P 0 
L 11.56826998 5.09156998 11.48858002 5.01188996 3 P 0 
L 11.48858002 5.01188996 11.48858002 4.92843002 3 P 0 
L 11.48818996 4.83353996 11.48818996 4.7485 3 P 0 
L 11.48818996 4.7485 11.56811004 4.66858002 3 P 0 
L 11.56811004 4.66858002 11.91141998 4.66858002 3 P 0 
L 11.91141998 4.66858002 11.91141998 4.82291004 3 P 0 
S P 0
OB 11.7 5.106380019685 I
OS 11.926380019685 5.106380019685
OS 11.926380019685 4.93
OS 11.779130019685 4.93
OS 11.779130019685 4.82763996063
OS 11.926380019685 4.82763996063
OS 11.926380019685 4.653619980315
OS 11.7 4.653619980315
OS 11.7 5.106380019685
OE
SE
L 11.48993327 4.62933287 11.48763307 4.63093346 2 P 0 ;0,1=205,2=0.000000
L 11.48763307 4.63093346 11.4849503 4.632 2 P 0 ;0,1=205,2=0.000000
L 11.4849503 4.632 11.48188356 4.632 2 P 0 ;0,1=205,2=0.000000
L 11.48188356 4.632 11.47843287 4.63039931 2 P 0 ;0,1=205,2=0.000000
L 11.47843287 4.63039931 11.4757501 4.62773327 2 P 0 ;0,1=205,2=0.000000
L 11.4757501 4.62773327 11.47383317 4.62453297 2 P 0 ;0,1=205,2=0.000000
L 11.47383317 4.62453297 11.47229951 4.6191998 2 P 0 ;0,1=205,2=0.000000
L 11.47229951 4.6191998 11.47191624 4.6143998 2 P 0 ;0,1=205,2=0.000000
L 11.47191624 4.6143998 11.47268337 4.6095999 2 P 0 ;0,1=205,2=0.000000
L 11.47268337 4.6095999 11.47383317 4.60639961 2 P 0 ;0,1=205,2=0.000000
L 11.47383317 4.60639961 11.47613337 4.60319931 2 P 0 ;0,1=205,2=0.000000
L 11.47613337 4.60319931 11.47881683 4.60106644 2 P 0 ;0,1=205,2=0.000000
L 11.47881683 4.60106644 11.48149961 4.6 2 P 0 ;0,1=205,2=0.000000
L 11.48149961 4.6 11.48418307 4.6 2 P 0 ;0,1=205,2=0.000000
L 11.48418307 4.6 11.48686654 4.60106644 2 P 0 ;0,1=205,2=0.000000
L 11.48686654 4.60106644 11.48916673 4.60266604 2 P 0 ;0,1=205,2=0.000000
L 11.48916673 4.60266604 11.49108366 4.60479892 2 P 0 ;0,1=205,2=0.000000
L 11.52016673 4.6 11.50483317 4.6 2 P 0 ;0,1=205,2=0.000000
L 11.50483317 4.6 11.50483317 4.632 2 P 0 ;0,1=205,2=0.000000
L 11.50483317 4.632 11.52016673 4.632 2 P 0 ;0,1=205,2=0.000000
L 11.51403327 4.61653366 11.50483317 4.61653366 2 P 0 ;0,1=205,2=0.000000
L 11.54349961 4.6 11.54349961 4.632 2 P 0 ;0,1=205,2=0.000000
L 11.54349961 4.632 11.5388999 4.6256003 2 P 0 ;0,1=205,2=0.000000
L 11.5388999 4.6 11.54809931 4.6 2 P 0 ;0,1=205,2=0.000000
A 5.60336004 4.5952 5.60336004 4.5952 5.59778996 4.5952 2 P 0 N
L 5.645 4.70966654 5.62 4.70966654 2 P 0 ;0,1=206,2=270.000000
L 5.62 4.70966654 5.62 4.71606663 2 P 0 ;0,1=206,2=270.000000
L 5.62 4.71606663 5.62125059 4.7182 2 P 0 ;0,1=206,2=270.000000
L 5.62125059 4.7182 5.62416663 4.7198001 2 P 0 ;0,1=206,2=270.000000
L 5.62416663 4.7198001 5.6275 4.72033337 2 P 0 ;0,1=206,2=270.000000
L 5.6275 4.72033337 5.63083337 4.7198001 2 P 0 ;0,1=206,2=270.000000
L 5.63083337 4.7198001 5.63333356 4.71846663 2 P 0 ;0,1=206,2=270.000000
L 5.63333356 4.71846663 5.63458406 4.71606663 2 P 0 ;0,1=206,2=270.000000
L 5.63458406 4.71606663 5.63458406 4.70966654 2 P 0 ;0,1=206,2=270.000000
L 5.64166742 4.7333999 5.6437503 4.73553327 2 P 0 ;0,1=206,2=270.000000
L 5.6437503 4.73553327 5.645 4.73793327 2 P 0 ;0,1=206,2=270.000000
L 5.645 4.73793327 5.645 4.74006663 2 P 0 ;0,1=206,2=270.000000
L 5.645 4.74006663 5.6437503 4.7422 2 P 0 ;0,1=206,2=270.000000
L 5.6437503 4.7422 5.64166742 4.7438001 2 P 0 ;0,1=206,2=270.000000
L 5.64166742 4.7438001 5.6387499 4.7446 2 P 0 ;0,1=206,2=270.000000
L 5.6387499 4.7446 5.63583386 4.74406673 2 P 0 ;0,1=206,2=270.000000
L 5.63583386 4.74406673 5.63333356 4.74273327 2 P 0 ;0,1=206,2=270.000000
L 5.63333356 4.74273327 5.63166654 4.74033327 2 P 0 ;0,1=206,2=270.000000
L 5.63166654 4.74033327 5.63083337 4.73713346 2 P 0 ;0,1=206,2=270.000000
L 5.63083337 4.73713346 5.62916703 4.73526663 2 P 0 ;0,1=206,2=270.000000
L 5.62916703 4.73526663 5.6262502 4.73446634 2 P 0 ;0,1=206,2=270.000000
L 5.6262502 4.73446634 5.62333346 4.7350001 2 P 0 ;0,1=206,2=270.000000
L 5.62333346 4.7350001 5.62125059 4.73633317 2 P 0 ;0,1=206,2=270.000000
L 5.62125059 4.73633317 5.62 4.7381999 2 P 0 ;0,1=206,2=270.000000
L 5.62 4.7381999 5.62 4.74006663 2 P 0 ;0,1=206,2=270.000000
L 5.62 4.74006663 5.62083317 4.74193337 2 P 0 ;0,1=206,2=270.000000
L 5.62083317 4.74193337 5.62291683 4.74353356 2 P 0 ;0,1=206,2=270.000000
L 5.62 4.7629997 5.645 4.7629997 2 P 0 ;0,1=206,2=270.000000
L 5.62 4.75686673 5.62 4.76913317 2 P 0 ;0,1=206,2=270.000000
L 5.62208366 4.79286663 5.62083317 4.79126644 2 P 0 ;0,1=206,2=270.000000
L 5.62083317 4.79126644 5.62 4.7894002 2 P 0 ;0,1=206,2=270.000000
L 5.62 4.7894002 5.62 4.78726683 2 P 0 ;0,1=206,2=270.000000
L 5.62 4.78726683 5.62125059 4.78486634 2 P 0 ;0,1=206,2=270.000000
L 5.62125059 4.78486634 5.62333346 4.7830001 2 P 0 ;0,1=206,2=270.000000
L 5.62333346 4.7830001 5.62583366 4.78166654 2 P 0 ;0,1=206,2=270.000000
L 5.62583366 4.78166654 5.6300002 4.78059961 2 P 0 ;0,1=206,2=270.000000
L 5.6300002 4.78059961 5.6337502 4.78033297 2 P 0 ;0,1=206,2=270.000000
L 5.6337502 4.78033297 5.6375001 4.78086673 2 P 0 ;0,1=206,2=270.000000
L 5.6375001 4.78086673 5.64000039 4.78166654 2 P 0 ;0,1=206,2=270.000000
L 5.64000039 4.78166654 5.64250059 4.78326663 2 P 0 ;0,1=206,2=270.000000
L 5.64250059 4.78326663 5.64416693 4.78513346 2 P 0 ;0,1=206,2=270.000000
L 5.64416693 4.78513346 5.645 4.7869997 2 P 0 ;0,1=206,2=270.000000
L 5.645 4.7869997 5.645 4.78886644 2 P 0 ;0,1=206,2=270.000000
L 5.645 4.78886644 5.64416693 4.79073327 2 P 0 ;0,1=206,2=270.000000
L 5.64416693 4.79073327 5.64291713 4.79233337 2 P 0 ;0,1=206,2=270.000000
L 5.64291713 4.79233337 5.64125089 4.79366693 2 P 0 ;0,1=206,2=270.000000
L 5.62416663 4.80593317 5.62166713 4.80753327 2 P 0 ;0,1=206,2=270.000000
L 5.62166713 4.80753327 5.62041663 4.8094 2 P 0 ;0,1=206,2=270.000000
L 5.62041663 4.8094 5.62 4.81153337 2 P 0 ;0,1=206,2=270.000000
L 5.62 4.81153337 5.62083317 4.8142 2 P 0 ;0,1=206,2=270.000000
L 5.62083317 4.8142 5.62291683 4.81606673 2 P 0 ;0,1=206,2=270.000000
L 5.62291683 4.81606673 5.62541634 4.8166 2 P 0 ;0,1=206,2=270.000000
L 5.62541634 4.8166 5.62791732 4.81633337 2 P 0 ;0,1=206,2=270.000000
L 5.62791732 4.81633337 5.6300002 4.81526644 2 P 0 ;0,1=206,2=270.000000
L 5.6300002 4.81526644 5.63416673 4.80993327 2 P 0 ;0,1=206,2=270.000000
L 5.63416673 4.80993327 5.63708356 4.80753327 2 P 0 ;0,1=206,2=270.000000
L 5.63708356 4.80753327 5.64125089 4.80593317 2 P 0 ;0,1=206,2=270.000000
L 5.64125089 4.80593317 5.645 4.8053999 2 P 0 ;0,1=206,2=270.000000
L 5.645 4.8053999 5.645 4.8166 2 P 0 ;0,1=206,2=270.000000
L 5.63458406 4.82993317 5.63166654 4.8317999 2 P 0 ;0,1=206,2=270.000000
L 5.63166654 4.8317999 5.6300002 4.8334 2 P 0 ;0,1=206,2=270.000000
L 5.6300002 4.8334 5.62916703 4.83553337 2 P 0 ;0,1=206,2=270.000000
L 5.62916703 4.83553337 5.6300002 4.8374002 2 P 0 ;0,1=206,2=270.000000
L 5.6300002 4.8374002 5.63166654 4.83873327 2 P 0 ;0,1=206,2=270.000000
L 5.63166654 4.83873327 5.63416673 4.8398001 2 P 0 ;0,1=206,2=270.000000
L 5.63416673 4.8398001 5.63708356 4.84006673 2 P 0 ;0,1=206,2=270.000000
L 5.63708356 4.84006673 5.63958376 4.8398001 2 P 0 ;0,1=206,2=270.000000
L 5.63958376 4.8398001 5.64208396 4.83873327 2 P 0 ;0,1=206,2=270.000000
L 5.64208396 4.83873327 5.64416693 4.83713307 2 P 0 ;0,1=206,2=270.000000
L 5.64416693 4.83713307 5.645 4.83526683 2 P 0 ;0,1=206,2=270.000000
L 5.645 4.83526683 5.64416693 4.83313346 2 P 0 ;0,1=206,2=270.000000
L 5.64416693 4.83313346 5.64166742 4.83126663 2 P 0 ;0,1=206,2=270.000000
L 5.64166742 4.83126663 5.63791673 4.8301998 2 P 0 ;0,1=206,2=270.000000
L 5.63791673 4.8301998 5.6337502 4.82993317 2 P 0 ;0,1=206,2=270.000000
L 5.6337502 4.82993317 5.62833386 4.83046634 2 P 0 ;0,1=206,2=270.000000
L 5.62833386 4.83046634 5.62541634 4.83126663 2 P 0 ;0,1=206,2=270.000000
L 5.62541634 4.83126663 5.6225003 4.8325997 2 P 0 ;0,1=206,2=270.000000
L 5.6225003 4.8325997 5.62041663 4.83446654 2 P 0 ;0,1=206,2=270.000000
L 5.62041663 4.83446654 5.62 4.83633327 2 P 0 ;0,1=206,2=270.000000
L 5.62 4.83633327 5.62083317 4.8382 2 P 0 ;0,1=206,2=270.000000
L 5.62083317 4.8382 5.62291683 4.83953356 2 P 0 ;0,1=206,2=270.000000
A 5.68266004 4.5952 5.68266004 4.5952 5.67708996 4.5952 2 P 0 N
L 5.72 4.70966654 5.695 4.70966654 2 P 0 ;0,1=207,2=270.000000
L 5.695 4.70966654 5.695 4.71606663 2 P 0 ;0,1=207,2=270.000000
L 5.695 4.71606663 5.69625059 4.7182 2 P 0 ;0,1=207,2=270.000000
L 5.69625059 4.7182 5.69916663 4.7198001 2 P 0 ;0,1=207,2=270.000000
L 5.69916663 4.7198001 5.7025 4.72033337 2 P 0 ;0,1=207,2=270.000000
L 5.7025 4.72033337 5.70583337 4.7198001 2 P 0 ;0,1=207,2=270.000000
L 5.70583337 4.7198001 5.70833356 4.71846663 2 P 0 ;0,1=207,2=270.000000
L 5.70833356 4.71846663 5.70958406 4.71606663 2 P 0 ;0,1=207,2=270.000000
L 5.70958406 4.71606663 5.70958406 4.70966654 2 P 0 ;0,1=207,2=270.000000
L 5.71666742 4.7333999 5.7187503 4.73553327 2 P 0 ;0,1=207,2=270.000000
L 5.7187503 4.73553327 5.72 4.73793327 2 P 0 ;0,1=207,2=270.000000
L 5.72 4.73793327 5.72 4.74006663 2 P 0 ;0,1=207,2=270.000000
L 5.72 4.74006663 5.7187503 4.7422 2 P 0 ;0,1=207,2=270.000000
L 5.7187503 4.7422 5.71666742 4.7438001 2 P 0 ;0,1=207,2=270.000000
L 5.71666742 4.7438001 5.7137499 4.7446 2 P 0 ;0,1=207,2=270.000000
L 5.7137499 4.7446 5.71083386 4.74406673 2 P 0 ;0,1=207,2=270.000000
L 5.71083386 4.74406673 5.70833356 4.74273327 2 P 0 ;0,1=207,2=270.000000
L 5.70833356 4.74273327 5.70666654 4.74033327 2 P 0 ;0,1=207,2=270.000000
L 5.70666654 4.74033327 5.70583337 4.73713346 2 P 0 ;0,1=207,2=270.000000
L 5.70583337 4.73713346 5.70416703 4.73526663 2 P 0 ;0,1=207,2=270.000000
L 5.70416703 4.73526663 5.7012502 4.73446634 2 P 0 ;0,1=207,2=270.000000
L 5.7012502 4.73446634 5.69833346 4.7350001 2 P 0 ;0,1=207,2=270.000000
L 5.69833346 4.7350001 5.69625059 4.73633317 2 P 0 ;0,1=207,2=270.000000
L 5.69625059 4.73633317 5.695 4.7381999 2 P 0 ;0,1=207,2=270.000000
L 5.695 4.7381999 5.695 4.74006663 2 P 0 ;0,1=207,2=270.000000
L 5.695 4.74006663 5.69583317 4.74193337 2 P 0 ;0,1=207,2=270.000000
L 5.69583317 4.74193337 5.69791683 4.74353356 2 P 0 ;0,1=207,2=270.000000
L 5.695 4.7629997 5.72 4.7629997 2 P 0 ;0,1=207,2=270.000000
L 5.695 4.75686673 5.695 4.76913317 2 P 0 ;0,1=207,2=270.000000
L 5.69708366 4.79286663 5.69583317 4.79126644 2 P 0 ;0,1=207,2=270.000000
L 5.69583317 4.79126644 5.695 4.7894002 2 P 0 ;0,1=207,2=270.000000
L 5.695 4.7894002 5.695 4.78726683 2 P 0 ;0,1=207,2=270.000000
L 5.695 4.78726683 5.69625059 4.78486634 2 P 0 ;0,1=207,2=270.000000
L 5.69625059 4.78486634 5.69833346 4.7830001 2 P 0 ;0,1=207,2=270.000000
L 5.69833346 4.7830001 5.70083366 4.78166654 2 P 0 ;0,1=207,2=270.000000
L 5.70083366 4.78166654 5.7050002 4.78059961 2 P 0 ;0,1=207,2=270.000000
L 5.7050002 4.78059961 5.7087502 4.78033297 2 P 0 ;0,1=207,2=270.000000
L 5.7087502 4.78033297 5.7125001 4.78086673 2 P 0 ;0,1=207,2=270.000000
L 5.7125001 4.78086673 5.71500039 4.78166654 2 P 0 ;0,1=207,2=270.000000
L 5.71500039 4.78166654 5.71750059 4.78326663 2 P 0 ;0,1=207,2=270.000000
L 5.71750059 4.78326663 5.71916693 4.78513346 2 P 0 ;0,1=207,2=270.000000
L 5.71916693 4.78513346 5.72 4.7869997 2 P 0 ;0,1=207,2=270.000000
L 5.72 4.7869997 5.72 4.78886644 2 P 0 ;0,1=207,2=270.000000
L 5.72 4.78886644 5.71916693 4.79073327 2 P 0 ;0,1=207,2=270.000000
L 5.71916693 4.79073327 5.71791713 4.79233337 2 P 0 ;0,1=207,2=270.000000
L 5.71791713 4.79233337 5.71625089 4.79366693 2 P 0 ;0,1=207,2=270.000000
L 5.71500039 4.80513327 5.71791713 4.80673297 2 P 0 ;0,1=207,2=270.000000
L 5.71791713 4.80673297 5.71958346 4.80886634 2 P 0 ;0,1=207,2=270.000000
L 5.71958346 4.80886634 5.72 4.81126683 2 P 0 ;0,1=207,2=270.000000
L 5.72 4.81126683 5.71958346 4.8134002 2 P 0 ;0,1=207,2=270.000000
L 5.71958346 4.8134002 5.71750059 4.81553356 2 P 0 ;0,1=207,2=270.000000
L 5.71750059 4.81553356 5.71500039 4.81686663 2 P 0 ;0,1=207,2=270.000000
L 5.71500039 4.81686663 5.7125001 4.81713317 2 P 0 ;0,1=207,2=270.000000
L 5.7125001 4.81713317 5.70958406 4.8166 2 P 0 ;0,1=207,2=270.000000
L 5.70958406 4.8166 5.70750039 4.81473327 2 P 0 ;0,1=207,2=270.000000
L 5.70750039 4.81473327 5.70666654 4.81286644 2 P 0 ;0,1=207,2=270.000000
L 5.70666654 4.81286644 5.70666654 4.81046654 2 P 0 ;0,1=207,2=270.000000
L 5.70666654 4.81286644 5.70541673 4.81446663 2 P 0 ;0,1=207,2=270.000000
L 5.70541673 4.81446663 5.70333386 4.8158001 2 P 0 ;0,1=207,2=270.000000
L 5.70333386 4.8158001 5.70083366 4.81633337 2 P 0 ;0,1=207,2=270.000000
L 5.70083366 4.81633337 5.69833346 4.8158001 2 P 0 ;0,1=207,2=270.000000
L 5.69833346 4.8158001 5.69625059 4.81446663 2 P 0 ;0,1=207,2=270.000000
L 5.69625059 4.81446663 5.695 4.81206663 2 P 0 ;0,1=207,2=270.000000
L 5.695 4.81206663 5.69541663 4.80966663 2 P 0 ;0,1=207,2=270.000000
L 5.69541663 4.80966663 5.69708366 4.80726663 2 P 0 ;0,1=207,2=270.000000
L 5.71500039 4.82913327 5.71791713 4.83073297 2 P 0 ;0,1=207,2=270.000000
L 5.71791713 4.83073297 5.71958346 4.83286634 2 P 0 ;0,1=207,2=270.000000
L 5.71958346 4.83286634 5.72 4.83526683 2 P 0 ;0,1=207,2=270.000000
L 5.72 4.83526683 5.71958346 4.8374002 2 P 0 ;0,1=207,2=270.000000
L 5.71958346 4.8374002 5.71750059 4.83953356 2 P 0 ;0,1=207,2=270.000000
L 5.71750059 4.83953356 5.71500039 4.84086663 2 P 0 ;0,1=207,2=270.000000
L 5.71500039 4.84086663 5.7125001 4.84113317 2 P 0 ;0,1=207,2=270.000000
L 5.7125001 4.84113317 5.70958406 4.8406 2 P 0 ;0,1=207,2=270.000000
L 5.70958406 4.8406 5.70750039 4.83873327 2 P 0 ;0,1=207,2=270.000000
L 5.70750039 4.83873327 5.70666654 4.83686644 2 P 0 ;0,1=207,2=270.000000
L 5.70666654 4.83686644 5.70666654 4.83446654 2 P 0 ;0,1=207,2=270.000000
L 5.70666654 4.83686644 5.70541673 4.83846663 2 P 0 ;0,1=207,2=270.000000
L 5.70541673 4.83846663 5.70333386 4.8398001 2 P 0 ;0,1=207,2=270.000000
L 5.70333386 4.8398001 5.70083366 4.84033337 2 P 0 ;0,1=207,2=270.000000
L 5.70083366 4.84033337 5.69833346 4.8398001 2 P 0 ;0,1=207,2=270.000000
L 5.69833346 4.8398001 5.69625059 4.83846663 2 P 0 ;0,1=207,2=270.000000
L 5.69625059 4.83846663 5.695 4.83606663 2 P 0 ;0,1=207,2=270.000000
L 5.695 4.83606663 5.69541663 4.83366663 2 P 0 ;0,1=207,2=270.000000
L 5.69541663 4.83366663 5.69708366 4.83126663 2 P 0 ;0,1=207,2=270.000000
A 5.84266004 4.5952 5.84266004 4.5952 5.83708996 4.5952 2 P 0 N
L 5.88 4.70966654 5.855 4.70966654 2 P 0 ;0,1=208,2=270.000000
L 5.855 4.70966654 5.855 4.71606663 2 P 0 ;0,1=208,2=270.000000
L 5.855 4.71606663 5.85625059 4.7182 2 P 0 ;0,1=208,2=270.000000
L 5.85625059 4.7182 5.85916663 4.7198001 2 P 0 ;0,1=208,2=270.000000
L 5.85916663 4.7198001 5.8625 4.72033337 2 P 0 ;0,1=208,2=270.000000
L 5.8625 4.72033337 5.86583337 4.7198001 2 P 0 ;0,1=208,2=270.000000
L 5.86583337 4.7198001 5.86833356 4.71846663 2 P 0 ;0,1=208,2=270.000000
L 5.86833356 4.71846663 5.86958406 4.71606663 2 P 0 ;0,1=208,2=270.000000
L 5.86958406 4.71606663 5.86958406 4.70966654 2 P 0 ;0,1=208,2=270.000000
L 5.87666742 4.7333999 5.8787503 4.73553327 2 P 0 ;0,1=208,2=270.000000
L 5.8787503 4.73553327 5.88 4.73793327 2 P 0 ;0,1=208,2=270.000000
L 5.88 4.73793327 5.88 4.74006663 2 P 0 ;0,1=208,2=270.000000
L 5.88 4.74006663 5.8787503 4.7422 2 P 0 ;0,1=208,2=270.000000
L 5.8787503 4.7422 5.87666742 4.7438001 2 P 0 ;0,1=208,2=270.000000
L 5.87666742 4.7438001 5.8737499 4.7446 2 P 0 ;0,1=208,2=270.000000
L 5.8737499 4.7446 5.87083386 4.74406673 2 P 0 ;0,1=208,2=270.000000
L 5.87083386 4.74406673 5.86833356 4.74273327 2 P 0 ;0,1=208,2=270.000000
L 5.86833356 4.74273327 5.86666654 4.74033327 2 P 0 ;0,1=208,2=270.000000
L 5.86666654 4.74033327 5.86583337 4.73713346 2 P 0 ;0,1=208,2=270.000000
L 5.86583337 4.73713346 5.86416703 4.73526663 2 P 0 ;0,1=208,2=270.000000
L 5.86416703 4.73526663 5.8612502 4.73446634 2 P 0 ;0,1=208,2=270.000000
L 5.8612502 4.73446634 5.85833346 4.7350001 2 P 0 ;0,1=208,2=270.000000
L 5.85833346 4.7350001 5.85625059 4.73633317 2 P 0 ;0,1=208,2=270.000000
L 5.85625059 4.73633317 5.855 4.7381999 2 P 0 ;0,1=208,2=270.000000
L 5.855 4.7381999 5.855 4.74006663 2 P 0 ;0,1=208,2=270.000000
L 5.855 4.74006663 5.85583317 4.74193337 2 P 0 ;0,1=208,2=270.000000
L 5.85583317 4.74193337 5.85791683 4.74353356 2 P 0 ;0,1=208,2=270.000000
L 5.855 4.7629997 5.88 4.7629997 2 P 0 ;0,1=208,2=270.000000
L 5.855 4.75686673 5.855 4.76913317 2 P 0 ;0,1=208,2=270.000000
L 5.85708366 4.79286663 5.85583317 4.79126644 2 P 0 ;0,1=208,2=270.000000
L 5.85583317 4.79126644 5.855 4.7894002 2 P 0 ;0,1=208,2=270.000000
L 5.855 4.7894002 5.855 4.78726683 2 P 0 ;0,1=208,2=270.000000
L 5.855 4.78726683 5.85625059 4.78486634 2 P 0 ;0,1=208,2=270.000000
L 5.85625059 4.78486634 5.85833346 4.7830001 2 P 0 ;0,1=208,2=270.000000
L 5.85833346 4.7830001 5.86083366 4.78166654 2 P 0 ;0,1=208,2=270.000000
L 5.86083366 4.78166654 5.8650002 4.78059961 2 P 0 ;0,1=208,2=270.000000
L 5.8650002 4.78059961 5.8687502 4.78033297 2 P 0 ;0,1=208,2=270.000000
L 5.8687502 4.78033297 5.8725001 4.78086673 2 P 0 ;0,1=208,2=270.000000
L 5.8725001 4.78086673 5.87500039 4.78166654 2 P 0 ;0,1=208,2=270.000000
L 5.87500039 4.78166654 5.87750059 4.78326663 2 P 0 ;0,1=208,2=270.000000
L 5.87750059 4.78326663 5.87916693 4.78513346 2 P 0 ;0,1=208,2=270.000000
L 5.87916693 4.78513346 5.88 4.7869997 2 P 0 ;0,1=208,2=270.000000
L 5.88 4.7869997 5.88 4.78886644 2 P 0 ;0,1=208,2=270.000000
L 5.88 4.78886644 5.87916693 4.79073327 2 P 0 ;0,1=208,2=270.000000
L 5.87916693 4.79073327 5.87791713 4.79233337 2 P 0 ;0,1=208,2=270.000000
L 5.87791713 4.79233337 5.87625089 4.79366693 2 P 0 ;0,1=208,2=270.000000
L 5.87500039 4.80513327 5.87791713 4.80673297 2 P 0 ;0,1=208,2=270.000000
L 5.87791713 4.80673297 5.87958346 4.80886634 2 P 0 ;0,1=208,2=270.000000
L 5.87958346 4.80886634 5.88 4.81126683 2 P 0 ;0,1=208,2=270.000000
L 5.88 4.81126683 5.87958346 4.8134002 2 P 0 ;0,1=208,2=270.000000
L 5.87958346 4.8134002 5.87750059 4.81553356 2 P 0 ;0,1=208,2=270.000000
L 5.87750059 4.81553356 5.87500039 4.81686663 2 P 0 ;0,1=208,2=270.000000
L 5.87500039 4.81686663 5.8725001 4.81713317 2 P 0 ;0,1=208,2=270.000000
L 5.8725001 4.81713317 5.86958406 4.8166 2 P 0 ;0,1=208,2=270.000000
L 5.86958406 4.8166 5.86750039 4.81473327 2 P 0 ;0,1=208,2=270.000000
L 5.86750039 4.81473327 5.86666654 4.81286644 2 P 0 ;0,1=208,2=270.000000
L 5.86666654 4.81286644 5.86666654 4.81046654 2 P 0 ;0,1=208,2=270.000000
L 5.86666654 4.81286644 5.86541673 4.81446663 2 P 0 ;0,1=208,2=270.000000
L 5.86541673 4.81446663 5.86333386 4.8158001 2 P 0 ;0,1=208,2=270.000000
L 5.86333386 4.8158001 5.86083366 4.81633337 2 P 0 ;0,1=208,2=270.000000
L 5.86083366 4.81633337 5.85833346 4.8158001 2 P 0 ;0,1=208,2=270.000000
L 5.85833346 4.8158001 5.85625059 4.81446663 2 P 0 ;0,1=208,2=270.000000
L 5.85625059 4.81446663 5.855 4.81206663 2 P 0 ;0,1=208,2=270.000000
L 5.855 4.81206663 5.85541663 4.80966663 2 P 0 ;0,1=208,2=270.000000
L 5.85541663 4.80966663 5.85708366 4.80726663 2 P 0 ;0,1=208,2=270.000000
L 5.88 4.8382 5.855 4.8382 2 P 0 ;0,1=208,2=270.000000
L 5.855 4.8382 5.87291673 4.82833297 2 P 0 ;0,1=208,2=270.000000
L 5.87291673 4.82833297 5.87291673 4.84166693 2 P 0 ;0,1=208,2=270.000000
A 5.76266004 4.5952 5.76266004 4.5952 5.75708996 4.5952 2 P 0 N
L 5.8 4.70966654 5.775 4.70966654 2 P 0 ;0,1=209,2=270.000000
L 5.775 4.70966654 5.775 4.71606663 2 P 0 ;0,1=209,2=270.000000
L 5.775 4.71606663 5.77625059 4.7182 2 P 0 ;0,1=209,2=270.000000
L 5.77625059 4.7182 5.77916663 4.7198001 2 P 0 ;0,1=209,2=270.000000
L 5.77916663 4.7198001 5.7825 4.72033337 2 P 0 ;0,1=209,2=270.000000
L 5.7825 4.72033337 5.78583337 4.7198001 2 P 0 ;0,1=209,2=270.000000
L 5.78583337 4.7198001 5.78833356 4.71846663 2 P 0 ;0,1=209,2=270.000000
L 5.78833356 4.71846663 5.78958406 4.71606663 2 P 0 ;0,1=209,2=270.000000
L 5.78958406 4.71606663 5.78958406 4.70966654 2 P 0 ;0,1=209,2=270.000000
L 5.79666742 4.7333999 5.7987503 4.73553327 2 P 0 ;0,1=209,2=270.000000
L 5.7987503 4.73553327 5.8 4.73793327 2 P 0 ;0,1=209,2=270.000000
L 5.8 4.73793327 5.8 4.74006663 2 P 0 ;0,1=209,2=270.000000
L 5.8 4.74006663 5.7987503 4.7422 2 P 0 ;0,1=209,2=270.000000
L 5.7987503 4.7422 5.79666742 4.7438001 2 P 0 ;0,1=209,2=270.000000
L 5.79666742 4.7438001 5.7937499 4.7446 2 P 0 ;0,1=209,2=270.000000
L 5.7937499 4.7446 5.79083386 4.74406673 2 P 0 ;0,1=209,2=270.000000
L 5.79083386 4.74406673 5.78833356 4.74273327 2 P 0 ;0,1=209,2=270.000000
L 5.78833356 4.74273327 5.78666654 4.74033327 2 P 0 ;0,1=209,2=270.000000
L 5.78666654 4.74033327 5.78583337 4.73713346 2 P 0 ;0,1=209,2=270.000000
L 5.78583337 4.73713346 5.78416703 4.73526663 2 P 0 ;0,1=209,2=270.000000
L 5.78416703 4.73526663 5.7812502 4.73446634 2 P 0 ;0,1=209,2=270.000000
L 5.7812502 4.73446634 5.77833346 4.7350001 2 P 0 ;0,1=209,2=270.000000
L 5.77833346 4.7350001 5.77625059 4.73633317 2 P 0 ;0,1=209,2=270.000000
L 5.77625059 4.73633317 5.775 4.7381999 2 P 0 ;0,1=209,2=270.000000
L 5.775 4.7381999 5.775 4.74006663 2 P 0 ;0,1=209,2=270.000000
L 5.775 4.74006663 5.77583317 4.74193337 2 P 0 ;0,1=209,2=270.000000
L 5.77583317 4.74193337 5.77791683 4.74353356 2 P 0 ;0,1=209,2=270.000000
L 5.775 4.7629997 5.8 4.7629997 2 P 0 ;0,1=209,2=270.000000
L 5.775 4.75686673 5.775 4.76913317 2 P 0 ;0,1=209,2=270.000000
L 5.77708366 4.79286663 5.77583317 4.79126644 2 P 0 ;0,1=209,2=270.000000
L 5.77583317 4.79126644 5.775 4.7894002 2 P 0 ;0,1=209,2=270.000000
L 5.775 4.7894002 5.775 4.78726683 2 P 0 ;0,1=209,2=270.000000
L 5.775 4.78726683 5.77625059 4.78486634 2 P 0 ;0,1=209,2=270.000000
L 5.77625059 4.78486634 5.77833346 4.7830001 2 P 0 ;0,1=209,2=270.000000
L 5.77833346 4.7830001 5.78083366 4.78166654 2 P 0 ;0,1=209,2=270.000000
L 5.78083366 4.78166654 5.7850002 4.78059961 2 P 0 ;0,1=209,2=270.000000
L 5.7850002 4.78059961 5.7887502 4.78033297 2 P 0 ;0,1=209,2=270.000000
L 5.7887502 4.78033297 5.7925001 4.78086673 2 P 0 ;0,1=209,2=270.000000
L 5.7925001 4.78086673 5.79500039 4.78166654 2 P 0 ;0,1=209,2=270.000000
L 5.79500039 4.78166654 5.79750059 4.78326663 2 P 0 ;0,1=209,2=270.000000
L 5.79750059 4.78326663 5.79916693 4.78513346 2 P 0 ;0,1=209,2=270.000000
L 5.79916693 4.78513346 5.8 4.7869997 2 P 0 ;0,1=209,2=270.000000
L 5.8 4.7869997 5.8 4.78886644 2 P 0 ;0,1=209,2=270.000000
L 5.8 4.78886644 5.79916693 4.79073327 2 P 0 ;0,1=209,2=270.000000
L 5.79916693 4.79073327 5.79791713 4.79233337 2 P 0 ;0,1=209,2=270.000000
L 5.79791713 4.79233337 5.79625089 4.79366693 2 P 0 ;0,1=209,2=270.000000
L 5.77916663 4.80593317 5.77666713 4.80753327 2 P 0 ;0,1=209,2=270.000000
L 5.77666713 4.80753327 5.77541663 4.8094 2 P 0 ;0,1=209,2=270.000000
L 5.77541663 4.8094 5.775 4.81153337 2 P 0 ;0,1=209,2=270.000000
L 5.775 4.81153337 5.77583317 4.8142 2 P 0 ;0,1=209,2=270.000000
L 5.77583317 4.8142 5.77791683 4.81606673 2 P 0 ;0,1=209,2=270.000000
L 5.77791683 4.81606673 5.78041634 4.8166 2 P 0 ;0,1=209,2=270.000000
L 5.78041634 4.8166 5.78291732 4.81633337 2 P 0 ;0,1=209,2=270.000000
L 5.78291732 4.81633337 5.7850002 4.81526644 2 P 0 ;0,1=209,2=270.000000
L 5.7850002 4.81526644 5.78916673 4.80993327 2 P 0 ;0,1=209,2=270.000000
L 5.78916673 4.80993327 5.79208356 4.80753327 2 P 0 ;0,1=209,2=270.000000
L 5.79208356 4.80753327 5.79625089 4.80593317 2 P 0 ;0,1=209,2=270.000000
L 5.79625089 4.80593317 5.8 4.8053999 2 P 0 ;0,1=209,2=270.000000
L 5.8 4.8053999 5.8 4.8166 2 P 0 ;0,1=209,2=270.000000
L 5.79708396 4.83046634 5.79916693 4.83233317 2 P 0 ;0,1=209,2=270.000000
L 5.79916693 4.83233317 5.8 4.83446654 2 P 0 ;0,1=209,2=270.000000
L 5.8 4.83446654 5.79916693 4.8365999 2 P 0 ;0,1=209,2=270.000000
L 5.79916693 4.8365999 5.79666742 4.83846663 2 P 0 ;0,1=209,2=270.000000
L 5.79666742 4.83846663 5.79291673 4.8398001 2 P 0 ;0,1=209,2=270.000000
L 5.79291673 4.8398001 5.78916673 4.84033337 2 P 0 ;0,1=209,2=270.000000
L 5.78916673 4.84033337 5.78458366 4.84033337 2 P 0 ;0,1=209,2=270.000000
L 5.78458366 4.84033337 5.78083366 4.8398001 2 P 0 ;0,1=209,2=270.000000
L 5.78083366 4.8398001 5.7775003 4.83846663 2 P 0 ;0,1=209,2=270.000000
L 5.7775003 4.83846663 5.77583317 4.83686644 2 P 0 ;0,1=209,2=270.000000
L 5.77583317 4.83686644 5.775 4.8349997 2 P 0 ;0,1=209,2=270.000000
L 5.775 4.8349997 5.77583317 4.83286634 2 P 0 ;0,1=209,2=270.000000
L 5.77583317 4.83286634 5.7775003 4.83126663 2 P 0 ;0,1=209,2=270.000000
L 5.7775003 4.83126663 5.7799997 4.8301998 2 P 0 ;0,1=209,2=270.000000
L 5.7799997 4.8301998 5.78333386 4.82966654 2 P 0 ;0,1=209,2=270.000000
L 5.78333386 4.82966654 5.7862499 4.8301998 2 P 0 ;0,1=209,2=270.000000
L 5.7862499 4.8301998 5.78916673 4.83153327 2 P 0 ;0,1=209,2=270.000000
L 5.78916673 4.83153327 5.79083386 4.83313346 2 P 0 ;0,1=209,2=270.000000
L 5.79083386 4.83313346 5.79125039 4.8349997 2 P 0 ;0,1=209,2=270.000000
L 5.79125039 4.8349997 5.79041722 4.83713307 2 P 0 ;0,1=209,2=270.000000
L 5.79041722 4.83713307 5.78833356 4.83873327 2 P 0 ;0,1=209,2=270.000000
L 5.78833356 4.83873327 5.78458366 4.84033337 2 P 0 ;0,1=209,2=270.000000
A 6.08266004 4.5952 6.08266004 4.5952 6.07708996 4.5952 2 P 0 N
L 6.12 4.70966654 6.095 4.70966654 2 P 0 ;0,1=210,2=270.000000
L 6.095 4.70966654 6.095 4.71606663 2 P 0 ;0,1=210,2=270.000000
L 6.095 4.71606663 6.09625059 4.7182 2 P 0 ;0,1=210,2=270.000000
L 6.09625059 4.7182 6.09916663 4.7198001 2 P 0 ;0,1=210,2=270.000000
L 6.09916663 4.7198001 6.1025 4.72033337 2 P 0 ;0,1=210,2=270.000000
L 6.1025 4.72033337 6.10583337 4.7198001 2 P 0 ;0,1=210,2=270.000000
L 6.10583337 4.7198001 6.10833356 4.71846663 2 P 0 ;0,1=210,2=270.000000
L 6.10833356 4.71846663 6.10958406 4.71606663 2 P 0 ;0,1=210,2=270.000000
L 6.10958406 4.71606663 6.10958406 4.70966654 2 P 0 ;0,1=210,2=270.000000
L 6.11666742 4.7333999 6.1187503 4.73553327 2 P 0 ;0,1=210,2=270.000000
L 6.1187503 4.73553327 6.12 4.73793327 2 P 0 ;0,1=210,2=270.000000
L 6.12 4.73793327 6.12 4.74006663 2 P 0 ;0,1=210,2=270.000000
L 6.12 4.74006663 6.1187503 4.7422 2 P 0 ;0,1=210,2=270.000000
L 6.1187503 4.7422 6.11666742 4.7438001 2 P 0 ;0,1=210,2=270.000000
L 6.11666742 4.7438001 6.1137499 4.7446 2 P 0 ;0,1=210,2=270.000000
L 6.1137499 4.7446 6.11083386 4.74406673 2 P 0 ;0,1=210,2=270.000000
L 6.11083386 4.74406673 6.10833356 4.74273327 2 P 0 ;0,1=210,2=270.000000
L 6.10833356 4.74273327 6.10666654 4.74033327 2 P 0 ;0,1=210,2=270.000000
L 6.10666654 4.74033327 6.10583337 4.73713346 2 P 0 ;0,1=210,2=270.000000
L 6.10583337 4.73713346 6.10416703 4.73526663 2 P 0 ;0,1=210,2=270.000000
L 6.10416703 4.73526663 6.1012502 4.73446634 2 P 0 ;0,1=210,2=270.000000
L 6.1012502 4.73446634 6.09833346 4.7350001 2 P 0 ;0,1=210,2=270.000000
L 6.09833346 4.7350001 6.09625059 4.73633317 2 P 0 ;0,1=210,2=270.000000
L 6.09625059 4.73633317 6.095 4.7381999 2 P 0 ;0,1=210,2=270.000000
L 6.095 4.7381999 6.095 4.74006663 2 P 0 ;0,1=210,2=270.000000
L 6.095 4.74006663 6.09583317 4.74193337 2 P 0 ;0,1=210,2=270.000000
L 6.09583317 4.74193337 6.09791683 4.74353356 2 P 0 ;0,1=210,2=270.000000
L 6.095 4.7629997 6.12 4.7629997 2 P 0 ;0,1=210,2=270.000000
L 6.095 4.75686673 6.095 4.76913317 2 P 0 ;0,1=210,2=270.000000
L 6.09708366 4.79286663 6.09583317 4.79126644 2 P 0 ;0,1=210,2=270.000000
L 6.09583317 4.79126644 6.095 4.7894002 2 P 0 ;0,1=210,2=270.000000
L 6.095 4.7894002 6.095 4.78726683 2 P 0 ;0,1=210,2=270.000000
L 6.095 4.78726683 6.09625059 4.78486634 2 P 0 ;0,1=210,2=270.000000
L 6.09625059 4.78486634 6.09833346 4.7830001 2 P 0 ;0,1=210,2=270.000000
L 6.09833346 4.7830001 6.10083366 4.78166654 2 P 0 ;0,1=210,2=270.000000
L 6.10083366 4.78166654 6.1050002 4.78059961 2 P 0 ;0,1=210,2=270.000000
L 6.1050002 4.78059961 6.1087502 4.78033297 2 P 0 ;0,1=210,2=270.000000
L 6.1087502 4.78033297 6.1125001 4.78086673 2 P 0 ;0,1=210,2=270.000000
L 6.1125001 4.78086673 6.11500039 4.78166654 2 P 0 ;0,1=210,2=270.000000
L 6.11500039 4.78166654 6.11750059 4.78326663 2 P 0 ;0,1=210,2=270.000000
L 6.11750059 4.78326663 6.11916693 4.78513346 2 P 0 ;0,1=210,2=270.000000
L 6.11916693 4.78513346 6.12 4.7869997 2 P 0 ;0,1=210,2=270.000000
L 6.12 4.7869997 6.12 4.78886644 2 P 0 ;0,1=210,2=270.000000
L 6.12 4.78886644 6.11916693 4.79073327 2 P 0 ;0,1=210,2=270.000000
L 6.11916693 4.79073327 6.11791713 4.79233337 2 P 0 ;0,1=210,2=270.000000
L 6.11791713 4.79233337 6.11625089 4.79366693 2 P 0 ;0,1=210,2=270.000000
L 6.12 4.8109997 6.095 4.8109997 2 P 0 ;0,1=210,2=270.000000
L 6.095 4.8109997 6.0999997 4.8077999 2 P 0 ;0,1=210,2=270.000000
L 6.12 4.8077999 6.12 4.81419951 2 P 0 ;0,1=210,2=270.000000
L 6.12 4.8382 6.095 4.8382 2 P 0 ;0,1=210,2=270.000000
L 6.095 4.8382 6.11291673 4.82833297 2 P 0 ;0,1=210,2=270.000000
L 6.11291673 4.82833297 6.11291673 4.84166693 2 P 0 ;0,1=210,2=270.000000
A 5.92266004 4.5952 5.92266004 4.5952 5.91708996 4.5952 2 P 0 N
L 5.96 4.70966654 5.935 4.70966654 2 P 0 ;0,1=211,2=270.000000
L 5.935 4.70966654 5.935 4.71606663 2 P 0 ;0,1=211,2=270.000000
L 5.935 4.71606663 5.93625059 4.7182 2 P 0 ;0,1=211,2=270.000000
L 5.93625059 4.7182 5.93916663 4.7198001 2 P 0 ;0,1=211,2=270.000000
L 5.93916663 4.7198001 5.9425 4.72033337 2 P 0 ;0,1=211,2=270.000000
L 5.9425 4.72033337 5.94583337 4.7198001 2 P 0 ;0,1=211,2=270.000000
L 5.94583337 4.7198001 5.94833356 4.71846663 2 P 0 ;0,1=211,2=270.000000
L 5.94833356 4.71846663 5.94958406 4.71606663 2 P 0 ;0,1=211,2=270.000000
L 5.94958406 4.71606663 5.94958406 4.70966654 2 P 0 ;0,1=211,2=270.000000
L 5.95666742 4.7333999 5.9587503 4.73553327 2 P 0 ;0,1=211,2=270.000000
L 5.9587503 4.73553327 5.96 4.73793327 2 P 0 ;0,1=211,2=270.000000
L 5.96 4.73793327 5.96 4.74006663 2 P 0 ;0,1=211,2=270.000000
L 5.96 4.74006663 5.9587503 4.7422 2 P 0 ;0,1=211,2=270.000000
L 5.9587503 4.7422 5.95666742 4.7438001 2 P 0 ;0,1=211,2=270.000000
L 5.95666742 4.7438001 5.9537499 4.7446 2 P 0 ;0,1=211,2=270.000000
L 5.9537499 4.7446 5.95083386 4.74406673 2 P 0 ;0,1=211,2=270.000000
L 5.95083386 4.74406673 5.94833356 4.74273327 2 P 0 ;0,1=211,2=270.000000
L 5.94833356 4.74273327 5.94666654 4.74033327 2 P 0 ;0,1=211,2=270.000000
L 5.94666654 4.74033327 5.94583337 4.73713346 2 P 0 ;0,1=211,2=270.000000
L 5.94583337 4.73713346 5.94416703 4.73526663 2 P 0 ;0,1=211,2=270.000000
L 5.94416703 4.73526663 5.9412502 4.73446634 2 P 0 ;0,1=211,2=270.000000
L 5.9412502 4.73446634 5.93833346 4.7350001 2 P 0 ;0,1=211,2=270.000000
L 5.93833346 4.7350001 5.93625059 4.73633317 2 P 0 ;0,1=211,2=270.000000
L 5.93625059 4.73633317 5.935 4.7381999 2 P 0 ;0,1=211,2=270.000000
L 5.935 4.7381999 5.935 4.74006663 2 P 0 ;0,1=211,2=270.000000
L 5.935 4.74006663 5.93583317 4.74193337 2 P 0 ;0,1=211,2=270.000000
L 5.93583317 4.74193337 5.93791683 4.74353356 2 P 0 ;0,1=211,2=270.000000
L 5.935 4.7629997 5.96 4.7629997 2 P 0 ;0,1=211,2=270.000000
L 5.935 4.75686673 5.935 4.76913317 2 P 0 ;0,1=211,2=270.000000
L 5.93708366 4.79286663 5.93583317 4.79126644 2 P 0 ;0,1=211,2=270.000000
L 5.93583317 4.79126644 5.935 4.7894002 2 P 0 ;0,1=211,2=270.000000
L 5.935 4.7894002 5.935 4.78726683 2 P 0 ;0,1=211,2=270.000000
L 5.935 4.78726683 5.93625059 4.78486634 2 P 0 ;0,1=211,2=270.000000
L 5.93625059 4.78486634 5.93833346 4.7830001 2 P 0 ;0,1=211,2=270.000000
L 5.93833346 4.7830001 5.94083366 4.78166654 2 P 0 ;0,1=211,2=270.000000
L 5.94083366 4.78166654 5.9450002 4.78059961 2 P 0 ;0,1=211,2=270.000000
L 5.9450002 4.78059961 5.9487502 4.78033297 2 P 0 ;0,1=211,2=270.000000
L 5.9487502 4.78033297 5.9525001 4.78086673 2 P 0 ;0,1=211,2=270.000000
L 5.9525001 4.78086673 5.95500039 4.78166654 2 P 0 ;0,1=211,2=270.000000
L 5.95500039 4.78166654 5.95750059 4.78326663 2 P 0 ;0,1=211,2=270.000000
L 5.95750059 4.78326663 5.95916693 4.78513346 2 P 0 ;0,1=211,2=270.000000
L 5.95916693 4.78513346 5.96 4.7869997 2 P 0 ;0,1=211,2=270.000000
L 5.96 4.7869997 5.96 4.78886644 2 P 0 ;0,1=211,2=270.000000
L 5.96 4.78886644 5.95916693 4.79073327 2 P 0 ;0,1=211,2=270.000000
L 5.95916693 4.79073327 5.95791713 4.79233337 2 P 0 ;0,1=211,2=270.000000
L 5.95791713 4.79233337 5.95625089 4.79366693 2 P 0 ;0,1=211,2=270.000000
L 5.96 4.8109997 5.935 4.8109997 2 P 0 ;0,1=211,2=270.000000
L 5.935 4.8109997 5.9399997 4.8077999 2 P 0 ;0,1=211,2=270.000000
L 5.96 4.8077999 5.96 4.81419951 2 P 0 ;0,1=211,2=270.000000
L 5.95625089 4.82913327 5.95833376 4.83073297 2 P 0 ;0,1=211,2=270.000000
L 5.95833376 4.83073297 5.95958346 4.8325997 2 P 0 ;0,1=211,2=270.000000
L 5.95958346 4.8325997 5.96 4.8349997 2 P 0 ;0,1=211,2=270.000000
L 5.96 4.8349997 5.95916693 4.8374002 2 P 0 ;0,1=211,2=270.000000
L 5.95916693 4.8374002 5.95750059 4.83926644 2 P 0 ;0,1=211,2=270.000000
L 5.95750059 4.83926644 5.95458376 4.8406 2 P 0 ;0,1=211,2=270.000000
L 5.95458376 4.8406 5.95125039 4.84086663 2 P 0 ;0,1=211,2=270.000000
L 5.95125039 4.84086663 5.94791703 4.84033337 2 P 0 ;0,1=211,2=270.000000
L 5.94791703 4.84033337 5.94583337 4.8389998 2 P 0 ;0,1=211,2=270.000000
L 5.94583337 4.8389998 5.94416703 4.83713307 2 P 0 ;0,1=211,2=270.000000
L 5.94416703 4.83713307 5.94375049 4.83526683 2 P 0 ;0,1=211,2=270.000000
L 5.94375049 4.83526683 5.94416703 4.8334 2 P 0 ;0,1=211,2=270.000000
L 5.94416703 4.8334 5.94583337 4.8310001 2 P 0 ;0,1=211,2=270.000000
L 5.94583337 4.8310001 5.935 4.8317999 2 P 0 ;0,1=211,2=270.000000
L 5.935 4.8317999 5.935 4.8389998 2 P 0 ;0,1=211,2=270.000000
A 6.00266004 4.5952 6.00266004 4.5952 5.99708996 4.5952 2 P 0 N
L 6.045 4.70966654 6.02 4.70966654 2 P 0 ;0,1=212,2=270.000000
L 6.02 4.70966654 6.02 4.71606663 2 P 0 ;0,1=212,2=270.000000
L 6.02 4.71606663 6.02125059 4.7182 2 P 0 ;0,1=212,2=270.000000
L 6.02125059 4.7182 6.02416663 4.7198001 2 P 0 ;0,1=212,2=270.000000
L 6.02416663 4.7198001 6.0275 4.72033337 2 P 0 ;0,1=212,2=270.000000
L 6.0275 4.72033337 6.03083337 4.7198001 2 P 0 ;0,1=212,2=270.000000
L 6.03083337 4.7198001 6.03333356 4.71846663 2 P 0 ;0,1=212,2=270.000000
L 6.03333356 4.71846663 6.03458406 4.71606663 2 P 0 ;0,1=212,2=270.000000
L 6.03458406 4.71606663 6.03458406 4.70966654 2 P 0 ;0,1=212,2=270.000000
L 6.04166742 4.7333999 6.0437503 4.73553327 2 P 0 ;0,1=212,2=270.000000
L 6.0437503 4.73553327 6.045 4.73793327 2 P 0 ;0,1=212,2=270.000000
L 6.045 4.73793327 6.045 4.74006663 2 P 0 ;0,1=212,2=270.000000
L 6.045 4.74006663 6.0437503 4.7422 2 P 0 ;0,1=212,2=270.000000
L 6.0437503 4.7422 6.04166742 4.7438001 2 P 0 ;0,1=212,2=270.000000
L 6.04166742 4.7438001 6.0387499 4.7446 2 P 0 ;0,1=212,2=270.000000
L 6.0387499 4.7446 6.03583386 4.74406673 2 P 0 ;0,1=212,2=270.000000
L 6.03583386 4.74406673 6.03333356 4.74273327 2 P 0 ;0,1=212,2=270.000000
L 6.03333356 4.74273327 6.03166654 4.74033327 2 P 0 ;0,1=212,2=270.000000
L 6.03166654 4.74033327 6.03083337 4.73713346 2 P 0 ;0,1=212,2=270.000000
L 6.03083337 4.73713346 6.02916703 4.73526663 2 P 0 ;0,1=212,2=270.000000
L 6.02916703 4.73526663 6.0262502 4.73446634 2 P 0 ;0,1=212,2=270.000000
L 6.0262502 4.73446634 6.02333346 4.7350001 2 P 0 ;0,1=212,2=270.000000
L 6.02333346 4.7350001 6.02125059 4.73633317 2 P 0 ;0,1=212,2=270.000000
L 6.02125059 4.73633317 6.02 4.7381999 2 P 0 ;0,1=212,2=270.000000
L 6.02 4.7381999 6.02 4.74006663 2 P 0 ;0,1=212,2=270.000000
L 6.02 4.74006663 6.02083317 4.74193337 2 P 0 ;0,1=212,2=270.000000
L 6.02083317 4.74193337 6.02291683 4.74353356 2 P 0 ;0,1=212,2=270.000000
L 6.02 4.7629997 6.045 4.7629997 2 P 0 ;0,1=212,2=270.000000
L 6.02 4.75686673 6.02 4.76913317 2 P 0 ;0,1=212,2=270.000000
L 6.02208366 4.79286663 6.02083317 4.79126644 2 P 0 ;0,1=212,2=270.000000
L 6.02083317 4.79126644 6.02 4.7894002 2 P 0 ;0,1=212,2=270.000000
L 6.02 4.7894002 6.02 4.78726683 2 P 0 ;0,1=212,2=270.000000
L 6.02 4.78726683 6.02125059 4.78486634 2 P 0 ;0,1=212,2=270.000000
L 6.02125059 4.78486634 6.02333346 4.7830001 2 P 0 ;0,1=212,2=270.000000
L 6.02333346 4.7830001 6.02583366 4.78166654 2 P 0 ;0,1=212,2=270.000000
L 6.02583366 4.78166654 6.0300002 4.78059961 2 P 0 ;0,1=212,2=270.000000
L 6.0300002 4.78059961 6.0337502 4.78033297 2 P 0 ;0,1=212,2=270.000000
L 6.0337502 4.78033297 6.0375001 4.78086673 2 P 0 ;0,1=212,2=270.000000
L 6.0375001 4.78086673 6.04000039 4.78166654 2 P 0 ;0,1=212,2=270.000000
L 6.04000039 4.78166654 6.04250059 4.78326663 2 P 0 ;0,1=212,2=270.000000
L 6.04250059 4.78326663 6.04416693 4.78513346 2 P 0 ;0,1=212,2=270.000000
L 6.04416693 4.78513346 6.045 4.7869997 2 P 0 ;0,1=212,2=270.000000
L 6.045 4.7869997 6.045 4.78886644 2 P 0 ;0,1=212,2=270.000000
L 6.045 4.78886644 6.04416693 4.79073327 2 P 0 ;0,1=212,2=270.000000
L 6.04416693 4.79073327 6.04291713 4.79233337 2 P 0 ;0,1=212,2=270.000000
L 6.04291713 4.79233337 6.04125089 4.79366693 2 P 0 ;0,1=212,2=270.000000
L 6.02416663 4.80593317 6.02166713 4.80753327 2 P 0 ;0,1=212,2=270.000000
L 6.02166713 4.80753327 6.02041663 4.8094 2 P 0 ;0,1=212,2=270.000000
L 6.02041663 4.8094 6.02 4.81153337 2 P 0 ;0,1=212,2=270.000000
L 6.02 4.81153337 6.02083317 4.8142 2 P 0 ;0,1=212,2=270.000000
L 6.02083317 4.8142 6.02291683 4.81606673 2 P 0 ;0,1=212,2=270.000000
L 6.02291683 4.81606673 6.02541634 4.8166 2 P 0 ;0,1=212,2=270.000000
L 6.02541634 4.8166 6.02791732 4.81633337 2 P 0 ;0,1=212,2=270.000000
L 6.02791732 4.81633337 6.0300002 4.81526644 2 P 0 ;0,1=212,2=270.000000
L 6.0300002 4.81526644 6.03416673 4.80993327 2 P 0 ;0,1=212,2=270.000000
L 6.03416673 4.80993327 6.03708356 4.80753327 2 P 0 ;0,1=212,2=270.000000
L 6.03708356 4.80753327 6.04125089 4.80593317 2 P 0 ;0,1=212,2=270.000000
L 6.04125089 4.80593317 6.045 4.8053999 2 P 0 ;0,1=212,2=270.000000
L 6.045 4.8053999 6.045 4.8166 2 P 0 ;0,1=212,2=270.000000
L 6.045 4.8349997 6.04458346 4.83686644 2 P 0 ;0,1=212,2=270.000000
L 6.04458346 4.83686644 6.04333376 4.8389998 2 P 0 ;0,1=212,2=270.000000
L 6.04333376 4.8389998 6.04125089 4.84033337 2 P 0 ;0,1=212,2=270.000000
L 6.04125089 4.84033337 6.03833327 4.84086663 2 P 0 ;0,1=212,2=270.000000
L 6.03833327 4.84086663 6.03541722 4.84033337 2 P 0 ;0,1=212,2=270.000000
L 6.03541722 4.84033337 6.03291703 4.83873327 2 P 0 ;0,1=212,2=270.000000
L 6.03291703 4.83873327 6.03166654 4.83633327 2 P 0 ;0,1=212,2=270.000000
L 6.03166654 4.83633327 6.03166654 4.83366663 2 P 0 ;0,1=212,2=270.000000
L 6.03166654 4.83366663 6.03083337 4.83206654 2 P 0 ;0,1=212,2=270.000000
L 6.03083337 4.83206654 6.02875049 4.83073297 2 P 0 ;0,1=212,2=270.000000
L 6.02875049 4.83073297 6.02583366 4.8301998 2 P 0 ;0,1=212,2=270.000000
L 6.02583366 4.8301998 6.02291683 4.8310001 2 P 0 ;0,1=212,2=270.000000
L 6.02291683 4.8310001 6.02083317 4.83286634 2 P 0 ;0,1=212,2=270.000000
L 6.02083317 4.83286634 6.02 4.8349997 2 P 0 ;0,1=212,2=270.000000
L 6.02 4.8349997 6.02083317 4.83713307 2 P 0 ;0,1=212,2=270.000000
L 6.02083317 4.83713307 6.02291683 4.8389998 2 P 0 ;0,1=212,2=270.000000
L 6.02291683 4.8389998 6.02583366 4.8398001 2 P 0 ;0,1=212,2=270.000000
L 6.02583366 4.8398001 6.02875049 4.83926644 2 P 0 ;0,1=212,2=270.000000
L 6.02875049 4.83926644 6.03083337 4.83793337 2 P 0 ;0,1=212,2=270.000000
L 6.03083337 4.83793337 6.03166654 4.83633327 2 P 0 ;0,1=212,2=270.000000
L 6.03166654 4.83633327 6.03166654 4.83366663 2 P 0 ;0,1=212,2=270.000000
L 6.03166654 4.83366663 6.03291703 4.83126663 2 P 0 ;0,1=212,2=270.000000
L 6.03291703 4.83126663 6.03541722 4.82966654 2 P 0 ;0,1=212,2=270.000000
L 6.03541722 4.82966654 6.03833327 4.82913327 2 P 0 ;0,1=212,2=270.000000
L 6.03833327 4.82913327 6.04125089 4.82966654 2 P 0 ;0,1=212,2=270.000000
L 6.04125089 4.82966654 6.04333376 4.8310001 2 P 0 ;0,1=212,2=270.000000
L 6.04333376 4.8310001 6.04458346 4.83313346 2 P 0 ;0,1=212,2=270.000000
L 6.04458346 4.83313346 6.045 4.8349997 2 P 0 ;0,1=212,2=270.000000
A 6.70766004 4.7052 6.70766004 4.7052 6.70208996 4.7052 2 P 0 N
L 6.64666654 4.48 6.64666654 4.505 2 P 0 ;0,1=213,2=0.000000
L 6.64666654 4.505 6.65306663 4.505 2 P 0 ;0,1=213,2=0.000000
L 6.65306663 4.505 6.6552 4.50374941 2 P 0 ;0,1=213,2=0.000000
L 6.6552 4.50374941 6.6568001 4.50083337 2 P 0 ;0,1=213,2=0.000000
L 6.6568001 4.50083337 6.65733337 4.4975 2 P 0 ;0,1=213,2=0.000000
L 6.65733337 4.4975 6.6568001 4.49416663 2 P 0 ;0,1=213,2=0.000000
L 6.6568001 4.49416663 6.65546663 4.49166644 2 P 0 ;0,1=213,2=0.000000
L 6.65546663 4.49166644 6.65306663 4.49041594 2 P 0 ;0,1=213,2=0.000000
L 6.65306663 4.49041594 6.64666654 4.49041594 2 P 0 ;0,1=213,2=0.000000
L 6.6703999 4.48333258 6.67253327 4.4812497 2 P 0 ;0,1=213,2=0.000000
L 6.67253327 4.4812497 6.67493327 4.48 2 P 0 ;0,1=213,2=0.000000
L 6.67493327 4.48 6.67706663 4.48 2 P 0 ;0,1=213,2=0.000000
L 6.67706663 4.48 6.6792 4.4812497 2 P 0 ;0,1=213,2=0.000000
L 6.6792 4.4812497 6.6808001 4.48333258 2 P 0 ;0,1=213,2=0.000000
L 6.6808001 4.48333258 6.6816 4.4862501 2 P 0 ;0,1=213,2=0.000000
L 6.6816 4.4862501 6.68106673 4.48916614 2 P 0 ;0,1=213,2=0.000000
L 6.68106673 4.48916614 6.67973327 4.49166644 2 P 0 ;0,1=213,2=0.000000
L 6.67973327 4.49166644 6.67733327 4.49333346 2 P 0 ;0,1=213,2=0.000000
L 6.67733327 4.49333346 6.67413346 4.49416663 2 P 0 ;0,1=213,2=0.000000
L 6.67413346 4.49416663 6.67226663 4.49583297 2 P 0 ;0,1=213,2=0.000000
L 6.67226663 4.49583297 6.67146634 4.4987498 2 P 0 ;0,1=213,2=0.000000
L 6.67146634 4.4987498 6.6720001 4.50166654 2 P 0 ;0,1=213,2=0.000000
L 6.6720001 4.50166654 6.67333317 4.50374941 2 P 0 ;0,1=213,2=0.000000
L 6.67333317 4.50374941 6.6751999 4.505 2 P 0 ;0,1=213,2=0.000000
L 6.6751999 4.505 6.67706663 4.505 2 P 0 ;0,1=213,2=0.000000
L 6.67706663 4.505 6.67893337 4.50416683 2 P 0 ;0,1=213,2=0.000000
L 6.67893337 4.50416683 6.68053356 4.50208317 2 P 0 ;0,1=213,2=0.000000
L 6.6999997 4.505 6.6999997 4.48 2 P 0 ;0,1=213,2=0.000000
L 6.69386673 4.505 6.70613317 4.505 2 P 0 ;0,1=213,2=0.000000
L 6.72986663 4.50291634 6.72826644 4.50416683 2 P 0 ;0,1=213,2=0.000000
L 6.72826644 4.50416683 6.7264002 4.505 2 P 0 ;0,1=213,2=0.000000
L 6.7264002 4.505 6.72426683 4.505 2 P 0 ;0,1=213,2=0.000000
L 6.72426683 4.505 6.72186634 4.50374941 2 P 0 ;0,1=213,2=0.000000
L 6.72186634 4.50374941 6.7200001 4.50166654 2 P 0 ;0,1=213,2=0.000000
L 6.7200001 4.50166654 6.71866654 4.49916634 2 P 0 ;0,1=213,2=0.000000
L 6.71866654 4.49916634 6.71759961 4.4949998 2 P 0 ;0,1=213,2=0.000000
L 6.71759961 4.4949998 6.71733297 4.4912498 2 P 0 ;0,1=213,2=0.000000
L 6.71733297 4.4912498 6.71786673 4.4874999 2 P 0 ;0,1=213,2=0.000000
L 6.71786673 4.4874999 6.71866654 4.48499961 2 P 0 ;0,1=213,2=0.000000
L 6.71866654 4.48499961 6.72026663 4.48249941 2 P 0 ;0,1=213,2=0.000000
L 6.72026663 4.48249941 6.72213346 4.48083307 2 P 0 ;0,1=213,2=0.000000
L 6.72213346 4.48083307 6.7239997 4.48 2 P 0 ;0,1=213,2=0.000000
L 6.7239997 4.48 6.72586644 4.48 2 P 0 ;0,1=213,2=0.000000
L 6.72586644 4.48 6.72773327 4.48083307 2 P 0 ;0,1=213,2=0.000000
L 6.72773327 4.48083307 6.72933337 4.48208287 2 P 0 ;0,1=213,2=0.000000
L 6.72933337 4.48208287 6.73066693 4.48374911 2 P 0 ;0,1=213,2=0.000000
L 6.74213327 4.48374911 6.74373297 4.48166624 2 P 0 ;0,1=213,2=0.000000
L 6.74373297 4.48166624 6.7455997 4.48041654 2 P 0 ;0,1=213,2=0.000000
L 6.7455997 4.48041654 6.7479997 4.48 2 P 0 ;0,1=213,2=0.000000
L 6.7479997 4.48 6.7504002 4.48083307 2 P 0 ;0,1=213,2=0.000000
L 6.7504002 4.48083307 6.75226644 4.48249941 2 P 0 ;0,1=213,2=0.000000
L 6.75226644 4.48249941 6.7536 4.48541624 2 P 0 ;0,1=213,2=0.000000
L 6.7536 4.48541624 6.75386663 4.48874961 2 P 0 ;0,1=213,2=0.000000
L 6.75386663 4.48874961 6.75333337 4.49208297 2 P 0 ;0,1=213,2=0.000000
L 6.75333337 4.49208297 6.7519998 4.49416663 2 P 0 ;0,1=213,2=0.000000
L 6.7519998 4.49416663 6.75013307 4.49583297 2 P 0 ;0,1=213,2=0.000000
L 6.75013307 4.49583297 6.74826683 4.49624951 2 P 0 ;0,1=213,2=0.000000
L 6.74826683 4.49624951 6.7464 4.49583297 2 P 0 ;0,1=213,2=0.000000
L 6.7464 4.49583297 6.7440001 4.49416663 2 P 0 ;0,1=213,2=0.000000
L 6.7440001 4.49416663 6.7447999 4.505 2 P 0 ;0,1=213,2=0.000000
L 6.7447999 4.505 6.7519998 4.505 2 P 0 ;0,1=213,2=0.000000
A 6.70766004 4.6252 6.70766004 4.6252 6.70208996 4.6252 2 P 0 N
L 6.64466654 4.44 6.64466654 4.465 2 P 0 ;0,1=214,2=0.000000
L 6.64466654 4.465 6.65106663 4.465 2 P 0 ;0,1=214,2=0.000000
L 6.65106663 4.465 6.6532 4.46374941 2 P 0 ;0,1=214,2=0.000000
L 6.6532 4.46374941 6.6548001 4.46083337 2 P 0 ;0,1=214,2=0.000000
L 6.6548001 4.46083337 6.65533337 4.4575 2 P 0 ;0,1=214,2=0.000000
L 6.65533337 4.4575 6.6548001 4.45416663 2 P 0 ;0,1=214,2=0.000000
L 6.6548001 4.45416663 6.65346663 4.45166644 2 P 0 ;0,1=214,2=0.000000
L 6.65346663 4.45166644 6.65106663 4.45041594 2 P 0 ;0,1=214,2=0.000000
L 6.65106663 4.45041594 6.64466654 4.45041594 2 P 0 ;0,1=214,2=0.000000
L 6.6683999 4.44333258 6.67053327 4.4412497 2 P 0 ;0,1=214,2=0.000000
L 6.67053327 4.4412497 6.67293327 4.44 2 P 0 ;0,1=214,2=0.000000
L 6.67293327 4.44 6.67506663 4.44 2 P 0 ;0,1=214,2=0.000000
L 6.67506663 4.44 6.6772 4.4412497 2 P 0 ;0,1=214,2=0.000000
L 6.6772 4.4412497 6.6788001 4.44333258 2 P 0 ;0,1=214,2=0.000000
L 6.6788001 4.44333258 6.6796 4.4462501 2 P 0 ;0,1=214,2=0.000000
L 6.6796 4.4462501 6.67906673 4.44916614 2 P 0 ;0,1=214,2=0.000000
L 6.67906673 4.44916614 6.67773327 4.45166644 2 P 0 ;0,1=214,2=0.000000
L 6.67773327 4.45166644 6.67533327 4.45333346 2 P 0 ;0,1=214,2=0.000000
L 6.67533327 4.45333346 6.67213346 4.45416663 2 P 0 ;0,1=214,2=0.000000
L 6.67213346 4.45416663 6.67026663 4.45583297 2 P 0 ;0,1=214,2=0.000000
L 6.67026663 4.45583297 6.66946634 4.4587498 2 P 0 ;0,1=214,2=0.000000
L 6.66946634 4.4587498 6.6700001 4.46166654 2 P 0 ;0,1=214,2=0.000000
L 6.6700001 4.46166654 6.67133317 4.46374941 2 P 0 ;0,1=214,2=0.000000
L 6.67133317 4.46374941 6.6731999 4.465 2 P 0 ;0,1=214,2=0.000000
L 6.6731999 4.465 6.67506663 4.465 2 P 0 ;0,1=214,2=0.000000
L 6.67506663 4.465 6.67693337 4.46416683 2 P 0 ;0,1=214,2=0.000000
L 6.67693337 4.46416683 6.67853356 4.46208317 2 P 0 ;0,1=214,2=0.000000
L 6.6979997 4.465 6.6979997 4.44 2 P 0 ;0,1=214,2=0.000000
L 6.69186673 4.465 6.70413317 4.465 2 P 0 ;0,1=214,2=0.000000
L 6.72786663 4.46291634 6.72626644 4.46416683 2 P 0 ;0,1=214,2=0.000000
L 6.72626644 4.46416683 6.7244002 4.465 2 P 0 ;0,1=214,2=0.000000
L 6.7244002 4.465 6.72226683 4.465 2 P 0 ;0,1=214,2=0.000000
L 6.72226683 4.465 6.71986634 4.46374941 2 P 0 ;0,1=214,2=0.000000
L 6.71986634 4.46374941 6.7180001 4.46166654 2 P 0 ;0,1=214,2=0.000000
L 6.7180001 4.46166654 6.71666654 4.45916634 2 P 0 ;0,1=214,2=0.000000
L 6.71666654 4.45916634 6.71559961 4.4549998 2 P 0 ;0,1=214,2=0.000000
L 6.71559961 4.4549998 6.71533297 4.4512498 2 P 0 ;0,1=214,2=0.000000
L 6.71533297 4.4512498 6.71586673 4.4474999 2 P 0 ;0,1=214,2=0.000000
L 6.71586673 4.4474999 6.71666654 4.44499961 2 P 0 ;0,1=214,2=0.000000
L 6.71666654 4.44499961 6.71826663 4.44249941 2 P 0 ;0,1=214,2=0.000000
L 6.71826663 4.44249941 6.72013346 4.44083307 2 P 0 ;0,1=214,2=0.000000
L 6.72013346 4.44083307 6.7219997 4.44 2 P 0 ;0,1=214,2=0.000000
L 6.7219997 4.44 6.72386644 4.44 2 P 0 ;0,1=214,2=0.000000
L 6.72386644 4.44 6.72573327 4.44083307 2 P 0 ;0,1=214,2=0.000000
L 6.72573327 4.44083307 6.72733337 4.44208287 2 P 0 ;0,1=214,2=0.000000
L 6.72733337 4.44208287 6.72866693 4.44374911 2 P 0 ;0,1=214,2=0.000000
L 6.7459997 4.44 6.7459997 4.465 2 P 0 ;0,1=214,2=0.000000
L 6.7459997 4.465 6.7427999 4.4600003 2 P 0 ;0,1=214,2=0.000000
L 6.7427999 4.44 6.74919951 4.44 2 P 0 ;0,1=214,2=0.000000
L 6.7699997 4.44 6.7699997 4.465 2 P 0 ;0,1=214,2=0.000000
L 6.7699997 4.465 6.7667999 4.4600003 2 P 0 ;0,1=214,2=0.000000
L 6.7667999 4.44 6.77319951 4.44 2 P 0 ;0,1=214,2=0.000000
A 6.87676004 4.81705 6.87676004 4.81705 6.87118996 4.81705 2 P 0 N
L 6.97666654 4.81 6.97666654 4.835 2 P 0 ;0,1=215,2=0.000000
L 6.97666654 4.835 6.98306663 4.835 2 P 0 ;0,1=215,2=0.000000
L 6.98306663 4.835 6.9852 4.83374941 2 P 0 ;0,1=215,2=0.000000
L 6.9852 4.83374941 6.9868001 4.83083337 2 P 0 ;0,1=215,2=0.000000
L 6.9868001 4.83083337 6.98733337 4.8275 2 P 0 ;0,1=215,2=0.000000
L 6.98733337 4.8275 6.9868001 4.82416663 2 P 0 ;0,1=215,2=0.000000
L 6.9868001 4.82416663 6.98546663 4.82166644 2 P 0 ;0,1=215,2=0.000000
L 6.98546663 4.82166644 6.98306663 4.82041594 2 P 0 ;0,1=215,2=0.000000
L 6.98306663 4.82041594 6.97666654 4.82041594 2 P 0 ;0,1=215,2=0.000000
L 7.0003999 4.81333258 7.00253327 4.8112497 2 P 0 ;0,1=215,2=0.000000
L 7.00253327 4.8112497 7.00493327 4.81 2 P 0 ;0,1=215,2=0.000000
L 7.00493327 4.81 7.00706663 4.81 2 P 0 ;0,1=215,2=0.000000
L 7.00706663 4.81 7.0092 4.8112497 2 P 0 ;0,1=215,2=0.000000
L 7.0092 4.8112497 7.0108001 4.81333258 2 P 0 ;0,1=215,2=0.000000
L 7.0108001 4.81333258 7.0116 4.8162501 2 P 0 ;0,1=215,2=0.000000
L 7.0116 4.8162501 7.01106673 4.81916614 2 P 0 ;0,1=215,2=0.000000
L 7.01106673 4.81916614 7.00973327 4.82166644 2 P 0 ;0,1=215,2=0.000000
L 7.00973327 4.82166644 7.00733327 4.82333346 2 P 0 ;0,1=215,2=0.000000
L 7.00733327 4.82333346 7.00413346 4.82416663 2 P 0 ;0,1=215,2=0.000000
L 7.00413346 4.82416663 7.00226663 4.82583297 2 P 0 ;0,1=215,2=0.000000
L 7.00226663 4.82583297 7.00146634 4.8287498 2 P 0 ;0,1=215,2=0.000000
L 7.00146634 4.8287498 7.0020001 4.83166654 2 P 0 ;0,1=215,2=0.000000
L 7.0020001 4.83166654 7.00333317 4.83374941 2 P 0 ;0,1=215,2=0.000000
L 7.00333317 4.83374941 7.0051999 4.835 2 P 0 ;0,1=215,2=0.000000
L 7.0051999 4.835 7.00706663 4.835 2 P 0 ;0,1=215,2=0.000000
L 7.00706663 4.835 7.00893337 4.83416683 2 P 0 ;0,1=215,2=0.000000
L 7.00893337 4.83416683 7.01053356 4.83208317 2 P 0 ;0,1=215,2=0.000000
L 7.0299997 4.835 7.0299997 4.81 2 P 0 ;0,1=215,2=0.000000
L 7.02386673 4.835 7.03613317 4.835 2 P 0 ;0,1=215,2=0.000000
L 7.05986663 4.83291634 7.05826644 4.83416683 2 P 0 ;0,1=215,2=0.000000
L 7.05826644 4.83416683 7.0564002 4.835 2 P 0 ;0,1=215,2=0.000000
L 7.0564002 4.835 7.05426683 4.835 2 P 0 ;0,1=215,2=0.000000
L 7.05426683 4.835 7.05186634 4.83374941 2 P 0 ;0,1=215,2=0.000000
L 7.05186634 4.83374941 7.0500001 4.83166654 2 P 0 ;0,1=215,2=0.000000
L 7.0500001 4.83166654 7.04866654 4.82916634 2 P 0 ;0,1=215,2=0.000000
L 7.04866654 4.82916634 7.04759961 4.8249998 2 P 0 ;0,1=215,2=0.000000
L 7.04759961 4.8249998 7.04733297 4.8212498 2 P 0 ;0,1=215,2=0.000000
L 7.04733297 4.8212498 7.04786673 4.8174999 2 P 0 ;0,1=215,2=0.000000
L 7.04786673 4.8174999 7.04866654 4.81499961 2 P 0 ;0,1=215,2=0.000000
L 7.04866654 4.81499961 7.05026663 4.81249941 2 P 0 ;0,1=215,2=0.000000
L 7.05026663 4.81249941 7.05213346 4.81083307 2 P 0 ;0,1=215,2=0.000000
L 7.05213346 4.81083307 7.0539997 4.81 2 P 0 ;0,1=215,2=0.000000
L 7.0539997 4.81 7.05586644 4.81 2 P 0 ;0,1=215,2=0.000000
L 7.05586644 4.81 7.05773327 4.81083307 2 P 0 ;0,1=215,2=0.000000
L 7.05773327 4.81083307 7.05933337 4.81208287 2 P 0 ;0,1=215,2=0.000000
L 7.05933337 4.81208287 7.06066693 4.81374911 2 P 0 ;0,1=215,2=0.000000
L 7.07293317 4.82041594 7.0747999 4.82333346 2 P 0 ;0,1=215,2=0.000000
L 7.0747999 4.82333346 7.0764 4.8249998 2 P 0 ;0,1=215,2=0.000000
L 7.0764 4.8249998 7.07853337 4.82583297 2 P 0 ;0,1=215,2=0.000000
L 7.07853337 4.82583297 7.0804002 4.8249998 2 P 0 ;0,1=215,2=0.000000
L 7.0804002 4.8249998 7.08173327 4.82333346 2 P 0 ;0,1=215,2=0.000000
L 7.08173327 4.82333346 7.0828001 4.82083327 2 P 0 ;0,1=215,2=0.000000
L 7.0828001 4.82083327 7.08306673 4.81791644 2 P 0 ;0,1=215,2=0.000000
L 7.08306673 4.81791644 7.0828001 4.81541624 2 P 0 ;0,1=215,2=0.000000
L 7.0828001 4.81541624 7.08173327 4.81291604 2 P 0 ;0,1=215,2=0.000000
L 7.08173327 4.81291604 7.08013307 4.81083307 2 P 0 ;0,1=215,2=0.000000
L 7.08013307 4.81083307 7.07826683 4.81 2 P 0 ;0,1=215,2=0.000000
L 7.07826683 4.81 7.07613346 4.81083307 2 P 0 ;0,1=215,2=0.000000
L 7.07613346 4.81083307 7.07426663 4.81333258 2 P 0 ;0,1=215,2=0.000000
L 7.07426663 4.81333258 7.0731998 4.81708327 2 P 0 ;0,1=215,2=0.000000
L 7.0731998 4.81708327 7.07293317 4.8212498 2 P 0 ;0,1=215,2=0.000000
L 7.07293317 4.8212498 7.07346634 4.82666614 2 P 0 ;0,1=215,2=0.000000
L 7.07346634 4.82666614 7.07426663 4.82958366 2 P 0 ;0,1=215,2=0.000000
L 7.07426663 4.82958366 7.0755997 4.8324997 2 P 0 ;0,1=215,2=0.000000
L 7.0755997 4.8324997 7.07746654 4.83458337 2 P 0 ;0,1=215,2=0.000000
L 7.07746654 4.83458337 7.07933327 4.835 2 P 0 ;0,1=215,2=0.000000
L 7.07933327 4.835 7.0812 4.83416683 2 P 0 ;0,1=215,2=0.000000
L 7.0812 4.83416683 7.08253356 4.83208317 2 P 0 ;0,1=215,2=0.000000
A 12.04556998 5 12.04556998 5 12.04 5 2 P 0 N
L 12.03208366 5.10386663 12.03083317 5.10226644 2 P 0 ;0,1=216,2=270.000000
L 12.03083317 5.10226644 12.03 5.1004002 2 P 0 ;0,1=216,2=270.000000
L 12.03 5.1004002 12.03 5.09826683 2 P 0 ;0,1=216,2=270.000000
L 12.03 5.09826683 12.03125059 5.09586634 2 P 0 ;0,1=216,2=270.000000
L 12.03125059 5.09586634 12.03333346 5.0940001 2 P 0 ;0,1=216,2=270.000000
L 12.03333346 5.0940001 12.03583366 5.09266654 2 P 0 ;0,1=216,2=270.000000
L 12.03583366 5.09266654 12.0400002 5.09159961 2 P 0 ;0,1=216,2=270.000000
L 12.0400002 5.09159961 12.0437502 5.09133297 2 P 0 ;0,1=216,2=270.000000
L 12.0437502 5.09133297 12.0475001 5.09186673 2 P 0 ;0,1=216,2=270.000000
L 12.0475001 5.09186673 12.05000039 5.09266654 2 P 0 ;0,1=216,2=270.000000
L 12.05000039 5.09266654 12.05250059 5.09426663 2 P 0 ;0,1=216,2=270.000000
L 12.05250059 5.09426663 12.05416693 5.09613346 2 P 0 ;0,1=216,2=270.000000
L 12.05416693 5.09613346 12.055 5.0979997 2 P 0 ;0,1=216,2=270.000000
L 12.055 5.0979997 12.055 5.09986644 2 P 0 ;0,1=216,2=270.000000
L 12.055 5.09986644 12.05416693 5.10173327 2 P 0 ;0,1=216,2=270.000000
L 12.05416693 5.10173327 12.05291713 5.10333337 2 P 0 ;0,1=216,2=270.000000
L 12.05291713 5.10333337 12.05125089 5.10466693 2 P 0 ;0,1=216,2=270.000000
L 12.055 5.1252 12.03 5.1252 2 P 0 ;0,1=216,2=270.000000
L 12.03 5.1252 12.04791673 5.11533297 2 P 0 ;0,1=216,2=270.000000
L 12.04791673 5.11533297 12.04791673 5.12866693 2 P 0 ;0,1=216,2=270.000000
L 12.03 5.1459997 12.03083317 5.14386634 2 P 0 ;0,1=216,2=270.000000
L 12.03083317 5.14386634 12.03291683 5.14226663 2 P 0 ;0,1=216,2=270.000000
L 12.03291683 5.14226663 12.03541634 5.1411998 2 P 0 ;0,1=216,2=270.000000
L 12.03541634 5.1411998 12.03875049 5.1403999 2 P 0 ;0,1=216,2=270.000000
L 12.03875049 5.1403999 12.04250039 5.14013327 2 P 0 ;0,1=216,2=270.000000
L 12.04250039 5.14013327 12.04625039 5.1403999 2 P 0 ;0,1=216,2=270.000000
L 12.04625039 5.1403999 12.04958376 5.1411998 2 P 0 ;0,1=216,2=270.000000
L 12.04958376 5.1411998 12.05208396 5.14226663 2 P 0 ;0,1=216,2=270.000000
L 12.05208396 5.14226663 12.05416693 5.14386634 2 P 0 ;0,1=216,2=270.000000
L 12.05416693 5.14386634 12.055 5.1459997 2 P 0 ;0,1=216,2=270.000000
L 12.055 5.1459997 12.05416693 5.14813307 2 P 0 ;0,1=216,2=270.000000
L 12.05416693 5.14813307 12.05208396 5.14973327 2 P 0 ;0,1=216,2=270.000000
L 12.05208396 5.14973327 12.04958376 5.1508001 2 P 0 ;0,1=216,2=270.000000
L 12.04958376 5.1508001 12.04625039 5.1516 2 P 0 ;0,1=216,2=270.000000
L 12.04625039 5.1516 12.04250039 5.15186663 2 P 0 ;0,1=216,2=270.000000
L 12.04250039 5.15186663 12.03875049 5.1516 2 P 0 ;0,1=216,2=270.000000
L 12.03875049 5.1516 12.03541634 5.1508001 2 P 0 ;0,1=216,2=270.000000
L 12.03541634 5.1508001 12.03291683 5.14973327 2 P 0 ;0,1=216,2=270.000000
L 12.03291683 5.14973327 12.03083317 5.14813307 2 P 0 ;0,1=216,2=270.000000
L 12.03083317 5.14813307 12.03 5.1459997 2 P 0 ;0,1=216,2=270.000000
L 12.05208396 5.16546634 12.05416693 5.16733317 2 P 0 ;0,1=216,2=270.000000
L 12.05416693 5.16733317 12.055 5.16946654 2 P 0 ;0,1=216,2=270.000000
L 12.055 5.16946654 12.05416693 5.1715999 2 P 0 ;0,1=216,2=270.000000
L 12.05416693 5.1715999 12.05166742 5.17346663 2 P 0 ;0,1=216,2=270.000000
L 12.05166742 5.17346663 12.04791673 5.1748001 2 P 0 ;0,1=216,2=270.000000
L 12.04791673 5.1748001 12.04416673 5.17533337 2 P 0 ;0,1=216,2=270.000000
L 12.04416673 5.17533337 12.03958366 5.17533337 2 P 0 ;0,1=216,2=270.000000
L 12.03958366 5.17533337 12.03583366 5.1748001 2 P 0 ;0,1=216,2=270.000000
L 12.03583366 5.1748001 12.0325003 5.17346663 2 P 0 ;0,1=216,2=270.000000
L 12.0325003 5.17346663 12.03083317 5.17186644 2 P 0 ;0,1=216,2=270.000000
L 12.03083317 5.17186644 12.03 5.1699997 2 P 0 ;0,1=216,2=270.000000
L 12.03 5.1699997 12.03083317 5.16786634 2 P 0 ;0,1=216,2=270.000000
L 12.03083317 5.16786634 12.0325003 5.16626663 2 P 0 ;0,1=216,2=270.000000
L 12.0325003 5.16626663 12.0349997 5.1651998 2 P 0 ;0,1=216,2=270.000000
L 12.0349997 5.1651998 12.03833386 5.16466654 2 P 0 ;0,1=216,2=270.000000
L 12.03833386 5.16466654 12.0412499 5.1651998 2 P 0 ;0,1=216,2=270.000000
L 12.0412499 5.1651998 12.04416673 5.16653327 2 P 0 ;0,1=216,2=270.000000
L 12.04416673 5.16653327 12.04583386 5.16813346 2 P 0 ;0,1=216,2=270.000000
L 12.04583386 5.16813346 12.04625039 5.1699997 2 P 0 ;0,1=216,2=270.000000
L 12.04625039 5.1699997 12.04541722 5.17213307 2 P 0 ;0,1=216,2=270.000000
L 12.04541722 5.17213307 12.04333356 5.17373327 2 P 0 ;0,1=216,2=270.000000
L 12.04333356 5.17373327 12.03958366 5.17533337 2 P 0 ;0,1=216,2=270.000000
A 12.20556998 5 12.20556998 5 12.2 5 2 P 0 N
L 12.18708366 5.10386663 12.18583317 5.10226644 2 P 0 ;0,1=217,2=270.000000
L 12.18583317 5.10226644 12.185 5.1004002 2 P 0 ;0,1=217,2=270.000000
L 12.185 5.1004002 12.185 5.09826683 2 P 0 ;0,1=217,2=270.000000
L 12.185 5.09826683 12.18625059 5.09586634 2 P 0 ;0,1=217,2=270.000000
L 12.18625059 5.09586634 12.18833346 5.0940001 2 P 0 ;0,1=217,2=270.000000
L 12.18833346 5.0940001 12.19083366 5.09266654 2 P 0 ;0,1=217,2=270.000000
L 12.19083366 5.09266654 12.1950002 5.09159961 2 P 0 ;0,1=217,2=270.000000
L 12.1950002 5.09159961 12.1987502 5.09133297 2 P 0 ;0,1=217,2=270.000000
L 12.1987502 5.09133297 12.2025001 5.09186673 2 P 0 ;0,1=217,2=270.000000
L 12.2025001 5.09186673 12.20500039 5.09266654 2 P 0 ;0,1=217,2=270.000000
L 12.20500039 5.09266654 12.20750059 5.09426663 2 P 0 ;0,1=217,2=270.000000
L 12.20750059 5.09426663 12.20916693 5.09613346 2 P 0 ;0,1=217,2=270.000000
L 12.20916693 5.09613346 12.21 5.0979997 2 P 0 ;0,1=217,2=270.000000
L 12.21 5.0979997 12.21 5.09986644 2 P 0 ;0,1=217,2=270.000000
L 12.21 5.09986644 12.20916693 5.10173327 2 P 0 ;0,1=217,2=270.000000
L 12.20916693 5.10173327 12.20791713 5.10333337 2 P 0 ;0,1=217,2=270.000000
L 12.20791713 5.10333337 12.20625089 5.10466693 2 P 0 ;0,1=217,2=270.000000
L 12.21 5.1252 12.185 5.1252 2 P 0 ;0,1=217,2=270.000000
L 12.185 5.1252 12.20291673 5.11533297 2 P 0 ;0,1=217,2=270.000000
L 12.20291673 5.11533297 12.20291673 5.12866693 2 P 0 ;0,1=217,2=270.000000
L 12.21 5.1459997 12.185 5.1459997 2 P 0 ;0,1=217,2=270.000000
L 12.185 5.1459997 12.1899997 5.1427999 2 P 0 ;0,1=217,2=270.000000
L 12.21 5.1427999 12.21 5.14919951 2 P 0 ;0,1=217,2=270.000000
L 12.185 5.1699997 12.18583317 5.16786634 2 P 0 ;0,1=217,2=270.000000
L 12.18583317 5.16786634 12.18791683 5.16626663 2 P 0 ;0,1=217,2=270.000000
L 12.18791683 5.16626663 12.19041634 5.1651998 2 P 0 ;0,1=217,2=270.000000
L 12.19041634 5.1651998 12.19375049 5.1643999 2 P 0 ;0,1=217,2=270.000000
L 12.19375049 5.1643999 12.19750039 5.16413327 2 P 0 ;0,1=217,2=270.000000
L 12.19750039 5.16413327 12.20125039 5.1643999 2 P 0 ;0,1=217,2=270.000000
L 12.20125039 5.1643999 12.20458376 5.1651998 2 P 0 ;0,1=217,2=270.000000
L 12.20458376 5.1651998 12.20708396 5.16626663 2 P 0 ;0,1=217,2=270.000000
L 12.20708396 5.16626663 12.20916693 5.16786634 2 P 0 ;0,1=217,2=270.000000
L 12.20916693 5.16786634 12.21 5.1699997 2 P 0 ;0,1=217,2=270.000000
L 12.21 5.1699997 12.20916693 5.17213307 2 P 0 ;0,1=217,2=270.000000
L 12.20916693 5.17213307 12.20708396 5.17373327 2 P 0 ;0,1=217,2=270.000000
L 12.20708396 5.17373327 12.20458376 5.1748001 2 P 0 ;0,1=217,2=270.000000
L 12.20458376 5.1748001 12.20125039 5.1756 2 P 0 ;0,1=217,2=270.000000
L 12.20125039 5.1756 12.19750039 5.17586663 2 P 0 ;0,1=217,2=270.000000
L 12.19750039 5.17586663 12.19375049 5.1756 2 P 0 ;0,1=217,2=270.000000
L 12.19375049 5.1756 12.19041634 5.1748001 2 P 0 ;0,1=217,2=270.000000
L 12.19041634 5.1748001 12.18791683 5.17373327 2 P 0 ;0,1=217,2=270.000000
L 12.18791683 5.17373327 12.18583317 5.17213307 2 P 0 ;0,1=217,2=270.000000
L 12.18583317 5.17213307 12.185 5.1699997 2 P 0 ;0,1=217,2=270.000000
A 10.55556998 5.18 10.55556998 5.18 10.55 5.18 2 P 0 N
L 10.64886663 5.19291634 10.64726644 5.19416683 2 P 0 ;0,1=218,2=0.000000
L 10.64726644 5.19416683 10.6454002 5.195 2 P 0 ;0,1=218,2=0.000000
L 10.6454002 5.195 10.64326683 5.195 2 P 0 ;0,1=218,2=0.000000
L 10.64326683 5.195 10.64086634 5.19374941 2 P 0 ;0,1=218,2=0.000000
L 10.64086634 5.19374941 10.6390001 5.19166654 2 P 0 ;0,1=218,2=0.000000
L 10.6390001 5.19166654 10.63766654 5.18916634 2 P 0 ;0,1=218,2=0.000000
L 10.63766654 5.18916634 10.63659961 5.1849998 2 P 0 ;0,1=218,2=0.000000
L 10.63659961 5.1849998 10.63633297 5.1812498 2 P 0 ;0,1=218,2=0.000000
L 10.63633297 5.1812498 10.63686673 5.1774999 2 P 0 ;0,1=218,2=0.000000
L 10.63686673 5.1774999 10.63766654 5.17499961 2 P 0 ;0,1=218,2=0.000000
L 10.63766654 5.17499961 10.63926663 5.17249941 2 P 0 ;0,1=218,2=0.000000
L 10.63926663 5.17249941 10.64113346 5.17083307 2 P 0 ;0,1=218,2=0.000000
L 10.64113346 5.17083307 10.6429997 5.17 2 P 0 ;0,1=218,2=0.000000
L 10.6429997 5.17 10.64486644 5.17 2 P 0 ;0,1=218,2=0.000000
L 10.64486644 5.17 10.64673327 5.17083307 2 P 0 ;0,1=218,2=0.000000
L 10.64673327 5.17083307 10.64833337 5.17208287 2 P 0 ;0,1=218,2=0.000000
L 10.64833337 5.17208287 10.64966693 5.17374911 2 P 0 ;0,1=218,2=0.000000
L 10.6702 5.17 10.6702 5.195 2 P 0 ;0,1=218,2=0.000000
L 10.6702 5.195 10.66033297 5.17708327 2 P 0 ;0,1=218,2=0.000000
L 10.66033297 5.17708327 10.67366693 5.17708327 2 P 0 ;0,1=218,2=0.000000
L 10.6909997 5.17 10.6909997 5.195 2 P 0 ;0,1=218,2=0.000000
L 10.6909997 5.195 10.6877999 5.1900003 2 P 0 ;0,1=218,2=0.000000
L 10.6877999 5.17 10.69419951 5.17 2 P 0 ;0,1=218,2=0.000000
L 10.70993317 5.19083337 10.71153327 5.19333287 2 P 0 ;0,1=218,2=0.000000
L 10.71153327 5.19333287 10.7134 5.19458337 2 P 0 ;0,1=218,2=0.000000
L 10.7134 5.19458337 10.71553337 5.195 2 P 0 ;0,1=218,2=0.000000
L 10.71553337 5.195 10.7182 5.19416683 2 P 0 ;0,1=218,2=0.000000
L 10.7182 5.19416683 10.72006673 5.19208317 2 P 0 ;0,1=218,2=0.000000
L 10.72006673 5.19208317 10.7206 5.18958366 2 P 0 ;0,1=218,2=0.000000
L 10.7206 5.18958366 10.72033337 5.18708268 2 P 0 ;0,1=218,2=0.000000
L 10.72033337 5.18708268 10.71926644 5.1849998 2 P 0 ;0,1=218,2=0.000000
L 10.71926644 5.1849998 10.71393327 5.18083327 2 P 0 ;0,1=218,2=0.000000
L 10.71393327 5.18083327 10.71153327 5.17791644 2 P 0 ;0,1=218,2=0.000000
L 10.71153327 5.17791644 10.70993317 5.17374911 2 P 0 ;0,1=218,2=0.000000
L 10.70993317 5.17374911 10.7093999 5.17 2 P 0 ;0,1=218,2=0.000000
L 10.7093999 5.17 10.7206 5.17 2 P 0 ;0,1=218,2=0.000000
A 10.55556998 5.26 10.55556998 5.26 10.55 5.26 2 P 0 N
L 10.64886663 5.27291634 10.64726644 5.27416683 2 P 0 ;0,1=219,2=0.000000
L 10.64726644 5.27416683 10.6454002 5.275 2 P 0 ;0,1=219,2=0.000000
L 10.6454002 5.275 10.64326683 5.275 2 P 0 ;0,1=219,2=0.000000
L 10.64326683 5.275 10.64086634 5.27374941 2 P 0 ;0,1=219,2=0.000000
L 10.64086634 5.27374941 10.6390001 5.27166654 2 P 0 ;0,1=219,2=0.000000
L 10.6390001 5.27166654 10.63766654 5.26916634 2 P 0 ;0,1=219,2=0.000000
L 10.63766654 5.26916634 10.63659961 5.2649998 2 P 0 ;0,1=219,2=0.000000
L 10.63659961 5.2649998 10.63633297 5.2612498 2 P 0 ;0,1=219,2=0.000000
L 10.63633297 5.2612498 10.63686673 5.2574999 2 P 0 ;0,1=219,2=0.000000
L 10.63686673 5.2574999 10.63766654 5.25499961 2 P 0 ;0,1=219,2=0.000000
L 10.63766654 5.25499961 10.63926663 5.25249941 2 P 0 ;0,1=219,2=0.000000
L 10.63926663 5.25249941 10.64113346 5.25083307 2 P 0 ;0,1=219,2=0.000000
L 10.64113346 5.25083307 10.6429997 5.25 2 P 0 ;0,1=219,2=0.000000
L 10.6429997 5.25 10.64486644 5.25 2 P 0 ;0,1=219,2=0.000000
L 10.64486644 5.25 10.64673327 5.25083307 2 P 0 ;0,1=219,2=0.000000
L 10.64673327 5.25083307 10.64833337 5.25208287 2 P 0 ;0,1=219,2=0.000000
L 10.64833337 5.25208287 10.64966693 5.25374911 2 P 0 ;0,1=219,2=0.000000
L 10.6702 5.25 10.6702 5.275 2 P 0 ;0,1=219,2=0.000000
L 10.6702 5.275 10.66033297 5.25708327 2 P 0 ;0,1=219,2=0.000000
L 10.66033297 5.25708327 10.67366693 5.25708327 2 P 0 ;0,1=219,2=0.000000
L 10.6909997 5.25 10.6909997 5.275 2 P 0 ;0,1=219,2=0.000000
L 10.6909997 5.275 10.6877999 5.2700003 2 P 0 ;0,1=219,2=0.000000
L 10.6877999 5.25 10.69419951 5.25 2 P 0 ;0,1=219,2=0.000000
L 10.7182 5.25 10.7182 5.275 2 P 0 ;0,1=219,2=0.000000
L 10.7182 5.275 10.70833297 5.25708327 2 P 0 ;0,1=219,2=0.000000
L 10.70833297 5.25708327 10.72166693 5.25708327 2 P 0 ;0,1=219,2=0.000000
A 9.91251004 4.65 9.91251004 4.65 9.91 4.65 1 P 0 N
L 9.89708366 4.73386663 9.89583317 4.73226644 2 P 0 ;0,1=220,2=270.000000
L 9.89583317 4.73226644 9.895 4.7304002 2 P 0 ;0,1=220,2=270.000000
L 9.895 4.7304002 9.895 4.72826683 2 P 0 ;0,1=220,2=270.000000
L 9.895 4.72826683 9.89625059 4.72586634 2 P 0 ;0,1=220,2=270.000000
L 9.89625059 4.72586634 9.89833346 4.7240001 2 P 0 ;0,1=220,2=270.000000
L 9.89833346 4.7240001 9.90083366 4.72266654 2 P 0 ;0,1=220,2=270.000000
L 9.90083366 4.72266654 9.9050002 4.72159961 2 P 0 ;0,1=220,2=270.000000
L 9.9050002 4.72159961 9.9087502 4.72133297 2 P 0 ;0,1=220,2=270.000000
L 9.9087502 4.72133297 9.9125001 4.72186673 2 P 0 ;0,1=220,2=270.000000
L 9.9125001 4.72186673 9.91500039 4.72266654 2 P 0 ;0,1=220,2=270.000000
L 9.91500039 4.72266654 9.91750059 4.72426663 2 P 0 ;0,1=220,2=270.000000
L 9.91750059 4.72426663 9.91916693 4.72613346 2 P 0 ;0,1=220,2=270.000000
L 9.91916693 4.72613346 9.92 4.7279997 2 P 0 ;0,1=220,2=270.000000
L 9.92 4.7279997 9.92 4.72986644 2 P 0 ;0,1=220,2=270.000000
L 9.92 4.72986644 9.91916693 4.73173327 2 P 0 ;0,1=220,2=270.000000
L 9.91916693 4.73173327 9.91791713 4.73333337 2 P 0 ;0,1=220,2=270.000000
L 9.91791713 4.73333337 9.91625089 4.73466693 2 P 0 ;0,1=220,2=270.000000
L 9.89916663 4.74693317 9.89666713 4.74853327 2 P 0 ;0,1=220,2=270.000000
L 9.89666713 4.74853327 9.89541663 4.7504 2 P 0 ;0,1=220,2=270.000000
L 9.89541663 4.7504 9.895 4.75253337 2 P 0 ;0,1=220,2=270.000000
L 9.895 4.75253337 9.89583317 4.7552 2 P 0 ;0,1=220,2=270.000000
L 9.89583317 4.7552 9.89791683 4.75706673 2 P 0 ;0,1=220,2=270.000000
L 9.89791683 4.75706673 9.90041634 4.7576 2 P 0 ;0,1=220,2=270.000000
L 9.90041634 4.7576 9.90291732 4.75733337 2 P 0 ;0,1=220,2=270.000000
L 9.90291732 4.75733337 9.9050002 4.75626644 2 P 0 ;0,1=220,2=270.000000
L 9.9050002 4.75626644 9.90916673 4.75093327 2 P 0 ;0,1=220,2=270.000000
L 9.90916673 4.75093327 9.91208356 4.74853327 2 P 0 ;0,1=220,2=270.000000
L 9.91208356 4.74853327 9.91625089 4.74693317 2 P 0 ;0,1=220,2=270.000000
L 9.91625089 4.74693317 9.92 4.7463999 2 P 0 ;0,1=220,2=270.000000
L 9.92 4.7463999 9.92 4.7576 2 P 0 ;0,1=220,2=270.000000
L 9.89916663 4.77093317 9.89666713 4.77253327 2 P 0 ;0,1=220,2=270.000000
L 9.89666713 4.77253327 9.89541663 4.7744 2 P 0 ;0,1=220,2=270.000000
L 9.89541663 4.7744 9.895 4.77653337 2 P 0 ;0,1=220,2=270.000000
L 9.895 4.77653337 9.89583317 4.7792 2 P 0 ;0,1=220,2=270.000000
L 9.89583317 4.7792 9.89791683 4.78106673 2 P 0 ;0,1=220,2=270.000000
L 9.89791683 4.78106673 9.90041634 4.7816 2 P 0 ;0,1=220,2=270.000000
L 9.90041634 4.7816 9.90291732 4.78133337 2 P 0 ;0,1=220,2=270.000000
L 9.90291732 4.78133337 9.9050002 4.78026644 2 P 0 ;0,1=220,2=270.000000
L 9.9050002 4.78026644 9.90916673 4.77493327 2 P 0 ;0,1=220,2=270.000000
L 9.90916673 4.77493327 9.91208356 4.77253327 2 P 0 ;0,1=220,2=270.000000
L 9.91208356 4.77253327 9.91625089 4.77093317 2 P 0 ;0,1=220,2=270.000000
L 9.91625089 4.77093317 9.92 4.7703999 2 P 0 ;0,1=220,2=270.000000
L 9.92 4.7703999 9.92 4.7816 2 P 0 ;0,1=220,2=270.000000
L 9.92 4.8032 9.895 4.8032 2 P 0 ;0,1=220,2=270.000000
L 9.895 4.8032 9.91291673 4.79333297 2 P 0 ;0,1=220,2=270.000000
L 9.91291673 4.79333297 9.91291673 4.80666693 2 P 0 ;0,1=220,2=270.000000
L 9.91500039 4.81813327 9.91791713 4.81973297 2 P 0 ;0,1=220,2=270.000000
L 9.91791713 4.81973297 9.91958346 4.82186634 2 P 0 ;0,1=220,2=270.000000
L 9.91958346 4.82186634 9.92 4.82426683 2 P 0 ;0,1=220,2=270.000000
L 9.92 4.82426683 9.91958346 4.8264002 2 P 0 ;0,1=220,2=270.000000
L 9.91958346 4.8264002 9.91750059 4.82853356 2 P 0 ;0,1=220,2=270.000000
L 9.91750059 4.82853356 9.91500039 4.82986663 2 P 0 ;0,1=220,2=270.000000
L 9.91500039 4.82986663 9.9125001 4.83013317 2 P 0 ;0,1=220,2=270.000000
L 9.9125001 4.83013317 9.90958406 4.8296 2 P 0 ;0,1=220,2=270.000000
L 9.90958406 4.8296 9.90750039 4.82773327 2 P 0 ;0,1=220,2=270.000000
L 9.90750039 4.82773327 9.90666654 4.82586644 2 P 0 ;0,1=220,2=270.000000
L 9.90666654 4.82586644 9.90666654 4.82346654 2 P 0 ;0,1=220,2=270.000000
L 9.90666654 4.82586644 9.90541673 4.82746663 2 P 0 ;0,1=220,2=270.000000
L 9.90541673 4.82746663 9.90333386 4.8288001 2 P 0 ;0,1=220,2=270.000000
L 9.90333386 4.8288001 9.90083366 4.82933337 2 P 0 ;0,1=220,2=270.000000
L 9.90083366 4.82933337 9.89833346 4.8288001 2 P 0 ;0,1=220,2=270.000000
L 9.89833346 4.8288001 9.89625059 4.82746663 2 P 0 ;0,1=220,2=270.000000
L 9.89625059 4.82746663 9.895 4.82506663 2 P 0 ;0,1=220,2=270.000000
L 9.895 4.82506663 9.89541663 4.82266663 2 P 0 ;0,1=220,2=270.000000
L 9.89541663 4.82266663 9.89708366 4.82026663 2 P 0 ;0,1=220,2=270.000000
A 3.57251004 4.5 3.57251004 4.5 3.57 4.5 1 P 0 N
L 3.55708366 4.32886663 3.55583317 4.32726644 2 P 0 ;0,1=221,2=270.000000
L 3.55583317 4.32726644 3.555 4.3254002 2 P 0 ;0,1=221,2=270.000000
L 3.555 4.3254002 3.555 4.32326683 2 P 0 ;0,1=221,2=270.000000
L 3.555 4.32326683 3.55625059 4.32086634 2 P 0 ;0,1=221,2=270.000000
L 3.55625059 4.32086634 3.55833346 4.3190001 2 P 0 ;0,1=221,2=270.000000
L 3.55833346 4.3190001 3.56083366 4.31766654 2 P 0 ;0,1=221,2=270.000000
L 3.56083366 4.31766654 3.5650002 4.31659961 2 P 0 ;0,1=221,2=270.000000
L 3.5650002 4.31659961 3.5687502 4.31633297 2 P 0 ;0,1=221,2=270.000000
L 3.5687502 4.31633297 3.5725001 4.31686673 2 P 0 ;0,1=221,2=270.000000
L 3.5725001 4.31686673 3.57500039 4.31766654 2 P 0 ;0,1=221,2=270.000000
L 3.57500039 4.31766654 3.57750059 4.31926663 2 P 0 ;0,1=221,2=270.000000
L 3.57750059 4.31926663 3.57916693 4.32113346 2 P 0 ;0,1=221,2=270.000000
L 3.57916693 4.32113346 3.58 4.3229997 2 P 0 ;0,1=221,2=270.000000
L 3.58 4.3229997 3.58 4.32486644 2 P 0 ;0,1=221,2=270.000000
L 3.58 4.32486644 3.57916693 4.32673327 2 P 0 ;0,1=221,2=270.000000
L 3.57916693 4.32673327 3.57791713 4.32833337 2 P 0 ;0,1=221,2=270.000000
L 3.57791713 4.32833337 3.57625089 4.32966693 2 P 0 ;0,1=221,2=270.000000
L 3.55916663 4.34193317 3.55666713 4.34353327 2 P 0 ;0,1=221,2=270.000000
L 3.55666713 4.34353327 3.55541663 4.3454 2 P 0 ;0,1=221,2=270.000000
L 3.55541663 4.3454 3.555 4.34753337 2 P 0 ;0,1=221,2=270.000000
L 3.555 4.34753337 3.55583317 4.3502 2 P 0 ;0,1=221,2=270.000000
L 3.55583317 4.3502 3.55791683 4.35206673 2 P 0 ;0,1=221,2=270.000000
L 3.55791683 4.35206673 3.56041634 4.3526 2 P 0 ;0,1=221,2=270.000000
L 3.56041634 4.3526 3.56291732 4.35233337 2 P 0 ;0,1=221,2=270.000000
L 3.56291732 4.35233337 3.5650002 4.35126644 2 P 0 ;0,1=221,2=270.000000
L 3.5650002 4.35126644 3.56916673 4.34593327 2 P 0 ;0,1=221,2=270.000000
L 3.56916673 4.34593327 3.57208356 4.34353327 2 P 0 ;0,1=221,2=270.000000
L 3.57208356 4.34353327 3.57625089 4.34193317 2 P 0 ;0,1=221,2=270.000000
L 3.57625089 4.34193317 3.58 4.3413999 2 P 0 ;0,1=221,2=270.000000
L 3.58 4.3413999 3.58 4.3526 2 P 0 ;0,1=221,2=270.000000
L 3.55916663 4.36593317 3.55666713 4.36753327 2 P 0 ;0,1=221,2=270.000000
L 3.55666713 4.36753327 3.55541663 4.3694 2 P 0 ;0,1=221,2=270.000000
L 3.55541663 4.3694 3.555 4.37153337 2 P 0 ;0,1=221,2=270.000000
L 3.555 4.37153337 3.55583317 4.3742 2 P 0 ;0,1=221,2=270.000000
L 3.55583317 4.3742 3.55791683 4.37606673 2 P 0 ;0,1=221,2=270.000000
L 3.55791683 4.37606673 3.56041634 4.3766 2 P 0 ;0,1=221,2=270.000000
L 3.56041634 4.3766 3.56291732 4.37633337 2 P 0 ;0,1=221,2=270.000000
L 3.56291732 4.37633337 3.5650002 4.37526644 2 P 0 ;0,1=221,2=270.000000
L 3.5650002 4.37526644 3.56916673 4.36993327 2 P 0 ;0,1=221,2=270.000000
L 3.56916673 4.36993327 3.57208356 4.36753327 2 P 0 ;0,1=221,2=270.000000
L 3.57208356 4.36753327 3.57625089 4.36593317 2 P 0 ;0,1=221,2=270.000000
L 3.57625089 4.36593317 3.58 4.3653999 2 P 0 ;0,1=221,2=270.000000
L 3.58 4.3653999 3.58 4.3766 2 P 0 ;0,1=221,2=270.000000
L 3.58 4.3982 3.555 4.3982 2 P 0 ;0,1=221,2=270.000000
L 3.555 4.3982 3.57291673 4.38833297 2 P 0 ;0,1=221,2=270.000000
L 3.57291673 4.38833297 3.57291673 4.40166693 2 P 0 ;0,1=221,2=270.000000
L 3.55916663 4.41393317 3.55666713 4.41553327 2 P 0 ;0,1=221,2=270.000000
L 3.55666713 4.41553327 3.55541663 4.4174 2 P 0 ;0,1=221,2=270.000000
L 3.55541663 4.4174 3.555 4.41953337 2 P 0 ;0,1=221,2=270.000000
L 3.555 4.41953337 3.55583317 4.4222 2 P 0 ;0,1=221,2=270.000000
L 3.55583317 4.4222 3.55791683 4.42406673 2 P 0 ;0,1=221,2=270.000000
L 3.55791683 4.42406673 3.56041634 4.4246 2 P 0 ;0,1=221,2=270.000000
L 3.56041634 4.4246 3.56291732 4.42433337 2 P 0 ;0,1=221,2=270.000000
L 3.56291732 4.42433337 3.5650002 4.42326644 2 P 0 ;0,1=221,2=270.000000
L 3.5650002 4.42326644 3.56916673 4.41793327 2 P 0 ;0,1=221,2=270.000000
L 3.56916673 4.41793327 3.57208356 4.41553327 2 P 0 ;0,1=221,2=270.000000
L 3.57208356 4.41553327 3.57625089 4.41393317 2 P 0 ;0,1=221,2=270.000000
L 3.57625089 4.41393317 3.58 4.4133999 2 P 0 ;0,1=221,2=270.000000
L 3.58 4.4133999 3.58 4.4246 2 P 0 ;0,1=221,2=270.000000
A 4.81251004 5.425 4.81251004 5.425 4.81 5.425 1 P 0 N
L 4.80208366 5.24886663 4.80083317 5.24726644 2 P 0 ;0,1=222,2=270.000000
L 4.80083317 5.24726644 4.8 5.2454002 2 P 0 ;0,1=222,2=270.000000
L 4.8 5.2454002 4.8 5.24326683 2 P 0 ;0,1=222,2=270.000000
L 4.8 5.24326683 4.80125059 5.24086634 2 P 0 ;0,1=222,2=270.000000
L 4.80125059 5.24086634 4.80333346 5.2390001 2 P 0 ;0,1=222,2=270.000000
L 4.80333346 5.2390001 4.80583366 5.23766654 2 P 0 ;0,1=222,2=270.000000
L 4.80583366 5.23766654 4.8100002 5.23659961 2 P 0 ;0,1=222,2=270.000000
L 4.8100002 5.23659961 4.8137502 5.23633297 2 P 0 ;0,1=222,2=270.000000
L 4.8137502 5.23633297 4.8175001 5.23686673 2 P 0 ;0,1=222,2=270.000000
L 4.8175001 5.23686673 4.82000039 5.23766654 2 P 0 ;0,1=222,2=270.000000
L 4.82000039 5.23766654 4.82250059 5.23926663 2 P 0 ;0,1=222,2=270.000000
L 4.82250059 5.23926663 4.82416693 5.24113346 2 P 0 ;0,1=222,2=270.000000
L 4.82416693 5.24113346 4.825 5.2429997 2 P 0 ;0,1=222,2=270.000000
L 4.825 5.2429997 4.825 5.24486644 2 P 0 ;0,1=222,2=270.000000
L 4.825 5.24486644 4.82416693 5.24673327 2 P 0 ;0,1=222,2=270.000000
L 4.82416693 5.24673327 4.82291713 5.24833337 2 P 0 ;0,1=222,2=270.000000
L 4.82291713 5.24833337 4.82125089 5.24966693 2 P 0 ;0,1=222,2=270.000000
L 4.80416663 5.26193317 4.80166713 5.26353327 2 P 0 ;0,1=222,2=270.000000
L 4.80166713 5.26353327 4.80041663 5.2654 2 P 0 ;0,1=222,2=270.000000
L 4.80041663 5.2654 4.8 5.26753337 2 P 0 ;0,1=222,2=270.000000
L 4.8 5.26753337 4.80083317 5.2702 2 P 0 ;0,1=222,2=270.000000
L 4.80083317 5.2702 4.80291683 5.27206673 2 P 0 ;0,1=222,2=270.000000
L 4.80291683 5.27206673 4.80541634 5.2726 2 P 0 ;0,1=222,2=270.000000
L 4.80541634 5.2726 4.80791732 5.27233337 2 P 0 ;0,1=222,2=270.000000
L 4.80791732 5.27233337 4.8100002 5.27126644 2 P 0 ;0,1=222,2=270.000000
L 4.8100002 5.27126644 4.81416673 5.26593327 2 P 0 ;0,1=222,2=270.000000
L 4.81416673 5.26593327 4.81708356 5.26353327 2 P 0 ;0,1=222,2=270.000000
L 4.81708356 5.26353327 4.82125089 5.26193317 2 P 0 ;0,1=222,2=270.000000
L 4.82125089 5.26193317 4.825 5.2613999 2 P 0 ;0,1=222,2=270.000000
L 4.825 5.2613999 4.825 5.2726 2 P 0 ;0,1=222,2=270.000000
L 4.80416663 5.28593317 4.80166713 5.28753327 2 P 0 ;0,1=222,2=270.000000
L 4.80166713 5.28753327 4.80041663 5.2894 2 P 0 ;0,1=222,2=270.000000
L 4.80041663 5.2894 4.8 5.29153337 2 P 0 ;0,1=222,2=270.000000
L 4.8 5.29153337 4.80083317 5.2942 2 P 0 ;0,1=222,2=270.000000
L 4.80083317 5.2942 4.80291683 5.29606673 2 P 0 ;0,1=222,2=270.000000
L 4.80291683 5.29606673 4.80541634 5.2966 2 P 0 ;0,1=222,2=270.000000
L 4.80541634 5.2966 4.80791732 5.29633337 2 P 0 ;0,1=222,2=270.000000
L 4.80791732 5.29633337 4.8100002 5.29526644 2 P 0 ;0,1=222,2=270.000000
L 4.8100002 5.29526644 4.81416673 5.28993327 2 P 0 ;0,1=222,2=270.000000
L 4.81416673 5.28993327 4.81708356 5.28753327 2 P 0 ;0,1=222,2=270.000000
L 4.81708356 5.28753327 4.82125089 5.28593317 2 P 0 ;0,1=222,2=270.000000
L 4.82125089 5.28593317 4.825 5.2853999 2 P 0 ;0,1=222,2=270.000000
L 4.825 5.2853999 4.825 5.2966 2 P 0 ;0,1=222,2=270.000000
L 4.825 5.3182 4.8 5.3182 2 P 0 ;0,1=222,2=270.000000
L 4.8 5.3182 4.81791673 5.30833297 2 P 0 ;0,1=222,2=270.000000
L 4.81791673 5.30833297 4.81791673 5.32166693 2 P 0 ;0,1=222,2=270.000000
L 4.81458406 5.33393317 4.81166654 5.3357999 2 P 0 ;0,1=222,2=270.000000
L 4.81166654 5.3357999 4.8100002 5.3374 2 P 0 ;0,1=222,2=270.000000
L 4.8100002 5.3374 4.80916703 5.33953337 2 P 0 ;0,1=222,2=270.000000
L 4.80916703 5.33953337 4.8100002 5.3414002 2 P 0 ;0,1=222,2=270.000000
L 4.8100002 5.3414002 4.81166654 5.34273327 2 P 0 ;0,1=222,2=270.000000
L 4.81166654 5.34273327 4.81416673 5.3438001 2 P 0 ;0,1=222,2=270.000000
L 4.81416673 5.3438001 4.81708356 5.34406673 2 P 0 ;0,1=222,2=270.000000
L 4.81708356 5.34406673 4.81958376 5.3438001 2 P 0 ;0,1=222,2=270.000000
L 4.81958376 5.3438001 4.82208396 5.34273327 2 P 0 ;0,1=222,2=270.000000
L 4.82208396 5.34273327 4.82416693 5.34113307 2 P 0 ;0,1=222,2=270.000000
L 4.82416693 5.34113307 4.825 5.33926683 2 P 0 ;0,1=222,2=270.000000
L 4.825 5.33926683 4.82416693 5.33713346 2 P 0 ;0,1=222,2=270.000000
L 4.82416693 5.33713346 4.82166742 5.33526663 2 P 0 ;0,1=222,2=270.000000
L 4.82166742 5.33526663 4.81791673 5.3341998 2 P 0 ;0,1=222,2=270.000000
L 4.81791673 5.3341998 4.8137502 5.33393317 2 P 0 ;0,1=222,2=270.000000
L 4.8137502 5.33393317 4.80833386 5.33446634 2 P 0 ;0,1=222,2=270.000000
L 4.80833386 5.33446634 4.80541634 5.33526663 2 P 0 ;0,1=222,2=270.000000
L 4.80541634 5.33526663 4.8025003 5.3365997 2 P 0 ;0,1=222,2=270.000000
L 4.8025003 5.3365997 4.80041663 5.33846654 2 P 0 ;0,1=222,2=270.000000
L 4.80041663 5.33846654 4.8 5.34033327 2 P 0 ;0,1=222,2=270.000000
L 4.8 5.34033327 4.80083317 5.3422 2 P 0 ;0,1=222,2=270.000000
L 4.80083317 5.3422 4.80291683 5.34353356 2 P 0 ;0,1=222,2=270.000000
A 5.16251004 5.6 5.16251004 5.6 5.16 5.6 1 P 0 N
L 5.15208366 5.72886663 5.15083317 5.72726644 2 P 0 ;0,1=223,2=270.000000
L 5.15083317 5.72726644 5.15 5.7254002 2 P 0 ;0,1=223,2=270.000000
L 5.15 5.7254002 5.15 5.72326683 2 P 0 ;0,1=223,2=270.000000
L 5.15 5.72326683 5.15125059 5.72086634 2 P 0 ;0,1=223,2=270.000000
L 5.15125059 5.72086634 5.15333346 5.7190001 2 P 0 ;0,1=223,2=270.000000
L 5.15333346 5.7190001 5.15583366 5.71766654 2 P 0 ;0,1=223,2=270.000000
L 5.15583366 5.71766654 5.1600002 5.71659961 2 P 0 ;0,1=223,2=270.000000
L 5.1600002 5.71659961 5.1637502 5.71633297 2 P 0 ;0,1=223,2=270.000000
L 5.1637502 5.71633297 5.1675001 5.71686673 2 P 0 ;0,1=223,2=270.000000
L 5.1675001 5.71686673 5.17000039 5.71766654 2 P 0 ;0,1=223,2=270.000000
L 5.17000039 5.71766654 5.17250059 5.71926663 2 P 0 ;0,1=223,2=270.000000
L 5.17250059 5.71926663 5.17416693 5.72113346 2 P 0 ;0,1=223,2=270.000000
L 5.17416693 5.72113346 5.175 5.7229997 2 P 0 ;0,1=223,2=270.000000
L 5.175 5.7229997 5.175 5.72486644 2 P 0 ;0,1=223,2=270.000000
L 5.175 5.72486644 5.17416693 5.72673327 2 P 0 ;0,1=223,2=270.000000
L 5.17416693 5.72673327 5.17291713 5.72833337 2 P 0 ;0,1=223,2=270.000000
L 5.17291713 5.72833337 5.17125089 5.72966693 2 P 0 ;0,1=223,2=270.000000
L 5.15416663 5.74193317 5.15166713 5.74353327 2 P 0 ;0,1=223,2=270.000000
L 5.15166713 5.74353327 5.15041663 5.7454 2 P 0 ;0,1=223,2=270.000000
L 5.15041663 5.7454 5.15 5.74753337 2 P 0 ;0,1=223,2=270.000000
L 5.15 5.74753337 5.15083317 5.7502 2 P 0 ;0,1=223,2=270.000000
L 5.15083317 5.7502 5.15291683 5.75206673 2 P 0 ;0,1=223,2=270.000000
L 5.15291683 5.75206673 5.15541634 5.7526 2 P 0 ;0,1=223,2=270.000000
L 5.15541634 5.7526 5.15791732 5.75233337 2 P 0 ;0,1=223,2=270.000000
L 5.15791732 5.75233337 5.1600002 5.75126644 2 P 0 ;0,1=223,2=270.000000
L 5.1600002 5.75126644 5.16416673 5.74593327 2 P 0 ;0,1=223,2=270.000000
L 5.16416673 5.74593327 5.16708356 5.74353327 2 P 0 ;0,1=223,2=270.000000
L 5.16708356 5.74353327 5.17125089 5.74193317 2 P 0 ;0,1=223,2=270.000000
L 5.17125089 5.74193317 5.175 5.7413999 2 P 0 ;0,1=223,2=270.000000
L 5.175 5.7413999 5.175 5.7526 2 P 0 ;0,1=223,2=270.000000
L 5.15416663 5.76593317 5.15166713 5.76753327 2 P 0 ;0,1=223,2=270.000000
L 5.15166713 5.76753327 5.15041663 5.7694 2 P 0 ;0,1=223,2=270.000000
L 5.15041663 5.7694 5.15 5.77153337 2 P 0 ;0,1=223,2=270.000000
L 5.15 5.77153337 5.15083317 5.7742 2 P 0 ;0,1=223,2=270.000000
L 5.15083317 5.7742 5.15291683 5.77606673 2 P 0 ;0,1=223,2=270.000000
L 5.15291683 5.77606673 5.15541634 5.7766 2 P 0 ;0,1=223,2=270.000000
L 5.15541634 5.7766 5.15791732 5.77633337 2 P 0 ;0,1=223,2=270.000000
L 5.15791732 5.77633337 5.1600002 5.77526644 2 P 0 ;0,1=223,2=270.000000
L 5.1600002 5.77526644 5.16416673 5.76993327 2 P 0 ;0,1=223,2=270.000000
L 5.16416673 5.76993327 5.16708356 5.76753327 2 P 0 ;0,1=223,2=270.000000
L 5.16708356 5.76753327 5.17125089 5.76593317 2 P 0 ;0,1=223,2=270.000000
L 5.17125089 5.76593317 5.175 5.7653999 2 P 0 ;0,1=223,2=270.000000
L 5.175 5.7653999 5.175 5.7766 2 P 0 ;0,1=223,2=270.000000
L 5.175 5.7982 5.15 5.7982 2 P 0 ;0,1=223,2=270.000000
L 5.15 5.7982 5.16791673 5.78833297 2 P 0 ;0,1=223,2=270.000000
L 5.16791673 5.78833297 5.16791673 5.80166693 2 P 0 ;0,1=223,2=270.000000
L 5.17125089 5.81313327 5.17333376 5.81473297 2 P 0 ;0,1=223,2=270.000000
L 5.17333376 5.81473297 5.17458346 5.8165997 2 P 0 ;0,1=223,2=270.000000
L 5.17458346 5.8165997 5.175 5.8189997 2 P 0 ;0,1=223,2=270.000000
L 5.175 5.8189997 5.17416693 5.8214002 2 P 0 ;0,1=223,2=270.000000
L 5.17416693 5.8214002 5.17250059 5.82326644 2 P 0 ;0,1=223,2=270.000000
L 5.17250059 5.82326644 5.16958376 5.8246 2 P 0 ;0,1=223,2=270.000000
L 5.16958376 5.8246 5.16625039 5.82486663 2 P 0 ;0,1=223,2=270.000000
L 5.16625039 5.82486663 5.16291703 5.82433337 2 P 0 ;0,1=223,2=270.000000
L 5.16291703 5.82433337 5.16083337 5.8229998 2 P 0 ;0,1=223,2=270.000000
L 5.16083337 5.8229998 5.15916703 5.82113307 2 P 0 ;0,1=223,2=270.000000
L 5.15916703 5.82113307 5.15875049 5.81926683 2 P 0 ;0,1=223,2=270.000000
L 5.15875049 5.81926683 5.15916703 5.8174 2 P 0 ;0,1=223,2=270.000000
L 5.15916703 5.8174 5.16083337 5.8150001 2 P 0 ;0,1=223,2=270.000000
L 5.16083337 5.8150001 5.15 5.8157999 2 P 0 ;0,1=223,2=270.000000
L 5.15 5.8157999 5.15 5.8229998 2 P 0 ;0,1=223,2=270.000000
A 4.96251004 5.425 4.96251004 5.425 4.96 5.425 1 P 0 N
L 4.95208366 5.24886663 4.95083317 5.24726644 2 P 0 ;0,1=224,2=270.000000
L 4.95083317 5.24726644 4.95 5.2454002 2 P 0 ;0,1=224,2=270.000000
L 4.95 5.2454002 4.95 5.24326683 2 P 0 ;0,1=224,2=270.000000
L 4.95 5.24326683 4.95125059 5.24086634 2 P 0 ;0,1=224,2=270.000000
L 4.95125059 5.24086634 4.95333346 5.2390001 2 P 0 ;0,1=224,2=270.000000
L 4.95333346 5.2390001 4.95583366 5.23766654 2 P 0 ;0,1=224,2=270.000000
L 4.95583366 5.23766654 4.9600002 5.23659961 2 P 0 ;0,1=224,2=270.000000
L 4.9600002 5.23659961 4.9637502 5.23633297 2 P 0 ;0,1=224,2=270.000000
L 4.9637502 5.23633297 4.9675001 5.23686673 2 P 0 ;0,1=224,2=270.000000
L 4.9675001 5.23686673 4.97000039 5.23766654 2 P 0 ;0,1=224,2=270.000000
L 4.97000039 5.23766654 4.97250059 5.23926663 2 P 0 ;0,1=224,2=270.000000
L 4.97250059 5.23926663 4.97416693 5.24113346 2 P 0 ;0,1=224,2=270.000000
L 4.97416693 5.24113346 4.975 5.2429997 2 P 0 ;0,1=224,2=270.000000
L 4.975 5.2429997 4.975 5.24486644 2 P 0 ;0,1=224,2=270.000000
L 4.975 5.24486644 4.97416693 5.24673327 2 P 0 ;0,1=224,2=270.000000
L 4.97416693 5.24673327 4.97291713 5.24833337 2 P 0 ;0,1=224,2=270.000000
L 4.97291713 5.24833337 4.97125089 5.24966693 2 P 0 ;0,1=224,2=270.000000
L 4.95416663 5.26193317 4.95166713 5.26353327 2 P 0 ;0,1=224,2=270.000000
L 4.95166713 5.26353327 4.95041663 5.2654 2 P 0 ;0,1=224,2=270.000000
L 4.95041663 5.2654 4.95 5.26753337 2 P 0 ;0,1=224,2=270.000000
L 4.95 5.26753337 4.95083317 5.2702 2 P 0 ;0,1=224,2=270.000000
L 4.95083317 5.2702 4.95291683 5.27206673 2 P 0 ;0,1=224,2=270.000000
L 4.95291683 5.27206673 4.95541634 5.2726 2 P 0 ;0,1=224,2=270.000000
L 4.95541634 5.2726 4.95791732 5.27233337 2 P 0 ;0,1=224,2=270.000000
L 4.95791732 5.27233337 4.9600002 5.27126644 2 P 0 ;0,1=224,2=270.000000
L 4.9600002 5.27126644 4.96416673 5.26593327 2 P 0 ;0,1=224,2=270.000000
L 4.96416673 5.26593327 4.96708356 5.26353327 2 P 0 ;0,1=224,2=270.000000
L 4.96708356 5.26353327 4.97125089 5.26193317 2 P 0 ;0,1=224,2=270.000000
L 4.97125089 5.26193317 4.975 5.2613999 2 P 0 ;0,1=224,2=270.000000
L 4.975 5.2613999 4.975 5.2726 2 P 0 ;0,1=224,2=270.000000
L 4.95416663 5.28593317 4.95166713 5.28753327 2 P 0 ;0,1=224,2=270.000000
L 4.95166713 5.28753327 4.95041663 5.2894 2 P 0 ;0,1=224,2=270.000000
L 4.95041663 5.2894 4.95 5.29153337 2 P 0 ;0,1=224,2=270.000000
L 4.95 5.29153337 4.95083317 5.2942 2 P 0 ;0,1=224,2=270.000000
L 4.95083317 5.2942 4.95291683 5.29606673 2 P 0 ;0,1=224,2=270.000000
L 4.95291683 5.29606673 4.95541634 5.2966 2 P 0 ;0,1=224,2=270.000000
L 4.95541634 5.2966 4.95791732 5.29633337 2 P 0 ;0,1=224,2=270.000000
L 4.95791732 5.29633337 4.9600002 5.29526644 2 P 0 ;0,1=224,2=270.000000
L 4.9600002 5.29526644 4.96416673 5.28993327 2 P 0 ;0,1=224,2=270.000000
L 4.96416673 5.28993327 4.96708356 5.28753327 2 P 0 ;0,1=224,2=270.000000
L 4.96708356 5.28753327 4.97125089 5.28593317 2 P 0 ;0,1=224,2=270.000000
L 4.97125089 5.28593317 4.975 5.2853999 2 P 0 ;0,1=224,2=270.000000
L 4.975 5.2853999 4.975 5.2966 2 P 0 ;0,1=224,2=270.000000
L 4.975 5.3182 4.95 5.3182 2 P 0 ;0,1=224,2=270.000000
L 4.95 5.3182 4.96791673 5.30833297 2 P 0 ;0,1=224,2=270.000000
L 4.96791673 5.30833297 4.96791673 5.32166693 2 P 0 ;0,1=224,2=270.000000
L 4.975 5.3422 4.95 5.3422 2 P 0 ;0,1=224,2=270.000000
L 4.95 5.3422 4.96791673 5.33233297 2 P 0 ;0,1=224,2=270.000000
L 4.96791673 5.33233297 4.96791673 5.34566693 2 P 0 ;0,1=224,2=270.000000
A 3.72251004 4.5 3.72251004 4.5 3.72 4.5 1 P 0 N
L 3.70708366 4.32886663 3.70583317 4.32726644 2 P 0 ;0,1=225,2=270.000000
L 3.70583317 4.32726644 3.705 4.3254002 2 P 0 ;0,1=225,2=270.000000
L 3.705 4.3254002 3.705 4.32326683 2 P 0 ;0,1=225,2=270.000000
L 3.705 4.32326683 3.70625059 4.32086634 2 P 0 ;0,1=225,2=270.000000
L 3.70625059 4.32086634 3.70833346 4.3190001 2 P 0 ;0,1=225,2=270.000000
L 3.70833346 4.3190001 3.71083366 4.31766654 2 P 0 ;0,1=225,2=270.000000
L 3.71083366 4.31766654 3.7150002 4.31659961 2 P 0 ;0,1=225,2=270.000000
L 3.7150002 4.31659961 3.7187502 4.31633297 2 P 0 ;0,1=225,2=270.000000
L 3.7187502 4.31633297 3.7225001 4.31686673 2 P 0 ;0,1=225,2=270.000000
L 3.7225001 4.31686673 3.72500039 4.31766654 2 P 0 ;0,1=225,2=270.000000
L 3.72500039 4.31766654 3.72750059 4.31926663 2 P 0 ;0,1=225,2=270.000000
L 3.72750059 4.31926663 3.72916693 4.32113346 2 P 0 ;0,1=225,2=270.000000
L 3.72916693 4.32113346 3.73 4.3229997 2 P 0 ;0,1=225,2=270.000000
L 3.73 4.3229997 3.73 4.32486644 2 P 0 ;0,1=225,2=270.000000
L 3.73 4.32486644 3.72916693 4.32673327 2 P 0 ;0,1=225,2=270.000000
L 3.72916693 4.32673327 3.72791713 4.32833337 2 P 0 ;0,1=225,2=270.000000
L 3.72791713 4.32833337 3.72625089 4.32966693 2 P 0 ;0,1=225,2=270.000000
L 3.70916663 4.34193317 3.70666713 4.34353327 2 P 0 ;0,1=225,2=270.000000
L 3.70666713 4.34353327 3.70541663 4.3454 2 P 0 ;0,1=225,2=270.000000
L 3.70541663 4.3454 3.705 4.34753337 2 P 0 ;0,1=225,2=270.000000
L 3.705 4.34753337 3.70583317 4.3502 2 P 0 ;0,1=225,2=270.000000
L 3.70583317 4.3502 3.70791683 4.35206673 2 P 0 ;0,1=225,2=270.000000
L 3.70791683 4.35206673 3.71041634 4.3526 2 P 0 ;0,1=225,2=270.000000
L 3.71041634 4.3526 3.71291732 4.35233337 2 P 0 ;0,1=225,2=270.000000
L 3.71291732 4.35233337 3.7150002 4.35126644 2 P 0 ;0,1=225,2=270.000000
L 3.7150002 4.35126644 3.71916673 4.34593327 2 P 0 ;0,1=225,2=270.000000
L 3.71916673 4.34593327 3.72208356 4.34353327 2 P 0 ;0,1=225,2=270.000000
L 3.72208356 4.34353327 3.72625089 4.34193317 2 P 0 ;0,1=225,2=270.000000
L 3.72625089 4.34193317 3.73 4.3413999 2 P 0 ;0,1=225,2=270.000000
L 3.73 4.3413999 3.73 4.3526 2 P 0 ;0,1=225,2=270.000000
L 3.70916663 4.36593317 3.70666713 4.36753327 2 P 0 ;0,1=225,2=270.000000
L 3.70666713 4.36753327 3.70541663 4.3694 2 P 0 ;0,1=225,2=270.000000
L 3.70541663 4.3694 3.705 4.37153337 2 P 0 ;0,1=225,2=270.000000
L 3.705 4.37153337 3.70583317 4.3742 2 P 0 ;0,1=225,2=270.000000
L 3.70583317 4.3742 3.70791683 4.37606673 2 P 0 ;0,1=225,2=270.000000
L 3.70791683 4.37606673 3.71041634 4.3766 2 P 0 ;0,1=225,2=270.000000
L 3.71041634 4.3766 3.71291732 4.37633337 2 P 0 ;0,1=225,2=270.000000
L 3.71291732 4.37633337 3.7150002 4.37526644 2 P 0 ;0,1=225,2=270.000000
L 3.7150002 4.37526644 3.71916673 4.36993327 2 P 0 ;0,1=225,2=270.000000
L 3.71916673 4.36993327 3.72208356 4.36753327 2 P 0 ;0,1=225,2=270.000000
L 3.72208356 4.36753327 3.72625089 4.36593317 2 P 0 ;0,1=225,2=270.000000
L 3.72625089 4.36593317 3.73 4.3653999 2 P 0 ;0,1=225,2=270.000000
L 3.73 4.3653999 3.73 4.3766 2 P 0 ;0,1=225,2=270.000000
L 3.72500039 4.38913327 3.72791713 4.39073297 2 P 0 ;0,1=225,2=270.000000
L 3.72791713 4.39073297 3.72958346 4.39286634 2 P 0 ;0,1=225,2=270.000000
L 3.72958346 4.39286634 3.73 4.39526683 2 P 0 ;0,1=225,2=270.000000
L 3.73 4.39526683 3.72958346 4.3974002 2 P 0 ;0,1=225,2=270.000000
L 3.72958346 4.3974002 3.72750059 4.39953356 2 P 0 ;0,1=225,2=270.000000
L 3.72750059 4.39953356 3.72500039 4.40086663 2 P 0 ;0,1=225,2=270.000000
L 3.72500039 4.40086663 3.7225001 4.40113317 2 P 0 ;0,1=225,2=270.000000
L 3.7225001 4.40113317 3.71958406 4.4006 2 P 0 ;0,1=225,2=270.000000
L 3.71958406 4.4006 3.71750039 4.39873327 2 P 0 ;0,1=225,2=270.000000
L 3.71750039 4.39873327 3.71666654 4.39686644 2 P 0 ;0,1=225,2=270.000000
L 3.71666654 4.39686644 3.71666654 4.39446654 2 P 0 ;0,1=225,2=270.000000
L 3.71666654 4.39686644 3.71541673 4.39846663 2 P 0 ;0,1=225,2=270.000000
L 3.71541673 4.39846663 3.71333386 4.3998001 2 P 0 ;0,1=225,2=270.000000
L 3.71333386 4.3998001 3.71083366 4.40033337 2 P 0 ;0,1=225,2=270.000000
L 3.71083366 4.40033337 3.70833346 4.3998001 2 P 0 ;0,1=225,2=270.000000
L 3.70833346 4.3998001 3.70625059 4.39846663 2 P 0 ;0,1=225,2=270.000000
L 3.70625059 4.39846663 3.705 4.39606663 2 P 0 ;0,1=225,2=270.000000
L 3.705 4.39606663 3.70541663 4.39366663 2 P 0 ;0,1=225,2=270.000000
L 3.70541663 4.39366663 3.70708366 4.39126663 2 P 0 ;0,1=225,2=270.000000
L 3.72708396 4.41446634 3.72916693 4.41633317 2 P 0 ;0,1=225,2=270.000000
L 3.72916693 4.41633317 3.73 4.41846654 2 P 0 ;0,1=225,2=270.000000
L 3.73 4.41846654 3.72916693 4.4205999 2 P 0 ;0,1=225,2=270.000000
L 3.72916693 4.4205999 3.72666742 4.42246663 2 P 0 ;0,1=225,2=270.000000
L 3.72666742 4.42246663 3.72291673 4.4238001 2 P 0 ;0,1=225,2=270.000000
L 3.72291673 4.4238001 3.71916673 4.42433337 2 P 0 ;0,1=225,2=270.000000
L 3.71916673 4.42433337 3.71458366 4.42433337 2 P 0 ;0,1=225,2=270.000000
L 3.71458366 4.42433337 3.71083366 4.4238001 2 P 0 ;0,1=225,2=270.000000
L 3.71083366 4.4238001 3.7075003 4.42246663 2 P 0 ;0,1=225,2=270.000000
L 3.7075003 4.42246663 3.70583317 4.42086644 2 P 0 ;0,1=225,2=270.000000
L 3.70583317 4.42086644 3.705 4.4189997 2 P 0 ;0,1=225,2=270.000000
L 3.705 4.4189997 3.70583317 4.41686634 2 P 0 ;0,1=225,2=270.000000
L 3.70583317 4.41686634 3.7075003 4.41526663 2 P 0 ;0,1=225,2=270.000000
L 3.7075003 4.41526663 3.7099997 4.4141998 2 P 0 ;0,1=225,2=270.000000
L 3.7099997 4.4141998 3.71333386 4.41366654 2 P 0 ;0,1=225,2=270.000000
L 3.71333386 4.41366654 3.7162499 4.4141998 2 P 0 ;0,1=225,2=270.000000
L 3.7162499 4.4141998 3.71916673 4.41553327 2 P 0 ;0,1=225,2=270.000000
L 3.71916673 4.41553327 3.72083386 4.41713346 2 P 0 ;0,1=225,2=270.000000
L 3.72083386 4.41713346 3.72125039 4.4189997 2 P 0 ;0,1=225,2=270.000000
L 3.72125039 4.4189997 3.72041722 4.42113307 2 P 0 ;0,1=225,2=270.000000
L 3.72041722 4.42113307 3.71833356 4.42273327 2 P 0 ;0,1=225,2=270.000000
L 3.71833356 4.42273327 3.71458366 4.42433337 2 P 0 ;0,1=225,2=270.000000
A 10.03251004 4.56 10.03251004 4.56 10.03 4.56 1 P 0 N
L 10.02208366 4.37886663 10.02083317 4.37726644 2 P 0 ;0,1=226,2=270.000000
L 10.02083317 4.37726644 10.02 4.3754002 2 P 0 ;0,1=226,2=270.000000
L 10.02 4.3754002 10.02 4.37326683 2 P 0 ;0,1=226,2=270.000000
L 10.02 4.37326683 10.02125059 4.37086634 2 P 0 ;0,1=226,2=270.000000
L 10.02125059 4.37086634 10.02333346 4.3690001 2 P 0 ;0,1=226,2=270.000000
L 10.02333346 4.3690001 10.02583366 4.36766654 2 P 0 ;0,1=226,2=270.000000
L 10.02583366 4.36766654 10.0300002 4.36659961 2 P 0 ;0,1=226,2=270.000000
L 10.0300002 4.36659961 10.0337502 4.36633297 2 P 0 ;0,1=226,2=270.000000
L 10.0337502 4.36633297 10.0375001 4.36686673 2 P 0 ;0,1=226,2=270.000000
L 10.0375001 4.36686673 10.04000039 4.36766654 2 P 0 ;0,1=226,2=270.000000
L 10.04000039 4.36766654 10.04250059 4.36926663 2 P 0 ;0,1=226,2=270.000000
L 10.04250059 4.36926663 10.04416693 4.37113346 2 P 0 ;0,1=226,2=270.000000
L 10.04416693 4.37113346 10.045 4.3729997 2 P 0 ;0,1=226,2=270.000000
L 10.045 4.3729997 10.045 4.37486644 2 P 0 ;0,1=226,2=270.000000
L 10.045 4.37486644 10.04416693 4.37673327 2 P 0 ;0,1=226,2=270.000000
L 10.04416693 4.37673327 10.04291713 4.37833337 2 P 0 ;0,1=226,2=270.000000
L 10.04291713 4.37833337 10.04125089 4.37966693 2 P 0 ;0,1=226,2=270.000000
L 10.02416663 4.39193317 10.02166713 4.39353327 2 P 0 ;0,1=226,2=270.000000
L 10.02166713 4.39353327 10.02041663 4.3954 2 P 0 ;0,1=226,2=270.000000
L 10.02041663 4.3954 10.02 4.39753337 2 P 0 ;0,1=226,2=270.000000
L 10.02 4.39753337 10.02083317 4.4002 2 P 0 ;0,1=226,2=270.000000
L 10.02083317 4.4002 10.02291683 4.40206673 2 P 0 ;0,1=226,2=270.000000
L 10.02291683 4.40206673 10.02541634 4.4026 2 P 0 ;0,1=226,2=270.000000
L 10.02541634 4.4026 10.02791732 4.40233337 2 P 0 ;0,1=226,2=270.000000
L 10.02791732 4.40233337 10.0300002 4.40126644 2 P 0 ;0,1=226,2=270.000000
L 10.0300002 4.40126644 10.03416673 4.39593327 2 P 0 ;0,1=226,2=270.000000
L 10.03416673 4.39593327 10.03708356 4.39353327 2 P 0 ;0,1=226,2=270.000000
L 10.03708356 4.39353327 10.04125089 4.39193317 2 P 0 ;0,1=226,2=270.000000
L 10.04125089 4.39193317 10.045 4.3913999 2 P 0 ;0,1=226,2=270.000000
L 10.045 4.3913999 10.045 4.4026 2 P 0 ;0,1=226,2=270.000000
L 10.02416663 4.41593317 10.02166713 4.41753327 2 P 0 ;0,1=226,2=270.000000
L 10.02166713 4.41753327 10.02041663 4.4194 2 P 0 ;0,1=226,2=270.000000
L 10.02041663 4.4194 10.02 4.42153337 2 P 0 ;0,1=226,2=270.000000
L 10.02 4.42153337 10.02083317 4.4242 2 P 0 ;0,1=226,2=270.000000
L 10.02083317 4.4242 10.02291683 4.42606673 2 P 0 ;0,1=226,2=270.000000
L 10.02291683 4.42606673 10.02541634 4.4266 2 P 0 ;0,1=226,2=270.000000
L 10.02541634 4.4266 10.02791732 4.42633337 2 P 0 ;0,1=226,2=270.000000
L 10.02791732 4.42633337 10.0300002 4.42526644 2 P 0 ;0,1=226,2=270.000000
L 10.0300002 4.42526644 10.03416673 4.41993327 2 P 0 ;0,1=226,2=270.000000
L 10.03416673 4.41993327 10.03708356 4.41753327 2 P 0 ;0,1=226,2=270.000000
L 10.03708356 4.41753327 10.04125089 4.41593317 2 P 0 ;0,1=226,2=270.000000
L 10.04125089 4.41593317 10.045 4.4153999 2 P 0 ;0,1=226,2=270.000000
L 10.045 4.4153999 10.045 4.4266 2 P 0 ;0,1=226,2=270.000000
L 10.045 4.4482 10.02 4.4482 2 P 0 ;0,1=226,2=270.000000
L 10.02 4.4482 10.03791673 4.43833297 2 P 0 ;0,1=226,2=270.000000
L 10.03791673 4.43833297 10.03791673 4.45166693 2 P 0 ;0,1=226,2=270.000000
L 10.02 4.4689997 10.02083317 4.46686634 2 P 0 ;0,1=226,2=270.000000
L 10.02083317 4.46686634 10.02291683 4.46526663 2 P 0 ;0,1=226,2=270.000000
L 10.02291683 4.46526663 10.02541634 4.4641998 2 P 0 ;0,1=226,2=270.000000
L 10.02541634 4.4641998 10.02875049 4.4633999 2 P 0 ;0,1=226,2=270.000000
L 10.02875049 4.4633999 10.03250039 4.46313327 2 P 0 ;0,1=226,2=270.000000
L 10.03250039 4.46313327 10.03625039 4.4633999 2 P 0 ;0,1=226,2=270.000000
L 10.03625039 4.4633999 10.03958376 4.4641998 2 P 0 ;0,1=226,2=270.000000
L 10.03958376 4.4641998 10.04208396 4.46526663 2 P 0 ;0,1=226,2=270.000000
L 10.04208396 4.46526663 10.04416693 4.46686634 2 P 0 ;0,1=226,2=270.000000
L 10.04416693 4.46686634 10.045 4.4689997 2 P 0 ;0,1=226,2=270.000000
L 10.045 4.4689997 10.04416693 4.47113307 2 P 0 ;0,1=226,2=270.000000
L 10.04416693 4.47113307 10.04208396 4.47273327 2 P 0 ;0,1=226,2=270.000000
L 10.04208396 4.47273327 10.03958376 4.4738001 2 P 0 ;0,1=226,2=270.000000
L 10.03958376 4.4738001 10.03625039 4.4746 2 P 0 ;0,1=226,2=270.000000
L 10.03625039 4.4746 10.03250039 4.47486663 2 P 0 ;0,1=226,2=270.000000
L 10.03250039 4.47486663 10.02875049 4.4746 2 P 0 ;0,1=226,2=270.000000
L 10.02875049 4.4746 10.02541634 4.4738001 2 P 0 ;0,1=226,2=270.000000
L 10.02541634 4.4738001 10.02291683 4.47273327 2 P 0 ;0,1=226,2=270.000000
L 10.02291683 4.47273327 10.02083317 4.47113307 2 P 0 ;0,1=226,2=270.000000
L 10.02083317 4.47113307 10.02 4.4689997 2 P 0 ;0,1=226,2=270.000000
A 4.14251004 4.7 4.14251004 4.7 4.14 4.7 1 P 0 N
L 4.12208366 4.24886663 4.12083317 4.24726644 2 P 0 ;0,1=227,2=270.000000
L 4.12083317 4.24726644 4.12 4.2454002 2 P 0 ;0,1=227,2=270.000000
L 4.12 4.2454002 4.12 4.24326683 2 P 0 ;0,1=227,2=270.000000
L 4.12 4.24326683 4.12125059 4.24086634 2 P 0 ;0,1=227,2=270.000000
L 4.12125059 4.24086634 4.12333346 4.2390001 2 P 0 ;0,1=227,2=270.000000
L 4.12333346 4.2390001 4.12583366 4.23766654 2 P 0 ;0,1=227,2=270.000000
L 4.12583366 4.23766654 4.1300002 4.23659961 2 P 0 ;0,1=227,2=270.000000
L 4.1300002 4.23659961 4.1337502 4.23633297 2 P 0 ;0,1=227,2=270.000000
L 4.1337502 4.23633297 4.1375001 4.23686673 2 P 0 ;0,1=227,2=270.000000
L 4.1375001 4.23686673 4.14000039 4.23766654 2 P 0 ;0,1=227,2=270.000000
L 4.14000039 4.23766654 4.14250059 4.23926663 2 P 0 ;0,1=227,2=270.000000
L 4.14250059 4.23926663 4.14416693 4.24113346 2 P 0 ;0,1=227,2=270.000000
L 4.14416693 4.24113346 4.145 4.2429997 2 P 0 ;0,1=227,2=270.000000
L 4.145 4.2429997 4.145 4.24486644 2 P 0 ;0,1=227,2=270.000000
L 4.145 4.24486644 4.14416693 4.24673327 2 P 0 ;0,1=227,2=270.000000
L 4.14416693 4.24673327 4.14291713 4.24833337 2 P 0 ;0,1=227,2=270.000000
L 4.14291713 4.24833337 4.14125089 4.24966693 2 P 0 ;0,1=227,2=270.000000
L 4.12416663 4.26193317 4.12166713 4.26353327 2 P 0 ;0,1=227,2=270.000000
L 4.12166713 4.26353327 4.12041663 4.2654 2 P 0 ;0,1=227,2=270.000000
L 4.12041663 4.2654 4.12 4.26753337 2 P 0 ;0,1=227,2=270.000000
L 4.12 4.26753337 4.12083317 4.2702 2 P 0 ;0,1=227,2=270.000000
L 4.12083317 4.2702 4.12291683 4.27206673 2 P 0 ;0,1=227,2=270.000000
L 4.12291683 4.27206673 4.12541634 4.2726 2 P 0 ;0,1=227,2=270.000000
L 4.12541634 4.2726 4.12791732 4.27233337 2 P 0 ;0,1=227,2=270.000000
L 4.12791732 4.27233337 4.1300002 4.27126644 2 P 0 ;0,1=227,2=270.000000
L 4.1300002 4.27126644 4.13416673 4.26593327 2 P 0 ;0,1=227,2=270.000000
L 4.13416673 4.26593327 4.13708356 4.26353327 2 P 0 ;0,1=227,2=270.000000
L 4.13708356 4.26353327 4.14125089 4.26193317 2 P 0 ;0,1=227,2=270.000000
L 4.14125089 4.26193317 4.145 4.2613999 2 P 0 ;0,1=227,2=270.000000
L 4.145 4.2613999 4.145 4.2726 2 P 0 ;0,1=227,2=270.000000
L 4.12416663 4.28593317 4.12166713 4.28753327 2 P 0 ;0,1=227,2=270.000000
L 4.12166713 4.28753327 4.12041663 4.2894 2 P 0 ;0,1=227,2=270.000000
L 4.12041663 4.2894 4.12 4.29153337 2 P 0 ;0,1=227,2=270.000000
L 4.12 4.29153337 4.12083317 4.2942 2 P 0 ;0,1=227,2=270.000000
L 4.12083317 4.2942 4.12291683 4.29606673 2 P 0 ;0,1=227,2=270.000000
L 4.12291683 4.29606673 4.12541634 4.2966 2 P 0 ;0,1=227,2=270.000000
L 4.12541634 4.2966 4.12791732 4.29633337 2 P 0 ;0,1=227,2=270.000000
L 4.12791732 4.29633337 4.1300002 4.29526644 2 P 0 ;0,1=227,2=270.000000
L 4.1300002 4.29526644 4.13416673 4.28993327 2 P 0 ;0,1=227,2=270.000000
L 4.13416673 4.28993327 4.13708356 4.28753327 2 P 0 ;0,1=227,2=270.000000
L 4.13708356 4.28753327 4.14125089 4.28593317 2 P 0 ;0,1=227,2=270.000000
L 4.14125089 4.28593317 4.145 4.2853999 2 P 0 ;0,1=227,2=270.000000
L 4.145 4.2853999 4.145 4.2966 2 P 0 ;0,1=227,2=270.000000
L 4.145 4.3182 4.12 4.3182 2 P 0 ;0,1=227,2=270.000000
L 4.12 4.3182 4.13791673 4.30833297 2 P 0 ;0,1=227,2=270.000000
L 4.13791673 4.30833297 4.13791673 4.32166693 2 P 0 ;0,1=227,2=270.000000
L 4.145 4.3389997 4.12 4.3389997 2 P 0 ;0,1=227,2=270.000000
L 4.12 4.3389997 4.1249997 4.3357999 2 P 0 ;0,1=227,2=270.000000
L 4.145 4.3357999 4.145 4.34219951 2 P 0 ;0,1=227,2=270.000000
A 5.53845 4.6031 5.53845 4.6031 5.53593996 4.6031 1 P 0 N
L 5.55 4.65966654 5.525 4.65966654 2 P 0 ;0,1=228,2=270.000000
L 5.525 4.65966654 5.525 4.66606663 2 P 0 ;0,1=228,2=270.000000
L 5.525 4.66606663 5.52625059 4.6682 2 P 0 ;0,1=228,2=270.000000
L 5.52625059 4.6682 5.52916663 4.6698001 2 P 0 ;0,1=228,2=270.000000
L 5.52916663 4.6698001 5.5325 4.67033337 2 P 0 ;0,1=228,2=270.000000
L 5.5325 4.67033337 5.53583337 4.6698001 2 P 0 ;0,1=228,2=270.000000
L 5.53583337 4.6698001 5.53833356 4.66846663 2 P 0 ;0,1=228,2=270.000000
L 5.53833356 4.66846663 5.53958406 4.66606663 2 P 0 ;0,1=228,2=270.000000
L 5.53958406 4.66606663 5.53958406 4.65966654 2 P 0 ;0,1=228,2=270.000000
L 5.54666742 4.6833999 5.5487503 4.68553327 2 P 0 ;0,1=228,2=270.000000
L 5.5487503 4.68553327 5.55 4.68793327 2 P 0 ;0,1=228,2=270.000000
L 5.55 4.68793327 5.55 4.69006663 2 P 0 ;0,1=228,2=270.000000
L 5.55 4.69006663 5.5487503 4.6922 2 P 0 ;0,1=228,2=270.000000
L 5.5487503 4.6922 5.54666742 4.6938001 2 P 0 ;0,1=228,2=270.000000
L 5.54666742 4.6938001 5.5437499 4.6946 2 P 0 ;0,1=228,2=270.000000
L 5.5437499 4.6946 5.54083386 4.69406673 2 P 0 ;0,1=228,2=270.000000
L 5.54083386 4.69406673 5.53833356 4.69273327 2 P 0 ;0,1=228,2=270.000000
L 5.53833356 4.69273327 5.53666654 4.69033327 2 P 0 ;0,1=228,2=270.000000
L 5.53666654 4.69033327 5.53583337 4.68713346 2 P 0 ;0,1=228,2=270.000000
L 5.53583337 4.68713346 5.53416703 4.68526663 2 P 0 ;0,1=228,2=270.000000
L 5.53416703 4.68526663 5.5312502 4.68446634 2 P 0 ;0,1=228,2=270.000000
L 5.5312502 4.68446634 5.52833346 4.6850001 2 P 0 ;0,1=228,2=270.000000
L 5.52833346 4.6850001 5.52625059 4.68633317 2 P 0 ;0,1=228,2=270.000000
L 5.52625059 4.68633317 5.525 4.6881999 2 P 0 ;0,1=228,2=270.000000
L 5.525 4.6881999 5.525 4.69006663 2 P 0 ;0,1=228,2=270.000000
L 5.525 4.69006663 5.52583317 4.69193337 2 P 0 ;0,1=228,2=270.000000
L 5.52583317 4.69193337 5.52791683 4.69353356 2 P 0 ;0,1=228,2=270.000000
L 5.525 4.7129997 5.55 4.7129997 2 P 0 ;0,1=228,2=270.000000
L 5.525 4.70686673 5.525 4.71913317 2 P 0 ;0,1=228,2=270.000000
L 5.52708366 4.74286663 5.52583317 4.74126644 2 P 0 ;0,1=228,2=270.000000
L 5.52583317 4.74126644 5.525 4.7394002 2 P 0 ;0,1=228,2=270.000000
L 5.525 4.7394002 5.525 4.73726683 2 P 0 ;0,1=228,2=270.000000
L 5.525 4.73726683 5.52625059 4.73486634 2 P 0 ;0,1=228,2=270.000000
L 5.52625059 4.73486634 5.52833346 4.7330001 2 P 0 ;0,1=228,2=270.000000
L 5.52833346 4.7330001 5.53083366 4.73166654 2 P 0 ;0,1=228,2=270.000000
L 5.53083366 4.73166654 5.5350002 4.73059961 2 P 0 ;0,1=228,2=270.000000
L 5.5350002 4.73059961 5.5387502 4.73033297 2 P 0 ;0,1=228,2=270.000000
L 5.5387502 4.73033297 5.5425001 4.73086673 2 P 0 ;0,1=228,2=270.000000
L 5.5425001 4.73086673 5.54500039 4.73166654 2 P 0 ;0,1=228,2=270.000000
L 5.54500039 4.73166654 5.54750059 4.73326663 2 P 0 ;0,1=228,2=270.000000
L 5.54750059 4.73326663 5.54916693 4.73513346 2 P 0 ;0,1=228,2=270.000000
L 5.54916693 4.73513346 5.55 4.7369997 2 P 0 ;0,1=228,2=270.000000
L 5.55 4.7369997 5.55 4.73886644 2 P 0 ;0,1=228,2=270.000000
L 5.55 4.73886644 5.54916693 4.74073327 2 P 0 ;0,1=228,2=270.000000
L 5.54916693 4.74073327 5.54791713 4.74233337 2 P 0 ;0,1=228,2=270.000000
L 5.54791713 4.74233337 5.54625089 4.74366693 2 P 0 ;0,1=228,2=270.000000
L 5.52916663 4.75593317 5.52666713 4.75753327 2 P 0 ;0,1=228,2=270.000000
L 5.52666713 4.75753327 5.52541663 4.7594 2 P 0 ;0,1=228,2=270.000000
L 5.52541663 4.7594 5.525 4.76153337 2 P 0 ;0,1=228,2=270.000000
L 5.525 4.76153337 5.52583317 4.7642 2 P 0 ;0,1=228,2=270.000000
L 5.52583317 4.7642 5.52791683 4.76606673 2 P 0 ;0,1=228,2=270.000000
L 5.52791683 4.76606673 5.53041634 4.7666 2 P 0 ;0,1=228,2=270.000000
L 5.53041634 4.7666 5.53291732 4.76633337 2 P 0 ;0,1=228,2=270.000000
L 5.53291732 4.76633337 5.5350002 4.76526644 2 P 0 ;0,1=228,2=270.000000
L 5.5350002 4.76526644 5.53916673 4.75993327 2 P 0 ;0,1=228,2=270.000000
L 5.53916673 4.75993327 5.54208356 4.75753327 2 P 0 ;0,1=228,2=270.000000
L 5.54208356 4.75753327 5.54625089 4.75593317 2 P 0 ;0,1=228,2=270.000000
L 5.54625089 4.75593317 5.55 4.7553999 2 P 0 ;0,1=228,2=270.000000
L 5.55 4.7553999 5.55 4.7666 2 P 0 ;0,1=228,2=270.000000
L 5.52916663 4.77993317 5.52666713 4.78153327 2 P 0 ;0,1=228,2=270.000000
L 5.52666713 4.78153327 5.52541663 4.7834 2 P 0 ;0,1=228,2=270.000000
L 5.52541663 4.7834 5.525 4.78553337 2 P 0 ;0,1=228,2=270.000000
L 5.525 4.78553337 5.52583317 4.7882 2 P 0 ;0,1=228,2=270.000000
L 5.52583317 4.7882 5.52791683 4.79006673 2 P 0 ;0,1=228,2=270.000000
L 5.52791683 4.79006673 5.53041634 4.7906 2 P 0 ;0,1=228,2=270.000000
L 5.53041634 4.7906 5.53291732 4.79033337 2 P 0 ;0,1=228,2=270.000000
L 5.53291732 4.79033337 5.5350002 4.78926644 2 P 0 ;0,1=228,2=270.000000
L 5.5350002 4.78926644 5.53916673 4.78393327 2 P 0 ;0,1=228,2=270.000000
L 5.53916673 4.78393327 5.54208356 4.78153327 2 P 0 ;0,1=228,2=270.000000
L 5.54208356 4.78153327 5.54625089 4.77993317 2 P 0 ;0,1=228,2=270.000000
L 5.54625089 4.77993317 5.55 4.7793999 2 P 0 ;0,1=228,2=270.000000
L 5.55 4.7793999 5.55 4.7906 2 P 0 ;0,1=228,2=270.000000
A 6.3687 4.94705 6.3687 4.94705 6.36618996 4.94705 1 P 0 N
L 6.15966654 4.945 6.15966654 4.97 2 P 0 ;0,1=229,2=0.000000
L 6.15966654 4.97 6.16606663 4.97 2 P 0 ;0,1=229,2=0.000000
L 6.16606663 4.97 6.1682 4.96874941 2 P 0 ;0,1=229,2=0.000000
L 6.1682 4.96874941 6.1698001 4.96583337 2 P 0 ;0,1=229,2=0.000000
L 6.1698001 4.96583337 6.17033337 4.9625 2 P 0 ;0,1=229,2=0.000000
L 6.17033337 4.9625 6.1698001 4.95916663 2 P 0 ;0,1=229,2=0.000000
L 6.1698001 4.95916663 6.16846663 4.95666644 2 P 0 ;0,1=229,2=0.000000
L 6.16846663 4.95666644 6.16606663 4.95541594 2 P 0 ;0,1=229,2=0.000000
L 6.16606663 4.95541594 6.15966654 4.95541594 2 P 0 ;0,1=229,2=0.000000
L 6.1833999 4.94833258 6.18553327 4.9462497 2 P 0 ;0,1=229,2=0.000000
L 6.18553327 4.9462497 6.18793327 4.945 2 P 0 ;0,1=229,2=0.000000
L 6.18793327 4.945 6.19006663 4.945 2 P 0 ;0,1=229,2=0.000000
L 6.19006663 4.945 6.1922 4.9462497 2 P 0 ;0,1=229,2=0.000000
L 6.1922 4.9462497 6.1938001 4.94833258 2 P 0 ;0,1=229,2=0.000000
L 6.1938001 4.94833258 6.1946 4.9512501 2 P 0 ;0,1=229,2=0.000000
L 6.1946 4.9512501 6.19406673 4.95416614 2 P 0 ;0,1=229,2=0.000000
L 6.19406673 4.95416614 6.19273327 4.95666644 2 P 0 ;0,1=229,2=0.000000
L 6.19273327 4.95666644 6.19033327 4.95833346 2 P 0 ;0,1=229,2=0.000000
L 6.19033327 4.95833346 6.18713346 4.95916663 2 P 0 ;0,1=229,2=0.000000
L 6.18713346 4.95916663 6.18526663 4.96083297 2 P 0 ;0,1=229,2=0.000000
L 6.18526663 4.96083297 6.18446634 4.9637498 2 P 0 ;0,1=229,2=0.000000
L 6.18446634 4.9637498 6.1850001 4.96666654 2 P 0 ;0,1=229,2=0.000000
L 6.1850001 4.96666654 6.18633317 4.96874941 2 P 0 ;0,1=229,2=0.000000
L 6.18633317 4.96874941 6.1881999 4.97 2 P 0 ;0,1=229,2=0.000000
L 6.1881999 4.97 6.19006663 4.97 2 P 0 ;0,1=229,2=0.000000
L 6.19006663 4.97 6.19193337 4.96916683 2 P 0 ;0,1=229,2=0.000000
L 6.19193337 4.96916683 6.19353356 4.96708317 2 P 0 ;0,1=229,2=0.000000
L 6.2129997 4.97 6.2129997 4.945 2 P 0 ;0,1=229,2=0.000000
L 6.20686673 4.97 6.21913317 4.97 2 P 0 ;0,1=229,2=0.000000
L 6.24286663 4.96791634 6.24126644 4.96916683 2 P 0 ;0,1=229,2=0.000000
L 6.24126644 4.96916683 6.2394002 4.97 2 P 0 ;0,1=229,2=0.000000
L 6.2394002 4.97 6.23726683 4.97 2 P 0 ;0,1=229,2=0.000000
L 6.23726683 4.97 6.23486634 4.96874941 2 P 0 ;0,1=229,2=0.000000
L 6.23486634 4.96874941 6.2330001 4.96666654 2 P 0 ;0,1=229,2=0.000000
L 6.2330001 4.96666654 6.23166654 4.96416634 2 P 0 ;0,1=229,2=0.000000
L 6.23166654 4.96416634 6.23059961 4.9599998 2 P 0 ;0,1=229,2=0.000000
L 6.23059961 4.9599998 6.23033297 4.9562498 2 P 0 ;0,1=229,2=0.000000
L 6.23033297 4.9562498 6.23086673 4.9524999 2 P 0 ;0,1=229,2=0.000000
L 6.23086673 4.9524999 6.23166654 4.94999961 2 P 0 ;0,1=229,2=0.000000
L 6.23166654 4.94999961 6.23326663 4.94749941 2 P 0 ;0,1=229,2=0.000000
L 6.23326663 4.94749941 6.23513346 4.94583307 2 P 0 ;0,1=229,2=0.000000
L 6.23513346 4.94583307 6.2369997 4.945 2 P 0 ;0,1=229,2=0.000000
L 6.2369997 4.945 6.23886644 4.945 2 P 0 ;0,1=229,2=0.000000
L 6.23886644 4.945 6.24073327 4.94583307 2 P 0 ;0,1=229,2=0.000000
L 6.24073327 4.94583307 6.24233337 4.94708287 2 P 0 ;0,1=229,2=0.000000
L 6.24233337 4.94708287 6.24366693 4.94874911 2 P 0 ;0,1=229,2=0.000000
L 6.2609997 4.945 6.2609997 4.97 2 P 0 ;0,1=229,2=0.000000
L 6.2609997 4.97 6.2577999 4.9650003 2 P 0 ;0,1=229,2=0.000000
L 6.2577999 4.945 6.26419951 4.945 2 P 0 ;0,1=229,2=0.000000
L 6.27913327 4.94999961 6.28073297 4.94708287 2 P 0 ;0,1=229,2=0.000000
L 6.28073297 4.94708287 6.28286634 4.94541654 2 P 0 ;0,1=229,2=0.000000
L 6.28286634 4.94541654 6.28526683 4.945 2 P 0 ;0,1=229,2=0.000000
L 6.28526683 4.945 6.2874002 4.94541654 2 P 0 ;0,1=229,2=0.000000
L 6.2874002 4.94541654 6.28953356 4.94749941 2 P 0 ;0,1=229,2=0.000000
L 6.28953356 4.94749941 6.29086663 4.94999961 2 P 0 ;0,1=229,2=0.000000
L 6.29086663 4.94999961 6.29113317 4.9524999 2 P 0 ;0,1=229,2=0.000000
L 6.29113317 4.9524999 6.2906 4.95541594 2 P 0 ;0,1=229,2=0.000000
L 6.2906 4.95541594 6.28873327 4.95749961 2 P 0 ;0,1=229,2=0.000000
L 6.28873327 4.95749961 6.28686644 4.95833346 2 P 0 ;0,1=229,2=0.000000
L 6.28686644 4.95833346 6.28446654 4.95833346 2 P 0 ;0,1=229,2=0.000000
L 6.28686644 4.95833346 6.28846663 4.95958327 2 P 0 ;0,1=229,2=0.000000
L 6.28846663 4.95958327 6.2898001 4.96166614 2 P 0 ;0,1=229,2=0.000000
L 6.2898001 4.96166614 6.29033337 4.96416634 2 P 0 ;0,1=229,2=0.000000
L 6.29033337 4.96416634 6.2898001 4.96666654 2 P 0 ;0,1=229,2=0.000000
L 6.2898001 4.96666654 6.28846663 4.96874941 2 P 0 ;0,1=229,2=0.000000
L 6.28846663 4.96874941 6.28606663 4.97 2 P 0 ;0,1=229,2=0.000000
L 6.28606663 4.97 6.28366663 4.96958337 2 P 0 ;0,1=229,2=0.000000
L 6.28366663 4.96958337 6.28126663 4.96791634 2 P 0 ;0,1=229,2=0.000000
A 6.4437 4.99705 6.4437 4.99705 6.44118996 4.99705 1 P 0 N
L 6.38666654 5.165 6.38666654 5.19 2 P 0 ;0,1=230,2=0.000000
L 6.38666654 5.19 6.39306663 5.19 2 P 0 ;0,1=230,2=0.000000
L 6.39306663 5.19 6.3952 5.18874941 2 P 0 ;0,1=230,2=0.000000
L 6.3952 5.18874941 6.3968001 5.18583337 2 P 0 ;0,1=230,2=0.000000
L 6.3968001 5.18583337 6.39733337 5.1825 2 P 0 ;0,1=230,2=0.000000
L 6.39733337 5.1825 6.3968001 5.17916663 2 P 0 ;0,1=230,2=0.000000
L 6.3968001 5.17916663 6.39546663 5.17666644 2 P 0 ;0,1=230,2=0.000000
L 6.39546663 5.17666644 6.39306663 5.17541594 2 P 0 ;0,1=230,2=0.000000
L 6.39306663 5.17541594 6.38666654 5.17541594 2 P 0 ;0,1=230,2=0.000000
L 6.4103999 5.16833258 6.41253327 5.1662497 2 P 0 ;0,1=230,2=0.000000
L 6.41253327 5.1662497 6.41493327 5.165 2 P 0 ;0,1=230,2=0.000000
L 6.41493327 5.165 6.41706663 5.165 2 P 0 ;0,1=230,2=0.000000
L 6.41706663 5.165 6.4192 5.1662497 2 P 0 ;0,1=230,2=0.000000
L 6.4192 5.1662497 6.4208001 5.16833258 2 P 0 ;0,1=230,2=0.000000
L 6.4208001 5.16833258 6.4216 5.1712501 2 P 0 ;0,1=230,2=0.000000
L 6.4216 5.1712501 6.42106673 5.17416614 2 P 0 ;0,1=230,2=0.000000
L 6.42106673 5.17416614 6.41973327 5.17666644 2 P 0 ;0,1=230,2=0.000000
L 6.41973327 5.17666644 6.41733327 5.17833346 2 P 0 ;0,1=230,2=0.000000
L 6.41733327 5.17833346 6.41413346 5.17916663 2 P 0 ;0,1=230,2=0.000000
L 6.41413346 5.17916663 6.41226663 5.18083297 2 P 0 ;0,1=230,2=0.000000
L 6.41226663 5.18083297 6.41146634 5.1837498 2 P 0 ;0,1=230,2=0.000000
L 6.41146634 5.1837498 6.4120001 5.18666654 2 P 0 ;0,1=230,2=0.000000
L 6.4120001 5.18666654 6.41333317 5.18874941 2 P 0 ;0,1=230,2=0.000000
L 6.41333317 5.18874941 6.4151999 5.19 2 P 0 ;0,1=230,2=0.000000
L 6.4151999 5.19 6.41706663 5.19 2 P 0 ;0,1=230,2=0.000000
L 6.41706663 5.19 6.41893337 5.18916683 2 P 0 ;0,1=230,2=0.000000
L 6.41893337 5.18916683 6.42053356 5.18708317 2 P 0 ;0,1=230,2=0.000000
L 6.4399997 5.19 6.4399997 5.165 2 P 0 ;0,1=230,2=0.000000
L 6.43386673 5.19 6.44613317 5.19 2 P 0 ;0,1=230,2=0.000000
L 6.46986663 5.18791634 6.46826644 5.18916683 2 P 0 ;0,1=230,2=0.000000
L 6.46826644 5.18916683 6.4664002 5.19 2 P 0 ;0,1=230,2=0.000000
L 6.4664002 5.19 6.46426683 5.19 2 P 0 ;0,1=230,2=0.000000
L 6.46426683 5.19 6.46186634 5.18874941 2 P 0 ;0,1=230,2=0.000000
L 6.46186634 5.18874941 6.4600001 5.18666654 2 P 0 ;0,1=230,2=0.000000
L 6.4600001 5.18666654 6.45866654 5.18416634 2 P 0 ;0,1=230,2=0.000000
L 6.45866654 5.18416634 6.45759961 5.1799998 2 P 0 ;0,1=230,2=0.000000
L 6.45759961 5.1799998 6.45733297 5.1762498 2 P 0 ;0,1=230,2=0.000000
L 6.45733297 5.1762498 6.45786673 5.1724999 2 P 0 ;0,1=230,2=0.000000
L 6.45786673 5.1724999 6.45866654 5.16999961 2 P 0 ;0,1=230,2=0.000000
L 6.45866654 5.16999961 6.46026663 5.16749941 2 P 0 ;0,1=230,2=0.000000
L 6.46026663 5.16749941 6.46213346 5.16583307 2 P 0 ;0,1=230,2=0.000000
L 6.46213346 5.16583307 6.4639997 5.165 2 P 0 ;0,1=230,2=0.000000
L 6.4639997 5.165 6.46586644 5.165 2 P 0 ;0,1=230,2=0.000000
L 6.46586644 5.165 6.46773327 5.16583307 2 P 0 ;0,1=230,2=0.000000
L 6.46773327 5.16583307 6.46933337 5.16708287 2 P 0 ;0,1=230,2=0.000000
L 6.46933337 5.16708287 6.47066693 5.16874911 2 P 0 ;0,1=230,2=0.000000
L 6.48293317 5.18583337 6.48453327 5.18833287 2 P 0 ;0,1=230,2=0.000000
L 6.48453327 5.18833287 6.4864 5.18958337 2 P 0 ;0,1=230,2=0.000000
L 6.4864 5.18958337 6.48853337 5.19 2 P 0 ;0,1=230,2=0.000000
L 6.48853337 5.19 6.4912 5.18916683 2 P 0 ;0,1=230,2=0.000000
L 6.4912 5.18916683 6.49306673 5.18708317 2 P 0 ;0,1=230,2=0.000000
L 6.49306673 5.18708317 6.4936 5.18458366 2 P 0 ;0,1=230,2=0.000000
L 6.4936 5.18458366 6.49333337 5.18208268 2 P 0 ;0,1=230,2=0.000000
L 6.49333337 5.18208268 6.49226644 5.1799998 2 P 0 ;0,1=230,2=0.000000
L 6.49226644 5.1799998 6.48693327 5.17583327 2 P 0 ;0,1=230,2=0.000000
L 6.48693327 5.17583327 6.48453327 5.17291644 2 P 0 ;0,1=230,2=0.000000
L 6.48453327 5.17291644 6.48293317 5.16874911 2 P 0 ;0,1=230,2=0.000000
L 6.48293317 5.16874911 6.4823999 5.165 2 P 0 ;0,1=230,2=0.000000
L 6.4823999 5.165 6.4936 5.165 2 P 0 ;0,1=230,2=0.000000
A 6.4437 5.04705 6.4437 5.04705 6.44118996 5.04705 1 P 0 N
L 6.38466654 5.205 6.38466654 5.23 2 P 0 ;0,1=231,2=0.000000
L 6.38466654 5.23 6.39106663 5.23 2 P 0 ;0,1=231,2=0.000000
L 6.39106663 5.23 6.3932 5.22874941 2 P 0 ;0,1=231,2=0.000000
L 6.3932 5.22874941 6.3948001 5.22583337 2 P 0 ;0,1=231,2=0.000000
L 6.3948001 5.22583337 6.39533337 5.2225 2 P 0 ;0,1=231,2=0.000000
L 6.39533337 5.2225 6.3948001 5.21916663 2 P 0 ;0,1=231,2=0.000000
L 6.3948001 5.21916663 6.39346663 5.21666644 2 P 0 ;0,1=231,2=0.000000
L 6.39346663 5.21666644 6.39106663 5.21541594 2 P 0 ;0,1=231,2=0.000000
L 6.39106663 5.21541594 6.38466654 5.21541594 2 P 0 ;0,1=231,2=0.000000
L 6.4083999 5.20833258 6.41053327 5.2062497 2 P 0 ;0,1=231,2=0.000000
L 6.41053327 5.2062497 6.41293327 5.205 2 P 0 ;0,1=231,2=0.000000
L 6.41293327 5.205 6.41506663 5.205 2 P 0 ;0,1=231,2=0.000000
L 6.41506663 5.205 6.4172 5.2062497 2 P 0 ;0,1=231,2=0.000000
L 6.4172 5.2062497 6.4188001 5.20833258 2 P 0 ;0,1=231,2=0.000000
L 6.4188001 5.20833258 6.4196 5.2112501 2 P 0 ;0,1=231,2=0.000000
L 6.4196 5.2112501 6.41906673 5.21416614 2 P 0 ;0,1=231,2=0.000000
L 6.41906673 5.21416614 6.41773327 5.21666644 2 P 0 ;0,1=231,2=0.000000
L 6.41773327 5.21666644 6.41533327 5.21833346 2 P 0 ;0,1=231,2=0.000000
L 6.41533327 5.21833346 6.41213346 5.21916663 2 P 0 ;0,1=231,2=0.000000
L 6.41213346 5.21916663 6.41026663 5.22083297 2 P 0 ;0,1=231,2=0.000000
L 6.41026663 5.22083297 6.40946634 5.2237498 2 P 0 ;0,1=231,2=0.000000
L 6.40946634 5.2237498 6.4100001 5.22666654 2 P 0 ;0,1=231,2=0.000000
L 6.4100001 5.22666654 6.41133317 5.22874941 2 P 0 ;0,1=231,2=0.000000
L 6.41133317 5.22874941 6.4131999 5.23 2 P 0 ;0,1=231,2=0.000000
L 6.4131999 5.23 6.41506663 5.23 2 P 0 ;0,1=231,2=0.000000
L 6.41506663 5.23 6.41693337 5.22916683 2 P 0 ;0,1=231,2=0.000000
L 6.41693337 5.22916683 6.41853356 5.22708317 2 P 0 ;0,1=231,2=0.000000
L 6.4379997 5.23 6.4379997 5.205 2 P 0 ;0,1=231,2=0.000000
L 6.43186673 5.23 6.44413317 5.23 2 P 0 ;0,1=231,2=0.000000
L 6.46786663 5.22791634 6.46626644 5.22916683 2 P 0 ;0,1=231,2=0.000000
L 6.46626644 5.22916683 6.4644002 5.23 2 P 0 ;0,1=231,2=0.000000
L 6.4644002 5.23 6.46226683 5.23 2 P 0 ;0,1=231,2=0.000000
L 6.46226683 5.23 6.45986634 5.22874941 2 P 0 ;0,1=231,2=0.000000
L 6.45986634 5.22874941 6.4580001 5.22666654 2 P 0 ;0,1=231,2=0.000000
L 6.4580001 5.22666654 6.45666654 5.22416634 2 P 0 ;0,1=231,2=0.000000
L 6.45666654 5.22416634 6.45559961 5.2199998 2 P 0 ;0,1=231,2=0.000000
L 6.45559961 5.2199998 6.45533297 5.2162498 2 P 0 ;0,1=231,2=0.000000
L 6.45533297 5.2162498 6.45586673 5.2124999 2 P 0 ;0,1=231,2=0.000000
L 6.45586673 5.2124999 6.45666654 5.20999961 2 P 0 ;0,1=231,2=0.000000
L 6.45666654 5.20999961 6.45826663 5.20749941 2 P 0 ;0,1=231,2=0.000000
L 6.45826663 5.20749941 6.46013346 5.20583307 2 P 0 ;0,1=231,2=0.000000
L 6.46013346 5.20583307 6.4619997 5.205 2 P 0 ;0,1=231,2=0.000000
L 6.4619997 5.205 6.46386644 5.205 2 P 0 ;0,1=231,2=0.000000
L 6.46386644 5.205 6.46573327 5.20583307 2 P 0 ;0,1=231,2=0.000000
L 6.46573327 5.20583307 6.46733337 5.20708287 2 P 0 ;0,1=231,2=0.000000
L 6.46733337 5.20708287 6.46866693 5.20874911 2 P 0 ;0,1=231,2=0.000000
L 6.4859997 5.205 6.4859997 5.23 2 P 0 ;0,1=231,2=0.000000
L 6.4859997 5.23 6.4827999 5.2250003 2 P 0 ;0,1=231,2=0.000000
L 6.4827999 5.205 6.48919951 5.205 2 P 0 ;0,1=231,2=0.000000
L 6.50493317 5.22583337 6.50653327 5.22833287 2 P 0 ;0,1=231,2=0.000000
L 6.50653327 5.22833287 6.5084 5.22958337 2 P 0 ;0,1=231,2=0.000000
L 6.5084 5.22958337 6.51053337 5.23 2 P 0 ;0,1=231,2=0.000000
L 6.51053337 5.23 6.5132 5.22916683 2 P 0 ;0,1=231,2=0.000000
L 6.5132 5.22916683 6.51506673 5.22708317 2 P 0 ;0,1=231,2=0.000000
L 6.51506673 5.22708317 6.5156 5.22458366 2 P 0 ;0,1=231,2=0.000000
L 6.5156 5.22458366 6.51533337 5.22208268 2 P 0 ;0,1=231,2=0.000000
L 6.51533337 5.22208268 6.51426644 5.2199998 2 P 0 ;0,1=231,2=0.000000
L 6.51426644 5.2199998 6.50893327 5.21583327 2 P 0 ;0,1=231,2=0.000000
L 6.50893327 5.21583327 6.50653327 5.21291644 2 P 0 ;0,1=231,2=0.000000
L 6.50653327 5.21291644 6.50493317 5.20874911 2 P 0 ;0,1=231,2=0.000000
L 6.50493317 5.20874911 6.5043999 5.205 2 P 0 ;0,1=231,2=0.000000
L 6.5043999 5.205 6.5156 5.205 2 P 0 ;0,1=231,2=0.000000
A 6.5787 4.75205 6.5787 4.75205 6.57618996 4.75205 1 P 0 N
L 6.58618996 4.44671654 6.56118996 4.44671654 2 P 0 ;0,1=232,2=270.000000
L 6.56118996 4.44671654 6.56118996 4.45311663 2 P 0 ;0,1=232,2=270.000000
L 6.56118996 4.45311663 6.56244055 4.45525 2 P 0 ;0,1=232,2=270.000000
L 6.56244055 4.45525 6.56535659 4.4568501 2 P 0 ;0,1=232,2=270.000000
L 6.56535659 4.4568501 6.56868996 4.45738337 2 P 0 ;0,1=232,2=270.000000
L 6.56868996 4.45738337 6.57202333 4.4568501 2 P 0 ;0,1=232,2=270.000000
L 6.57202333 4.4568501 6.57452352 4.45551663 2 P 0 ;0,1=232,2=270.000000
L 6.57452352 4.45551663 6.57577402 4.45311663 2 P 0 ;0,1=232,2=270.000000
L 6.57577402 4.45311663 6.57577402 4.44671654 2 P 0 ;0,1=232,2=270.000000
L 6.58285738 4.4704499 6.58494026 4.47258327 2 P 0 ;0,1=232,2=270.000000
L 6.58494026 4.47258327 6.58618996 4.47498327 2 P 0 ;0,1=232,2=270.000000
L 6.58618996 4.47498327 6.58618996 4.47711663 2 P 0 ;0,1=232,2=270.000000
L 6.58618996 4.47711663 6.58494026 4.47925 2 P 0 ;0,1=232,2=270.000000
L 6.58494026 4.47925 6.58285738 4.4808501 2 P 0 ;0,1=232,2=270.000000
L 6.58285738 4.4808501 6.57993986 4.48165 2 P 0 ;0,1=232,2=270.000000
L 6.57993986 4.48165 6.57702382 4.48111673 2 P 0 ;0,1=232,2=270.000000
L 6.57702382 4.48111673 6.57452352 4.47978327 2 P 0 ;0,1=232,2=270.000000
L 6.57452352 4.47978327 6.5728565 4.47738327 2 P 0 ;0,1=232,2=270.000000
L 6.5728565 4.47738327 6.57202333 4.47418346 2 P 0 ;0,1=232,2=270.000000
L 6.57202333 4.47418346 6.57035699 4.47231663 2 P 0 ;0,1=232,2=270.000000
L 6.57035699 4.47231663 6.56744016 4.47151634 2 P 0 ;0,1=232,2=270.000000
L 6.56744016 4.47151634 6.56452343 4.4720501 2 P 0 ;0,1=232,2=270.000000
L 6.56452343 4.4720501 6.56244055 4.47338317 2 P 0 ;0,1=232,2=270.000000
L 6.56244055 4.47338317 6.56118996 4.4752499 2 P 0 ;0,1=232,2=270.000000
L 6.56118996 4.4752499 6.56118996 4.47711663 2 P 0 ;0,1=232,2=270.000000
L 6.56118996 4.47711663 6.56202313 4.47898337 2 P 0 ;0,1=232,2=270.000000
L 6.56202313 4.47898337 6.56410679 4.48058356 2 P 0 ;0,1=232,2=270.000000
L 6.56118996 4.5000497 6.58618996 4.5000497 2 P 0 ;0,1=232,2=270.000000
L 6.56118996 4.49391673 6.56118996 4.50618317 2 P 0 ;0,1=232,2=270.000000
L 6.56327362 4.52991663 6.56202313 4.52831644 2 P 0 ;0,1=232,2=270.000000
L 6.56202313 4.52831644 6.56118996 4.5264502 2 P 0 ;0,1=232,2=270.000000
L 6.56118996 4.5264502 6.56118996 4.52431683 2 P 0 ;0,1=232,2=270.000000
L 6.56118996 4.52431683 6.56244055 4.52191634 2 P 0 ;0,1=232,2=270.000000
L 6.56244055 4.52191634 6.56452343 4.5200501 2 P 0 ;0,1=232,2=270.000000
L 6.56452343 4.5200501 6.56702362 4.51871654 2 P 0 ;0,1=232,2=270.000000
L 6.56702362 4.51871654 6.57119016 4.51764961 2 P 0 ;0,1=232,2=270.000000
L 6.57119016 4.51764961 6.57494016 4.51738297 2 P 0 ;0,1=232,2=270.000000
L 6.57494016 4.51738297 6.57869006 4.51791673 2 P 0 ;0,1=232,2=270.000000
L 6.57869006 4.51791673 6.58119035 4.51871654 2 P 0 ;0,1=232,2=270.000000
L 6.58119035 4.51871654 6.58369055 4.52031663 2 P 0 ;0,1=232,2=270.000000
L 6.58369055 4.52031663 6.58535689 4.52218346 2 P 0 ;0,1=232,2=270.000000
L 6.58535689 4.52218346 6.58618996 4.5240497 2 P 0 ;0,1=232,2=270.000000
L 6.58618996 4.5240497 6.58618996 4.52591644 2 P 0 ;0,1=232,2=270.000000
L 6.58618996 4.52591644 6.58535689 4.52778327 2 P 0 ;0,1=232,2=270.000000
L 6.58535689 4.52778327 6.58410709 4.52938337 2 P 0 ;0,1=232,2=270.000000
L 6.58410709 4.52938337 6.58244085 4.53071693 2 P 0 ;0,1=232,2=270.000000
L 6.56535659 4.54298317 6.56285709 4.54458327 2 P 0 ;0,1=232,2=270.000000
L 6.56285709 4.54458327 6.56160659 4.54645 2 P 0 ;0,1=232,2=270.000000
L 6.56160659 4.54645 6.56118996 4.54858337 2 P 0 ;0,1=232,2=270.000000
L 6.56118996 4.54858337 6.56202313 4.55125 2 P 0 ;0,1=232,2=270.000000
L 6.56202313 4.55125 6.56410679 4.55311673 2 P 0 ;0,1=232,2=270.000000
L 6.56410679 4.55311673 6.5666063 4.55365 2 P 0 ;0,1=232,2=270.000000
L 6.5666063 4.55365 6.56910728 4.55338337 2 P 0 ;0,1=232,2=270.000000
L 6.56910728 4.55338337 6.57119016 4.55231644 2 P 0 ;0,1=232,2=270.000000
L 6.57119016 4.55231644 6.57535669 4.54698327 2 P 0 ;0,1=232,2=270.000000
L 6.57535669 4.54698327 6.57827352 4.54458327 2 P 0 ;0,1=232,2=270.000000
L 6.57827352 4.54458327 6.58244085 4.54298317 2 P 0 ;0,1=232,2=270.000000
L 6.58244085 4.54298317 6.58618996 4.5424499 2 P 0 ;0,1=232,2=270.000000
L 6.58618996 4.5424499 6.58618996 4.55365 2 P 0 ;0,1=232,2=270.000000
L 6.58618996 4.5720497 6.56118996 4.5720497 2 P 0 ;0,1=232,2=270.000000
L 6.56118996 4.5720497 6.56618967 4.5688499 2 P 0 ;0,1=232,2=270.000000
L 6.58618996 4.5688499 6.58618996 4.57524951 2 P 0 ;0,1=232,2=270.000000
A 6.6987 4.77205 6.6987 4.77205 6.69618996 4.77205 1 P 0 N
L 6.64666654 4.52 6.64666654 4.545 2 P 0 ;0,1=233,2=0.000000
L 6.64666654 4.545 6.65306663 4.545 2 P 0 ;0,1=233,2=0.000000
L 6.65306663 4.545 6.6552 4.54374941 2 P 0 ;0,1=233,2=0.000000
L 6.6552 4.54374941 6.6568001 4.54083337 2 P 0 ;0,1=233,2=0.000000
L 6.6568001 4.54083337 6.65733337 4.5375 2 P 0 ;0,1=233,2=0.000000
L 6.65733337 4.5375 6.6568001 4.53416663 2 P 0 ;0,1=233,2=0.000000
L 6.6568001 4.53416663 6.65546663 4.53166644 2 P 0 ;0,1=233,2=0.000000
L 6.65546663 4.53166644 6.65306663 4.53041594 2 P 0 ;0,1=233,2=0.000000
L 6.65306663 4.53041594 6.64666654 4.53041594 2 P 0 ;0,1=233,2=0.000000
L 6.6703999 4.52333258 6.67253327 4.5212497 2 P 0 ;0,1=233,2=0.000000
L 6.67253327 4.5212497 6.67493327 4.52 2 P 0 ;0,1=233,2=0.000000
L 6.67493327 4.52 6.67706663 4.52 2 P 0 ;0,1=233,2=0.000000
L 6.67706663 4.52 6.6792 4.5212497 2 P 0 ;0,1=233,2=0.000000
L 6.6792 4.5212497 6.6808001 4.52333258 2 P 0 ;0,1=233,2=0.000000
L 6.6808001 4.52333258 6.6816 4.5262501 2 P 0 ;0,1=233,2=0.000000
L 6.6816 4.5262501 6.68106673 4.52916614 2 P 0 ;0,1=233,2=0.000000
L 6.68106673 4.52916614 6.67973327 4.53166644 2 P 0 ;0,1=233,2=0.000000
L 6.67973327 4.53166644 6.67733327 4.53333346 2 P 0 ;0,1=233,2=0.000000
L 6.67733327 4.53333346 6.67413346 4.53416663 2 P 0 ;0,1=233,2=0.000000
L 6.67413346 4.53416663 6.67226663 4.53583297 2 P 0 ;0,1=233,2=0.000000
L 6.67226663 4.53583297 6.67146634 4.5387498 2 P 0 ;0,1=233,2=0.000000
L 6.67146634 4.5387498 6.6720001 4.54166654 2 P 0 ;0,1=233,2=0.000000
L 6.6720001 4.54166654 6.67333317 4.54374941 2 P 0 ;0,1=233,2=0.000000
L 6.67333317 4.54374941 6.6751999 4.545 2 P 0 ;0,1=233,2=0.000000
L 6.6751999 4.545 6.67706663 4.545 2 P 0 ;0,1=233,2=0.000000
L 6.67706663 4.545 6.67893337 4.54416683 2 P 0 ;0,1=233,2=0.000000
L 6.67893337 4.54416683 6.68053356 4.54208317 2 P 0 ;0,1=233,2=0.000000
L 6.6999997 4.545 6.6999997 4.52 2 P 0 ;0,1=233,2=0.000000
L 6.69386673 4.545 6.70613317 4.545 2 P 0 ;0,1=233,2=0.000000
L 6.72986663 4.54291634 6.72826644 4.54416683 2 P 0 ;0,1=233,2=0.000000
L 6.72826644 4.54416683 6.7264002 4.545 2 P 0 ;0,1=233,2=0.000000
L 6.7264002 4.545 6.72426683 4.545 2 P 0 ;0,1=233,2=0.000000
L 6.72426683 4.545 6.72186634 4.54374941 2 P 0 ;0,1=233,2=0.000000
L 6.72186634 4.54374941 6.7200001 4.54166654 2 P 0 ;0,1=233,2=0.000000
L 6.7200001 4.54166654 6.71866654 4.53916634 2 P 0 ;0,1=233,2=0.000000
L 6.71866654 4.53916634 6.71759961 4.5349998 2 P 0 ;0,1=233,2=0.000000
L 6.71759961 4.5349998 6.71733297 4.5312498 2 P 0 ;0,1=233,2=0.000000
L 6.71733297 4.5312498 6.71786673 4.5274999 2 P 0 ;0,1=233,2=0.000000
L 6.71786673 4.5274999 6.71866654 4.52499961 2 P 0 ;0,1=233,2=0.000000
L 6.71866654 4.52499961 6.72026663 4.52249941 2 P 0 ;0,1=233,2=0.000000
L 6.72026663 4.52249941 6.72213346 4.52083307 2 P 0 ;0,1=233,2=0.000000
L 6.72213346 4.52083307 6.7239997 4.52 2 P 0 ;0,1=233,2=0.000000
L 6.7239997 4.52 6.72586644 4.52 2 P 0 ;0,1=233,2=0.000000
L 6.72586644 4.52 6.72773327 4.52083307 2 P 0 ;0,1=233,2=0.000000
L 6.72773327 4.52083307 6.72933337 4.52208287 2 P 0 ;0,1=233,2=0.000000
L 6.72933337 4.52208287 6.73066693 4.52374911 2 P 0 ;0,1=233,2=0.000000
L 6.7479997 4.52 6.74986644 4.52041654 2 P 0 ;0,1=233,2=0.000000
L 6.74986644 4.52041654 6.7519998 4.52166624 2 P 0 ;0,1=233,2=0.000000
L 6.7519998 4.52166624 6.75333337 4.52374911 2 P 0 ;0,1=233,2=0.000000
L 6.75333337 4.52374911 6.75386663 4.52666673 2 P 0 ;0,1=233,2=0.000000
L 6.75386663 4.52666673 6.75333337 4.52958278 2 P 0 ;0,1=233,2=0.000000
L 6.75333337 4.52958278 6.75173327 4.53208297 2 P 0 ;0,1=233,2=0.000000
L 6.75173327 4.53208297 6.74933327 4.53333346 2 P 0 ;0,1=233,2=0.000000
L 6.74933327 4.53333346 6.74666663 4.53333346 2 P 0 ;0,1=233,2=0.000000
L 6.74666663 4.53333346 6.74506654 4.53416663 2 P 0 ;0,1=233,2=0.000000
L 6.74506654 4.53416663 6.74373297 4.53624951 2 P 0 ;0,1=233,2=0.000000
L 6.74373297 4.53624951 6.7431998 4.53916634 2 P 0 ;0,1=233,2=0.000000
L 6.7431998 4.53916634 6.7440001 4.54208317 2 P 0 ;0,1=233,2=0.000000
L 6.7440001 4.54208317 6.74586634 4.54416683 2 P 0 ;0,1=233,2=0.000000
L 6.74586634 4.54416683 6.7479997 4.545 2 P 0 ;0,1=233,2=0.000000
L 6.7479997 4.545 6.75013307 4.54416683 2 P 0 ;0,1=233,2=0.000000
L 6.75013307 4.54416683 6.7519998 4.54208317 2 P 0 ;0,1=233,2=0.000000
L 6.7519998 4.54208317 6.7528001 4.53916634 2 P 0 ;0,1=233,2=0.000000
L 6.7528001 4.53916634 6.75226644 4.53624951 2 P 0 ;0,1=233,2=0.000000
L 6.75226644 4.53624951 6.75093337 4.53416663 2 P 0 ;0,1=233,2=0.000000
L 6.75093337 4.53416663 6.74933327 4.53333346 2 P 0 ;0,1=233,2=0.000000
L 6.74933327 4.53333346 6.74666663 4.53333346 2 P 0 ;0,1=233,2=0.000000
L 6.74666663 4.53333346 6.74426663 4.53208297 2 P 0 ;0,1=233,2=0.000000
L 6.74426663 4.53208297 6.74266654 4.52958278 2 P 0 ;0,1=233,2=0.000000
L 6.74266654 4.52958278 6.74213327 4.52666673 2 P 0 ;0,1=233,2=0.000000
L 6.74213327 4.52666673 6.74266654 4.52374911 2 P 0 ;0,1=233,2=0.000000
L 6.74266654 4.52374911 6.7440001 4.52166624 2 P 0 ;0,1=233,2=0.000000
L 6.7440001 4.52166624 6.74613346 4.52041654 2 P 0 ;0,1=233,2=0.000000
L 6.74613346 4.52041654 6.7479997 4.52 2 P 0 ;0,1=233,2=0.000000
A 6.71251004 5.07 6.71251004 5.07 6.71 5.07 1 P 0 N
L 6.725 5.16166654 6.7 5.16166654 2 P 0 ;0,1=234,2=270.000000
L 6.7 5.16166654 6.7 5.16806663 2 P 0 ;0,1=234,2=270.000000
L 6.7 5.16806663 6.70125059 5.1702 2 P 0 ;0,1=234,2=270.000000
L 6.70125059 5.1702 6.70416663 5.1718001 2 P 0 ;0,1=234,2=270.000000
L 6.70416663 5.1718001 6.7075 5.17233337 2 P 0 ;0,1=234,2=270.000000
L 6.7075 5.17233337 6.71083337 5.1718001 2 P 0 ;0,1=234,2=270.000000
L 6.71083337 5.1718001 6.71333356 5.17046663 2 P 0 ;0,1=234,2=270.000000
L 6.71333356 5.17046663 6.71458406 5.16806663 2 P 0 ;0,1=234,2=270.000000
L 6.71458406 5.16806663 6.71458406 5.16166654 2 P 0 ;0,1=234,2=270.000000
L 6.72166742 5.1853999 6.7237503 5.18753327 2 P 0 ;0,1=234,2=270.000000
L 6.7237503 5.18753327 6.725 5.18993327 2 P 0 ;0,1=234,2=270.000000
L 6.725 5.18993327 6.725 5.19206663 2 P 0 ;0,1=234,2=270.000000
L 6.725 5.19206663 6.7237503 5.1942 2 P 0 ;0,1=234,2=270.000000
L 6.7237503 5.1942 6.72166742 5.1958001 2 P 0 ;0,1=234,2=270.000000
L 6.72166742 5.1958001 6.7187499 5.1966 2 P 0 ;0,1=234,2=270.000000
L 6.7187499 5.1966 6.71583386 5.19606673 2 P 0 ;0,1=234,2=270.000000
L 6.71583386 5.19606673 6.71333356 5.19473327 2 P 0 ;0,1=234,2=270.000000
L 6.71333356 5.19473327 6.71166654 5.19233327 2 P 0 ;0,1=234,2=270.000000
L 6.71166654 5.19233327 6.71083337 5.18913346 2 P 0 ;0,1=234,2=270.000000
L 6.71083337 5.18913346 6.70916703 5.18726663 2 P 0 ;0,1=234,2=270.000000
L 6.70916703 5.18726663 6.7062502 5.18646634 2 P 0 ;0,1=234,2=270.000000
L 6.7062502 5.18646634 6.70333346 5.1870001 2 P 0 ;0,1=234,2=270.000000
L 6.70333346 5.1870001 6.70125059 5.18833317 2 P 0 ;0,1=234,2=270.000000
L 6.70125059 5.18833317 6.7 5.1901999 2 P 0 ;0,1=234,2=270.000000
L 6.7 5.1901999 6.7 5.19206663 2 P 0 ;0,1=234,2=270.000000
L 6.7 5.19206663 6.70083317 5.19393337 2 P 0 ;0,1=234,2=270.000000
L 6.70083317 5.19393337 6.70291683 5.19553356 2 P 0 ;0,1=234,2=270.000000
L 6.7 5.2149997 6.725 5.2149997 2 P 0 ;0,1=234,2=270.000000
L 6.7 5.20886673 6.7 5.22113317 2 P 0 ;0,1=234,2=270.000000
L 6.70208366 5.24486663 6.70083317 5.24326644 2 P 0 ;0,1=234,2=270.000000
L 6.70083317 5.24326644 6.7 5.2414002 2 P 0 ;0,1=234,2=270.000000
L 6.7 5.2414002 6.7 5.23926683 2 P 0 ;0,1=234,2=270.000000
L 6.7 5.23926683 6.70125059 5.23686634 2 P 0 ;0,1=234,2=270.000000
L 6.70125059 5.23686634 6.70333346 5.2350001 2 P 0 ;0,1=234,2=270.000000
L 6.70333346 5.2350001 6.70583366 5.23366654 2 P 0 ;0,1=234,2=270.000000
L 6.70583366 5.23366654 6.7100002 5.23259961 2 P 0 ;0,1=234,2=270.000000
L 6.7100002 5.23259961 6.7137502 5.23233297 2 P 0 ;0,1=234,2=270.000000
L 6.7137502 5.23233297 6.7175001 5.23286673 2 P 0 ;0,1=234,2=270.000000
L 6.7175001 5.23286673 6.72000039 5.23366654 2 P 0 ;0,1=234,2=270.000000
L 6.72000039 5.23366654 6.72250059 5.23526663 2 P 0 ;0,1=234,2=270.000000
L 6.72250059 5.23526663 6.72416693 5.23713346 2 P 0 ;0,1=234,2=270.000000
L 6.72416693 5.23713346 6.725 5.2389997 2 P 0 ;0,1=234,2=270.000000
L 6.725 5.2389997 6.725 5.24086644 2 P 0 ;0,1=234,2=270.000000
L 6.725 5.24086644 6.72416693 5.24273327 2 P 0 ;0,1=234,2=270.000000
L 6.72416693 5.24273327 6.72291713 5.24433337 2 P 0 ;0,1=234,2=270.000000
L 6.72291713 5.24433337 6.72125089 5.24566693 2 P 0 ;0,1=234,2=270.000000
L 6.725 5.2629997 6.7 5.2629997 2 P 0 ;0,1=234,2=270.000000
L 6.7 5.2629997 6.7049997 5.2597999 2 P 0 ;0,1=234,2=270.000000
L 6.725 5.2597999 6.725 5.26619951 2 P 0 ;0,1=234,2=270.000000
A 4.10741004 4.81198996 4.10741004 4.81198996 4.1049 4.81198996 1 P 0 N
L 4.08208366 4.39386663 4.08083317 4.39226644 2 P 0 ;0,1=235,2=270.000000
L 4.08083317 4.39226644 4.08 4.3904002 2 P 0 ;0,1=235,2=270.000000
L 4.08 4.3904002 4.08 4.38826683 2 P 0 ;0,1=235,2=270.000000
L 4.08 4.38826683 4.08125059 4.38586634 2 P 0 ;0,1=235,2=270.000000
L 4.08125059 4.38586634 4.08333346 4.3840001 2 P 0 ;0,1=235,2=270.000000
L 4.08333346 4.3840001 4.08583366 4.38266654 2 P 0 ;0,1=235,2=270.000000
L 4.08583366 4.38266654 4.0900002 4.38159961 2 P 0 ;0,1=235,2=270.000000
L 4.0900002 4.38159961 4.0937502 4.38133297 2 P 0 ;0,1=235,2=270.000000
L 4.0937502 4.38133297 4.0975001 4.38186673 2 P 0 ;0,1=235,2=270.000000
L 4.0975001 4.38186673 4.10000039 4.38266654 2 P 0 ;0,1=235,2=270.000000
L 4.10000039 4.38266654 4.10250059 4.38426663 2 P 0 ;0,1=235,2=270.000000
L 4.10250059 4.38426663 4.10416693 4.38613346 2 P 0 ;0,1=235,2=270.000000
L 4.10416693 4.38613346 4.105 4.3879997 2 P 0 ;0,1=235,2=270.000000
L 4.105 4.3879997 4.105 4.38986644 2 P 0 ;0,1=235,2=270.000000
L 4.105 4.38986644 4.10416693 4.39173327 2 P 0 ;0,1=235,2=270.000000
L 4.10416693 4.39173327 4.10291713 4.39333337 2 P 0 ;0,1=235,2=270.000000
L 4.10291713 4.39333337 4.10125089 4.39466693 2 P 0 ;0,1=235,2=270.000000
L 4.08416663 4.40693317 4.08166713 4.40853327 2 P 0 ;0,1=235,2=270.000000
L 4.08166713 4.40853327 4.08041663 4.4104 2 P 0 ;0,1=235,2=270.000000
L 4.08041663 4.4104 4.08 4.41253337 2 P 0 ;0,1=235,2=270.000000
L 4.08 4.41253337 4.08083317 4.4152 2 P 0 ;0,1=235,2=270.000000
L 4.08083317 4.4152 4.08291683 4.41706673 2 P 0 ;0,1=235,2=270.000000
L 4.08291683 4.41706673 4.08541634 4.4176 2 P 0 ;0,1=235,2=270.000000
L 4.08541634 4.4176 4.08791732 4.41733337 2 P 0 ;0,1=235,2=270.000000
L 4.08791732 4.41733337 4.0900002 4.41626644 2 P 0 ;0,1=235,2=270.000000
L 4.0900002 4.41626644 4.09416673 4.41093327 2 P 0 ;0,1=235,2=270.000000
L 4.09416673 4.41093327 4.09708356 4.40853327 2 P 0 ;0,1=235,2=270.000000
L 4.09708356 4.40853327 4.10125089 4.40693317 2 P 0 ;0,1=235,2=270.000000
L 4.10125089 4.40693317 4.105 4.4063999 2 P 0 ;0,1=235,2=270.000000
L 4.105 4.4063999 4.105 4.4176 2 P 0 ;0,1=235,2=270.000000
L 4.08416663 4.43093317 4.08166713 4.43253327 2 P 0 ;0,1=235,2=270.000000
L 4.08166713 4.43253327 4.08041663 4.4344 2 P 0 ;0,1=235,2=270.000000
L 4.08041663 4.4344 4.08 4.43653337 2 P 0 ;0,1=235,2=270.000000
L 4.08 4.43653337 4.08083317 4.4392 2 P 0 ;0,1=235,2=270.000000
L 4.08083317 4.4392 4.08291683 4.44106673 2 P 0 ;0,1=235,2=270.000000
L 4.08291683 4.44106673 4.08541634 4.4416 2 P 0 ;0,1=235,2=270.000000
L 4.08541634 4.4416 4.08791732 4.44133337 2 P 0 ;0,1=235,2=270.000000
L 4.08791732 4.44133337 4.0900002 4.44026644 2 P 0 ;0,1=235,2=270.000000
L 4.0900002 4.44026644 4.09416673 4.43493327 2 P 0 ;0,1=235,2=270.000000
L 4.09416673 4.43493327 4.09708356 4.43253327 2 P 0 ;0,1=235,2=270.000000
L 4.09708356 4.43253327 4.10125089 4.43093317 2 P 0 ;0,1=235,2=270.000000
L 4.10125089 4.43093317 4.105 4.4303999 2 P 0 ;0,1=235,2=270.000000
L 4.105 4.4303999 4.105 4.4416 2 P 0 ;0,1=235,2=270.000000
L 4.10000039 4.45413327 4.10291713 4.45573297 2 P 0 ;0,1=235,2=270.000000
L 4.10291713 4.45573297 4.10458346 4.45786634 2 P 0 ;0,1=235,2=270.000000
L 4.10458346 4.45786634 4.105 4.46026683 2 P 0 ;0,1=235,2=270.000000
L 4.105 4.46026683 4.10458346 4.4624002 2 P 0 ;0,1=235,2=270.000000
L 4.10458346 4.4624002 4.10250059 4.46453356 2 P 0 ;0,1=235,2=270.000000
L 4.10250059 4.46453356 4.10000039 4.46586663 2 P 0 ;0,1=235,2=270.000000
L 4.10000039 4.46586663 4.0975001 4.46613317 2 P 0 ;0,1=235,2=270.000000
L 4.0975001 4.46613317 4.09458406 4.4656 2 P 0 ;0,1=235,2=270.000000
L 4.09458406 4.4656 4.09250039 4.46373327 2 P 0 ;0,1=235,2=270.000000
L 4.09250039 4.46373327 4.09166654 4.46186644 2 P 0 ;0,1=235,2=270.000000
L 4.09166654 4.46186644 4.09166654 4.45946654 2 P 0 ;0,1=235,2=270.000000
L 4.09166654 4.46186644 4.09041673 4.46346663 2 P 0 ;0,1=235,2=270.000000
L 4.09041673 4.46346663 4.08833386 4.4648001 2 P 0 ;0,1=235,2=270.000000
L 4.08833386 4.4648001 4.08583366 4.46533337 2 P 0 ;0,1=235,2=270.000000
L 4.08583366 4.46533337 4.08333346 4.4648001 2 P 0 ;0,1=235,2=270.000000
L 4.08333346 4.4648001 4.08125059 4.46346663 2 P 0 ;0,1=235,2=270.000000
L 4.08125059 4.46346663 4.08 4.46106663 2 P 0 ;0,1=235,2=270.000000
L 4.08 4.46106663 4.08041663 4.45866663 2 P 0 ;0,1=235,2=270.000000
L 4.08041663 4.45866663 4.08208366 4.45626663 2 P 0 ;0,1=235,2=270.000000
L 4.105 4.4839997 4.10458346 4.48586644 2 P 0 ;0,1=235,2=270.000000
L 4.10458346 4.48586644 4.10333376 4.4879998 2 P 0 ;0,1=235,2=270.000000
L 4.10333376 4.4879998 4.10125089 4.48933337 2 P 0 ;0,1=235,2=270.000000
L 4.10125089 4.48933337 4.09833327 4.48986663 2 P 0 ;0,1=235,2=270.000000
L 4.09833327 4.48986663 4.09541722 4.48933337 2 P 0 ;0,1=235,2=270.000000
L 4.09541722 4.48933337 4.09291703 4.48773327 2 P 0 ;0,1=235,2=270.000000
L 4.09291703 4.48773327 4.09166654 4.48533327 2 P 0 ;0,1=235,2=270.000000
L 4.09166654 4.48533327 4.09166654 4.48266663 2 P 0 ;0,1=235,2=270.000000
L 4.09166654 4.48266663 4.09083337 4.48106654 2 P 0 ;0,1=235,2=270.000000
L 4.09083337 4.48106654 4.08875049 4.47973297 2 P 0 ;0,1=235,2=270.000000
L 4.08875049 4.47973297 4.08583366 4.4791998 2 P 0 ;0,1=235,2=270.000000
L 4.08583366 4.4791998 4.08291683 4.4800001 2 P 0 ;0,1=235,2=270.000000
L 4.08291683 4.4800001 4.08083317 4.48186634 2 P 0 ;0,1=235,2=270.000000
L 4.08083317 4.48186634 4.08 4.4839997 2 P 0 ;0,1=235,2=270.000000
L 4.08 4.4839997 4.08083317 4.48613307 2 P 0 ;0,1=235,2=270.000000
L 4.08083317 4.48613307 4.08291683 4.4879998 2 P 0 ;0,1=235,2=270.000000
L 4.08291683 4.4879998 4.08583366 4.4888001 2 P 0 ;0,1=235,2=270.000000
L 4.08583366 4.4888001 4.08875049 4.48826644 2 P 0 ;0,1=235,2=270.000000
L 4.08875049 4.48826644 4.09083337 4.48693337 2 P 0 ;0,1=235,2=270.000000
L 4.09083337 4.48693337 4.09166654 4.48533327 2 P 0 ;0,1=235,2=270.000000
L 4.09166654 4.48533327 4.09166654 4.48266663 2 P 0 ;0,1=235,2=270.000000
L 4.09166654 4.48266663 4.09291703 4.48026663 2 P 0 ;0,1=235,2=270.000000
L 4.09291703 4.48026663 4.09541722 4.47866654 2 P 0 ;0,1=235,2=270.000000
L 4.09541722 4.47866654 4.09833327 4.47813327 2 P 0 ;0,1=235,2=270.000000
L 4.09833327 4.47813327 4.10125089 4.47866654 2 P 0 ;0,1=235,2=270.000000
L 4.10125089 4.47866654 4.10333376 4.4800001 2 P 0 ;0,1=235,2=270.000000
L 4.10333376 4.4800001 4.10458346 4.48213346 2 P 0 ;0,1=235,2=270.000000
L 4.10458346 4.48213346 4.105 4.4839997 2 P 0 ;0,1=235,2=270.000000
A 1.31251004 5.4 1.31251004 5.4 1.31 5.4 1 P 0 N
L 1.26708366 5.34886663 1.26583317 5.34726644 2 P 0 ;0,1=236,2=270.000000
L 1.26583317 5.34726644 1.265 5.3454002 2 P 0 ;0,1=236,2=270.000000
L 1.265 5.3454002 1.265 5.34326683 2 P 0 ;0,1=236,2=270.000000
L 1.265 5.34326683 1.26625059 5.34086634 2 P 0 ;0,1=236,2=270.000000
L 1.26625059 5.34086634 1.26833346 5.3390001 2 P 0 ;0,1=236,2=270.000000
L 1.26833346 5.3390001 1.27083366 5.33766654 2 P 0 ;0,1=236,2=270.000000
L 1.27083366 5.33766654 1.2750002 5.33659961 2 P 0 ;0,1=236,2=270.000000
L 1.2750002 5.33659961 1.2787502 5.33633297 2 P 0 ;0,1=236,2=270.000000
L 1.2787502 5.33633297 1.2825001 5.33686673 2 P 0 ;0,1=236,2=270.000000
L 1.2825001 5.33686673 1.28500039 5.33766654 2 P 0 ;0,1=236,2=270.000000
L 1.28500039 5.33766654 1.28750059 5.33926663 2 P 0 ;0,1=236,2=270.000000
L 1.28750059 5.33926663 1.28916693 5.34113346 2 P 0 ;0,1=236,2=270.000000
L 1.28916693 5.34113346 1.29 5.3429997 2 P 0 ;0,1=236,2=270.000000
L 1.29 5.3429997 1.29 5.34486644 2 P 0 ;0,1=236,2=270.000000
L 1.29 5.34486644 1.28916693 5.34673327 2 P 0 ;0,1=236,2=270.000000
L 1.28916693 5.34673327 1.28791713 5.34833337 2 P 0 ;0,1=236,2=270.000000
L 1.28791713 5.34833337 1.28625089 5.34966693 2 P 0 ;0,1=236,2=270.000000
L 1.26916663 5.36193317 1.26666713 5.36353327 2 P 0 ;0,1=236,2=270.000000
L 1.26666713 5.36353327 1.26541663 5.3654 2 P 0 ;0,1=236,2=270.000000
L 1.26541663 5.3654 1.265 5.36753337 2 P 0 ;0,1=236,2=270.000000
L 1.265 5.36753337 1.26583317 5.3702 2 P 0 ;0,1=236,2=270.000000
L 1.26583317 5.3702 1.26791683 5.37206673 2 P 0 ;0,1=236,2=270.000000
L 1.26791683 5.37206673 1.27041634 5.3726 2 P 0 ;0,1=236,2=270.000000
L 1.27041634 5.3726 1.27291732 5.37233337 2 P 0 ;0,1=236,2=270.000000
L 1.27291732 5.37233337 1.2750002 5.37126644 2 P 0 ;0,1=236,2=270.000000
L 1.2750002 5.37126644 1.27916673 5.36593327 2 P 0 ;0,1=236,2=270.000000
L 1.27916673 5.36593327 1.28208356 5.36353327 2 P 0 ;0,1=236,2=270.000000
L 1.28208356 5.36353327 1.28625089 5.36193317 2 P 0 ;0,1=236,2=270.000000
L 1.28625089 5.36193317 1.29 5.3613999 2 P 0 ;0,1=236,2=270.000000
L 1.29 5.3613999 1.29 5.3726 2 P 0 ;0,1=236,2=270.000000
L 1.29 5.3909997 1.265 5.3909997 2 P 0 ;0,1=236,2=270.000000
L 1.265 5.3909997 1.2699997 5.3877999 2 P 0 ;0,1=236,2=270.000000
L 1.29 5.3877999 1.29 5.39419951 2 P 0 ;0,1=236,2=270.000000
L 1.29 5.4149997 1.28958346 5.41686644 2 P 0 ;0,1=236,2=270.000000
L 1.28958346 5.41686644 1.28833376 5.4189998 2 P 0 ;0,1=236,2=270.000000
L 1.28833376 5.4189998 1.28625089 5.42033337 2 P 0 ;0,1=236,2=270.000000
L 1.28625089 5.42033337 1.28333327 5.42086663 2 P 0 ;0,1=236,2=270.000000
L 1.28333327 5.42086663 1.28041722 5.42033337 2 P 0 ;0,1=236,2=270.000000
L 1.28041722 5.42033337 1.27791703 5.41873327 2 P 0 ;0,1=236,2=270.000000
L 1.27791703 5.41873327 1.27666654 5.41633327 2 P 0 ;0,1=236,2=270.000000
L 1.27666654 5.41633327 1.27666654 5.41366663 2 P 0 ;0,1=236,2=270.000000
L 1.27666654 5.41366663 1.27583337 5.41206654 2 P 0 ;0,1=236,2=270.000000
L 1.27583337 5.41206654 1.27375049 5.41073297 2 P 0 ;0,1=236,2=270.000000
L 1.27375049 5.41073297 1.27083366 5.4101998 2 P 0 ;0,1=236,2=270.000000
L 1.27083366 5.4101998 1.26791683 5.4110001 2 P 0 ;0,1=236,2=270.000000
L 1.26791683 5.4110001 1.26583317 5.41286634 2 P 0 ;0,1=236,2=270.000000
L 1.26583317 5.41286634 1.265 5.4149997 2 P 0 ;0,1=236,2=270.000000
L 1.265 5.4149997 1.26583317 5.41713307 2 P 0 ;0,1=236,2=270.000000
L 1.26583317 5.41713307 1.26791683 5.4189998 2 P 0 ;0,1=236,2=270.000000
L 1.26791683 5.4189998 1.27083366 5.4198001 2 P 0 ;0,1=236,2=270.000000
L 1.27083366 5.4198001 1.27375049 5.41926644 2 P 0 ;0,1=236,2=270.000000
L 1.27375049 5.41926644 1.27583337 5.41793337 2 P 0 ;0,1=236,2=270.000000
L 1.27583337 5.41793337 1.27666654 5.41633327 2 P 0 ;0,1=236,2=270.000000
L 1.27666654 5.41633327 1.27666654 5.41366663 2 P 0 ;0,1=236,2=270.000000
L 1.27666654 5.41366663 1.27791703 5.41126663 2 P 0 ;0,1=236,2=270.000000
L 1.27791703 5.41126663 1.28041722 5.40966654 2 P 0 ;0,1=236,2=270.000000
L 1.28041722 5.40966654 1.28333327 5.40913327 2 P 0 ;0,1=236,2=270.000000
L 1.28333327 5.40913327 1.28625089 5.40966654 2 P 0 ;0,1=236,2=270.000000
L 1.28625089 5.40966654 1.28833376 5.4110001 2 P 0 ;0,1=236,2=270.000000
L 1.28833376 5.4110001 1.28958346 5.41313346 2 P 0 ;0,1=236,2=270.000000
L 1.28958346 5.41313346 1.29 5.4149997 2 P 0 ;0,1=236,2=270.000000
L 1.29 5.4389997 1.28958346 5.44086644 2 P 0 ;0,1=236,2=270.000000
L 1.28958346 5.44086644 1.28833376 5.4429998 2 P 0 ;0,1=236,2=270.000000
L 1.28833376 5.4429998 1.28625089 5.44433337 2 P 0 ;0,1=236,2=270.000000
L 1.28625089 5.44433337 1.28333327 5.44486663 2 P 0 ;0,1=236,2=270.000000
L 1.28333327 5.44486663 1.28041722 5.44433337 2 P 0 ;0,1=236,2=270.000000
L 1.28041722 5.44433337 1.27791703 5.44273327 2 P 0 ;0,1=236,2=270.000000
L 1.27791703 5.44273327 1.27666654 5.44033327 2 P 0 ;0,1=236,2=270.000000
L 1.27666654 5.44033327 1.27666654 5.43766663 2 P 0 ;0,1=236,2=270.000000
L 1.27666654 5.43766663 1.27583337 5.43606654 2 P 0 ;0,1=236,2=270.000000
L 1.27583337 5.43606654 1.27375049 5.43473297 2 P 0 ;0,1=236,2=270.000000
L 1.27375049 5.43473297 1.27083366 5.4341998 2 P 0 ;0,1=236,2=270.000000
L 1.27083366 5.4341998 1.26791683 5.4350001 2 P 0 ;0,1=236,2=270.000000
L 1.26791683 5.4350001 1.26583317 5.43686634 2 P 0 ;0,1=236,2=270.000000
L 1.26583317 5.43686634 1.265 5.4389997 2 P 0 ;0,1=236,2=270.000000
L 1.265 5.4389997 1.26583317 5.44113307 2 P 0 ;0,1=236,2=270.000000
L 1.26583317 5.44113307 1.26791683 5.4429998 2 P 0 ;0,1=236,2=270.000000
L 1.26791683 5.4429998 1.27083366 5.4438001 2 P 0 ;0,1=236,2=270.000000
L 1.27083366 5.4438001 1.27375049 5.44326644 2 P 0 ;0,1=236,2=270.000000
L 1.27375049 5.44326644 1.27583337 5.44193337 2 P 0 ;0,1=236,2=270.000000
L 1.27583337 5.44193337 1.27666654 5.44033327 2 P 0 ;0,1=236,2=270.000000
L 1.27666654 5.44033327 1.27666654 5.43766663 2 P 0 ;0,1=236,2=270.000000
L 1.27666654 5.43766663 1.27791703 5.43526663 2 P 0 ;0,1=236,2=270.000000
L 1.27791703 5.43526663 1.28041722 5.43366654 2 P 0 ;0,1=236,2=270.000000
L 1.28041722 5.43366654 1.28333327 5.43313327 2 P 0 ;0,1=236,2=270.000000
L 1.28333327 5.43313327 1.28625089 5.43366654 2 P 0 ;0,1=236,2=270.000000
L 1.28625089 5.43366654 1.28833376 5.4350001 2 P 0 ;0,1=236,2=270.000000
L 1.28833376 5.4350001 1.28958346 5.43713346 2 P 0 ;0,1=236,2=270.000000
L 1.28958346 5.43713346 1.29 5.4389997 2 P 0 ;0,1=236,2=270.000000
A 12.12251004 5.01 12.12251004 5.01 12.12 5.01 1 P 0 N
L 12.11208366 5.07386663 12.11083317 5.07226644 2 P 0 ;0,1=237,2=270.000000
L 12.11083317 5.07226644 12.11 5.0704002 2 P 0 ;0,1=237,2=270.000000
L 12.11 5.0704002 12.11 5.06826683 2 P 0 ;0,1=237,2=270.000000
L 12.11 5.06826683 12.11125059 5.06586634 2 P 0 ;0,1=237,2=270.000000
L 12.11125059 5.06586634 12.11333346 5.0640001 2 P 0 ;0,1=237,2=270.000000
L 12.11333346 5.0640001 12.11583366 5.06266654 2 P 0 ;0,1=237,2=270.000000
L 12.11583366 5.06266654 12.1200002 5.06159961 2 P 0 ;0,1=237,2=270.000000
L 12.1200002 5.06159961 12.1237502 5.06133297 2 P 0 ;0,1=237,2=270.000000
L 12.1237502 5.06133297 12.1275001 5.06186673 2 P 0 ;0,1=237,2=270.000000
L 12.1275001 5.06186673 12.13000039 5.06266654 2 P 0 ;0,1=237,2=270.000000
L 12.13000039 5.06266654 12.13250059 5.06426663 2 P 0 ;0,1=237,2=270.000000
L 12.13250059 5.06426663 12.13416693 5.06613346 2 P 0 ;0,1=237,2=270.000000
L 12.13416693 5.06613346 12.135 5.0679997 2 P 0 ;0,1=237,2=270.000000
L 12.135 5.0679997 12.135 5.06986644 2 P 0 ;0,1=237,2=270.000000
L 12.135 5.06986644 12.13416693 5.07173327 2 P 0 ;0,1=237,2=270.000000
L 12.13416693 5.07173327 12.13291713 5.07333337 2 P 0 ;0,1=237,2=270.000000
L 12.13291713 5.07333337 12.13125089 5.07466693 2 P 0 ;0,1=237,2=270.000000
L 12.135 5.0952 12.11 5.0952 2 P 0 ;0,1=237,2=270.000000
L 12.11 5.0952 12.12791673 5.08533297 2 P 0 ;0,1=237,2=270.000000
L 12.12791673 5.08533297 12.12791673 5.09866693 2 P 0 ;0,1=237,2=270.000000
L 12.135 5.1159997 12.11 5.1159997 2 P 0 ;0,1=237,2=270.000000
L 12.11 5.1159997 12.1149997 5.1127999 2 P 0 ;0,1=237,2=270.000000
L 12.135 5.1127999 12.135 5.11919951 2 P 0 ;0,1=237,2=270.000000
L 12.13000039 5.13413327 12.13291713 5.13573297 2 P 0 ;0,1=237,2=270.000000
L 12.13291713 5.13573297 12.13458346 5.13786634 2 P 0 ;0,1=237,2=270.000000
L 12.13458346 5.13786634 12.135 5.14026683 2 P 0 ;0,1=237,2=270.000000
L 12.135 5.14026683 12.13458346 5.1424002 2 P 0 ;0,1=237,2=270.000000
L 12.13458346 5.1424002 12.13250059 5.14453356 2 P 0 ;0,1=237,2=270.000000
L 12.13250059 5.14453356 12.13000039 5.14586663 2 P 0 ;0,1=237,2=270.000000
L 12.13000039 5.14586663 12.1275001 5.14613317 2 P 0 ;0,1=237,2=270.000000
L 12.1275001 5.14613317 12.12458406 5.1456 2 P 0 ;0,1=237,2=270.000000
L 12.12458406 5.1456 12.12250039 5.14373327 2 P 0 ;0,1=237,2=270.000000
L 12.12250039 5.14373327 12.12166654 5.14186644 2 P 0 ;0,1=237,2=270.000000
L 12.12166654 5.14186644 12.12166654 5.13946654 2 P 0 ;0,1=237,2=270.000000
L 12.12166654 5.14186644 12.12041673 5.14346663 2 P 0 ;0,1=237,2=270.000000
L 12.12041673 5.14346663 12.11833386 5.1448001 2 P 0 ;0,1=237,2=270.000000
L 12.11833386 5.1448001 12.11583366 5.14533337 2 P 0 ;0,1=237,2=270.000000
L 12.11583366 5.14533337 12.11333346 5.1448001 2 P 0 ;0,1=237,2=270.000000
L 12.11333346 5.1448001 12.11125059 5.14346663 2 P 0 ;0,1=237,2=270.000000
L 12.11125059 5.14346663 12.11 5.14106663 2 P 0 ;0,1=237,2=270.000000
L 12.11 5.14106663 12.11041663 5.13866663 2 P 0 ;0,1=237,2=270.000000
L 12.11041663 5.13866663 12.11208366 5.13626663 2 P 0 ;0,1=237,2=270.000000
A 10.56251004 5.32 10.56251004 5.32 10.56 5.32 1 P 0 N
L 10.65386663 5.33291634 10.65226644 5.33416683 2 P 0 ;0,1=238,2=0.000000
L 10.65226644 5.33416683 10.6504002 5.335 2 P 0 ;0,1=238,2=0.000000
L 10.6504002 5.335 10.64826683 5.335 2 P 0 ;0,1=238,2=0.000000
L 10.64826683 5.335 10.64586634 5.33374941 2 P 0 ;0,1=238,2=0.000000
L 10.64586634 5.33374941 10.6440001 5.33166654 2 P 0 ;0,1=238,2=0.000000
L 10.6440001 5.33166654 10.64266654 5.32916634 2 P 0 ;0,1=238,2=0.000000
L 10.64266654 5.32916634 10.64159961 5.3249998 2 P 0 ;0,1=238,2=0.000000
L 10.64159961 5.3249998 10.64133297 5.3212498 2 P 0 ;0,1=238,2=0.000000
L 10.64133297 5.3212498 10.64186673 5.3174999 2 P 0 ;0,1=238,2=0.000000
L 10.64186673 5.3174999 10.64266654 5.31499961 2 P 0 ;0,1=238,2=0.000000
L 10.64266654 5.31499961 10.64426663 5.31249941 2 P 0 ;0,1=238,2=0.000000
L 10.64426663 5.31249941 10.64613346 5.31083307 2 P 0 ;0,1=238,2=0.000000
L 10.64613346 5.31083307 10.6479997 5.31 2 P 0 ;0,1=238,2=0.000000
L 10.6479997 5.31 10.64986644 5.31 2 P 0 ;0,1=238,2=0.000000
L 10.64986644 5.31 10.65173327 5.31083307 2 P 0 ;0,1=238,2=0.000000
L 10.65173327 5.31083307 10.65333337 5.31208287 2 P 0 ;0,1=238,2=0.000000
L 10.65333337 5.31208287 10.65466693 5.31374911 2 P 0 ;0,1=238,2=0.000000
L 10.6752 5.31 10.6752 5.335 2 P 0 ;0,1=238,2=0.000000
L 10.6752 5.335 10.66533297 5.31708327 2 P 0 ;0,1=238,2=0.000000
L 10.66533297 5.31708327 10.67866693 5.31708327 2 P 0 ;0,1=238,2=0.000000
L 10.6959997 5.31 10.6959997 5.335 2 P 0 ;0,1=238,2=0.000000
L 10.6959997 5.335 10.6927999 5.3300003 2 P 0 ;0,1=238,2=0.000000
L 10.6927999 5.31 10.69919951 5.31 2 P 0 ;0,1=238,2=0.000000
L 10.7199997 5.31 10.7199997 5.335 2 P 0 ;0,1=238,2=0.000000
L 10.7199997 5.335 10.7167999 5.3300003 2 P 0 ;0,1=238,2=0.000000
L 10.7167999 5.31 10.72319951 5.31 2 P 0 ;0,1=238,2=0.000000
A 1.40751004 5.84 1.40751004 5.84 1.405 5.84 1 P 0 N
L 1.48208366 5.85886663 1.48083317 5.85726644 2 P 0 ;0,1=239,2=270.000000
L 1.48083317 5.85726644 1.48 5.8554002 2 P 0 ;0,1=239,2=270.000000
L 1.48 5.8554002 1.48 5.85326683 2 P 0 ;0,1=239,2=270.000000
L 1.48 5.85326683 1.48125059 5.85086634 2 P 0 ;0,1=239,2=270.000000
L 1.48125059 5.85086634 1.48333346 5.8490001 2 P 0 ;0,1=239,2=270.000000
L 1.48333346 5.8490001 1.48583366 5.84766654 2 P 0 ;0,1=239,2=270.000000
L 1.48583366 5.84766654 1.4900002 5.84659961 2 P 0 ;0,1=239,2=270.000000
L 1.4900002 5.84659961 1.4937502 5.84633297 2 P 0 ;0,1=239,2=270.000000
L 1.4937502 5.84633297 1.4975001 5.84686673 2 P 0 ;0,1=239,2=270.000000
L 1.4975001 5.84686673 1.50000039 5.84766654 2 P 0 ;0,1=239,2=270.000000
L 1.50000039 5.84766654 1.50250059 5.84926663 2 P 0 ;0,1=239,2=270.000000
L 1.50250059 5.84926663 1.50416693 5.85113346 2 P 0 ;0,1=239,2=270.000000
L 1.50416693 5.85113346 1.505 5.8529997 2 P 0 ;0,1=239,2=270.000000
L 1.505 5.8529997 1.505 5.85486644 2 P 0 ;0,1=239,2=270.000000
L 1.505 5.85486644 1.50416693 5.85673327 2 P 0 ;0,1=239,2=270.000000
L 1.50416693 5.85673327 1.50291713 5.85833337 2 P 0 ;0,1=239,2=270.000000
L 1.50291713 5.85833337 1.50125089 5.85966693 2 P 0 ;0,1=239,2=270.000000
L 1.48416663 5.87193317 1.48166713 5.87353327 2 P 0 ;0,1=239,2=270.000000
L 1.48166713 5.87353327 1.48041663 5.8754 2 P 0 ;0,1=239,2=270.000000
L 1.48041663 5.8754 1.48 5.87753337 2 P 0 ;0,1=239,2=270.000000
L 1.48 5.87753337 1.48083317 5.8802 2 P 0 ;0,1=239,2=270.000000
L 1.48083317 5.8802 1.48291683 5.88206673 2 P 0 ;0,1=239,2=270.000000
L 1.48291683 5.88206673 1.48541634 5.8826 2 P 0 ;0,1=239,2=270.000000
L 1.48541634 5.8826 1.48791732 5.88233337 2 P 0 ;0,1=239,2=270.000000
L 1.48791732 5.88233337 1.4900002 5.88126644 2 P 0 ;0,1=239,2=270.000000
L 1.4900002 5.88126644 1.49416673 5.87593327 2 P 0 ;0,1=239,2=270.000000
L 1.49416673 5.87593327 1.49708356 5.87353327 2 P 0 ;0,1=239,2=270.000000
L 1.49708356 5.87353327 1.50125089 5.87193317 2 P 0 ;0,1=239,2=270.000000
L 1.50125089 5.87193317 1.505 5.8713999 2 P 0 ;0,1=239,2=270.000000
L 1.505 5.8713999 1.505 5.8826 2 P 0 ;0,1=239,2=270.000000
L 1.505 5.9009997 1.48 5.9009997 2 P 0 ;0,1=239,2=270.000000
L 1.48 5.9009997 1.4849997 5.8977999 2 P 0 ;0,1=239,2=270.000000
L 1.505 5.8977999 1.505 5.90419951 2 P 0 ;0,1=239,2=270.000000
L 1.50208396 5.92046634 1.50416693 5.92233317 2 P 0 ;0,1=239,2=270.000000
L 1.50416693 5.92233317 1.505 5.92446654 2 P 0 ;0,1=239,2=270.000000
L 1.505 5.92446654 1.50416693 5.9265999 2 P 0 ;0,1=239,2=270.000000
L 1.50416693 5.9265999 1.50166742 5.92846663 2 P 0 ;0,1=239,2=270.000000
L 1.50166742 5.92846663 1.49791673 5.9298001 2 P 0 ;0,1=239,2=270.000000
L 1.49791673 5.9298001 1.49416673 5.93033337 2 P 0 ;0,1=239,2=270.000000
L 1.49416673 5.93033337 1.48958366 5.93033337 2 P 0 ;0,1=239,2=270.000000
L 1.48958366 5.93033337 1.48583366 5.9298001 2 P 0 ;0,1=239,2=270.000000
L 1.48583366 5.9298001 1.4825003 5.92846663 2 P 0 ;0,1=239,2=270.000000
L 1.4825003 5.92846663 1.48083317 5.92686644 2 P 0 ;0,1=239,2=270.000000
L 1.48083317 5.92686644 1.48 5.9249997 2 P 0 ;0,1=239,2=270.000000
L 1.48 5.9249997 1.48083317 5.92286634 2 P 0 ;0,1=239,2=270.000000
L 1.48083317 5.92286634 1.4825003 5.92126663 2 P 0 ;0,1=239,2=270.000000
L 1.4825003 5.92126663 1.4849997 5.9201998 2 P 0 ;0,1=239,2=270.000000
L 1.4849997 5.9201998 1.48833386 5.91966654 2 P 0 ;0,1=239,2=270.000000
L 1.48833386 5.91966654 1.4912499 5.9201998 2 P 0 ;0,1=239,2=270.000000
L 1.4912499 5.9201998 1.49416673 5.92153327 2 P 0 ;0,1=239,2=270.000000
L 1.49416673 5.92153327 1.49583386 5.92313346 2 P 0 ;0,1=239,2=270.000000
L 1.49583386 5.92313346 1.49625039 5.9249997 2 P 0 ;0,1=239,2=270.000000
L 1.49625039 5.9249997 1.49541722 5.92713307 2 P 0 ;0,1=239,2=270.000000
L 1.49541722 5.92713307 1.49333356 5.92873327 2 P 0 ;0,1=239,2=270.000000
L 1.49333356 5.92873327 1.48958366 5.93033337 2 P 0 ;0,1=239,2=270.000000
L 1.48416663 5.94393317 1.48166713 5.94553327 2 P 0 ;0,1=239,2=270.000000
L 1.48166713 5.94553327 1.48041663 5.9474 2 P 0 ;0,1=239,2=270.000000
L 1.48041663 5.9474 1.48 5.94953337 2 P 0 ;0,1=239,2=270.000000
L 1.48 5.94953337 1.48083317 5.9522 2 P 0 ;0,1=239,2=270.000000
L 1.48083317 5.9522 1.48291683 5.95406673 2 P 0 ;0,1=239,2=270.000000
L 1.48291683 5.95406673 1.48541634 5.9546 2 P 0 ;0,1=239,2=270.000000
L 1.48541634 5.9546 1.48791732 5.95433337 2 P 0 ;0,1=239,2=270.000000
L 1.48791732 5.95433337 1.4900002 5.95326644 2 P 0 ;0,1=239,2=270.000000
L 1.4900002 5.95326644 1.49416673 5.94793327 2 P 0 ;0,1=239,2=270.000000
L 1.49416673 5.94793327 1.49708356 5.94553327 2 P 0 ;0,1=239,2=270.000000
L 1.49708356 5.94553327 1.50125089 5.94393317 2 P 0 ;0,1=239,2=270.000000
L 1.50125089 5.94393317 1.505 5.9433999 2 P 0 ;0,1=239,2=270.000000
L 1.505 5.9433999 1.505 5.9546 2 P 0 ;0,1=239,2=270.000000
A 1.30751004 5.84 1.30751004 5.84 1.305 5.84 1 P 0 N
L 1.21708366 5.85386663 1.21583317 5.85226644 2 P 0 ;0,1=240,2=270.000000
L 1.21583317 5.85226644 1.215 5.8504002 2 P 0 ;0,1=240,2=270.000000
L 1.215 5.8504002 1.215 5.84826683 2 P 0 ;0,1=240,2=270.000000
L 1.215 5.84826683 1.21625059 5.84586634 2 P 0 ;0,1=240,2=270.000000
L 1.21625059 5.84586634 1.21833346 5.8440001 2 P 0 ;0,1=240,2=270.000000
L 1.21833346 5.8440001 1.22083366 5.84266654 2 P 0 ;0,1=240,2=270.000000
L 1.22083366 5.84266654 1.2250002 5.84159961 2 P 0 ;0,1=240,2=270.000000
L 1.2250002 5.84159961 1.2287502 5.84133297 2 P 0 ;0,1=240,2=270.000000
L 1.2287502 5.84133297 1.2325001 5.84186673 2 P 0 ;0,1=240,2=270.000000
L 1.2325001 5.84186673 1.23500039 5.84266654 2 P 0 ;0,1=240,2=270.000000
L 1.23500039 5.84266654 1.23750059 5.84426663 2 P 0 ;0,1=240,2=270.000000
L 1.23750059 5.84426663 1.23916693 5.84613346 2 P 0 ;0,1=240,2=270.000000
L 1.23916693 5.84613346 1.24 5.8479997 2 P 0 ;0,1=240,2=270.000000
L 1.24 5.8479997 1.24 5.84986644 2 P 0 ;0,1=240,2=270.000000
L 1.24 5.84986644 1.23916693 5.85173327 2 P 0 ;0,1=240,2=270.000000
L 1.23916693 5.85173327 1.23791713 5.85333337 2 P 0 ;0,1=240,2=270.000000
L 1.23791713 5.85333337 1.23625089 5.85466693 2 P 0 ;0,1=240,2=270.000000
L 1.21916663 5.86693317 1.21666713 5.86853327 2 P 0 ;0,1=240,2=270.000000
L 1.21666713 5.86853327 1.21541663 5.8704 2 P 0 ;0,1=240,2=270.000000
L 1.21541663 5.8704 1.215 5.87253337 2 P 0 ;0,1=240,2=270.000000
L 1.215 5.87253337 1.21583317 5.8752 2 P 0 ;0,1=240,2=270.000000
L 1.21583317 5.8752 1.21791683 5.87706673 2 P 0 ;0,1=240,2=270.000000
L 1.21791683 5.87706673 1.22041634 5.8776 2 P 0 ;0,1=240,2=270.000000
L 1.22041634 5.8776 1.22291732 5.87733337 2 P 0 ;0,1=240,2=270.000000
L 1.22291732 5.87733337 1.2250002 5.87626644 2 P 0 ;0,1=240,2=270.000000
L 1.2250002 5.87626644 1.22916673 5.87093327 2 P 0 ;0,1=240,2=270.000000
L 1.22916673 5.87093327 1.23208356 5.86853327 2 P 0 ;0,1=240,2=270.000000
L 1.23208356 5.86853327 1.23625089 5.86693317 2 P 0 ;0,1=240,2=270.000000
L 1.23625089 5.86693317 1.24 5.8663999 2 P 0 ;0,1=240,2=270.000000
L 1.24 5.8663999 1.24 5.8776 2 P 0 ;0,1=240,2=270.000000
L 1.24 5.8959997 1.215 5.8959997 2 P 0 ;0,1=240,2=270.000000
L 1.215 5.8959997 1.2199997 5.8927999 2 P 0 ;0,1=240,2=270.000000
L 1.24 5.8927999 1.24 5.89919951 2 P 0 ;0,1=240,2=270.000000
L 1.23708396 5.91546634 1.23916693 5.91733317 2 P 0 ;0,1=240,2=270.000000
L 1.23916693 5.91733317 1.24 5.91946654 2 P 0 ;0,1=240,2=270.000000
L 1.24 5.91946654 1.23916693 5.9215999 2 P 0 ;0,1=240,2=270.000000
L 1.23916693 5.9215999 1.23666742 5.92346663 2 P 0 ;0,1=240,2=270.000000
L 1.23666742 5.92346663 1.23291673 5.9248001 2 P 0 ;0,1=240,2=270.000000
L 1.23291673 5.9248001 1.22916673 5.92533337 2 P 0 ;0,1=240,2=270.000000
L 1.22916673 5.92533337 1.22458366 5.92533337 2 P 0 ;0,1=240,2=270.000000
L 1.22458366 5.92533337 1.22083366 5.9248001 2 P 0 ;0,1=240,2=270.000000
L 1.22083366 5.9248001 1.2175003 5.92346663 2 P 0 ;0,1=240,2=270.000000
L 1.2175003 5.92346663 1.21583317 5.92186644 2 P 0 ;0,1=240,2=270.000000
L 1.21583317 5.92186644 1.215 5.9199997 2 P 0 ;0,1=240,2=270.000000
L 1.215 5.9199997 1.21583317 5.91786634 2 P 0 ;0,1=240,2=270.000000
L 1.21583317 5.91786634 1.2175003 5.91626663 2 P 0 ;0,1=240,2=270.000000
L 1.2175003 5.91626663 1.2199997 5.9151998 2 P 0 ;0,1=240,2=270.000000
L 1.2199997 5.9151998 1.22333386 5.91466654 2 P 0 ;0,1=240,2=270.000000
L 1.22333386 5.91466654 1.2262499 5.9151998 2 P 0 ;0,1=240,2=270.000000
L 1.2262499 5.9151998 1.22916673 5.91653327 2 P 0 ;0,1=240,2=270.000000
L 1.22916673 5.91653327 1.23083386 5.91813346 2 P 0 ;0,1=240,2=270.000000
L 1.23083386 5.91813346 1.23125039 5.9199997 2 P 0 ;0,1=240,2=270.000000
L 1.23125039 5.9199997 1.23041722 5.92213307 2 P 0 ;0,1=240,2=270.000000
L 1.23041722 5.92213307 1.22833356 5.92373327 2 P 0 ;0,1=240,2=270.000000
L 1.22833356 5.92373327 1.22458366 5.92533337 2 P 0 ;0,1=240,2=270.000000
L 1.215 5.9439997 1.21583317 5.94186634 2 P 0 ;0,1=240,2=270.000000
L 1.21583317 5.94186634 1.21791683 5.94026663 2 P 0 ;0,1=240,2=270.000000
L 1.21791683 5.94026663 1.22041634 5.9391998 2 P 0 ;0,1=240,2=270.000000
L 1.22041634 5.9391998 1.22375049 5.9383999 2 P 0 ;0,1=240,2=270.000000
L 1.22375049 5.9383999 1.22750039 5.93813327 2 P 0 ;0,1=240,2=270.000000
L 1.22750039 5.93813327 1.23125039 5.9383999 2 P 0 ;0,1=240,2=270.000000
L 1.23125039 5.9383999 1.23458376 5.9391998 2 P 0 ;0,1=240,2=270.000000
L 1.23458376 5.9391998 1.23708396 5.94026663 2 P 0 ;0,1=240,2=270.000000
L 1.23708396 5.94026663 1.23916693 5.94186634 2 P 0 ;0,1=240,2=270.000000
L 1.23916693 5.94186634 1.24 5.9439997 2 P 0 ;0,1=240,2=270.000000
L 1.24 5.9439997 1.23916693 5.94613307 2 P 0 ;0,1=240,2=270.000000
L 1.23916693 5.94613307 1.23708396 5.94773327 2 P 0 ;0,1=240,2=270.000000
L 1.23708396 5.94773327 1.23458376 5.9488001 2 P 0 ;0,1=240,2=270.000000
L 1.23458376 5.9488001 1.23125039 5.9496 2 P 0 ;0,1=240,2=270.000000
L 1.23125039 5.9496 1.22750039 5.94986663 2 P 0 ;0,1=240,2=270.000000
L 1.22750039 5.94986663 1.22375049 5.9496 2 P 0 ;0,1=240,2=270.000000
L 1.22375049 5.9496 1.22041634 5.9488001 2 P 0 ;0,1=240,2=270.000000
L 1.22041634 5.9488001 1.21791683 5.94773327 2 P 0 ;0,1=240,2=270.000000
L 1.21791683 5.94773327 1.21583317 5.94613307 2 P 0 ;0,1=240,2=270.000000
L 1.21583317 5.94613307 1.215 5.9439997 2 P 0 ;0,1=240,2=270.000000
A 1.46251004 5.4 1.46251004 5.4 1.46 5.4 1 P 0 N
L 1.50608366 5.24086663 1.50483317 5.23926644 2 P 0 ;0,1=241,2=270.000000
L 1.50483317 5.23926644 1.504 5.2374002 2 P 0 ;0,1=241,2=270.000000
L 1.504 5.2374002 1.504 5.23526683 2 P 0 ;0,1=241,2=270.000000
L 1.504 5.23526683 1.50525059 5.23286634 2 P 0 ;0,1=241,2=270.000000
L 1.50525059 5.23286634 1.50733346 5.2310001 2 P 0 ;0,1=241,2=270.000000
L 1.50733346 5.2310001 1.50983366 5.22966654 2 P 0 ;0,1=241,2=270.000000
L 1.50983366 5.22966654 1.5140002 5.22859961 2 P 0 ;0,1=241,2=270.000000
L 1.5140002 5.22859961 1.5177502 5.22833297 2 P 0 ;0,1=241,2=270.000000
L 1.5177502 5.22833297 1.5215001 5.22886673 2 P 0 ;0,1=241,2=270.000000
L 1.5215001 5.22886673 1.52400039 5.22966654 2 P 0 ;0,1=241,2=270.000000
L 1.52400039 5.22966654 1.52650059 5.23126663 2 P 0 ;0,1=241,2=270.000000
L 1.52650059 5.23126663 1.52816693 5.23313346 2 P 0 ;0,1=241,2=270.000000
L 1.52816693 5.23313346 1.529 5.2349997 2 P 0 ;0,1=241,2=270.000000
L 1.529 5.2349997 1.529 5.23686644 2 P 0 ;0,1=241,2=270.000000
L 1.529 5.23686644 1.52816693 5.23873327 2 P 0 ;0,1=241,2=270.000000
L 1.52816693 5.23873327 1.52691713 5.24033337 2 P 0 ;0,1=241,2=270.000000
L 1.52691713 5.24033337 1.52525089 5.24166693 2 P 0 ;0,1=241,2=270.000000
L 1.50816663 5.25393317 1.50566713 5.25553327 2 P 0 ;0,1=241,2=270.000000
L 1.50566713 5.25553327 1.50441663 5.2574 2 P 0 ;0,1=241,2=270.000000
L 1.50441663 5.2574 1.504 5.25953337 2 P 0 ;0,1=241,2=270.000000
L 1.504 5.25953337 1.50483317 5.2622 2 P 0 ;0,1=241,2=270.000000
L 1.50483317 5.2622 1.50691683 5.26406673 2 P 0 ;0,1=241,2=270.000000
L 1.50691683 5.26406673 1.50941634 5.2646 2 P 0 ;0,1=241,2=270.000000
L 1.50941634 5.2646 1.51191732 5.26433337 2 P 0 ;0,1=241,2=270.000000
L 1.51191732 5.26433337 1.5140002 5.26326644 2 P 0 ;0,1=241,2=270.000000
L 1.5140002 5.26326644 1.51816673 5.25793327 2 P 0 ;0,1=241,2=270.000000
L 1.51816673 5.25793327 1.52108356 5.25553327 2 P 0 ;0,1=241,2=270.000000
L 1.52108356 5.25553327 1.52525089 5.25393317 2 P 0 ;0,1=241,2=270.000000
L 1.52525089 5.25393317 1.529 5.2533999 2 P 0 ;0,1=241,2=270.000000
L 1.529 5.2533999 1.529 5.2646 2 P 0 ;0,1=241,2=270.000000
L 1.529 5.2829997 1.504 5.2829997 2 P 0 ;0,1=241,2=270.000000
L 1.504 5.2829997 1.5089997 5.2797999 2 P 0 ;0,1=241,2=270.000000
L 1.529 5.2797999 1.529 5.28619951 2 P 0 ;0,1=241,2=270.000000
L 1.529 5.3069997 1.52858346 5.30886644 2 P 0 ;0,1=241,2=270.000000
L 1.52858346 5.30886644 1.52733376 5.3109998 2 P 0 ;0,1=241,2=270.000000
L 1.52733376 5.3109998 1.52525089 5.31233337 2 P 0 ;0,1=241,2=270.000000
L 1.52525089 5.31233337 1.52233327 5.31286663 2 P 0 ;0,1=241,2=270.000000
L 1.52233327 5.31286663 1.51941722 5.31233337 2 P 0 ;0,1=241,2=270.000000
L 1.51941722 5.31233337 1.51691703 5.31073327 2 P 0 ;0,1=241,2=270.000000
L 1.51691703 5.31073327 1.51566654 5.30833327 2 P 0 ;0,1=241,2=270.000000
L 1.51566654 5.30833327 1.51566654 5.30566663 2 P 0 ;0,1=241,2=270.000000
L 1.51566654 5.30566663 1.51483337 5.30406654 2 P 0 ;0,1=241,2=270.000000
L 1.51483337 5.30406654 1.51275049 5.30273297 2 P 0 ;0,1=241,2=270.000000
L 1.51275049 5.30273297 1.50983366 5.3021998 2 P 0 ;0,1=241,2=270.000000
L 1.50983366 5.3021998 1.50691683 5.3030001 2 P 0 ;0,1=241,2=270.000000
L 1.50691683 5.3030001 1.50483317 5.30486634 2 P 0 ;0,1=241,2=270.000000
L 1.50483317 5.30486634 1.504 5.3069997 2 P 0 ;0,1=241,2=270.000000
L 1.504 5.3069997 1.50483317 5.30913307 2 P 0 ;0,1=241,2=270.000000
L 1.50483317 5.30913307 1.50691683 5.3109998 2 P 0 ;0,1=241,2=270.000000
L 1.50691683 5.3109998 1.50983366 5.3118001 2 P 0 ;0,1=241,2=270.000000
L 1.50983366 5.3118001 1.51275049 5.31126644 2 P 0 ;0,1=241,2=270.000000
L 1.51275049 5.31126644 1.51483337 5.30993337 2 P 0 ;0,1=241,2=270.000000
L 1.51483337 5.30993337 1.51566654 5.30833327 2 P 0 ;0,1=241,2=270.000000
L 1.51566654 5.30833327 1.51566654 5.30566663 2 P 0 ;0,1=241,2=270.000000
L 1.51566654 5.30566663 1.51691703 5.30326663 2 P 0 ;0,1=241,2=270.000000
L 1.51691703 5.30326663 1.51941722 5.30166654 2 P 0 ;0,1=241,2=270.000000
L 1.51941722 5.30166654 1.52233327 5.30113327 2 P 0 ;0,1=241,2=270.000000
L 1.52233327 5.30113327 1.52525089 5.30166654 2 P 0 ;0,1=241,2=270.000000
L 1.52525089 5.30166654 1.52733376 5.3030001 2 P 0 ;0,1=241,2=270.000000
L 1.52733376 5.3030001 1.52858346 5.30513346 2 P 0 ;0,1=241,2=270.000000
L 1.52858346 5.30513346 1.529 5.3069997 2 P 0 ;0,1=241,2=270.000000
L 1.51858406 5.32593317 1.51566654 5.3277999 2 P 0 ;0,1=241,2=270.000000
L 1.51566654 5.3277999 1.5140002 5.3294 2 P 0 ;0,1=241,2=270.000000
L 1.5140002 5.3294 1.51316703 5.33153337 2 P 0 ;0,1=241,2=270.000000
L 1.51316703 5.33153337 1.5140002 5.3334002 2 P 0 ;0,1=241,2=270.000000
L 1.5140002 5.3334002 1.51566654 5.33473327 2 P 0 ;0,1=241,2=270.000000
L 1.51566654 5.33473327 1.51816673 5.3358001 2 P 0 ;0,1=241,2=270.000000
L 1.51816673 5.3358001 1.52108356 5.33606673 2 P 0 ;0,1=241,2=270.000000
L 1.52108356 5.33606673 1.52358376 5.3358001 2 P 0 ;0,1=241,2=270.000000
L 1.52358376 5.3358001 1.52608396 5.33473327 2 P 0 ;0,1=241,2=270.000000
L 1.52608396 5.33473327 1.52816693 5.33313307 2 P 0 ;0,1=241,2=270.000000
L 1.52816693 5.33313307 1.529 5.33126683 2 P 0 ;0,1=241,2=270.000000
L 1.529 5.33126683 1.52816693 5.32913346 2 P 0 ;0,1=241,2=270.000000
L 1.52816693 5.32913346 1.52566742 5.32726663 2 P 0 ;0,1=241,2=270.000000
L 1.52566742 5.32726663 1.52191673 5.3261998 2 P 0 ;0,1=241,2=270.000000
L 1.52191673 5.3261998 1.5177502 5.32593317 2 P 0 ;0,1=241,2=270.000000
L 1.5177502 5.32593317 1.51233386 5.32646634 2 P 0 ;0,1=241,2=270.000000
L 1.51233386 5.32646634 1.50941634 5.32726663 2 P 0 ;0,1=241,2=270.000000
L 1.50941634 5.32726663 1.5065003 5.3285997 2 P 0 ;0,1=241,2=270.000000
L 1.5065003 5.3285997 1.50441663 5.33046654 2 P 0 ;0,1=241,2=270.000000
L 1.50441663 5.33046654 1.504 5.33233327 2 P 0 ;0,1=241,2=270.000000
L 1.504 5.33233327 1.50483317 5.3342 2 P 0 ;0,1=241,2=270.000000
L 1.50483317 5.3342 1.50691683 5.33553356 2 P 0 ;0,1=241,2=270.000000
A 1.41251004 5.4 1.41251004 5.4 1.41 5.4 1 P 0 N
L 1.46608366 5.24086663 1.46483317 5.23926644 2 P 0 ;0,1=242,2=270.000000
L 1.46483317 5.23926644 1.464 5.2374002 2 P 0 ;0,1=242,2=270.000000
L 1.464 5.2374002 1.464 5.23526683 2 P 0 ;0,1=242,2=270.000000
L 1.464 5.23526683 1.46525059 5.23286634 2 P 0 ;0,1=242,2=270.000000
L 1.46525059 5.23286634 1.46733346 5.2310001 2 P 0 ;0,1=242,2=270.000000
L 1.46733346 5.2310001 1.46983366 5.22966654 2 P 0 ;0,1=242,2=270.000000
L 1.46983366 5.22966654 1.4740002 5.22859961 2 P 0 ;0,1=242,2=270.000000
L 1.4740002 5.22859961 1.4777502 5.22833297 2 P 0 ;0,1=242,2=270.000000
L 1.4777502 5.22833297 1.4815001 5.22886673 2 P 0 ;0,1=242,2=270.000000
L 1.4815001 5.22886673 1.48400039 5.22966654 2 P 0 ;0,1=242,2=270.000000
L 1.48400039 5.22966654 1.48650059 5.23126663 2 P 0 ;0,1=242,2=270.000000
L 1.48650059 5.23126663 1.48816693 5.23313346 2 P 0 ;0,1=242,2=270.000000
L 1.48816693 5.23313346 1.489 5.2349997 2 P 0 ;0,1=242,2=270.000000
L 1.489 5.2349997 1.489 5.23686644 2 P 0 ;0,1=242,2=270.000000
L 1.489 5.23686644 1.48816693 5.23873327 2 P 0 ;0,1=242,2=270.000000
L 1.48816693 5.23873327 1.48691713 5.24033337 2 P 0 ;0,1=242,2=270.000000
L 1.48691713 5.24033337 1.48525089 5.24166693 2 P 0 ;0,1=242,2=270.000000
L 1.46816663 5.25393317 1.46566713 5.25553327 2 P 0 ;0,1=242,2=270.000000
L 1.46566713 5.25553327 1.46441663 5.2574 2 P 0 ;0,1=242,2=270.000000
L 1.46441663 5.2574 1.464 5.25953337 2 P 0 ;0,1=242,2=270.000000
L 1.464 5.25953337 1.46483317 5.2622 2 P 0 ;0,1=242,2=270.000000
L 1.46483317 5.2622 1.46691683 5.26406673 2 P 0 ;0,1=242,2=270.000000
L 1.46691683 5.26406673 1.46941634 5.2646 2 P 0 ;0,1=242,2=270.000000
L 1.46941634 5.2646 1.47191732 5.26433337 2 P 0 ;0,1=242,2=270.000000
L 1.47191732 5.26433337 1.4740002 5.26326644 2 P 0 ;0,1=242,2=270.000000
L 1.4740002 5.26326644 1.47816673 5.25793327 2 P 0 ;0,1=242,2=270.000000
L 1.47816673 5.25793327 1.48108356 5.25553327 2 P 0 ;0,1=242,2=270.000000
L 1.48108356 5.25553327 1.48525089 5.25393317 2 P 0 ;0,1=242,2=270.000000
L 1.48525089 5.25393317 1.489 5.2533999 2 P 0 ;0,1=242,2=270.000000
L 1.489 5.2533999 1.489 5.2646 2 P 0 ;0,1=242,2=270.000000
L 1.489 5.2829997 1.464 5.2829997 2 P 0 ;0,1=242,2=270.000000
L 1.464 5.2829997 1.4689997 5.2797999 2 P 0 ;0,1=242,2=270.000000
L 1.489 5.2797999 1.489 5.28619951 2 P 0 ;0,1=242,2=270.000000
L 1.489 5.3069997 1.48858346 5.30886644 2 P 0 ;0,1=242,2=270.000000
L 1.48858346 5.30886644 1.48733376 5.3109998 2 P 0 ;0,1=242,2=270.000000
L 1.48733376 5.3109998 1.48525089 5.31233337 2 P 0 ;0,1=242,2=270.000000
L 1.48525089 5.31233337 1.48233327 5.31286663 2 P 0 ;0,1=242,2=270.000000
L 1.48233327 5.31286663 1.47941722 5.31233337 2 P 0 ;0,1=242,2=270.000000
L 1.47941722 5.31233337 1.47691703 5.31073327 2 P 0 ;0,1=242,2=270.000000
L 1.47691703 5.31073327 1.47566654 5.30833327 2 P 0 ;0,1=242,2=270.000000
L 1.47566654 5.30833327 1.47566654 5.30566663 2 P 0 ;0,1=242,2=270.000000
L 1.47566654 5.30566663 1.47483337 5.30406654 2 P 0 ;0,1=242,2=270.000000
L 1.47483337 5.30406654 1.47275049 5.30273297 2 P 0 ;0,1=242,2=270.000000
L 1.47275049 5.30273297 1.46983366 5.3021998 2 P 0 ;0,1=242,2=270.000000
L 1.46983366 5.3021998 1.46691683 5.3030001 2 P 0 ;0,1=242,2=270.000000
L 1.46691683 5.3030001 1.46483317 5.30486634 2 P 0 ;0,1=242,2=270.000000
L 1.46483317 5.30486634 1.464 5.3069997 2 P 0 ;0,1=242,2=270.000000
L 1.464 5.3069997 1.46483317 5.30913307 2 P 0 ;0,1=242,2=270.000000
L 1.46483317 5.30913307 1.46691683 5.3109998 2 P 0 ;0,1=242,2=270.000000
L 1.46691683 5.3109998 1.46983366 5.3118001 2 P 0 ;0,1=242,2=270.000000
L 1.46983366 5.3118001 1.47275049 5.31126644 2 P 0 ;0,1=242,2=270.000000
L 1.47275049 5.31126644 1.47483337 5.30993337 2 P 0 ;0,1=242,2=270.000000
L 1.47483337 5.30993337 1.47566654 5.30833327 2 P 0 ;0,1=242,2=270.000000
L 1.47566654 5.30833327 1.47566654 5.30566663 2 P 0 ;0,1=242,2=270.000000
L 1.47566654 5.30566663 1.47691703 5.30326663 2 P 0 ;0,1=242,2=270.000000
L 1.47691703 5.30326663 1.47941722 5.30166654 2 P 0 ;0,1=242,2=270.000000
L 1.47941722 5.30166654 1.48233327 5.30113327 2 P 0 ;0,1=242,2=270.000000
L 1.48233327 5.30113327 1.48525089 5.30166654 2 P 0 ;0,1=242,2=270.000000
L 1.48525089 5.30166654 1.48733376 5.3030001 2 P 0 ;0,1=242,2=270.000000
L 1.48733376 5.3030001 1.48858346 5.30513346 2 P 0 ;0,1=242,2=270.000000
L 1.48858346 5.30513346 1.489 5.3069997 2 P 0 ;0,1=242,2=270.000000
L 1.48525089 5.32513327 1.48733376 5.32673297 2 P 0 ;0,1=242,2=270.000000
L 1.48733376 5.32673297 1.48858346 5.3285997 2 P 0 ;0,1=242,2=270.000000
L 1.48858346 5.3285997 1.489 5.3309997 2 P 0 ;0,1=242,2=270.000000
L 1.489 5.3309997 1.48816693 5.3334002 2 P 0 ;0,1=242,2=270.000000
L 1.48816693 5.3334002 1.48650059 5.33526644 2 P 0 ;0,1=242,2=270.000000
L 1.48650059 5.33526644 1.48358376 5.3366 2 P 0 ;0,1=242,2=270.000000
L 1.48358376 5.3366 1.48025039 5.33686663 2 P 0 ;0,1=242,2=270.000000
L 1.48025039 5.33686663 1.47691703 5.33633337 2 P 0 ;0,1=242,2=270.000000
L 1.47691703 5.33633337 1.47483337 5.3349998 2 P 0 ;0,1=242,2=270.000000
L 1.47483337 5.3349998 1.47316703 5.33313307 2 P 0 ;0,1=242,2=270.000000
L 1.47316703 5.33313307 1.47275049 5.33126683 2 P 0 ;0,1=242,2=270.000000
L 1.47275049 5.33126683 1.47316703 5.3294 2 P 0 ;0,1=242,2=270.000000
L 1.47316703 5.3294 1.47483337 5.3270001 2 P 0 ;0,1=242,2=270.000000
L 1.47483337 5.3270001 1.464 5.3277999 2 P 0 ;0,1=242,2=270.000000
L 1.464 5.3277999 1.464 5.3349998 2 P 0 ;0,1=242,2=270.000000
A 0.73251004 5.13 0.73251004 5.13 0.73 5.13 1 P 0 N
L 0.63208366 5.09886663 0.63083317 5.09726644 2 P 0 ;0,1=243,2=270.000000
L 0.63083317 5.09726644 0.63 5.0954002 2 P 0 ;0,1=243,2=270.000000
L 0.63 5.0954002 0.63 5.09326683 2 P 0 ;0,1=243,2=270.000000
L 0.63 5.09326683 0.63125059 5.09086634 2 P 0 ;0,1=243,2=270.000000
L 0.63125059 5.09086634 0.63333346 5.0890001 2 P 0 ;0,1=243,2=270.000000
L 0.63333346 5.0890001 0.63583366 5.08766654 2 P 0 ;0,1=243,2=270.000000
L 0.63583366 5.08766654 0.6400002 5.08659961 2 P 0 ;0,1=243,2=270.000000
L 0.6400002 5.08659961 0.6437502 5.08633297 2 P 0 ;0,1=243,2=270.000000
L 0.6437502 5.08633297 0.6475001 5.08686673 2 P 0 ;0,1=243,2=270.000000
L 0.6475001 5.08686673 0.65000039 5.08766654 2 P 0 ;0,1=243,2=270.000000
L 0.65000039 5.08766654 0.65250059 5.08926663 2 P 0 ;0,1=243,2=270.000000
L 0.65250059 5.08926663 0.65416693 5.09113346 2 P 0 ;0,1=243,2=270.000000
L 0.65416693 5.09113346 0.655 5.0929997 2 P 0 ;0,1=243,2=270.000000
L 0.655 5.0929997 0.655 5.09486644 2 P 0 ;0,1=243,2=270.000000
L 0.655 5.09486644 0.65416693 5.09673327 2 P 0 ;0,1=243,2=270.000000
L 0.65416693 5.09673327 0.65291713 5.09833337 2 P 0 ;0,1=243,2=270.000000
L 0.65291713 5.09833337 0.65125089 5.09966693 2 P 0 ;0,1=243,2=270.000000
L 0.63416663 5.11193317 0.63166713 5.11353327 2 P 0 ;0,1=243,2=270.000000
L 0.63166713 5.11353327 0.63041663 5.1154 2 P 0 ;0,1=243,2=270.000000
L 0.63041663 5.1154 0.63 5.11753337 2 P 0 ;0,1=243,2=270.000000
L 0.63 5.11753337 0.63083317 5.1202 2 P 0 ;0,1=243,2=270.000000
L 0.63083317 5.1202 0.63291683 5.12206673 2 P 0 ;0,1=243,2=270.000000
L 0.63291683 5.12206673 0.63541634 5.1226 2 P 0 ;0,1=243,2=270.000000
L 0.63541634 5.1226 0.63791732 5.12233337 2 P 0 ;0,1=243,2=270.000000
L 0.63791732 5.12233337 0.6400002 5.12126644 2 P 0 ;0,1=243,2=270.000000
L 0.6400002 5.12126644 0.64416673 5.11593327 2 P 0 ;0,1=243,2=270.000000
L 0.64416673 5.11593327 0.64708356 5.11353327 2 P 0 ;0,1=243,2=270.000000
L 0.64708356 5.11353327 0.65125089 5.11193317 2 P 0 ;0,1=243,2=270.000000
L 0.65125089 5.11193317 0.655 5.1113999 2 P 0 ;0,1=243,2=270.000000
L 0.655 5.1113999 0.655 5.1226 2 P 0 ;0,1=243,2=270.000000
L 0.655 5.1409997 0.63 5.1409997 2 P 0 ;0,1=243,2=270.000000
L 0.63 5.1409997 0.6349997 5.1377999 2 P 0 ;0,1=243,2=270.000000
L 0.655 5.1377999 0.655 5.14419951 2 P 0 ;0,1=243,2=270.000000
L 0.655 5.16446654 0.64958376 5.1649997 2 P 0 ;0,1=243,2=270.000000
L 0.64958376 5.1649997 0.64500069 5.1658 2 P 0 ;0,1=243,2=270.000000
L 0.64500069 5.1658 0.64083337 5.16686644 2 P 0 ;0,1=243,2=270.000000
L 0.64083337 5.16686644 0.6362502 5.1682 2 P 0 ;0,1=243,2=270.000000
L 0.6362502 5.1682 0.63 5.17033337 2 P 0 ;0,1=243,2=270.000000
L 0.63 5.17033337 0.63 5.15966654 2 P 0 ;0,1=243,2=270.000000
L 0.65000039 5.18313327 0.65291713 5.18473297 2 P 0 ;0,1=243,2=270.000000
L 0.65291713 5.18473297 0.65458346 5.18686634 2 P 0 ;0,1=243,2=270.000000
L 0.65458346 5.18686634 0.655 5.18926683 2 P 0 ;0,1=243,2=270.000000
L 0.655 5.18926683 0.65458346 5.1914002 2 P 0 ;0,1=243,2=270.000000
L 0.65458346 5.1914002 0.65250059 5.19353356 2 P 0 ;0,1=243,2=270.000000
L 0.65250059 5.19353356 0.65000039 5.19486663 2 P 0 ;0,1=243,2=270.000000
L 0.65000039 5.19486663 0.6475001 5.19513317 2 P 0 ;0,1=243,2=270.000000
L 0.6475001 5.19513317 0.64458406 5.1946 2 P 0 ;0,1=243,2=270.000000
L 0.64458406 5.1946 0.64250039 5.19273327 2 P 0 ;0,1=243,2=270.000000
L 0.64250039 5.19273327 0.64166654 5.19086644 2 P 0 ;0,1=243,2=270.000000
L 0.64166654 5.19086644 0.64166654 5.18846654 2 P 0 ;0,1=243,2=270.000000
L 0.64166654 5.19086644 0.64041673 5.19246663 2 P 0 ;0,1=243,2=270.000000
L 0.64041673 5.19246663 0.63833386 5.1938001 2 P 0 ;0,1=243,2=270.000000
L 0.63833386 5.1938001 0.63583366 5.19433337 2 P 0 ;0,1=243,2=270.000000
L 0.63583366 5.19433337 0.63333346 5.1938001 2 P 0 ;0,1=243,2=270.000000
L 0.63333346 5.1938001 0.63125059 5.19246663 2 P 0 ;0,1=243,2=270.000000
L 0.63125059 5.19246663 0.63 5.19006663 2 P 0 ;0,1=243,2=270.000000
L 0.63 5.19006663 0.63041663 5.18766663 2 P 0 ;0,1=243,2=270.000000
L 0.63041663 5.18766663 0.63208366 5.18526663 2 P 0 ;0,1=243,2=270.000000
A 0.73251004 5.25 0.73251004 5.25 0.73 5.25 1 P 0 N
L 0.66208366 5.21886663 0.66083317 5.21726644 2 P 0 ;0,1=244,2=270.000000
L 0.66083317 5.21726644 0.66 5.2154002 2 P 0 ;0,1=244,2=270.000000
L 0.66 5.2154002 0.66 5.21326683 2 P 0 ;0,1=244,2=270.000000
L 0.66 5.21326683 0.66125059 5.21086634 2 P 0 ;0,1=244,2=270.000000
L 0.66125059 5.21086634 0.66333346 5.2090001 2 P 0 ;0,1=244,2=270.000000
L 0.66333346 5.2090001 0.66583366 5.20766654 2 P 0 ;0,1=244,2=270.000000
L 0.66583366 5.20766654 0.6700002 5.20659961 2 P 0 ;0,1=244,2=270.000000
L 0.6700002 5.20659961 0.6737502 5.20633297 2 P 0 ;0,1=244,2=270.000000
L 0.6737502 5.20633297 0.6775001 5.20686673 2 P 0 ;0,1=244,2=270.000000
L 0.6775001 5.20686673 0.68000039 5.20766654 2 P 0 ;0,1=244,2=270.000000
L 0.68000039 5.20766654 0.68250059 5.20926663 2 P 0 ;0,1=244,2=270.000000
L 0.68250059 5.20926663 0.68416693 5.21113346 2 P 0 ;0,1=244,2=270.000000
L 0.68416693 5.21113346 0.685 5.2129997 2 P 0 ;0,1=244,2=270.000000
L 0.685 5.2129997 0.685 5.21486644 2 P 0 ;0,1=244,2=270.000000
L 0.685 5.21486644 0.68416693 5.21673327 2 P 0 ;0,1=244,2=270.000000
L 0.68416693 5.21673327 0.68291713 5.21833337 2 P 0 ;0,1=244,2=270.000000
L 0.68291713 5.21833337 0.68125089 5.21966693 2 P 0 ;0,1=244,2=270.000000
L 0.66416663 5.23193317 0.66166713 5.23353327 2 P 0 ;0,1=244,2=270.000000
L 0.66166713 5.23353327 0.66041663 5.2354 2 P 0 ;0,1=244,2=270.000000
L 0.66041663 5.2354 0.66 5.23753337 2 P 0 ;0,1=244,2=270.000000
L 0.66 5.23753337 0.66083317 5.2402 2 P 0 ;0,1=244,2=270.000000
L 0.66083317 5.2402 0.66291683 5.24206673 2 P 0 ;0,1=244,2=270.000000
L 0.66291683 5.24206673 0.66541634 5.2426 2 P 0 ;0,1=244,2=270.000000
L 0.66541634 5.2426 0.66791732 5.24233337 2 P 0 ;0,1=244,2=270.000000
L 0.66791732 5.24233337 0.6700002 5.24126644 2 P 0 ;0,1=244,2=270.000000
L 0.6700002 5.24126644 0.67416673 5.23593327 2 P 0 ;0,1=244,2=270.000000
L 0.67416673 5.23593327 0.67708356 5.23353327 2 P 0 ;0,1=244,2=270.000000
L 0.67708356 5.23353327 0.68125089 5.23193317 2 P 0 ;0,1=244,2=270.000000
L 0.68125089 5.23193317 0.685 5.2313999 2 P 0 ;0,1=244,2=270.000000
L 0.685 5.2313999 0.685 5.2426 2 P 0 ;0,1=244,2=270.000000
L 0.685 5.2609997 0.66 5.2609997 2 P 0 ;0,1=244,2=270.000000
L 0.66 5.2609997 0.6649997 5.2577999 2 P 0 ;0,1=244,2=270.000000
L 0.685 5.2577999 0.685 5.26419951 2 P 0 ;0,1=244,2=270.000000
L 0.685 5.28446654 0.67958376 5.2849997 2 P 0 ;0,1=244,2=270.000000
L 0.67958376 5.2849997 0.67500069 5.2858 2 P 0 ;0,1=244,2=270.000000
L 0.67500069 5.2858 0.67083337 5.28686644 2 P 0 ;0,1=244,2=270.000000
L 0.67083337 5.28686644 0.6662502 5.2882 2 P 0 ;0,1=244,2=270.000000
L 0.6662502 5.2882 0.66 5.29033337 2 P 0 ;0,1=244,2=270.000000
L 0.66 5.29033337 0.66 5.27966654 2 P 0 ;0,1=244,2=270.000000
L 0.66416663 5.30393317 0.66166713 5.30553327 2 P 0 ;0,1=244,2=270.000000
L 0.66166713 5.30553327 0.66041663 5.3074 2 P 0 ;0,1=244,2=270.000000
L 0.66041663 5.3074 0.66 5.30953337 2 P 0 ;0,1=244,2=270.000000
L 0.66 5.30953337 0.66083317 5.3122 2 P 0 ;0,1=244,2=270.000000
L 0.66083317 5.3122 0.66291683 5.31406673 2 P 0 ;0,1=244,2=270.000000
L 0.66291683 5.31406673 0.66541634 5.3146 2 P 0 ;0,1=244,2=270.000000
L 0.66541634 5.3146 0.66791732 5.31433337 2 P 0 ;0,1=244,2=270.000000
L 0.66791732 5.31433337 0.6700002 5.31326644 2 P 0 ;0,1=244,2=270.000000
L 0.6700002 5.31326644 0.67416673 5.30793327 2 P 0 ;0,1=244,2=270.000000
L 0.67416673 5.30793327 0.67708356 5.30553327 2 P 0 ;0,1=244,2=270.000000
L 0.67708356 5.30553327 0.68125089 5.30393317 2 P 0 ;0,1=244,2=270.000000
L 0.68125089 5.30393317 0.685 5.3033999 2 P 0 ;0,1=244,2=270.000000
L 0.685 5.3033999 0.685 5.3146 2 P 0 ;0,1=244,2=270.000000
A 3.77251004 4.81 3.77251004 4.81 3.77 4.81 1 P 0 N
L 3.75208366 4.39386663 3.75083317 4.39226644 2 P 0 ;0,1=245,2=270.000000
L 3.75083317 4.39226644 3.75 4.3904002 2 P 0 ;0,1=245,2=270.000000
L 3.75 4.3904002 3.75 4.38826683 2 P 0 ;0,1=245,2=270.000000
L 3.75 4.38826683 3.75125059 4.38586634 2 P 0 ;0,1=245,2=270.000000
L 3.75125059 4.38586634 3.75333346 4.3840001 2 P 0 ;0,1=245,2=270.000000
L 3.75333346 4.3840001 3.75583366 4.38266654 2 P 0 ;0,1=245,2=270.000000
L 3.75583366 4.38266654 3.7600002 4.38159961 2 P 0 ;0,1=245,2=270.000000
L 3.7600002 4.38159961 3.7637502 4.38133297 2 P 0 ;0,1=245,2=270.000000
L 3.7637502 4.38133297 3.7675001 4.38186673 2 P 0 ;0,1=245,2=270.000000
L 3.7675001 4.38186673 3.77000039 4.38266654 2 P 0 ;0,1=245,2=270.000000
L 3.77000039 4.38266654 3.77250059 4.38426663 2 P 0 ;0,1=245,2=270.000000
L 3.77250059 4.38426663 3.77416693 4.38613346 2 P 0 ;0,1=245,2=270.000000
L 3.77416693 4.38613346 3.775 4.3879997 2 P 0 ;0,1=245,2=270.000000
L 3.775 4.3879997 3.775 4.38986644 2 P 0 ;0,1=245,2=270.000000
L 3.775 4.38986644 3.77416693 4.39173327 2 P 0 ;0,1=245,2=270.000000
L 3.77416693 4.39173327 3.77291713 4.39333337 2 P 0 ;0,1=245,2=270.000000
L 3.77291713 4.39333337 3.77125089 4.39466693 2 P 0 ;0,1=245,2=270.000000
L 3.75416663 4.40693317 3.75166713 4.40853327 2 P 0 ;0,1=245,2=270.000000
L 3.75166713 4.40853327 3.75041663 4.4104 2 P 0 ;0,1=245,2=270.000000
L 3.75041663 4.4104 3.75 4.41253337 2 P 0 ;0,1=245,2=270.000000
L 3.75 4.41253337 3.75083317 4.4152 2 P 0 ;0,1=245,2=270.000000
L 3.75083317 4.4152 3.75291683 4.41706673 2 P 0 ;0,1=245,2=270.000000
L 3.75291683 4.41706673 3.75541634 4.4176 2 P 0 ;0,1=245,2=270.000000
L 3.75541634 4.4176 3.75791732 4.41733337 2 P 0 ;0,1=245,2=270.000000
L 3.75791732 4.41733337 3.7600002 4.41626644 2 P 0 ;0,1=245,2=270.000000
L 3.7600002 4.41626644 3.76416673 4.41093327 2 P 0 ;0,1=245,2=270.000000
L 3.76416673 4.41093327 3.76708356 4.40853327 2 P 0 ;0,1=245,2=270.000000
L 3.76708356 4.40853327 3.77125089 4.40693317 2 P 0 ;0,1=245,2=270.000000
L 3.77125089 4.40693317 3.775 4.4063999 2 P 0 ;0,1=245,2=270.000000
L 3.775 4.4063999 3.775 4.4176 2 P 0 ;0,1=245,2=270.000000
L 3.75416663 4.43093317 3.75166713 4.43253327 2 P 0 ;0,1=245,2=270.000000
L 3.75166713 4.43253327 3.75041663 4.4344 2 P 0 ;0,1=245,2=270.000000
L 3.75041663 4.4344 3.75 4.43653337 2 P 0 ;0,1=245,2=270.000000
L 3.75 4.43653337 3.75083317 4.4392 2 P 0 ;0,1=245,2=270.000000
L 3.75083317 4.4392 3.75291683 4.44106673 2 P 0 ;0,1=245,2=270.000000
L 3.75291683 4.44106673 3.75541634 4.4416 2 P 0 ;0,1=245,2=270.000000
L 3.75541634 4.4416 3.75791732 4.44133337 2 P 0 ;0,1=245,2=270.000000
L 3.75791732 4.44133337 3.7600002 4.44026644 2 P 0 ;0,1=245,2=270.000000
L 3.7600002 4.44026644 3.76416673 4.43493327 2 P 0 ;0,1=245,2=270.000000
L 3.76416673 4.43493327 3.76708356 4.43253327 2 P 0 ;0,1=245,2=270.000000
L 3.76708356 4.43253327 3.77125089 4.43093317 2 P 0 ;0,1=245,2=270.000000
L 3.77125089 4.43093317 3.775 4.4303999 2 P 0 ;0,1=245,2=270.000000
L 3.775 4.4303999 3.775 4.4416 2 P 0 ;0,1=245,2=270.000000
L 3.77000039 4.45413327 3.77291713 4.45573297 2 P 0 ;0,1=245,2=270.000000
L 3.77291713 4.45573297 3.77458346 4.45786634 2 P 0 ;0,1=245,2=270.000000
L 3.77458346 4.45786634 3.775 4.46026683 2 P 0 ;0,1=245,2=270.000000
L 3.775 4.46026683 3.77458346 4.4624002 2 P 0 ;0,1=245,2=270.000000
L 3.77458346 4.4624002 3.77250059 4.46453356 2 P 0 ;0,1=245,2=270.000000
L 3.77250059 4.46453356 3.77000039 4.46586663 2 P 0 ;0,1=245,2=270.000000
L 3.77000039 4.46586663 3.7675001 4.46613317 2 P 0 ;0,1=245,2=270.000000
L 3.7675001 4.46613317 3.76458406 4.4656 2 P 0 ;0,1=245,2=270.000000
L 3.76458406 4.4656 3.76250039 4.46373327 2 P 0 ;0,1=245,2=270.000000
L 3.76250039 4.46373327 3.76166654 4.46186644 2 P 0 ;0,1=245,2=270.000000
L 3.76166654 4.46186644 3.76166654 4.45946654 2 P 0 ;0,1=245,2=270.000000
L 3.76166654 4.46186644 3.76041673 4.46346663 2 P 0 ;0,1=245,2=270.000000
L 3.76041673 4.46346663 3.75833386 4.4648001 2 P 0 ;0,1=245,2=270.000000
L 3.75833386 4.4648001 3.75583366 4.46533337 2 P 0 ;0,1=245,2=270.000000
L 3.75583366 4.46533337 3.75333346 4.4648001 2 P 0 ;0,1=245,2=270.000000
L 3.75333346 4.4648001 3.75125059 4.46346663 2 P 0 ;0,1=245,2=270.000000
L 3.75125059 4.46346663 3.75 4.46106663 2 P 0 ;0,1=245,2=270.000000
L 3.75 4.46106663 3.75041663 4.45866663 2 P 0 ;0,1=245,2=270.000000
L 3.75041663 4.45866663 3.75208366 4.45626663 2 P 0 ;0,1=245,2=270.000000
L 3.76458406 4.47893317 3.76166654 4.4807999 2 P 0 ;0,1=245,2=270.000000
L 3.76166654 4.4807999 3.7600002 4.4824 2 P 0 ;0,1=245,2=270.000000
L 3.7600002 4.4824 3.75916703 4.48453337 2 P 0 ;0,1=245,2=270.000000
L 3.75916703 4.48453337 3.7600002 4.4864002 2 P 0 ;0,1=245,2=270.000000
L 3.7600002 4.4864002 3.76166654 4.48773327 2 P 0 ;0,1=245,2=270.000000
L 3.76166654 4.48773327 3.76416673 4.4888001 2 P 0 ;0,1=245,2=270.000000
L 3.76416673 4.4888001 3.76708356 4.48906673 2 P 0 ;0,1=245,2=270.000000
L 3.76708356 4.48906673 3.76958376 4.4888001 2 P 0 ;0,1=245,2=270.000000
L 3.76958376 4.4888001 3.77208396 4.48773327 2 P 0 ;0,1=245,2=270.000000
L 3.77208396 4.48773327 3.77416693 4.48613307 2 P 0 ;0,1=245,2=270.000000
L 3.77416693 4.48613307 3.775 4.48426683 2 P 0 ;0,1=245,2=270.000000
L 3.775 4.48426683 3.77416693 4.48213346 2 P 0 ;0,1=245,2=270.000000
L 3.77416693 4.48213346 3.77166742 4.48026663 2 P 0 ;0,1=245,2=270.000000
L 3.77166742 4.48026663 3.76791673 4.4791998 2 P 0 ;0,1=245,2=270.000000
L 3.76791673 4.4791998 3.7637502 4.47893317 2 P 0 ;0,1=245,2=270.000000
L 3.7637502 4.47893317 3.75833386 4.47946634 2 P 0 ;0,1=245,2=270.000000
L 3.75833386 4.47946634 3.75541634 4.48026663 2 P 0 ;0,1=245,2=270.000000
L 3.75541634 4.48026663 3.7525003 4.4815997 2 P 0 ;0,1=245,2=270.000000
L 3.7525003 4.4815997 3.75041663 4.48346654 2 P 0 ;0,1=245,2=270.000000
L 3.75041663 4.48346654 3.75 4.48533327 2 P 0 ;0,1=245,2=270.000000
L 3.75 4.48533327 3.75083317 4.4872 2 P 0 ;0,1=245,2=270.000000
L 3.75083317 4.4872 3.75291683 4.48853356 2 P 0 ;0,1=245,2=270.000000
A 7.24511004 4.64851004 7.24511004 4.64851004 7.2426 4.64851004 1 P 0 N
L 7.23208366 4.48386663 7.23083317 4.48226644 2 P 0 ;0,1=246,2=270.000000
L 7.23083317 4.48226644 7.23 4.4804002 2 P 0 ;0,1=246,2=270.000000
L 7.23 4.4804002 7.23 4.47826683 2 P 0 ;0,1=246,2=270.000000
L 7.23 4.47826683 7.23125059 4.47586634 2 P 0 ;0,1=246,2=270.000000
L 7.23125059 4.47586634 7.23333346 4.4740001 2 P 0 ;0,1=246,2=270.000000
L 7.23333346 4.4740001 7.23583366 4.47266654 2 P 0 ;0,1=246,2=270.000000
L 7.23583366 4.47266654 7.2400002 4.47159961 2 P 0 ;0,1=246,2=270.000000
L 7.2400002 4.47159961 7.2437502 4.47133297 2 P 0 ;0,1=246,2=270.000000
L 7.2437502 4.47133297 7.2475001 4.47186673 2 P 0 ;0,1=246,2=270.000000
L 7.2475001 4.47186673 7.25000039 4.47266654 2 P 0 ;0,1=246,2=270.000000
L 7.25000039 4.47266654 7.25250059 4.47426663 2 P 0 ;0,1=246,2=270.000000
L 7.25250059 4.47426663 7.25416693 4.47613346 2 P 0 ;0,1=246,2=270.000000
L 7.25416693 4.47613346 7.255 4.4779997 2 P 0 ;0,1=246,2=270.000000
L 7.255 4.4779997 7.255 4.47986644 2 P 0 ;0,1=246,2=270.000000
L 7.255 4.47986644 7.25416693 4.48173327 2 P 0 ;0,1=246,2=270.000000
L 7.25416693 4.48173327 7.25291713 4.48333337 2 P 0 ;0,1=246,2=270.000000
L 7.25291713 4.48333337 7.25125089 4.48466693 2 P 0 ;0,1=246,2=270.000000
L 7.23416663 4.49693317 7.23166713 4.49853327 2 P 0 ;0,1=246,2=270.000000
L 7.23166713 4.49853327 7.23041663 4.5004 2 P 0 ;0,1=246,2=270.000000
L 7.23041663 4.5004 7.23 4.50253337 2 P 0 ;0,1=246,2=270.000000
L 7.23 4.50253337 7.23083317 4.5052 2 P 0 ;0,1=246,2=270.000000
L 7.23083317 4.5052 7.23291683 4.50706673 2 P 0 ;0,1=246,2=270.000000
L 7.23291683 4.50706673 7.23541634 4.5076 2 P 0 ;0,1=246,2=270.000000
L 7.23541634 4.5076 7.23791732 4.50733337 2 P 0 ;0,1=246,2=270.000000
L 7.23791732 4.50733337 7.2400002 4.50626644 2 P 0 ;0,1=246,2=270.000000
L 7.2400002 4.50626644 7.24416673 4.50093327 2 P 0 ;0,1=246,2=270.000000
L 7.24416673 4.50093327 7.24708356 4.49853327 2 P 0 ;0,1=246,2=270.000000
L 7.24708356 4.49853327 7.25125089 4.49693317 2 P 0 ;0,1=246,2=270.000000
L 7.25125089 4.49693317 7.255 4.4963999 2 P 0 ;0,1=246,2=270.000000
L 7.255 4.4963999 7.255 4.5076 2 P 0 ;0,1=246,2=270.000000
L 7.255 4.5259997 7.23 4.5259997 2 P 0 ;0,1=246,2=270.000000
L 7.23 4.5259997 7.2349997 4.5227999 2 P 0 ;0,1=246,2=270.000000
L 7.255 4.5227999 7.255 4.52919951 2 P 0 ;0,1=246,2=270.000000
L 7.25208396 4.54546634 7.25416693 4.54733317 2 P 0 ;0,1=246,2=270.000000
L 7.25416693 4.54733317 7.255 4.54946654 2 P 0 ;0,1=246,2=270.000000
L 7.255 4.54946654 7.25416693 4.5515999 2 P 0 ;0,1=246,2=270.000000
L 7.25416693 4.5515999 7.25166742 4.55346663 2 P 0 ;0,1=246,2=270.000000
L 7.25166742 4.55346663 7.24791673 4.5548001 2 P 0 ;0,1=246,2=270.000000
L 7.24791673 4.5548001 7.24416673 4.55533337 2 P 0 ;0,1=246,2=270.000000
L 7.24416673 4.55533337 7.23958366 4.55533337 2 P 0 ;0,1=246,2=270.000000
L 7.23958366 4.55533337 7.23583366 4.5548001 2 P 0 ;0,1=246,2=270.000000
L 7.23583366 4.5548001 7.2325003 4.55346663 2 P 0 ;0,1=246,2=270.000000
L 7.2325003 4.55346663 7.23083317 4.55186644 2 P 0 ;0,1=246,2=270.000000
L 7.23083317 4.55186644 7.23 4.5499997 2 P 0 ;0,1=246,2=270.000000
L 7.23 4.5499997 7.23083317 4.54786634 2 P 0 ;0,1=246,2=270.000000
L 7.23083317 4.54786634 7.2325003 4.54626663 2 P 0 ;0,1=246,2=270.000000
L 7.2325003 4.54626663 7.2349997 4.5451998 2 P 0 ;0,1=246,2=270.000000
L 7.2349997 4.5451998 7.23833386 4.54466654 2 P 0 ;0,1=246,2=270.000000
L 7.23833386 4.54466654 7.2412499 4.5451998 2 P 0 ;0,1=246,2=270.000000
L 7.2412499 4.5451998 7.24416673 4.54653327 2 P 0 ;0,1=246,2=270.000000
L 7.24416673 4.54653327 7.24583386 4.54813346 2 P 0 ;0,1=246,2=270.000000
L 7.24583386 4.54813346 7.24625039 4.5499997 2 P 0 ;0,1=246,2=270.000000
L 7.24625039 4.5499997 7.24541722 4.55213307 2 P 0 ;0,1=246,2=270.000000
L 7.24541722 4.55213307 7.24333356 4.55373327 2 P 0 ;0,1=246,2=270.000000
L 7.24333356 4.55373327 7.23958366 4.55533337 2 P 0 ;0,1=246,2=270.000000
L 7.255 4.57346654 7.24958376 4.5739997 2 P 0 ;0,1=246,2=270.000000
L 7.24958376 4.5739997 7.24500069 4.5748 2 P 0 ;0,1=246,2=270.000000
L 7.24500069 4.5748 7.24083337 4.57586644 2 P 0 ;0,1=246,2=270.000000
L 7.24083337 4.57586644 7.2362502 4.5772 2 P 0 ;0,1=246,2=270.000000
L 7.2362502 4.5772 7.23 4.57933337 2 P 0 ;0,1=246,2=270.000000
L 7.23 4.57933337 7.23 4.56866654 2 P 0 ;0,1=246,2=270.000000
A 7.19511004 4.99851004 7.19511004 4.99851004 7.1926 4.99851004 1 P 0 N
L 7.13708366 4.93386663 7.13583317 4.93226644 2 P 0 ;0,1=247,2=270.000000
L 7.13583317 4.93226644 7.135 4.9304002 2 P 0 ;0,1=247,2=270.000000
L 7.135 4.9304002 7.135 4.92826683 2 P 0 ;0,1=247,2=270.000000
L 7.135 4.92826683 7.13625059 4.92586634 2 P 0 ;0,1=247,2=270.000000
L 7.13625059 4.92586634 7.13833346 4.9240001 2 P 0 ;0,1=247,2=270.000000
L 7.13833346 4.9240001 7.14083366 4.92266654 2 P 0 ;0,1=247,2=270.000000
L 7.14083366 4.92266654 7.1450002 4.92159961 2 P 0 ;0,1=247,2=270.000000
L 7.1450002 4.92159961 7.1487502 4.92133297 2 P 0 ;0,1=247,2=270.000000
L 7.1487502 4.92133297 7.1525001 4.92186673 2 P 0 ;0,1=247,2=270.000000
L 7.1525001 4.92186673 7.15500039 4.92266654 2 P 0 ;0,1=247,2=270.000000
L 7.15500039 4.92266654 7.15750059 4.92426663 2 P 0 ;0,1=247,2=270.000000
L 7.15750059 4.92426663 7.15916693 4.92613346 2 P 0 ;0,1=247,2=270.000000
L 7.15916693 4.92613346 7.16 4.9279997 2 P 0 ;0,1=247,2=270.000000
L 7.16 4.9279997 7.16 4.92986644 2 P 0 ;0,1=247,2=270.000000
L 7.16 4.92986644 7.15916693 4.93173327 2 P 0 ;0,1=247,2=270.000000
L 7.15916693 4.93173327 7.15791713 4.93333337 2 P 0 ;0,1=247,2=270.000000
L 7.15791713 4.93333337 7.15625089 4.93466693 2 P 0 ;0,1=247,2=270.000000
L 7.13916663 4.94693317 7.13666713 4.94853327 2 P 0 ;0,1=247,2=270.000000
L 7.13666713 4.94853327 7.13541663 4.9504 2 P 0 ;0,1=247,2=270.000000
L 7.13541663 4.9504 7.135 4.95253337 2 P 0 ;0,1=247,2=270.000000
L 7.135 4.95253337 7.13583317 4.9552 2 P 0 ;0,1=247,2=270.000000
L 7.13583317 4.9552 7.13791683 4.95706673 2 P 0 ;0,1=247,2=270.000000
L 7.13791683 4.95706673 7.14041634 4.9576 2 P 0 ;0,1=247,2=270.000000
L 7.14041634 4.9576 7.14291732 4.95733337 2 P 0 ;0,1=247,2=270.000000
L 7.14291732 4.95733337 7.1450002 4.95626644 2 P 0 ;0,1=247,2=270.000000
L 7.1450002 4.95626644 7.14916673 4.95093327 2 P 0 ;0,1=247,2=270.000000
L 7.14916673 4.95093327 7.15208356 4.94853327 2 P 0 ;0,1=247,2=270.000000
L 7.15208356 4.94853327 7.15625089 4.94693317 2 P 0 ;0,1=247,2=270.000000
L 7.15625089 4.94693317 7.16 4.9463999 2 P 0 ;0,1=247,2=270.000000
L 7.16 4.9463999 7.16 4.9576 2 P 0 ;0,1=247,2=270.000000
L 7.16 4.9759997 7.135 4.9759997 2 P 0 ;0,1=247,2=270.000000
L 7.135 4.9759997 7.1399997 4.9727999 2 P 0 ;0,1=247,2=270.000000
L 7.16 4.9727999 7.16 4.97919951 2 P 0 ;0,1=247,2=270.000000
L 7.15708396 4.99546634 7.15916693 4.99733317 2 P 0 ;0,1=247,2=270.000000
L 7.15916693 4.99733317 7.16 4.99946654 2 P 0 ;0,1=247,2=270.000000
L 7.16 4.99946654 7.15916693 5.0015999 2 P 0 ;0,1=247,2=270.000000
L 7.15916693 5.0015999 7.15666742 5.00346663 2 P 0 ;0,1=247,2=270.000000
L 7.15666742 5.00346663 7.15291673 5.0048001 2 P 0 ;0,1=247,2=270.000000
L 7.15291673 5.0048001 7.14916673 5.00533337 2 P 0 ;0,1=247,2=270.000000
L 7.14916673 5.00533337 7.14458366 5.00533337 2 P 0 ;0,1=247,2=270.000000
L 7.14458366 5.00533337 7.14083366 5.0048001 2 P 0 ;0,1=247,2=270.000000
L 7.14083366 5.0048001 7.1375003 5.00346663 2 P 0 ;0,1=247,2=270.000000
L 7.1375003 5.00346663 7.13583317 5.00186644 2 P 0 ;0,1=247,2=270.000000
L 7.13583317 5.00186644 7.135 4.9999997 2 P 0 ;0,1=247,2=270.000000
L 7.135 4.9999997 7.13583317 4.99786634 2 P 0 ;0,1=247,2=270.000000
L 7.13583317 4.99786634 7.1375003 4.99626663 2 P 0 ;0,1=247,2=270.000000
L 7.1375003 4.99626663 7.1399997 4.9951998 2 P 0 ;0,1=247,2=270.000000
L 7.1399997 4.9951998 7.14333386 4.99466654 2 P 0 ;0,1=247,2=270.000000
L 7.14333386 4.99466654 7.1462499 4.9951998 2 P 0 ;0,1=247,2=270.000000
L 7.1462499 4.9951998 7.14916673 4.99653327 2 P 0 ;0,1=247,2=270.000000
L 7.14916673 4.99653327 7.15083386 4.99813346 2 P 0 ;0,1=247,2=270.000000
L 7.15083386 4.99813346 7.15125039 4.9999997 2 P 0 ;0,1=247,2=270.000000
L 7.15125039 4.9999997 7.15041722 5.00213307 2 P 0 ;0,1=247,2=270.000000
L 7.15041722 5.00213307 7.14833356 5.00373327 2 P 0 ;0,1=247,2=270.000000
L 7.14833356 5.00373327 7.14458366 5.00533337 2 P 0 ;0,1=247,2=270.000000
L 7.14958406 5.01893317 7.14666654 5.0207999 2 P 0 ;0,1=247,2=270.000000
L 7.14666654 5.0207999 7.1450002 5.0224 2 P 0 ;0,1=247,2=270.000000
L 7.1450002 5.0224 7.14416703 5.02453337 2 P 0 ;0,1=247,2=270.000000
L 7.14416703 5.02453337 7.1450002 5.0264002 2 P 0 ;0,1=247,2=270.000000
L 7.1450002 5.0264002 7.14666654 5.02773327 2 P 0 ;0,1=247,2=270.000000
L 7.14666654 5.02773327 7.14916673 5.0288001 2 P 0 ;0,1=247,2=270.000000
L 7.14916673 5.0288001 7.15208356 5.02906673 2 P 0 ;0,1=247,2=270.000000
L 7.15208356 5.02906673 7.15458376 5.0288001 2 P 0 ;0,1=247,2=270.000000
L 7.15458376 5.0288001 7.15708396 5.02773327 2 P 0 ;0,1=247,2=270.000000
L 7.15708396 5.02773327 7.15916693 5.02613307 2 P 0 ;0,1=247,2=270.000000
L 7.15916693 5.02613307 7.16 5.02426683 2 P 0 ;0,1=247,2=270.000000
L 7.16 5.02426683 7.15916693 5.02213346 2 P 0 ;0,1=247,2=270.000000
L 7.15916693 5.02213346 7.15666742 5.02026663 2 P 0 ;0,1=247,2=270.000000
L 7.15666742 5.02026663 7.15291673 5.0191998 2 P 0 ;0,1=247,2=270.000000
L 7.15291673 5.0191998 7.1487502 5.01893317 2 P 0 ;0,1=247,2=270.000000
L 7.1487502 5.01893317 7.14333386 5.01946634 2 P 0 ;0,1=247,2=270.000000
L 7.14333386 5.01946634 7.14041634 5.02026663 2 P 0 ;0,1=247,2=270.000000
L 7.14041634 5.02026663 7.1375003 5.0215997 2 P 0 ;0,1=247,2=270.000000
L 7.1375003 5.0215997 7.13541663 5.02346654 2 P 0 ;0,1=247,2=270.000000
L 7.13541663 5.02346654 7.135 5.02533327 2 P 0 ;0,1=247,2=270.000000
L 7.135 5.02533327 7.13583317 5.0272 2 P 0 ;0,1=247,2=270.000000
L 7.13583317 5.0272 7.13791683 5.02853356 2 P 0 ;0,1=247,2=270.000000
A 1.24156998 4.64851004 1.24156998 4.64851004 1.23906004 4.64851004 1 P 0 N
L 1.22708366 4.48886663 1.22583317 4.48726644 2 P 0 ;0,1=248,2=270.000000
L 1.22583317 4.48726644 1.225 4.4854002 2 P 0 ;0,1=248,2=270.000000
L 1.225 4.4854002 1.225 4.48326683 2 P 0 ;0,1=248,2=270.000000
L 1.225 4.48326683 1.22625059 4.48086634 2 P 0 ;0,1=248,2=270.000000
L 1.22625059 4.48086634 1.22833346 4.4790001 2 P 0 ;0,1=248,2=270.000000
L 1.22833346 4.4790001 1.23083366 4.47766654 2 P 0 ;0,1=248,2=270.000000
L 1.23083366 4.47766654 1.2350002 4.47659961 2 P 0 ;0,1=248,2=270.000000
L 1.2350002 4.47659961 1.2387502 4.47633297 2 P 0 ;0,1=248,2=270.000000
L 1.2387502 4.47633297 1.2425001 4.47686673 2 P 0 ;0,1=248,2=270.000000
L 1.2425001 4.47686673 1.24500039 4.47766654 2 P 0 ;0,1=248,2=270.000000
L 1.24500039 4.47766654 1.24750059 4.47926663 2 P 0 ;0,1=248,2=270.000000
L 1.24750059 4.47926663 1.24916693 4.48113346 2 P 0 ;0,1=248,2=270.000000
L 1.24916693 4.48113346 1.25 4.4829997 2 P 0 ;0,1=248,2=270.000000
L 1.25 4.4829997 1.25 4.48486644 2 P 0 ;0,1=248,2=270.000000
L 1.25 4.48486644 1.24916693 4.48673327 2 P 0 ;0,1=248,2=270.000000
L 1.24916693 4.48673327 1.24791713 4.48833337 2 P 0 ;0,1=248,2=270.000000
L 1.24791713 4.48833337 1.24625089 4.48966693 2 P 0 ;0,1=248,2=270.000000
L 1.22916663 4.50193317 1.22666713 4.50353327 2 P 0 ;0,1=248,2=270.000000
L 1.22666713 4.50353327 1.22541663 4.5054 2 P 0 ;0,1=248,2=270.000000
L 1.22541663 4.5054 1.225 4.50753337 2 P 0 ;0,1=248,2=270.000000
L 1.225 4.50753337 1.22583317 4.5102 2 P 0 ;0,1=248,2=270.000000
L 1.22583317 4.5102 1.22791683 4.51206673 2 P 0 ;0,1=248,2=270.000000
L 1.22791683 4.51206673 1.23041634 4.5126 2 P 0 ;0,1=248,2=270.000000
L 1.23041634 4.5126 1.23291732 4.51233337 2 P 0 ;0,1=248,2=270.000000
L 1.23291732 4.51233337 1.2350002 4.51126644 2 P 0 ;0,1=248,2=270.000000
L 1.2350002 4.51126644 1.23916673 4.50593327 2 P 0 ;0,1=248,2=270.000000
L 1.23916673 4.50593327 1.24208356 4.50353327 2 P 0 ;0,1=248,2=270.000000
L 1.24208356 4.50353327 1.24625089 4.50193317 2 P 0 ;0,1=248,2=270.000000
L 1.24625089 4.50193317 1.25 4.5013999 2 P 0 ;0,1=248,2=270.000000
L 1.25 4.5013999 1.25 4.5126 2 P 0 ;0,1=248,2=270.000000
L 1.25 4.5309997 1.225 4.5309997 2 P 0 ;0,1=248,2=270.000000
L 1.225 4.5309997 1.2299997 4.5277999 2 P 0 ;0,1=248,2=270.000000
L 1.25 4.5277999 1.25 4.53419951 2 P 0 ;0,1=248,2=270.000000
L 1.24708396 4.55046634 1.24916693 4.55233317 2 P 0 ;0,1=248,2=270.000000
L 1.24916693 4.55233317 1.25 4.55446654 2 P 0 ;0,1=248,2=270.000000
L 1.25 4.55446654 1.24916693 4.5565999 2 P 0 ;0,1=248,2=270.000000
L 1.24916693 4.5565999 1.24666742 4.55846663 2 P 0 ;0,1=248,2=270.000000
L 1.24666742 4.55846663 1.24291673 4.5598001 2 P 0 ;0,1=248,2=270.000000
L 1.24291673 4.5598001 1.23916673 4.56033337 2 P 0 ;0,1=248,2=270.000000
L 1.23916673 4.56033337 1.23458366 4.56033337 2 P 0 ;0,1=248,2=270.000000
L 1.23458366 4.56033337 1.23083366 4.5598001 2 P 0 ;0,1=248,2=270.000000
L 1.23083366 4.5598001 1.2275003 4.55846663 2 P 0 ;0,1=248,2=270.000000
L 1.2275003 4.55846663 1.22583317 4.55686644 2 P 0 ;0,1=248,2=270.000000
L 1.22583317 4.55686644 1.225 4.5549997 2 P 0 ;0,1=248,2=270.000000
L 1.225 4.5549997 1.22583317 4.55286634 2 P 0 ;0,1=248,2=270.000000
L 1.22583317 4.55286634 1.2275003 4.55126663 2 P 0 ;0,1=248,2=270.000000
L 1.2275003 4.55126663 1.2299997 4.5501998 2 P 0 ;0,1=248,2=270.000000
L 1.2299997 4.5501998 1.23333386 4.54966654 2 P 0 ;0,1=248,2=270.000000
L 1.23333386 4.54966654 1.2362499 4.5501998 2 P 0 ;0,1=248,2=270.000000
L 1.2362499 4.5501998 1.23916673 4.55153327 2 P 0 ;0,1=248,2=270.000000
L 1.23916673 4.55153327 1.24083386 4.55313346 2 P 0 ;0,1=248,2=270.000000
L 1.24083386 4.55313346 1.24125039 4.5549997 2 P 0 ;0,1=248,2=270.000000
L 1.24125039 4.5549997 1.24041722 4.55713307 2 P 0 ;0,1=248,2=270.000000
L 1.24041722 4.55713307 1.23833356 4.55873327 2 P 0 ;0,1=248,2=270.000000
L 1.23833356 4.55873327 1.23458366 4.56033337 2 P 0 ;0,1=248,2=270.000000
L 1.24625089 4.57313327 1.24833376 4.57473297 2 P 0 ;0,1=248,2=270.000000
L 1.24833376 4.57473297 1.24958346 4.5765997 2 P 0 ;0,1=248,2=270.000000
L 1.24958346 4.5765997 1.25 4.5789997 2 P 0 ;0,1=248,2=270.000000
L 1.25 4.5789997 1.24916693 4.5814002 2 P 0 ;0,1=248,2=270.000000
L 1.24916693 4.5814002 1.24750059 4.58326644 2 P 0 ;0,1=248,2=270.000000
L 1.24750059 4.58326644 1.24458376 4.5846 2 P 0 ;0,1=248,2=270.000000
L 1.24458376 4.5846 1.24125039 4.58486663 2 P 0 ;0,1=248,2=270.000000
L 1.24125039 4.58486663 1.23791703 4.58433337 2 P 0 ;0,1=248,2=270.000000
L 1.23791703 4.58433337 1.23583337 4.5829998 2 P 0 ;0,1=248,2=270.000000
L 1.23583337 4.5829998 1.23416703 4.58113307 2 P 0 ;0,1=248,2=270.000000
L 1.23416703 4.58113307 1.23375049 4.57926683 2 P 0 ;0,1=248,2=270.000000
L 1.23375049 4.57926683 1.23416703 4.5774 2 P 0 ;0,1=248,2=270.000000
L 1.23416703 4.5774 1.23583337 4.5750001 2 P 0 ;0,1=248,2=270.000000
L 1.23583337 4.5750001 1.225 4.5757999 2 P 0 ;0,1=248,2=270.000000
L 1.225 4.5757999 1.225 4.5829998 2 P 0 ;0,1=248,2=270.000000
A 1.19156998 4.99851004 1.19156998 4.99851004 1.18906004 4.99851004 1 P 0 N
L 1.14208366 4.94386663 1.14083317 4.94226644 2 P 0 ;0,1=249,2=270.000000
L 1.14083317 4.94226644 1.14 4.9404002 2 P 0 ;0,1=249,2=270.000000
L 1.14 4.9404002 1.14 4.93826683 2 P 0 ;0,1=249,2=270.000000
L 1.14 4.93826683 1.14125059 4.93586634 2 P 0 ;0,1=249,2=270.000000
L 1.14125059 4.93586634 1.14333346 4.9340001 2 P 0 ;0,1=249,2=270.000000
L 1.14333346 4.9340001 1.14583366 4.93266654 2 P 0 ;0,1=249,2=270.000000
L 1.14583366 4.93266654 1.1500002 4.93159961 2 P 0 ;0,1=249,2=270.000000
L 1.1500002 4.93159961 1.1537502 4.93133297 2 P 0 ;0,1=249,2=270.000000
L 1.1537502 4.93133297 1.1575001 4.93186673 2 P 0 ;0,1=249,2=270.000000
L 1.1575001 4.93186673 1.16000039 4.93266654 2 P 0 ;0,1=249,2=270.000000
L 1.16000039 4.93266654 1.16250059 4.93426663 2 P 0 ;0,1=249,2=270.000000
L 1.16250059 4.93426663 1.16416693 4.93613346 2 P 0 ;0,1=249,2=270.000000
L 1.16416693 4.93613346 1.165 4.9379997 2 P 0 ;0,1=249,2=270.000000
L 1.165 4.9379997 1.165 4.93986644 2 P 0 ;0,1=249,2=270.000000
L 1.165 4.93986644 1.16416693 4.94173327 2 P 0 ;0,1=249,2=270.000000
L 1.16416693 4.94173327 1.16291713 4.94333337 2 P 0 ;0,1=249,2=270.000000
L 1.16291713 4.94333337 1.16125089 4.94466693 2 P 0 ;0,1=249,2=270.000000
L 1.14416663 4.95693317 1.14166713 4.95853327 2 P 0 ;0,1=249,2=270.000000
L 1.14166713 4.95853327 1.14041663 4.9604 2 P 0 ;0,1=249,2=270.000000
L 1.14041663 4.9604 1.14 4.96253337 2 P 0 ;0,1=249,2=270.000000
L 1.14 4.96253337 1.14083317 4.9652 2 P 0 ;0,1=249,2=270.000000
L 1.14083317 4.9652 1.14291683 4.96706673 2 P 0 ;0,1=249,2=270.000000
L 1.14291683 4.96706673 1.14541634 4.9676 2 P 0 ;0,1=249,2=270.000000
L 1.14541634 4.9676 1.14791732 4.96733337 2 P 0 ;0,1=249,2=270.000000
L 1.14791732 4.96733337 1.1500002 4.96626644 2 P 0 ;0,1=249,2=270.000000
L 1.1500002 4.96626644 1.15416673 4.96093327 2 P 0 ;0,1=249,2=270.000000
L 1.15416673 4.96093327 1.15708356 4.95853327 2 P 0 ;0,1=249,2=270.000000
L 1.15708356 4.95853327 1.16125089 4.95693317 2 P 0 ;0,1=249,2=270.000000
L 1.16125089 4.95693317 1.165 4.9563999 2 P 0 ;0,1=249,2=270.000000
L 1.165 4.9563999 1.165 4.9676 2 P 0 ;0,1=249,2=270.000000
L 1.165 4.9859997 1.14 4.9859997 2 P 0 ;0,1=249,2=270.000000
L 1.14 4.9859997 1.1449997 4.9827999 2 P 0 ;0,1=249,2=270.000000
L 1.165 4.9827999 1.165 4.98919951 2 P 0 ;0,1=249,2=270.000000
L 1.16208396 5.00546634 1.16416693 5.00733317 2 P 0 ;0,1=249,2=270.000000
L 1.16416693 5.00733317 1.165 5.00946654 2 P 0 ;0,1=249,2=270.000000
L 1.165 5.00946654 1.16416693 5.0115999 2 P 0 ;0,1=249,2=270.000000
L 1.16416693 5.0115999 1.16166742 5.01346663 2 P 0 ;0,1=249,2=270.000000
L 1.16166742 5.01346663 1.15791673 5.0148001 2 P 0 ;0,1=249,2=270.000000
L 1.15791673 5.0148001 1.15416673 5.01533337 2 P 0 ;0,1=249,2=270.000000
L 1.15416673 5.01533337 1.14958366 5.01533337 2 P 0 ;0,1=249,2=270.000000
L 1.14958366 5.01533337 1.14583366 5.0148001 2 P 0 ;0,1=249,2=270.000000
L 1.14583366 5.0148001 1.1425003 5.01346663 2 P 0 ;0,1=249,2=270.000000
L 1.1425003 5.01346663 1.14083317 5.01186644 2 P 0 ;0,1=249,2=270.000000
L 1.14083317 5.01186644 1.14 5.0099997 2 P 0 ;0,1=249,2=270.000000
L 1.14 5.0099997 1.14083317 5.00786634 2 P 0 ;0,1=249,2=270.000000
L 1.14083317 5.00786634 1.1425003 5.00626663 2 P 0 ;0,1=249,2=270.000000
L 1.1425003 5.00626663 1.1449997 5.0051998 2 P 0 ;0,1=249,2=270.000000
L 1.1449997 5.0051998 1.14833386 5.00466654 2 P 0 ;0,1=249,2=270.000000
L 1.14833386 5.00466654 1.1512499 5.0051998 2 P 0 ;0,1=249,2=270.000000
L 1.1512499 5.0051998 1.15416673 5.00653327 2 P 0 ;0,1=249,2=270.000000
L 1.15416673 5.00653327 1.15583386 5.00813346 2 P 0 ;0,1=249,2=270.000000
L 1.15583386 5.00813346 1.15625039 5.0099997 2 P 0 ;0,1=249,2=270.000000
L 1.15625039 5.0099997 1.15541722 5.01213307 2 P 0 ;0,1=249,2=270.000000
L 1.15541722 5.01213307 1.15333356 5.01373327 2 P 0 ;0,1=249,2=270.000000
L 1.15333356 5.01373327 1.14958366 5.01533337 2 P 0 ;0,1=249,2=270.000000
L 1.165 5.0372 1.14 5.0372 2 P 0 ;0,1=249,2=270.000000
L 1.14 5.0372 1.15791673 5.02733297 2 P 0 ;0,1=249,2=270.000000
L 1.15791673 5.02733297 1.15791673 5.04066693 2 P 0 ;0,1=249,2=270.000000
A 1.45751004 5.84 1.45751004 5.84 1.455 5.84 1 P 0 N
L 1.52208366 5.85886663 1.52083317 5.85726644 2 P 0 ;0,1=250,2=270.000000
L 1.52083317 5.85726644 1.52 5.8554002 2 P 0 ;0,1=250,2=270.000000
L 1.52 5.8554002 1.52 5.85326683 2 P 0 ;0,1=250,2=270.000000
L 1.52 5.85326683 1.52125059 5.85086634 2 P 0 ;0,1=250,2=270.000000
L 1.52125059 5.85086634 1.52333346 5.8490001 2 P 0 ;0,1=250,2=270.000000
L 1.52333346 5.8490001 1.52583366 5.84766654 2 P 0 ;0,1=250,2=270.000000
L 1.52583366 5.84766654 1.5300002 5.84659961 2 P 0 ;0,1=250,2=270.000000
L 1.5300002 5.84659961 1.5337502 5.84633297 2 P 0 ;0,1=250,2=270.000000
L 1.5337502 5.84633297 1.5375001 5.84686673 2 P 0 ;0,1=250,2=270.000000
L 1.5375001 5.84686673 1.54000039 5.84766654 2 P 0 ;0,1=250,2=270.000000
L 1.54000039 5.84766654 1.54250059 5.84926663 2 P 0 ;0,1=250,2=270.000000
L 1.54250059 5.84926663 1.54416693 5.85113346 2 P 0 ;0,1=250,2=270.000000
L 1.54416693 5.85113346 1.545 5.8529997 2 P 0 ;0,1=250,2=270.000000
L 1.545 5.8529997 1.545 5.85486644 2 P 0 ;0,1=250,2=270.000000
L 1.545 5.85486644 1.54416693 5.85673327 2 P 0 ;0,1=250,2=270.000000
L 1.54416693 5.85673327 1.54291713 5.85833337 2 P 0 ;0,1=250,2=270.000000
L 1.54291713 5.85833337 1.54125089 5.85966693 2 P 0 ;0,1=250,2=270.000000
L 1.52416663 5.87193317 1.52166713 5.87353327 2 P 0 ;0,1=250,2=270.000000
L 1.52166713 5.87353327 1.52041663 5.8754 2 P 0 ;0,1=250,2=270.000000
L 1.52041663 5.8754 1.52 5.87753337 2 P 0 ;0,1=250,2=270.000000
L 1.52 5.87753337 1.52083317 5.8802 2 P 0 ;0,1=250,2=270.000000
L 1.52083317 5.8802 1.52291683 5.88206673 2 P 0 ;0,1=250,2=270.000000
L 1.52291683 5.88206673 1.52541634 5.8826 2 P 0 ;0,1=250,2=270.000000
L 1.52541634 5.8826 1.52791732 5.88233337 2 P 0 ;0,1=250,2=270.000000
L 1.52791732 5.88233337 1.5300002 5.88126644 2 P 0 ;0,1=250,2=270.000000
L 1.5300002 5.88126644 1.53416673 5.87593327 2 P 0 ;0,1=250,2=270.000000
L 1.53416673 5.87593327 1.53708356 5.87353327 2 P 0 ;0,1=250,2=270.000000
L 1.53708356 5.87353327 1.54125089 5.87193317 2 P 0 ;0,1=250,2=270.000000
L 1.54125089 5.87193317 1.545 5.8713999 2 P 0 ;0,1=250,2=270.000000
L 1.545 5.8713999 1.545 5.8826 2 P 0 ;0,1=250,2=270.000000
L 1.545 5.9009997 1.52 5.9009997 2 P 0 ;0,1=250,2=270.000000
L 1.52 5.9009997 1.5249997 5.8977999 2 P 0 ;0,1=250,2=270.000000
L 1.545 5.8977999 1.545 5.90419951 2 P 0 ;0,1=250,2=270.000000
L 1.54208396 5.92046634 1.54416693 5.92233317 2 P 0 ;0,1=250,2=270.000000
L 1.54416693 5.92233317 1.545 5.92446654 2 P 0 ;0,1=250,2=270.000000
L 1.545 5.92446654 1.54416693 5.9265999 2 P 0 ;0,1=250,2=270.000000
L 1.54416693 5.9265999 1.54166742 5.92846663 2 P 0 ;0,1=250,2=270.000000
L 1.54166742 5.92846663 1.53791673 5.9298001 2 P 0 ;0,1=250,2=270.000000
L 1.53791673 5.9298001 1.53416673 5.93033337 2 P 0 ;0,1=250,2=270.000000
L 1.53416673 5.93033337 1.52958366 5.93033337 2 P 0 ;0,1=250,2=270.000000
L 1.52958366 5.93033337 1.52583366 5.9298001 2 P 0 ;0,1=250,2=270.000000
L 1.52583366 5.9298001 1.5225003 5.92846663 2 P 0 ;0,1=250,2=270.000000
L 1.5225003 5.92846663 1.52083317 5.92686644 2 P 0 ;0,1=250,2=270.000000
L 1.52083317 5.92686644 1.52 5.9249997 2 P 0 ;0,1=250,2=270.000000
L 1.52 5.9249997 1.52083317 5.92286634 2 P 0 ;0,1=250,2=270.000000
L 1.52083317 5.92286634 1.5225003 5.92126663 2 P 0 ;0,1=250,2=270.000000
L 1.5225003 5.92126663 1.5249997 5.9201998 2 P 0 ;0,1=250,2=270.000000
L 1.5249997 5.9201998 1.52833386 5.91966654 2 P 0 ;0,1=250,2=270.000000
L 1.52833386 5.91966654 1.5312499 5.9201998 2 P 0 ;0,1=250,2=270.000000
L 1.5312499 5.9201998 1.53416673 5.92153327 2 P 0 ;0,1=250,2=270.000000
L 1.53416673 5.92153327 1.53583386 5.92313346 2 P 0 ;0,1=250,2=270.000000
L 1.53583386 5.92313346 1.53625039 5.9249997 2 P 0 ;0,1=250,2=270.000000
L 1.53625039 5.9249997 1.53541722 5.92713307 2 P 0 ;0,1=250,2=270.000000
L 1.53541722 5.92713307 1.53333356 5.92873327 2 P 0 ;0,1=250,2=270.000000
L 1.53333356 5.92873327 1.52958366 5.93033337 2 P 0 ;0,1=250,2=270.000000
L 1.54000039 5.94313327 1.54291713 5.94473297 2 P 0 ;0,1=250,2=270.000000
L 1.54291713 5.94473297 1.54458346 5.94686634 2 P 0 ;0,1=250,2=270.000000
L 1.54458346 5.94686634 1.545 5.94926683 2 P 0 ;0,1=250,2=270.000000
L 1.545 5.94926683 1.54458346 5.9514002 2 P 0 ;0,1=250,2=270.000000
L 1.54458346 5.9514002 1.54250059 5.95353356 2 P 0 ;0,1=250,2=270.000000
L 1.54250059 5.95353356 1.54000039 5.95486663 2 P 0 ;0,1=250,2=270.000000
L 1.54000039 5.95486663 1.5375001 5.95513317 2 P 0 ;0,1=250,2=270.000000
L 1.5375001 5.95513317 1.53458406 5.9546 2 P 0 ;0,1=250,2=270.000000
L 1.53458406 5.9546 1.53250039 5.95273327 2 P 0 ;0,1=250,2=270.000000
L 1.53250039 5.95273327 1.53166654 5.95086644 2 P 0 ;0,1=250,2=270.000000
L 1.53166654 5.95086644 1.53166654 5.94846654 2 P 0 ;0,1=250,2=270.000000
L 1.53166654 5.95086644 1.53041673 5.95246663 2 P 0 ;0,1=250,2=270.000000
L 1.53041673 5.95246663 1.52833386 5.9538001 2 P 0 ;0,1=250,2=270.000000
L 1.52833386 5.9538001 1.52583366 5.95433337 2 P 0 ;0,1=250,2=270.000000
L 1.52583366 5.95433337 1.52333346 5.9538001 2 P 0 ;0,1=250,2=270.000000
L 1.52333346 5.9538001 1.52125059 5.95246663 2 P 0 ;0,1=250,2=270.000000
L 1.52125059 5.95246663 1.52 5.95006663 2 P 0 ;0,1=250,2=270.000000
L 1.52 5.95006663 1.52041663 5.94766663 2 P 0 ;0,1=250,2=270.000000
L 1.52041663 5.94766663 1.52208366 5.94526663 2 P 0 ;0,1=250,2=270.000000
A 1.35751004 5.84 1.35751004 5.84 1.355 5.84 1 P 0 N
L 1.25708366 5.85386663 1.25583317 5.85226644 2 P 0 ;0,1=251,2=270.000000
L 1.25583317 5.85226644 1.255 5.8504002 2 P 0 ;0,1=251,2=270.000000
L 1.255 5.8504002 1.255 5.84826683 2 P 0 ;0,1=251,2=270.000000
L 1.255 5.84826683 1.25625059 5.84586634 2 P 0 ;0,1=251,2=270.000000
L 1.25625059 5.84586634 1.25833346 5.8440001 2 P 0 ;0,1=251,2=270.000000
L 1.25833346 5.8440001 1.26083366 5.84266654 2 P 0 ;0,1=251,2=270.000000
L 1.26083366 5.84266654 1.2650002 5.84159961 2 P 0 ;0,1=251,2=270.000000
L 1.2650002 5.84159961 1.2687502 5.84133297 2 P 0 ;0,1=251,2=270.000000
L 1.2687502 5.84133297 1.2725001 5.84186673 2 P 0 ;0,1=251,2=270.000000
L 1.2725001 5.84186673 1.27500039 5.84266654 2 P 0 ;0,1=251,2=270.000000
L 1.27500039 5.84266654 1.27750059 5.84426663 2 P 0 ;0,1=251,2=270.000000
L 1.27750059 5.84426663 1.27916693 5.84613346 2 P 0 ;0,1=251,2=270.000000
L 1.27916693 5.84613346 1.28 5.8479997 2 P 0 ;0,1=251,2=270.000000
L 1.28 5.8479997 1.28 5.84986644 2 P 0 ;0,1=251,2=270.000000
L 1.28 5.84986644 1.27916693 5.85173327 2 P 0 ;0,1=251,2=270.000000
L 1.27916693 5.85173327 1.27791713 5.85333337 2 P 0 ;0,1=251,2=270.000000
L 1.27791713 5.85333337 1.27625089 5.85466693 2 P 0 ;0,1=251,2=270.000000
L 1.25916663 5.86693317 1.25666713 5.86853327 2 P 0 ;0,1=251,2=270.000000
L 1.25666713 5.86853327 1.25541663 5.8704 2 P 0 ;0,1=251,2=270.000000
L 1.25541663 5.8704 1.255 5.87253337 2 P 0 ;0,1=251,2=270.000000
L 1.255 5.87253337 1.25583317 5.8752 2 P 0 ;0,1=251,2=270.000000
L 1.25583317 5.8752 1.25791683 5.87706673 2 P 0 ;0,1=251,2=270.000000
L 1.25791683 5.87706673 1.26041634 5.8776 2 P 0 ;0,1=251,2=270.000000
L 1.26041634 5.8776 1.26291732 5.87733337 2 P 0 ;0,1=251,2=270.000000
L 1.26291732 5.87733337 1.2650002 5.87626644 2 P 0 ;0,1=251,2=270.000000
L 1.2650002 5.87626644 1.26916673 5.87093327 2 P 0 ;0,1=251,2=270.000000
L 1.26916673 5.87093327 1.27208356 5.86853327 2 P 0 ;0,1=251,2=270.000000
L 1.27208356 5.86853327 1.27625089 5.86693317 2 P 0 ;0,1=251,2=270.000000
L 1.27625089 5.86693317 1.28 5.8663999 2 P 0 ;0,1=251,2=270.000000
L 1.28 5.8663999 1.28 5.8776 2 P 0 ;0,1=251,2=270.000000
L 1.28 5.8959997 1.255 5.8959997 2 P 0 ;0,1=251,2=270.000000
L 1.255 5.8959997 1.2599997 5.8927999 2 P 0 ;0,1=251,2=270.000000
L 1.28 5.8927999 1.28 5.89919951 2 P 0 ;0,1=251,2=270.000000
L 1.27708396 5.91546634 1.27916693 5.91733317 2 P 0 ;0,1=251,2=270.000000
L 1.27916693 5.91733317 1.28 5.91946654 2 P 0 ;0,1=251,2=270.000000
L 1.28 5.91946654 1.27916693 5.9215999 2 P 0 ;0,1=251,2=270.000000
L 1.27916693 5.9215999 1.27666742 5.92346663 2 P 0 ;0,1=251,2=270.000000
L 1.27666742 5.92346663 1.27291673 5.9248001 2 P 0 ;0,1=251,2=270.000000
L 1.27291673 5.9248001 1.26916673 5.92533337 2 P 0 ;0,1=251,2=270.000000
L 1.26916673 5.92533337 1.26458366 5.92533337 2 P 0 ;0,1=251,2=270.000000
L 1.26458366 5.92533337 1.26083366 5.9248001 2 P 0 ;0,1=251,2=270.000000
L 1.26083366 5.9248001 1.2575003 5.92346663 2 P 0 ;0,1=251,2=270.000000
L 1.2575003 5.92346663 1.25583317 5.92186644 2 P 0 ;0,1=251,2=270.000000
L 1.25583317 5.92186644 1.255 5.9199997 2 P 0 ;0,1=251,2=270.000000
L 1.255 5.9199997 1.25583317 5.91786634 2 P 0 ;0,1=251,2=270.000000
L 1.25583317 5.91786634 1.2575003 5.91626663 2 P 0 ;0,1=251,2=270.000000
L 1.2575003 5.91626663 1.2599997 5.9151998 2 P 0 ;0,1=251,2=270.000000
L 1.2599997 5.9151998 1.26333386 5.91466654 2 P 0 ;0,1=251,2=270.000000
L 1.26333386 5.91466654 1.2662499 5.9151998 2 P 0 ;0,1=251,2=270.000000
L 1.2662499 5.9151998 1.26916673 5.91653327 2 P 0 ;0,1=251,2=270.000000
L 1.26916673 5.91653327 1.27083386 5.91813346 2 P 0 ;0,1=251,2=270.000000
L 1.27083386 5.91813346 1.27125039 5.9199997 2 P 0 ;0,1=251,2=270.000000
L 1.27125039 5.9199997 1.27041722 5.92213307 2 P 0 ;0,1=251,2=270.000000
L 1.27041722 5.92213307 1.26833356 5.92373327 2 P 0 ;0,1=251,2=270.000000
L 1.26833356 5.92373327 1.26458366 5.92533337 2 P 0 ;0,1=251,2=270.000000
L 1.28 5.9439997 1.255 5.9439997 2 P 0 ;0,1=251,2=270.000000
L 1.255 5.9439997 1.2599997 5.9407999 2 P 0 ;0,1=251,2=270.000000
L 1.28 5.9407999 1.28 5.94719951 2 P 0 ;0,1=251,2=270.000000
A 1.36251004 5.4 1.36251004 5.4 1.36 5.4 1 P 0 N
L 1.42608366 5.24086663 1.42483317 5.23926644 2 P 0 ;0,1=252,2=270.000000
L 1.42483317 5.23926644 1.424 5.2374002 2 P 0 ;0,1=252,2=270.000000
L 1.424 5.2374002 1.424 5.23526683 2 P 0 ;0,1=252,2=270.000000
L 1.424 5.23526683 1.42525059 5.23286634 2 P 0 ;0,1=252,2=270.000000
L 1.42525059 5.23286634 1.42733346 5.2310001 2 P 0 ;0,1=252,2=270.000000
L 1.42733346 5.2310001 1.42983366 5.22966654 2 P 0 ;0,1=252,2=270.000000
L 1.42983366 5.22966654 1.4340002 5.22859961 2 P 0 ;0,1=252,2=270.000000
L 1.4340002 5.22859961 1.4377502 5.22833297 2 P 0 ;0,1=252,2=270.000000
L 1.4377502 5.22833297 1.4415001 5.22886673 2 P 0 ;0,1=252,2=270.000000
L 1.4415001 5.22886673 1.44400039 5.22966654 2 P 0 ;0,1=252,2=270.000000
L 1.44400039 5.22966654 1.44650059 5.23126663 2 P 0 ;0,1=252,2=270.000000
L 1.44650059 5.23126663 1.44816693 5.23313346 2 P 0 ;0,1=252,2=270.000000
L 1.44816693 5.23313346 1.449 5.2349997 2 P 0 ;0,1=252,2=270.000000
L 1.449 5.2349997 1.449 5.23686644 2 P 0 ;0,1=252,2=270.000000
L 1.449 5.23686644 1.44816693 5.23873327 2 P 0 ;0,1=252,2=270.000000
L 1.44816693 5.23873327 1.44691713 5.24033337 2 P 0 ;0,1=252,2=270.000000
L 1.44691713 5.24033337 1.44525089 5.24166693 2 P 0 ;0,1=252,2=270.000000
L 1.42816663 5.25393317 1.42566713 5.25553327 2 P 0 ;0,1=252,2=270.000000
L 1.42566713 5.25553327 1.42441663 5.2574 2 P 0 ;0,1=252,2=270.000000
L 1.42441663 5.2574 1.424 5.25953337 2 P 0 ;0,1=252,2=270.000000
L 1.424 5.25953337 1.42483317 5.2622 2 P 0 ;0,1=252,2=270.000000
L 1.42483317 5.2622 1.42691683 5.26406673 2 P 0 ;0,1=252,2=270.000000
L 1.42691683 5.26406673 1.42941634 5.2646 2 P 0 ;0,1=252,2=270.000000
L 1.42941634 5.2646 1.43191732 5.26433337 2 P 0 ;0,1=252,2=270.000000
L 1.43191732 5.26433337 1.4340002 5.26326644 2 P 0 ;0,1=252,2=270.000000
L 1.4340002 5.26326644 1.43816673 5.25793327 2 P 0 ;0,1=252,2=270.000000
L 1.43816673 5.25793327 1.44108356 5.25553327 2 P 0 ;0,1=252,2=270.000000
L 1.44108356 5.25553327 1.44525089 5.25393317 2 P 0 ;0,1=252,2=270.000000
L 1.44525089 5.25393317 1.449 5.2533999 2 P 0 ;0,1=252,2=270.000000
L 1.449 5.2533999 1.449 5.2646 2 P 0 ;0,1=252,2=270.000000
L 1.449 5.2829997 1.424 5.2829997 2 P 0 ;0,1=252,2=270.000000
L 1.424 5.2829997 1.4289997 5.2797999 2 P 0 ;0,1=252,2=270.000000
L 1.449 5.2797999 1.449 5.28619951 2 P 0 ;0,1=252,2=270.000000
L 1.449 5.3069997 1.44858346 5.30886644 2 P 0 ;0,1=252,2=270.000000
L 1.44858346 5.30886644 1.44733376 5.3109998 2 P 0 ;0,1=252,2=270.000000
L 1.44733376 5.3109998 1.44525089 5.31233337 2 P 0 ;0,1=252,2=270.000000
L 1.44525089 5.31233337 1.44233327 5.31286663 2 P 0 ;0,1=252,2=270.000000
L 1.44233327 5.31286663 1.43941722 5.31233337 2 P 0 ;0,1=252,2=270.000000
L 1.43941722 5.31233337 1.43691703 5.31073327 2 P 0 ;0,1=252,2=270.000000
L 1.43691703 5.31073327 1.43566654 5.30833327 2 P 0 ;0,1=252,2=270.000000
L 1.43566654 5.30833327 1.43566654 5.30566663 2 P 0 ;0,1=252,2=270.000000
L 1.43566654 5.30566663 1.43483337 5.30406654 2 P 0 ;0,1=252,2=270.000000
L 1.43483337 5.30406654 1.43275049 5.30273297 2 P 0 ;0,1=252,2=270.000000
L 1.43275049 5.30273297 1.42983366 5.3021998 2 P 0 ;0,1=252,2=270.000000
L 1.42983366 5.3021998 1.42691683 5.3030001 2 P 0 ;0,1=252,2=270.000000
L 1.42691683 5.3030001 1.42483317 5.30486634 2 P 0 ;0,1=252,2=270.000000
L 1.42483317 5.30486634 1.424 5.3069997 2 P 0 ;0,1=252,2=270.000000
L 1.424 5.3069997 1.42483317 5.30913307 2 P 0 ;0,1=252,2=270.000000
L 1.42483317 5.30913307 1.42691683 5.3109998 2 P 0 ;0,1=252,2=270.000000
L 1.42691683 5.3109998 1.42983366 5.3118001 2 P 0 ;0,1=252,2=270.000000
L 1.42983366 5.3118001 1.43275049 5.31126644 2 P 0 ;0,1=252,2=270.000000
L 1.43275049 5.31126644 1.43483337 5.30993337 2 P 0 ;0,1=252,2=270.000000
L 1.43483337 5.30993337 1.43566654 5.30833327 2 P 0 ;0,1=252,2=270.000000
L 1.43566654 5.30833327 1.43566654 5.30566663 2 P 0 ;0,1=252,2=270.000000
L 1.43566654 5.30566663 1.43691703 5.30326663 2 P 0 ;0,1=252,2=270.000000
L 1.43691703 5.30326663 1.43941722 5.30166654 2 P 0 ;0,1=252,2=270.000000
L 1.43941722 5.30166654 1.44233327 5.30113327 2 P 0 ;0,1=252,2=270.000000
L 1.44233327 5.30113327 1.44525089 5.30166654 2 P 0 ;0,1=252,2=270.000000
L 1.44525089 5.30166654 1.44733376 5.3030001 2 P 0 ;0,1=252,2=270.000000
L 1.44733376 5.3030001 1.44858346 5.30513346 2 P 0 ;0,1=252,2=270.000000
L 1.44858346 5.30513346 1.449 5.3069997 2 P 0 ;0,1=252,2=270.000000
L 1.44608396 5.32646634 1.44816693 5.32833317 2 P 0 ;0,1=252,2=270.000000
L 1.44816693 5.32833317 1.449 5.33046654 2 P 0 ;0,1=252,2=270.000000
L 1.449 5.33046654 1.44816693 5.3325999 2 P 0 ;0,1=252,2=270.000000
L 1.44816693 5.3325999 1.44566742 5.33446663 2 P 0 ;0,1=252,2=270.000000
L 1.44566742 5.33446663 1.44191673 5.3358001 2 P 0 ;0,1=252,2=270.000000
L 1.44191673 5.3358001 1.43816673 5.33633337 2 P 0 ;0,1=252,2=270.000000
L 1.43816673 5.33633337 1.43358366 5.33633337 2 P 0 ;0,1=252,2=270.000000
L 1.43358366 5.33633337 1.42983366 5.3358001 2 P 0 ;0,1=252,2=270.000000
L 1.42983366 5.3358001 1.4265003 5.33446663 2 P 0 ;0,1=252,2=270.000000
L 1.4265003 5.33446663 1.42483317 5.33286644 2 P 0 ;0,1=252,2=270.000000
L 1.42483317 5.33286644 1.424 5.3309997 2 P 0 ;0,1=252,2=270.000000
L 1.424 5.3309997 1.42483317 5.32886634 2 P 0 ;0,1=252,2=270.000000
L 1.42483317 5.32886634 1.4265003 5.32726663 2 P 0 ;0,1=252,2=270.000000
L 1.4265003 5.32726663 1.4289997 5.3261998 2 P 0 ;0,1=252,2=270.000000
L 1.4289997 5.3261998 1.43233386 5.32566654 2 P 0 ;0,1=252,2=270.000000
L 1.43233386 5.32566654 1.4352499 5.3261998 2 P 0 ;0,1=252,2=270.000000
L 1.4352499 5.3261998 1.43816673 5.32753327 2 P 0 ;0,1=252,2=270.000000
L 1.43816673 5.32753327 1.43983386 5.32913346 2 P 0 ;0,1=252,2=270.000000
L 1.43983386 5.32913346 1.44025039 5.3309997 2 P 0 ;0,1=252,2=270.000000
L 1.44025039 5.3309997 1.43941722 5.33313307 2 P 0 ;0,1=252,2=270.000000
L 1.43941722 5.33313307 1.43733356 5.33473327 2 P 0 ;0,1=252,2=270.000000
L 1.43733356 5.33473327 1.43358366 5.33633337 2 P 0 ;0,1=252,2=270.000000
A 1.03251004 5.11 1.03251004 5.11 1.03 5.11 1 P 0 N
L 1.01708366 4.84386663 1.01583317 4.84226644 2 P 0 ;0,1=253,2=270.000000
L 1.01583317 4.84226644 1.015 4.8404002 2 P 0 ;0,1=253,2=270.000000
L 1.015 4.8404002 1.015 4.83826683 2 P 0 ;0,1=253,2=270.000000
L 1.015 4.83826683 1.01625059 4.83586634 2 P 0 ;0,1=253,2=270.000000
L 1.01625059 4.83586634 1.01833346 4.8340001 2 P 0 ;0,1=253,2=270.000000
L 1.01833346 4.8340001 1.02083366 4.83266654 2 P 0 ;0,1=253,2=270.000000
L 1.02083366 4.83266654 1.0250002 4.83159961 2 P 0 ;0,1=253,2=270.000000
L 1.0250002 4.83159961 1.0287502 4.83133297 2 P 0 ;0,1=253,2=270.000000
L 1.0287502 4.83133297 1.0325001 4.83186673 2 P 0 ;0,1=253,2=270.000000
L 1.0325001 4.83186673 1.03500039 4.83266654 2 P 0 ;0,1=253,2=270.000000
L 1.03500039 4.83266654 1.03750059 4.83426663 2 P 0 ;0,1=253,2=270.000000
L 1.03750059 4.83426663 1.03916693 4.83613346 2 P 0 ;0,1=253,2=270.000000
L 1.03916693 4.83613346 1.04 4.8379997 2 P 0 ;0,1=253,2=270.000000
L 1.04 4.8379997 1.04 4.83986644 2 P 0 ;0,1=253,2=270.000000
L 1.04 4.83986644 1.03916693 4.84173327 2 P 0 ;0,1=253,2=270.000000
L 1.03916693 4.84173327 1.03791713 4.84333337 2 P 0 ;0,1=253,2=270.000000
L 1.03791713 4.84333337 1.03625089 4.84466693 2 P 0 ;0,1=253,2=270.000000
L 1.01916663 4.85693317 1.01666713 4.85853327 2 P 0 ;0,1=253,2=270.000000
L 1.01666713 4.85853327 1.01541663 4.8604 2 P 0 ;0,1=253,2=270.000000
L 1.01541663 4.8604 1.015 4.86253337 2 P 0 ;0,1=253,2=270.000000
L 1.015 4.86253337 1.01583317 4.8652 2 P 0 ;0,1=253,2=270.000000
L 1.01583317 4.8652 1.01791683 4.86706673 2 P 0 ;0,1=253,2=270.000000
L 1.01791683 4.86706673 1.02041634 4.8676 2 P 0 ;0,1=253,2=270.000000
L 1.02041634 4.8676 1.02291732 4.86733337 2 P 0 ;0,1=253,2=270.000000
L 1.02291732 4.86733337 1.0250002 4.86626644 2 P 0 ;0,1=253,2=270.000000
L 1.0250002 4.86626644 1.02916673 4.86093327 2 P 0 ;0,1=253,2=270.000000
L 1.02916673 4.86093327 1.03208356 4.85853327 2 P 0 ;0,1=253,2=270.000000
L 1.03208356 4.85853327 1.03625089 4.85693317 2 P 0 ;0,1=253,2=270.000000
L 1.03625089 4.85693317 1.04 4.8563999 2 P 0 ;0,1=253,2=270.000000
L 1.04 4.8563999 1.04 4.8676 2 P 0 ;0,1=253,2=270.000000
L 1.04 4.8859997 1.015 4.8859997 2 P 0 ;0,1=253,2=270.000000
L 1.015 4.8859997 1.0199997 4.8827999 2 P 0 ;0,1=253,2=270.000000
L 1.04 4.8827999 1.04 4.88919951 2 P 0 ;0,1=253,2=270.000000
L 1.04 4.90946654 1.03458376 4.9099997 2 P 0 ;0,1=253,2=270.000000
L 1.03458376 4.9099997 1.03000069 4.9108 2 P 0 ;0,1=253,2=270.000000
L 1.03000069 4.9108 1.02583337 4.91186644 2 P 0 ;0,1=253,2=270.000000
L 1.02583337 4.91186644 1.0212502 4.9132 2 P 0 ;0,1=253,2=270.000000
L 1.0212502 4.9132 1.015 4.91533337 2 P 0 ;0,1=253,2=270.000000
L 1.015 4.91533337 1.015 4.90466654 2 P 0 ;0,1=253,2=270.000000
L 1.04 4.9372 1.015 4.9372 2 P 0 ;0,1=253,2=270.000000
L 1.015 4.9372 1.03291673 4.92733297 2 P 0 ;0,1=253,2=270.000000
L 1.03291673 4.92733297 1.03291673 4.94066693 2 P 0 ;0,1=253,2=270.000000
L 0.58298996 5.82436998 0.58298996 5.79563002 3 P 0 
L 0.58298996 5.79563002 0.45701004 5.79563002 3 P 0 
L 0.45701004 5.79563002 0.45701004 5.82436998 3 P 0 
L 0.45701004 5.82436998 0.58298996 5.82436998 3 P 0 
L 0.5029997 5.92 0.50086634 5.92041654 2 P 0 ;0,1=254,2=0.000000
L 0.50086634 5.92041654 0.4990001 5.92208287 2 P 0 ;0,1=254,2=0.000000
L 0.4990001 5.92208287 0.4973999 5.92458307 2 P 0 ;0,1=254,2=0.000000
L 0.4973999 5.92458307 0.49633297 5.9274999 2 P 0 ;0,1=254,2=0.000000
L 0.49633297 5.9274999 0.4957998 5.93083327 2 P 0 ;0,1=254,2=0.000000
L 0.4957998 5.93083327 0.4957998 5.93416663 2 P 0 ;0,1=254,2=0.000000
L 0.4957998 5.93416663 0.49633297 5.9375 2 P 0 ;0,1=254,2=0.000000
L 0.49633297 5.9375 0.4973999 5.94041683 2 P 0 ;0,1=254,2=0.000000
L 0.4973999 5.94041683 0.4990001 5.94291634 2 P 0 ;0,1=254,2=0.000000
L 0.4990001 5.94291634 0.50086634 5.94458337 2 P 0 ;0,1=254,2=0.000000
L 0.50086634 5.94458337 0.5029997 5.945 2 P 0 ;0,1=254,2=0.000000
L 0.5029997 5.945 0.50513307 5.94458337 2 P 0 ;0,1=254,2=0.000000
L 0.50513307 5.94458337 0.5069998 5.94291634 2 P 0 ;0,1=254,2=0.000000
L 0.5069998 5.94291634 0.5086 5.94041683 2 P 0 ;0,1=254,2=0.000000
L 0.5086 5.94041683 0.50966693 5.9375 2 P 0 ;0,1=254,2=0.000000
L 0.50966693 5.9375 0.5102001 5.93416663 2 P 0 ;0,1=254,2=0.000000
L 0.5102001 5.93416663 0.5102001 5.93083327 2 P 0 ;0,1=254,2=0.000000
L 0.5102001 5.93083327 0.50966693 5.9274999 2 P 0 ;0,1=254,2=0.000000
L 0.50966693 5.9274999 0.5086 5.92458307 2 P 0 ;0,1=254,2=0.000000
L 0.5086 5.92458307 0.5069998 5.92208287 2 P 0 ;0,1=254,2=0.000000
L 0.5069998 5.92208287 0.50513307 5.92041654 2 P 0 ;0,1=254,2=0.000000
L 0.50513307 5.92041654 0.5029997 5.92 2 P 0 ;0,1=254,2=0.000000
L 0.50513307 5.92666673 0.50833337 5.92 2 P 0 ;0,1=254,2=0.000000
L 0.5269997 5.92 0.5269997 5.945 2 P 0 ;0,1=254,2=0.000000
L 0.5269997 5.945 0.5237999 5.9400003 2 P 0 ;0,1=254,2=0.000000
L 0.5237999 5.92 0.53019951 5.92 2 P 0 ;0,1=254,2=0.000000
L 0.54713327 5.745 0.54713327 5.77 2 P 0 ;0,1=255,2=0.000000
L 0.54713327 5.77 0.55246654 5.77 2 P 0 ;0,1=255,2=0.000000
L 0.55246654 5.77 0.5545999 5.76874941 2 P 0 ;0,1=255,2=0.000000
L 0.5545999 5.76874941 0.5562 5.76708317 2 P 0 ;0,1=255,2=0.000000
L 0.5562 5.76708317 0.55753356 5.76458366 2 P 0 ;0,1=255,2=0.000000
L 0.55753356 5.76458366 0.5586 5.76166614 2 P 0 ;0,1=255,2=0.000000
L 0.5586 5.76166614 0.55886663 5.75749961 2 P 0 ;0,1=255,2=0.000000
L 0.55886663 5.75749961 0.5586 5.75333307 2 P 0 ;0,1=255,2=0.000000
L 0.5586 5.75333307 0.55753356 5.75041624 2 P 0 ;0,1=255,2=0.000000
L 0.55753356 5.75041624 0.5562 5.74791604 2 P 0 ;0,1=255,2=0.000000
L 0.5562 5.74791604 0.5545999 5.7462497 2 P 0 ;0,1=255,2=0.000000
L 0.5545999 5.7462497 0.55246654 5.745 2 P 0 ;0,1=255,2=0.000000
L 0.55246654 5.745 0.54713327 5.745 2 P 0 ;0,1=255,2=0.000000
L 0.5645999 5.89749961 0.56993346 5.89749961 2 P 0 ;0,1=256,2=0.000000
L 0.56993346 5.89749961 0.56993346 5.88999961 2 P 0 ;0,1=256,2=0.000000
L 0.56993346 5.88999961 0.56833337 5.88749941 2 P 0 ;0,1=256,2=0.000000
L 0.56833337 5.88749941 0.56646663 5.88583307 2 P 0 ;0,1=256,2=0.000000
L 0.56646663 5.88583307 0.5638 5.885 2 P 0 ;0,1=256,2=0.000000
L 0.5638 5.885 0.56113346 5.88583307 2 P 0 ;0,1=256,2=0.000000
L 0.56113346 5.88583307 0.55926663 5.88749941 2 P 0 ;0,1=256,2=0.000000
L 0.55926663 5.88749941 0.55766654 5.88999961 2 P 0 ;0,1=256,2=0.000000
L 0.55766654 5.88999961 0.55659961 5.89291644 2 P 0 ;0,1=256,2=0.000000
L 0.55659961 5.89291644 0.55606644 5.8962498 2 P 0 ;0,1=256,2=0.000000
L 0.55606644 5.8962498 0.55606644 5.89916663 2 P 0 ;0,1=256,2=0.000000
L 0.55606644 5.89916663 0.55659961 5.90166614 2 P 0 ;0,1=256,2=0.000000
L 0.55659961 5.90166614 0.55766654 5.90458366 2 P 0 ;0,1=256,2=0.000000
L 0.55766654 5.90458366 0.55926663 5.90708317 2 P 0 ;0,1=256,2=0.000000
L 0.55926663 5.90708317 0.56086634 5.90874941 2 P 0 ;0,1=256,2=0.000000
L 0.56086634 5.90874941 0.5629997 5.91 2 P 0 ;0,1=256,2=0.000000
L 0.5629997 5.91 0.56486644 5.91 2 P 0 ;0,1=256,2=0.000000
L 0.56486644 5.91 0.5669998 5.90916683 2 P 0 ;0,1=256,2=0.000000
L 0.5669998 5.90916683 0.5686 5.9074997 2 P 0 ;0,1=256,2=0.000000
L 0.4523999 5.88833258 0.45453327 5.8862497 2 P 0 ;0,1=257,2=0.000000
L 0.45453327 5.8862497 0.45693327 5.885 2 P 0 ;0,1=257,2=0.000000
L 0.45693327 5.885 0.45906663 5.885 2 P 0 ;0,1=257,2=0.000000
L 0.45906663 5.885 0.4612 5.8862497 2 P 0 ;0,1=257,2=0.000000
L 0.4612 5.8862497 0.4628001 5.88833258 2 P 0 ;0,1=257,2=0.000000
L 0.4628001 5.88833258 0.4636 5.8912501 2 P 0 ;0,1=257,2=0.000000
L 0.4636 5.8912501 0.46306673 5.89416614 2 P 0 ;0,1=257,2=0.000000
L 0.46306673 5.89416614 0.46173327 5.89666644 2 P 0 ;0,1=257,2=0.000000
L 0.46173327 5.89666644 0.45933327 5.89833346 2 P 0 ;0,1=257,2=0.000000
L 0.45933327 5.89833346 0.45613346 5.89916663 2 P 0 ;0,1=257,2=0.000000
L 0.45613346 5.89916663 0.45426663 5.90083297 2 P 0 ;0,1=257,2=0.000000
L 0.45426663 5.90083297 0.45346634 5.9037498 2 P 0 ;0,1=257,2=0.000000
L 0.45346634 5.9037498 0.4540001 5.90666654 2 P 0 ;0,1=257,2=0.000000
L 0.4540001 5.90666654 0.45533317 5.90874941 2 P 0 ;0,1=257,2=0.000000
L 0.45533317 5.90874941 0.4571999 5.91 2 P 0 ;0,1=257,2=0.000000
L 0.4571999 5.91 0.45906663 5.91 2 P 0 ;0,1=257,2=0.000000
L 0.45906663 5.91 0.46093337 5.90916683 2 P 0 ;0,1=257,2=0.000000
L 0.46093337 5.90916683 0.46253356 5.90708317 2 P 0 ;0,1=257,2=0.000000
L 5.11723996 5.58996004 5.11723996 5.59213002 3 P 0 
L 5.11723996 5.59213002 5.10936998 5.6 3 P 0 
L 5.10936998 5.6 5.11723996 5.60786998 3 P 0 
L 5.11723996 5.60786998 5.11723996 5.61003996 3 P 0 
L 5.11723996 5.61003996 5.02276004 5.61003996 3 P 0 
L 5.02276004 5.61003996 5.02276004 5.58996004 3 P 0 
L 5.02276004 5.58996004 5.11723996 5.58996004 3 P 0 
L 5.12786998 5.63543002 5.12786998 5.64723996 3 P 0 
L 5.12786998 5.64723996 5.11606004 5.63936998 3 P 0 
L 5.11606004 5.63936998 5.12786998 5.6315 3 P 0 
L 5.12786998 5.6315 5.12393996 5.64231998 3 P 0 
L 5.12393996 5.64231998 5.12 5.63936998 3 P 0 
L 5.12 5.63936998 5.12393996 5.63641998 3 P 0 
L 5.12393996 5.63641998 5.12393996 5.64231998 3 P 0 
L 5.12393996 5.64231998 5.12786998 5.63543002 3 P 0 
L 5.12786998 5.63543002 5.12786998 5.64723996 3 P 0 
L 5.12786998 5.64723996 5.12786998 5.6315 3 P 0 
L 5.12786998 5.6315 5.12786998 5.63543002 3 P 0 
L 5.11 5.71713327 5.12791673 5.71713327 2 P 0 ;0,1=258,2=270.000000
L 5.12791673 5.71713327 5.13166742 5.7181998 2 P 0 ;0,1=258,2=270.000000
L 5.13166742 5.7181998 5.13416693 5.72033317 2 P 0 ;0,1=258,2=270.000000
L 5.13416693 5.72033317 5.135 5.7229997 2 P 0 ;0,1=258,2=270.000000
L 5.135 5.7229997 5.13416693 5.72566673 2 P 0 ;0,1=258,2=270.000000
L 5.13416693 5.72566673 5.13166742 5.7278001 2 P 0 ;0,1=258,2=270.000000
L 5.13166742 5.7278001 5.12791673 5.72886663 2 P 0 ;0,1=258,2=270.000000
L 5.12791673 5.72886663 5.11 5.72886663 2 P 0 ;0,1=258,2=270.000000
L 5.135 5.7469997 5.11 5.7469997 2 P 0 ;0,1=258,2=270.000000
L 5.11 5.7469997 5.1149997 5.7437999 2 P 0 ;0,1=258,2=270.000000
L 5.135 5.7437999 5.135 5.75019951 2 P 0 ;0,1=258,2=270.000000
L 5.135 5.77046654 5.12958376 5.7709997 2 P 0 ;0,1=258,2=270.000000
L 5.12958376 5.7709997 5.12500069 5.7718 2 P 0 ;0,1=258,2=270.000000
L 5.12500069 5.7718 5.12083337 5.77286644 2 P 0 ;0,1=258,2=270.000000
L 5.12083337 5.77286644 5.1162502 5.7742 2 P 0 ;0,1=258,2=270.000000
L 5.1162502 5.7742 5.11 5.77633337 2 P 0 ;0,1=258,2=270.000000
L 5.11 5.77633337 5.11 5.76566654 2 P 0 ;0,1=258,2=270.000000
L 5.135 5.79446654 5.12958376 5.7949997 2 P 0 ;0,1=258,2=270.000000
L 5.12958376 5.7949997 5.12500069 5.7958 2 P 0 ;0,1=258,2=270.000000
L 5.12500069 5.7958 5.12083337 5.79686644 2 P 0 ;0,1=258,2=270.000000
L 5.12083337 5.79686644 5.1162502 5.7982 2 P 0 ;0,1=258,2=270.000000
L 5.1162502 5.7982 5.11 5.80033337 2 P 0 ;0,1=258,2=270.000000
L 5.11 5.80033337 5.11 5.78966654 2 P 0 ;0,1=258,2=270.000000
L 4.05003996 4.73723996 4.04786998 4.73723996 3 P 0 
L 4.04786998 4.73723996 4.04 4.72936998 3 P 0 
L 4.04 4.72936998 4.03213002 4.73723996 3 P 0 
L 4.03213002 4.73723996 4.02996004 4.73723996 3 P 0 
L 4.02996004 4.73723996 4.02996004 4.64276004 3 P 0 
L 4.02996004 4.64276004 4.05003996 4.64276004 3 P 0 
L 4.05003996 4.64276004 4.05003996 4.73723996 3 P 0 
L 4.00456998 4.74786998 3.99276004 4.74786998 3 P 0 
L 3.99276004 4.74786998 4.00063002 4.73606004 3 P 0 
L 4.00063002 4.73606004 4.0085 4.74786998 3 P 0 
L 4.0085 4.74786998 3.99768002 4.74393996 3 P 0 
L 3.99768002 4.74393996 4.00063002 4.74 3 P 0 
L 4.00063002 4.74 4.00358002 4.74393996 3 P 0 
L 4.00358002 4.74393996 3.99768002 4.74393996 3 P 0 
L 3.99768002 4.74393996 4.00456998 4.74786998 3 P 0 
L 4.00456998 4.74786998 3.99276004 4.74786998 3 P 0 
L 3.99276004 4.74786998 4.0085 4.74786998 3 P 0 
L 4.0085 4.74786998 4.00456998 4.74786998 3 P 0 
L 3.99213327 4.31 3.99213327 4.29208327 2 P 0 ;0,1=259,2=0.000000
L 3.99213327 4.29208327 3.9931998 4.28833258 2 P 0 ;0,1=259,2=0.000000
L 3.9931998 4.28833258 3.99533317 4.28583307 2 P 0 ;0,1=259,2=0.000000
L 3.99533317 4.28583307 3.9979997 4.285 2 P 0 ;0,1=259,2=0.000000
L 3.9979997 4.285 4.00066673 4.28583307 2 P 0 ;0,1=259,2=0.000000
L 4.00066673 4.28583307 4.0028001 4.28833258 2 P 0 ;0,1=259,2=0.000000
L 4.0028001 4.28833258 4.00386663 4.29208327 2 P 0 ;0,1=259,2=0.000000
L 4.00386663 4.29208327 4.00386663 4.31 2 P 0 ;0,1=259,2=0.000000
L 4.0219997 4.285 4.0219997 4.31 2 P 0 ;0,1=259,2=0.000000
L 4.0219997 4.31 4.0187999 4.3050003 2 P 0 ;0,1=259,2=0.000000
L 4.0187999 4.285 4.02519951 4.285 2 P 0 ;0,1=259,2=0.000000
L 4.04546654 4.285 4.0459997 4.29041624 2 P 0 ;0,1=259,2=0.000000
L 4.0459997 4.29041624 4.0468 4.29499931 2 P 0 ;0,1=259,2=0.000000
L 4.0468 4.29499931 4.04786644 4.29916663 2 P 0 ;0,1=259,2=0.000000
L 4.04786644 4.29916663 4.0492 4.3037498 2 P 0 ;0,1=259,2=0.000000
L 4.0492 4.3037498 4.05133337 4.31 2 P 0 ;0,1=259,2=0.000000
L 4.05133337 4.31 4.04066654 4.31 2 P 0 ;0,1=259,2=0.000000
L 4.06493317 4.29541594 4.0667999 4.29833346 2 P 0 ;0,1=259,2=0.000000
L 4.0667999 4.29833346 4.0684 4.2999998 2 P 0 ;0,1=259,2=0.000000
L 4.0684 4.2999998 4.07053337 4.30083297 2 P 0 ;0,1=259,2=0.000000
L 4.07053337 4.30083297 4.0724002 4.2999998 2 P 0 ;0,1=259,2=0.000000
L 4.0724002 4.2999998 4.07373327 4.29833346 2 P 0 ;0,1=259,2=0.000000
L 4.07373327 4.29833346 4.0748001 4.29583327 2 P 0 ;0,1=259,2=0.000000
L 4.0748001 4.29583327 4.07506673 4.29291644 2 P 0 ;0,1=259,2=0.000000
L 4.07506673 4.29291644 4.0748001 4.29041624 2 P 0 ;0,1=259,2=0.000000
L 4.0748001 4.29041624 4.07373327 4.28791604 2 P 0 ;0,1=259,2=0.000000
L 4.07373327 4.28791604 4.07213307 4.28583307 2 P 0 ;0,1=259,2=0.000000
L 4.07213307 4.28583307 4.07026683 4.285 2 P 0 ;0,1=259,2=0.000000
L 4.07026683 4.285 4.06813346 4.28583307 2 P 0 ;0,1=259,2=0.000000
L 4.06813346 4.28583307 4.06626663 4.28833258 2 P 0 ;0,1=259,2=0.000000
L 4.06626663 4.28833258 4.0651998 4.29208327 2 P 0 ;0,1=259,2=0.000000
L 4.0651998 4.29208327 4.06493317 4.2962498 2 P 0 ;0,1=259,2=0.000000
L 4.06493317 4.2962498 4.06546634 4.30166614 2 P 0 ;0,1=259,2=0.000000
L 4.06546634 4.30166614 4.06626663 4.30458366 2 P 0 ;0,1=259,2=0.000000
L 4.06626663 4.30458366 4.0675997 4.3074997 2 P 0 ;0,1=259,2=0.000000
L 4.0675997 4.3074997 4.06946654 4.30958337 2 P 0 ;0,1=259,2=0.000000
L 4.06946654 4.30958337 4.07133327 4.31 2 P 0 ;0,1=259,2=0.000000
L 4.07133327 4.31 4.0732 4.30916683 2 P 0 ;0,1=259,2=0.000000
L 4.0732 4.30916683 4.07453356 4.30708317 2 P 0 ;0,1=259,2=0.000000
L 10.04723996 4.67996004 10.04723996 4.68213002 3 P 0 
L 10.04723996 4.68213002 10.03936998 4.69 3 P 0 
L 10.03936998 4.69 10.04723996 4.69786998 3 P 0 
L 10.04723996 4.69786998 10.04723996 4.70003996 3 P 0 
L 10.04723996 4.70003996 9.95276004 4.70003996 3 P 0 
L 9.95276004 4.70003996 9.95276004 4.67996004 3 P 0 
L 9.95276004 4.67996004 10.04723996 4.67996004 3 P 0 
L 10.05786998 4.72543002 10.05786998 4.73723996 3 P 0 
L 10.05786998 4.73723996 10.04606004 4.72936998 3 P 0 
L 10.04606004 4.72936998 10.05786998 4.7215 3 P 0 
L 10.05786998 4.7215 10.05393996 4.73231998 3 P 0 
L 10.05393996 4.73231998 10.05 4.72936998 3 P 0 
L 10.05 4.72936998 10.05393996 4.72641998 3 P 0 
L 10.05393996 4.72641998 10.05393996 4.73231998 3 P 0 
L 10.05393996 4.73231998 10.05786998 4.72543002 3 P 0 
L 10.05786998 4.72543002 10.05786998 4.73723996 3 P 0 
L 10.05786998 4.73723996 10.05786998 4.7215 3 P 0 
L 10.05786998 4.7215 10.05786998 4.72543002 3 P 0 
L 9.95213327 4.8 9.95213327 4.78208327 2 P 0 ;0,1=260,2=0.000000
L 9.95213327 4.78208327 9.9531998 4.77833258 2 P 0 ;0,1=260,2=0.000000
L 9.9531998 4.77833258 9.95533317 4.77583307 2 P 0 ;0,1=260,2=0.000000
L 9.95533317 4.77583307 9.9579997 4.775 2 P 0 ;0,1=260,2=0.000000
L 9.9579997 4.775 9.96066673 4.77583307 2 P 0 ;0,1=260,2=0.000000
L 9.96066673 4.77583307 9.9628001 4.77833258 2 P 0 ;0,1=260,2=0.000000
L 9.9628001 4.77833258 9.96386663 4.78208327 2 P 0 ;0,1=260,2=0.000000
L 9.96386663 4.78208327 9.96386663 4.8 2 P 0 ;0,1=260,2=0.000000
L 9.9819997 4.775 9.9819997 4.8 2 P 0 ;0,1=260,2=0.000000
L 9.9819997 4.8 9.9787999 4.7950003 2 P 0 ;0,1=260,2=0.000000
L 9.9787999 4.775 9.98519951 4.775 2 P 0 ;0,1=260,2=0.000000
L 10.00546654 4.775 10.0059997 4.78041624 2 P 0 ;0,1=260,2=0.000000
L 10.0059997 4.78041624 10.0068 4.78499931 2 P 0 ;0,1=260,2=0.000000
L 10.0068 4.78499931 10.00786644 4.78916663 2 P 0 ;0,1=260,2=0.000000
L 10.00786644 4.78916663 10.0092 4.7937498 2 P 0 ;0,1=260,2=0.000000
L 10.0092 4.7937498 10.01133337 4.8 2 P 0 ;0,1=260,2=0.000000
L 10.01133337 4.8 10.00066654 4.8 2 P 0 ;0,1=260,2=0.000000
L 10.02413327 4.77874911 10.02573297 4.77666624 2 P 0 ;0,1=260,2=0.000000
L 10.02573297 4.77666624 10.0275997 4.77541654 2 P 0 ;0,1=260,2=0.000000
L 10.0275997 4.77541654 10.0299997 4.775 2 P 0 ;0,1=260,2=0.000000
L 10.0299997 4.775 10.0324002 4.77583307 2 P 0 ;0,1=260,2=0.000000
L 10.0324002 4.77583307 10.03426644 4.77749941 2 P 0 ;0,1=260,2=0.000000
L 10.03426644 4.77749941 10.0356 4.78041624 2 P 0 ;0,1=260,2=0.000000
L 10.0356 4.78041624 10.03586663 4.78374961 2 P 0 ;0,1=260,2=0.000000
L 10.03586663 4.78374961 10.03533337 4.78708297 2 P 0 ;0,1=260,2=0.000000
L 10.03533337 4.78708297 10.0339998 4.78916663 2 P 0 ;0,1=260,2=0.000000
L 10.0339998 4.78916663 10.03213307 4.79083297 2 P 0 ;0,1=260,2=0.000000
L 10.03213307 4.79083297 10.03026683 4.79124951 2 P 0 ;0,1=260,2=0.000000
L 10.03026683 4.79124951 10.0284 4.79083297 2 P 0 ;0,1=260,2=0.000000
L 10.0284 4.79083297 10.0260001 4.78916663 2 P 0 ;0,1=260,2=0.000000
L 10.0260001 4.78916663 10.0267999 4.8 2 P 0 ;0,1=260,2=0.000000
L 10.0267999 4.8 10.0339998 4.8 2 P 0 ;0,1=260,2=0.000000
L 3.71723996 4.61996004 3.71723996 4.62213002 3 P 0 
L 3.71723996 4.62213002 3.70936998 4.63 3 P 0 
L 3.70936998 4.63 3.71723996 4.63786998 3 P 0 
L 3.71723996 4.63786998 3.71723996 4.64003996 3 P 0 
L 3.71723996 4.64003996 3.62276004 4.64003996 3 P 0 
L 3.62276004 4.64003996 3.62276004 4.61996004 3 P 0 
L 3.62276004 4.61996004 3.71723996 4.61996004 3 P 0 
L 3.72786998 4.66543002 3.72786998 4.67723996 3 P 0 
L 3.72786998 4.67723996 3.71606004 4.66936998 3 P 0 
L 3.71606004 4.66936998 3.72786998 4.6615 3 P 0 
L 3.72786998 4.6615 3.72393996 4.67231998 3 P 0 
L 3.72393996 4.67231998 3.72 4.66936998 3 P 0 
L 3.72 4.66936998 3.72393996 4.66641998 3 P 0 
L 3.72393996 4.66641998 3.72393996 4.67231998 3 P 0 
L 3.72393996 4.67231998 3.72786998 4.66543002 3 P 0 
L 3.72786998 4.66543002 3.72786998 4.67723996 3 P 0 
L 3.72786998 4.67723996 3.72786998 4.6615 3 P 0 
L 3.72786998 4.6615 3.72786998 4.66543002 3 P 0 
L 3.58 4.58713327 3.59791673 4.58713327 2 P 0 ;0,1=261,2=270.000000
L 3.59791673 4.58713327 3.60166742 4.5881998 2 P 0 ;0,1=261,2=270.000000
L 3.60166742 4.5881998 3.60416693 4.59033317 2 P 0 ;0,1=261,2=270.000000
L 3.60416693 4.59033317 3.605 4.5929997 2 P 0 ;0,1=261,2=270.000000
L 3.605 4.5929997 3.60416693 4.59566673 2 P 0 ;0,1=261,2=270.000000
L 3.60416693 4.59566673 3.60166742 4.5978001 2 P 0 ;0,1=261,2=270.000000
L 3.60166742 4.5978001 3.59791673 4.59886663 2 P 0 ;0,1=261,2=270.000000
L 3.59791673 4.59886663 3.58 4.59886663 2 P 0 ;0,1=261,2=270.000000
L 3.605 4.6169997 3.58 4.6169997 2 P 0 ;0,1=261,2=270.000000
L 3.58 4.6169997 3.5849997 4.6137999 2 P 0 ;0,1=261,2=270.000000
L 3.605 4.6137999 3.605 4.62019951 2 P 0 ;0,1=261,2=270.000000
L 3.605 4.64046654 3.59958376 4.6409997 2 P 0 ;0,1=261,2=270.000000
L 3.59958376 4.6409997 3.59500069 4.6418 2 P 0 ;0,1=261,2=270.000000
L 3.59500069 4.6418 3.59083337 4.64286644 2 P 0 ;0,1=261,2=270.000000
L 3.59083337 4.64286644 3.5862502 4.6442 2 P 0 ;0,1=261,2=270.000000
L 3.5862502 4.6442 3.58 4.64633337 2 P 0 ;0,1=261,2=270.000000
L 3.58 4.64633337 3.58 4.63566654 2 P 0 ;0,1=261,2=270.000000
L 3.605 4.6682 3.58 4.6682 2 P 0 ;0,1=261,2=270.000000
L 3.58 4.6682 3.59791673 4.65833297 2 P 0 ;0,1=261,2=270.000000
L 3.59791673 4.65833297 3.59791673 4.67166693 2 P 0 ;0,1=261,2=270.000000
L 1.05786998 5.2815 1.05786998 5.28543002 3 P 0 
L 1.04723996 5.23996004 1.04723996 5.24213002 3 P 0 
L 1.04723996 5.24213002 1.03936998 5.25 3 P 0 
L 1.03936998 5.25 1.04723996 5.25786998 3 P 0 
L 1.04723996 5.25786998 1.04723996 5.26003996 3 P 0 
L 1.04723996 5.26003996 0.95276004 5.26003996 3 P 0 
L 0.95276004 5.26003996 0.95276004 5.23996004 3 P 0 
L 0.95276004 5.23996004 1.04723996 5.23996004 3 P 0 
L 1.05786998 5.28543002 1.05786998 5.29723996 3 P 0 
L 1.05786998 5.29723996 1.04606004 5.28936998 3 P 0 
L 1.04606004 5.28936998 1.05786998 5.2815 3 P 0 
L 1.05786998 5.2815 1.05393996 5.29231998 3 P 0 
L 1.05393996 5.29231998 1.05 5.28936998 3 P 0 
L 1.05 5.28936998 1.05393996 5.28641998 3 P 0 
L 1.05393996 5.28641998 1.05393996 5.29231998 3 P 0 
L 1.05393996 5.29231998 1.05786998 5.28543002 3 P 0 
L 1.05786998 5.28543002 1.05786998 5.29723996 3 P 0 
L 1.05786998 5.29723996 1.05786998 5.2815 3 P 0 
L 1.08 5.22713327 1.09791673 5.22713327 2 P 0 ;0,1=262,2=270.000000
L 1.09791673 5.22713327 1.10166742 5.2281998 2 P 0 ;0,1=262,2=270.000000
L 1.10166742 5.2281998 1.10416693 5.23033317 2 P 0 ;0,1=262,2=270.000000
L 1.10416693 5.23033317 1.105 5.2329997 2 P 0 ;0,1=262,2=270.000000
L 1.105 5.2329997 1.10416693 5.23566673 2 P 0 ;0,1=262,2=270.000000
L 1.10416693 5.23566673 1.10166742 5.2378001 2 P 0 ;0,1=262,2=270.000000
L 1.10166742 5.2378001 1.09791673 5.23886663 2 P 0 ;0,1=262,2=270.000000
L 1.09791673 5.23886663 1.08 5.23886663 2 P 0 ;0,1=262,2=270.000000
L 1.105 5.2569997 1.08 5.2569997 2 P 0 ;0,1=262,2=270.000000
L 1.08 5.2569997 1.0849997 5.2537999 2 P 0 ;0,1=262,2=270.000000
L 1.105 5.2537999 1.105 5.26019951 2 P 0 ;0,1=262,2=270.000000
L 1.09458406 5.27593317 1.09166654 5.2777999 2 P 0 ;0,1=262,2=270.000000
L 1.09166654 5.2777999 1.0900002 5.2794 2 P 0 ;0,1=262,2=270.000000
L 1.0900002 5.2794 1.08916703 5.28153337 2 P 0 ;0,1=262,2=270.000000
L 1.08916703 5.28153337 1.0900002 5.2834002 2 P 0 ;0,1=262,2=270.000000
L 1.0900002 5.2834002 1.09166654 5.28473327 2 P 0 ;0,1=262,2=270.000000
L 1.09166654 5.28473327 1.09416673 5.2858001 2 P 0 ;0,1=262,2=270.000000
L 1.09416673 5.2858001 1.09708356 5.28606673 2 P 0 ;0,1=262,2=270.000000
L 1.09708356 5.28606673 1.09958376 5.2858001 2 P 0 ;0,1=262,2=270.000000
L 1.09958376 5.2858001 1.10208396 5.28473327 2 P 0 ;0,1=262,2=270.000000
L 1.10208396 5.28473327 1.10416693 5.28313307 2 P 0 ;0,1=262,2=270.000000
L 1.10416693 5.28313307 1.105 5.28126683 2 P 0 ;0,1=262,2=270.000000
L 1.105 5.28126683 1.10416693 5.27913346 2 P 0 ;0,1=262,2=270.000000
L 1.10416693 5.27913346 1.10166742 5.27726663 2 P 0 ;0,1=262,2=270.000000
L 1.10166742 5.27726663 1.09791673 5.2761998 2 P 0 ;0,1=262,2=270.000000
L 1.09791673 5.2761998 1.0937502 5.27593317 2 P 0 ;0,1=262,2=270.000000
L 1.0937502 5.27593317 1.08833386 5.27646634 2 P 0 ;0,1=262,2=270.000000
L 1.08833386 5.27646634 1.08541634 5.27726663 2 P 0 ;0,1=262,2=270.000000
L 1.08541634 5.27726663 1.0825003 5.2785997 2 P 0 ;0,1=262,2=270.000000
L 1.0825003 5.2785997 1.08041663 5.28046654 2 P 0 ;0,1=262,2=270.000000
L 1.08041663 5.28046654 1.08 5.28233327 2 P 0 ;0,1=262,2=270.000000
L 1.08 5.28233327 1.08083317 5.2842 2 P 0 ;0,1=262,2=270.000000
L 1.08083317 5.2842 1.08291683 5.28553356 2 P 0 ;0,1=262,2=270.000000
L 1.10125089 5.29913327 1.10333376 5.30073297 2 P 0 ;0,1=262,2=270.000000
L 1.10333376 5.30073297 1.10458346 5.3025997 2 P 0 ;0,1=262,2=270.000000
L 1.10458346 5.3025997 1.105 5.3049997 2 P 0 ;0,1=262,2=270.000000
L 1.105 5.3049997 1.10416693 5.3074002 2 P 0 ;0,1=262,2=270.000000
L 1.10416693 5.3074002 1.10250059 5.30926644 2 P 0 ;0,1=262,2=270.000000
L 1.10250059 5.30926644 1.09958376 5.3106 2 P 0 ;0,1=262,2=270.000000
L 1.09958376 5.3106 1.09625039 5.31086663 2 P 0 ;0,1=262,2=270.000000
L 1.09625039 5.31086663 1.09291703 5.31033337 2 P 0 ;0,1=262,2=270.000000
L 1.09291703 5.31033337 1.09083337 5.3089998 2 P 0 ;0,1=262,2=270.000000
L 1.09083337 5.3089998 1.08916703 5.30713307 2 P 0 ;0,1=262,2=270.000000
L 1.08916703 5.30713307 1.08875049 5.30526683 2 P 0 ;0,1=262,2=270.000000
L 1.08875049 5.30526683 1.08916703 5.3034 2 P 0 ;0,1=262,2=270.000000
L 1.08916703 5.3034 1.09083337 5.3010001 2 P 0 ;0,1=262,2=270.000000
L 1.09083337 5.3010001 1.08 5.3017999 2 P 0 ;0,1=262,2=270.000000
L 1.08 5.3017999 1.08 5.3089998 2 P 0 ;0,1=262,2=270.000000
L 3.74213002 4.6485 3.74213002 4.64456998 3 P 0 
L 3.75276004 4.69003996 3.75276004 4.68786998 3 P 0 
L 3.75276004 4.68786998 3.76063002 4.68 3 P 0 
L 3.76063002 4.68 3.75276004 4.67213002 3 P 0 
L 3.75276004 4.67213002 3.75276004 4.66996004 3 P 0 
L 3.75276004 4.66996004 3.84723996 4.66996004 3 P 0 
L 3.84723996 4.66996004 3.84723996 4.69003996 3 P 0 
L 3.84723996 4.69003996 3.75276004 4.69003996 3 P 0 
L 3.74213002 4.64456998 3.74213002 4.63276004 3 P 0 
L 3.74213002 4.63276004 3.75393996 4.64063002 3 P 0 
L 3.75393996 4.64063002 3.74213002 4.6485 3 P 0 
L 3.74213002 4.6485 3.74606004 4.63768002 3 P 0 
L 3.74606004 4.63768002 3.75 4.64063002 3 P 0 
L 3.75 4.64063002 3.74606004 4.64358002 3 P 0 
L 3.74606004 4.64358002 3.74606004 4.63768002 3 P 0 
L 3.74606004 4.63768002 3.74213002 4.64456998 3 P 0 
L 3.74213002 4.64456998 3.74213002 4.63276004 3 P 0 
L 3.74213002 4.63276004 3.74213002 4.6485 3 P 0 
L 3.75213327 4.32 3.75213327 4.30208327 2 P 0 ;0,1=263,2=0.000000
L 3.75213327 4.30208327 3.7531998 4.29833258 2 P 0 ;0,1=263,2=0.000000
L 3.7531998 4.29833258 3.75533317 4.29583307 2 P 0 ;0,1=263,2=0.000000
L 3.75533317 4.29583307 3.7579997 4.295 2 P 0 ;0,1=263,2=0.000000
L 3.7579997 4.295 3.76066673 4.29583307 2 P 0 ;0,1=263,2=0.000000
L 3.76066673 4.29583307 3.7628001 4.29833258 2 P 0 ;0,1=263,2=0.000000
L 3.7628001 4.29833258 3.76386663 4.30208327 2 P 0 ;0,1=263,2=0.000000
L 3.76386663 4.30208327 3.76386663 4.32 2 P 0 ;0,1=263,2=0.000000
L 3.7819997 4.295 3.7819997 4.32 2 P 0 ;0,1=263,2=0.000000
L 3.7819997 4.32 3.7787999 4.3150003 2 P 0 ;0,1=263,2=0.000000
L 3.7787999 4.295 3.78519951 4.295 2 P 0 ;0,1=263,2=0.000000
L 3.80546654 4.295 3.8059997 4.30041624 2 P 0 ;0,1=263,2=0.000000
L 3.8059997 4.30041624 3.8068 4.30499931 2 P 0 ;0,1=263,2=0.000000
L 3.8068 4.30499931 3.80786644 4.30916663 2 P 0 ;0,1=263,2=0.000000
L 3.80786644 4.30916663 3.8092 4.3137498 2 P 0 ;0,1=263,2=0.000000
L 3.8092 4.3137498 3.81133337 4.32 2 P 0 ;0,1=263,2=0.000000
L 3.81133337 4.32 3.80066654 4.32 2 P 0 ;0,1=263,2=0.000000
L 3.82413327 4.29999961 3.82573297 4.29708287 2 P 0 ;0,1=263,2=0.000000
L 3.82573297 4.29708287 3.82786634 4.29541654 2 P 0 ;0,1=263,2=0.000000
L 3.82786634 4.29541654 3.83026683 4.295 2 P 0 ;0,1=263,2=0.000000
L 3.83026683 4.295 3.8324002 4.29541654 2 P 0 ;0,1=263,2=0.000000
L 3.8324002 4.29541654 3.83453356 4.29749941 2 P 0 ;0,1=263,2=0.000000
L 3.83453356 4.29749941 3.83586663 4.29999961 2 P 0 ;0,1=263,2=0.000000
L 3.83586663 4.29999961 3.83613317 4.3024999 2 P 0 ;0,1=263,2=0.000000
L 3.83613317 4.3024999 3.8356 4.30541594 2 P 0 ;0,1=263,2=0.000000
L 3.8356 4.30541594 3.83373327 4.30749961 2 P 0 ;0,1=263,2=0.000000
L 3.83373327 4.30749961 3.83186644 4.30833346 2 P 0 ;0,1=263,2=0.000000
L 3.83186644 4.30833346 3.82946654 4.30833346 2 P 0 ;0,1=263,2=0.000000
L 3.83186644 4.30833346 3.83346663 4.30958327 2 P 0 ;0,1=263,2=0.000000
L 3.83346663 4.30958327 3.8348001 4.31166614 2 P 0 ;0,1=263,2=0.000000
L 3.8348001 4.31166614 3.83533337 4.31416634 2 P 0 ;0,1=263,2=0.000000
L 3.83533337 4.31416634 3.8348001 4.31666654 2 P 0 ;0,1=263,2=0.000000
L 3.8348001 4.31666654 3.83346663 4.31874941 2 P 0 ;0,1=263,2=0.000000
L 3.83346663 4.31874941 3.83106663 4.32 2 P 0 ;0,1=263,2=0.000000
L 3.83106663 4.32 3.82866663 4.31958337 2 P 0 ;0,1=263,2=0.000000
L 3.82866663 4.31958337 3.82626663 4.31791634 2 P 0 ;0,1=263,2=0.000000
L 0.86528002 5.15835 0.77471998 5.15835 3 P 0 
L 0.77471998 5.15835 0.77471998 5.16818996 3 P 0 
L 0.77471998 5.16818996 0.78653996 5.18 3 P 0 
L 0.78653996 5.18 0.77471998 5.19181004 3 P 0 
L 0.77471998 5.19181004 0.77471998 5.20165 3 P 0 
L 0.77471998 5.20165 0.86528002 5.20165 3 P 0 
L 0.86528002 5.20165 0.86528002 5.16031004 3 P 0 
L 0.77668996 5.12488002 0.76685 5.11701004 3 P 0 
L 0.76685 5.11701004 0.76685 5.13276004 3 P 0 
L 0.76685 5.13276004 0.77668996 5.12488002 3 P 0 
L 0.77668996 5.12488002 0.77078996 5.12488002 3 P 0 
L 0.75 5.24213327 0.76791673 5.24213327 2 P 0 ;0,1=264,2=270.000000
L 0.76791673 5.24213327 0.77166742 5.2431998 2 P 0 ;0,1=264,2=270.000000
L 0.77166742 5.2431998 0.77416693 5.24533317 2 P 0 ;0,1=264,2=270.000000
L 0.77416693 5.24533317 0.775 5.2479997 2 P 0 ;0,1=264,2=270.000000
L 0.775 5.2479997 0.77416693 5.25066673 2 P 0 ;0,1=264,2=270.000000
L 0.77416693 5.25066673 0.77166742 5.2528001 2 P 0 ;0,1=264,2=270.000000
L 0.77166742 5.2528001 0.76791673 5.25386663 2 P 0 ;0,1=264,2=270.000000
L 0.76791673 5.25386663 0.75 5.25386663 2 P 0 ;0,1=264,2=270.000000
L 0.775 5.2719997 0.75 5.2719997 2 P 0 ;0,1=264,2=270.000000
L 0.75 5.2719997 0.7549997 5.2687999 2 P 0 ;0,1=264,2=270.000000
L 0.775 5.2687999 0.775 5.27519951 2 P 0 ;0,1=264,2=270.000000
L 0.76458406 5.29093317 0.76166654 5.2927999 2 P 0 ;0,1=264,2=270.000000
L 0.76166654 5.2927999 0.7600002 5.2944 2 P 0 ;0,1=264,2=270.000000
L 0.7600002 5.2944 0.75916703 5.29653337 2 P 0 ;0,1=264,2=270.000000
L 0.75916703 5.29653337 0.7600002 5.2984002 2 P 0 ;0,1=264,2=270.000000
L 0.7600002 5.2984002 0.76166654 5.29973327 2 P 0 ;0,1=264,2=270.000000
L 0.76166654 5.29973327 0.76416673 5.3008001 2 P 0 ;0,1=264,2=270.000000
L 0.76416673 5.3008001 0.76708356 5.30106673 2 P 0 ;0,1=264,2=270.000000
L 0.76708356 5.30106673 0.76958376 5.3008001 2 P 0 ;0,1=264,2=270.000000
L 0.76958376 5.3008001 0.77208396 5.29973327 2 P 0 ;0,1=264,2=270.000000
L 0.77208396 5.29973327 0.77416693 5.29813307 2 P 0 ;0,1=264,2=270.000000
L 0.77416693 5.29813307 0.775 5.29626683 2 P 0 ;0,1=264,2=270.000000
L 0.775 5.29626683 0.77416693 5.29413346 2 P 0 ;0,1=264,2=270.000000
L 0.77416693 5.29413346 0.77166742 5.29226663 2 P 0 ;0,1=264,2=270.000000
L 0.77166742 5.29226663 0.76791673 5.2911998 2 P 0 ;0,1=264,2=270.000000
L 0.76791673 5.2911998 0.7637502 5.29093317 2 P 0 ;0,1=264,2=270.000000
L 0.7637502 5.29093317 0.75833386 5.29146634 2 P 0 ;0,1=264,2=270.000000
L 0.75833386 5.29146634 0.75541634 5.29226663 2 P 0 ;0,1=264,2=270.000000
L 0.75541634 5.29226663 0.7525003 5.2935997 2 P 0 ;0,1=264,2=270.000000
L 0.7525003 5.2935997 0.75041663 5.29546654 2 P 0 ;0,1=264,2=270.000000
L 0.75041663 5.29546654 0.75 5.29733327 2 P 0 ;0,1=264,2=270.000000
L 0.75 5.29733327 0.75083317 5.2992 2 P 0 ;0,1=264,2=270.000000
L 0.75083317 5.2992 0.75291683 5.30053356 2 P 0 ;0,1=264,2=270.000000
L 0.775 5.3232 0.75 5.3232 2 P 0 ;0,1=264,2=270.000000
L 0.75 5.3232 0.76791673 5.31333297 2 P 0 ;0,1=264,2=270.000000
L 0.76791673 5.31333297 0.76791673 5.32666693 2 P 0 ;0,1=264,2=270.000000
A 1.23206998 4.79583002 1.23206998 4.79583002 1.22606998 4.79583002 6 P 0 N
L 1.2241 4.84308002 1.35401998 4.84308002 3 P 0 
L 1.35401998 4.84308002 1.35401998 4.91393996 3 P 0 
L 1.35401998 4.91393996 1.2241 4.91393996 3 P 0 
L 1.2241 4.91393996 1.2241 4.89426004 3 P 0 
L 1.2241 4.89426004 1.23985 4.87851004 3 P 0 
L 1.23985 4.87851004 1.2241 4.86276004 3 P 0 
L 1.2241 4.86276004 1.2241 4.84308002 3 P 0 
L 1.175 4.79213327 1.19291673 4.79213327 2 P 0 ;0,1=265,2=270.000000
L 1.19291673 4.79213327 1.19666742 4.7931998 2 P 0 ;0,1=265,2=270.000000
L 1.19666742 4.7931998 1.19916693 4.79533317 2 P 0 ;0,1=265,2=270.000000
L 1.19916693 4.79533317 1.2 4.7979997 2 P 0 ;0,1=265,2=270.000000
L 1.2 4.7979997 1.19916693 4.80066673 2 P 0 ;0,1=265,2=270.000000
L 1.19916693 4.80066673 1.19666742 4.8028001 2 P 0 ;0,1=265,2=270.000000
L 1.19666742 4.8028001 1.19291673 4.80386663 2 P 0 ;0,1=265,2=270.000000
L 1.19291673 4.80386663 1.175 4.80386663 2 P 0 ;0,1=265,2=270.000000
L 1.2 4.8219997 1.175 4.8219997 2 P 0 ;0,1=265,2=270.000000
L 1.175 4.8219997 1.1799997 4.8187999 2 P 0 ;0,1=265,2=270.000000
L 1.2 4.8187999 1.2 4.82519951 2 P 0 ;0,1=265,2=270.000000
L 1.2 4.84546654 1.19458376 4.8459997 2 P 0 ;0,1=265,2=270.000000
L 1.19458376 4.8459997 1.19000069 4.8468 2 P 0 ;0,1=265,2=270.000000
L 1.19000069 4.8468 1.18583337 4.84786644 2 P 0 ;0,1=265,2=270.000000
L 1.18583337 4.84786644 1.1812502 4.8492 2 P 0 ;0,1=265,2=270.000000
L 1.1812502 4.8492 1.175 4.85133337 2 P 0 ;0,1=265,2=270.000000
L 1.175 4.85133337 1.175 4.84066654 2 P 0 ;0,1=265,2=270.000000
L 1.175 4.8699997 1.17583317 4.86786634 2 P 0 ;0,1=265,2=270.000000
L 1.17583317 4.86786634 1.17791683 4.86626663 2 P 0 ;0,1=265,2=270.000000
L 1.17791683 4.86626663 1.18041634 4.8651998 2 P 0 ;0,1=265,2=270.000000
L 1.18041634 4.8651998 1.18375049 4.8643999 2 P 0 ;0,1=265,2=270.000000
L 1.18375049 4.8643999 1.18750039 4.86413327 2 P 0 ;0,1=265,2=270.000000
L 1.18750039 4.86413327 1.19125039 4.8643999 2 P 0 ;0,1=265,2=270.000000
L 1.19125039 4.8643999 1.19458376 4.8651998 2 P 0 ;0,1=265,2=270.000000
L 1.19458376 4.8651998 1.19708396 4.86626663 2 P 0 ;0,1=265,2=270.000000
L 1.19708396 4.86626663 1.19916693 4.86786634 2 P 0 ;0,1=265,2=270.000000
L 1.19916693 4.86786634 1.2 4.8699997 2 P 0 ;0,1=265,2=270.000000
L 1.2 4.8699997 1.19916693 4.87213307 2 P 0 ;0,1=265,2=270.000000
L 1.19916693 4.87213307 1.19708396 4.87373327 2 P 0 ;0,1=265,2=270.000000
L 1.19708396 4.87373327 1.19458376 4.8748001 2 P 0 ;0,1=265,2=270.000000
L 1.19458376 4.8748001 1.19125039 4.8756 2 P 0 ;0,1=265,2=270.000000
L 1.19125039 4.8756 1.18750039 4.87586663 2 P 0 ;0,1=265,2=270.000000
L 1.18750039 4.87586663 1.18375049 4.8756 2 P 0 ;0,1=265,2=270.000000
L 1.18375049 4.8756 1.18041634 4.8748001 2 P 0 ;0,1=265,2=270.000000
L 1.18041634 4.8748001 1.17791683 4.87373327 2 P 0 ;0,1=265,2=270.000000
L 1.17791683 4.87373327 1.17583317 4.87213307 2 P 0 ;0,1=265,2=270.000000
L 1.17583317 4.87213307 1.175 4.8699997 2 P 0 ;0,1=265,2=270.000000
A 7.23561004 4.79583002 7.23561004 4.79583002 7.22961004 4.79583002 6 P 0 N
L 7.22763996 4.84308002 7.35756004 4.84308002 3 P 0 
L 7.35756004 4.84308002 7.35756004 4.91393996 3 P 0 
L 7.35756004 4.91393996 7.22763996 4.91393996 3 P 0 
L 7.22763996 4.91393996 7.22763996 4.89426004 3 P 0 
L 7.22763996 4.89426004 7.24338996 4.87851004 3 P 0 
L 7.24338996 4.87851004 7.22763996 4.86276004 3 P 0 
L 7.22763996 4.86276004 7.22763996 4.84308002 3 P 0 
L 7.175 4.78213327 7.19291673 4.78213327 2 P 0 ;0,1=266,2=270.000000
L 7.19291673 4.78213327 7.19666742 4.7831998 2 P 0 ;0,1=266,2=270.000000
L 7.19666742 4.7831998 7.19916693 4.78533317 2 P 0 ;0,1=266,2=270.000000
L 7.19916693 4.78533317 7.2 4.7879997 2 P 0 ;0,1=266,2=270.000000
L 7.2 4.7879997 7.19916693 4.79066673 2 P 0 ;0,1=266,2=270.000000
L 7.19916693 4.79066673 7.19666742 4.7928001 2 P 0 ;0,1=266,2=270.000000
L 7.19666742 4.7928001 7.19291673 4.79386663 2 P 0 ;0,1=266,2=270.000000
L 7.19291673 4.79386663 7.175 4.79386663 2 P 0 ;0,1=266,2=270.000000
L 7.2 4.8119997 7.175 4.8119997 2 P 0 ;0,1=266,2=270.000000
L 7.175 4.8119997 7.1799997 4.8087999 2 P 0 ;0,1=266,2=270.000000
L 7.2 4.8087999 7.2 4.81519951 2 P 0 ;0,1=266,2=270.000000
L 7.2 4.83546654 7.19458376 4.8359997 2 P 0 ;0,1=266,2=270.000000
L 7.19458376 4.8359997 7.19000069 4.8368 2 P 0 ;0,1=266,2=270.000000
L 7.19000069 4.8368 7.18583337 4.83786644 2 P 0 ;0,1=266,2=270.000000
L 7.18583337 4.83786644 7.1812502 4.8392 2 P 0 ;0,1=266,2=270.000000
L 7.1812502 4.8392 7.175 4.84133337 2 P 0 ;0,1=266,2=270.000000
L 7.175 4.84133337 7.175 4.83066654 2 P 0 ;0,1=266,2=270.000000
L 7.2 4.8599997 7.175 4.8599997 2 P 0 ;0,1=266,2=270.000000
L 7.175 4.8599997 7.1799997 4.8567999 2 P 0 ;0,1=266,2=270.000000
L 7.2 4.8567999 7.2 4.86319951 2 P 0 ;0,1=266,2=270.000000
L 3.58478996 0.62203996 3.5716 0.62203996 3 P 0 
L 3.5716 0.62203996 3.5716 0.41416004 3 P 0 
L 3.5716 0.41416004 3.58478996 0.41416004 3 P 0 
L 3.83518996 0.62203996 3.84838002 0.62203996 3 P 0 
L 3.84838002 0.62203996 3.84838002 0.41416004 3 P 0 
L 3.84838002 0.41416004 3.83518996 0.41416004 3 P 0 
L 3.60998996 0.67813996 3.5903 0.7057 3 P 0 
L 3.5903 0.7057 3.62968002 0.7057 3 P 0 
L 3.62968002 0.7057 3.60998996 0.67813996 3 P 0 
L 3.60998996 0.67813996 3.59818002 0.70176004 3 P 0 
L 3.59818002 0.70176004 3.6218 0.70176004 3 P 0 
L 3.6218 0.70176004 3.60998996 0.67813996 3 P 0 
L 3.60998996 0.67813996 3.60605 0.69781998 3 P 0 
L 3.60605 0.69781998 3.61786004 0.69781998 3 P 0 
L 3.61786004 0.69781998 3.60998996 0.68995 3 P 0 
L 3.50266654 0.68499961 3.5040001 0.68249941 2 P 0 ;0,1=267,2=0.000000
L 3.5040001 0.68249941 3.5055997 0.68083307 2 P 0 ;0,1=267,2=0.000000
L 3.5055997 0.68083307 3.50746654 0.68 2 P 0 ;0,1=267,2=0.000000
L 3.50746654 0.68 3.5095999 0.68083307 2 P 0 ;0,1=267,2=0.000000
L 3.5095999 0.68083307 3.5112 0.68249941 2 P 0 ;0,1=267,2=0.000000
L 3.5112 0.68249941 3.5128001 0.68499961 2 P 0 ;0,1=267,2=0.000000
L 3.5128001 0.68499961 3.51333337 0.68833307 2 P 0 ;0,1=267,2=0.000000
L 3.51333337 0.68833307 3.51333337 0.705 2 P 0 ;0,1=267,2=0.000000
L 3.5319997 0.68 3.5319997 0.705 2 P 0 ;0,1=267,2=0.000000
L 3.5319997 0.705 3.5287999 0.7000003 2 P 0 ;0,1=267,2=0.000000
L 3.5287999 0.68 3.53519951 0.68 2 P 0 ;0,1=267,2=0.000000
L 3.55093317 0.69041594 3.5527999 0.69333346 2 P 0 ;0,1=267,2=0.000000
L 3.5527999 0.69333346 3.5544 0.6949998 2 P 0 ;0,1=267,2=0.000000
L 3.5544 0.6949998 3.55653337 0.69583297 2 P 0 ;0,1=267,2=0.000000
L 3.55653337 0.69583297 3.5584002 0.6949998 2 P 0 ;0,1=267,2=0.000000
L 3.5584002 0.6949998 3.55973327 0.69333346 2 P 0 ;0,1=267,2=0.000000
L 3.55973327 0.69333346 3.5608001 0.69083327 2 P 0 ;0,1=267,2=0.000000
L 3.5608001 0.69083327 3.56106673 0.68791644 2 P 0 ;0,1=267,2=0.000000
L 3.56106673 0.68791644 3.5608001 0.68541624 2 P 0 ;0,1=267,2=0.000000
L 3.5608001 0.68541624 3.55973327 0.68291604 2 P 0 ;0,1=267,2=0.000000
L 3.55973327 0.68291604 3.55813307 0.68083307 2 P 0 ;0,1=267,2=0.000000
L 3.55813307 0.68083307 3.55626683 0.68 2 P 0 ;0,1=267,2=0.000000
L 3.55626683 0.68 3.55413346 0.68083307 2 P 0 ;0,1=267,2=0.000000
L 3.55413346 0.68083307 3.55226663 0.68333258 2 P 0 ;0,1=267,2=0.000000
L 3.55226663 0.68333258 3.5511998 0.68708327 2 P 0 ;0,1=267,2=0.000000
L 3.5511998 0.68708327 3.55093317 0.6912498 2 P 0 ;0,1=267,2=0.000000
L 3.55093317 0.6912498 3.55146634 0.69666614 2 P 0 ;0,1=267,2=0.000000
L 3.55146634 0.69666614 3.55226663 0.69958366 2 P 0 ;0,1=267,2=0.000000
L 3.55226663 0.69958366 3.5535997 0.7024997 2 P 0 ;0,1=267,2=0.000000
L 3.5535997 0.7024997 3.55546654 0.70458337 2 P 0 ;0,1=267,2=0.000000
L 3.55546654 0.70458337 3.55733327 0.705 2 P 0 ;0,1=267,2=0.000000
L 3.55733327 0.705 3.5592 0.70416683 2 P 0 ;0,1=267,2=0.000000
L 3.5592 0.70416683 3.56053356 0.70208317 2 P 0 ;0,1=267,2=0.000000
L 3.56793317 0.38583337 3.56953327 0.38833287 2 P 0 ;0,1=53,2=0.000000
L 3.56953327 0.38833287 3.5714 0.38958337 2 P 0 ;0,1=53,2=0.000000
L 3.5714 0.38958337 3.57353337 0.39 2 P 0 ;0,1=53,2=0.000000
L 3.57353337 0.39 3.5762 0.38916683 2 P 0 ;0,1=53,2=0.000000
L 3.5762 0.38916683 3.57806673 0.38708317 2 P 0 ;0,1=53,2=0.000000
L 3.57806673 0.38708317 3.5786 0.38458366 2 P 0 ;0,1=53,2=0.000000
L 3.5786 0.38458366 3.57833337 0.38208268 2 P 0 ;0,1=53,2=0.000000
L 3.57833337 0.38208268 3.57726644 0.3799998 2 P 0 ;0,1=53,2=0.000000
L 3.57726644 0.3799998 3.57193327 0.37583327 2 P 0 ;0,1=53,2=0.000000
L 3.57193327 0.37583327 3.56953327 0.37291644 2 P 0 ;0,1=53,2=0.000000
L 3.56953327 0.37291644 3.56793317 0.36874911 2 P 0 ;0,1=53,2=0.000000
L 3.56793317 0.36874911 3.5673999 0.365 2 P 0 ;0,1=53,2=0.000000
L 3.5673999 0.365 3.5786 0.365 2 P 0 ;0,1=53,2=0.000000
L 3.8479997 0.365 3.8479997 0.39 2 P 0 ;0,1=26,2=0.000000
L 3.8479997 0.39 3.8447999 0.3850003 2 P 0 ;0,1=26,2=0.000000
L 3.8447999 0.365 3.85119951 0.365 2 P 0 ;0,1=26,2=0.000000
L 3.8719997 0.39 3.86986634 0.38916683 2 P 0 ;0,1=26,2=0.000000
L 3.86986634 0.38916683 3.86826663 0.38708317 2 P 0 ;0,1=26,2=0.000000
L 3.86826663 0.38708317 3.8671998 0.38458366 2 P 0 ;0,1=26,2=0.000000
L 3.8671998 0.38458366 3.8663999 0.38124951 2 P 0 ;0,1=26,2=0.000000
L 3.8663999 0.38124951 3.86613327 0.37749961 2 P 0 ;0,1=26,2=0.000000
L 3.86613327 0.37749961 3.8663999 0.37374961 2 P 0 ;0,1=26,2=0.000000
L 3.8663999 0.37374961 3.8671998 0.37041624 2 P 0 ;0,1=26,2=0.000000
L 3.8671998 0.37041624 3.86826663 0.36791604 2 P 0 ;0,1=26,2=0.000000
L 3.86826663 0.36791604 3.86986634 0.36583307 2 P 0 ;0,1=26,2=0.000000
L 3.86986634 0.36583307 3.8719997 0.365 2 P 0 ;0,1=26,2=0.000000
L 3.8719997 0.365 3.87413307 0.36583307 2 P 0 ;0,1=26,2=0.000000
L 3.87413307 0.36583307 3.87573327 0.36791604 2 P 0 ;0,1=26,2=0.000000
L 3.87573327 0.36791604 3.8768001 0.37041624 2 P 0 ;0,1=26,2=0.000000
L 3.8768001 0.37041624 3.8776 0.37374961 2 P 0 ;0,1=26,2=0.000000
L 3.8776 0.37374961 3.87786663 0.37749961 2 P 0 ;0,1=26,2=0.000000
L 3.87786663 0.37749961 3.8776 0.38124951 2 P 0 ;0,1=26,2=0.000000
L 3.8776 0.38124951 3.8768001 0.38458366 2 P 0 ;0,1=26,2=0.000000
L 3.8768001 0.38458366 3.87573327 0.38708317 2 P 0 ;0,1=26,2=0.000000
L 3.87573327 0.38708317 3.87413307 0.38916683 2 P 0 ;0,1=26,2=0.000000
L 3.87413307 0.38916683 3.8719997 0.39 2 P 0 ;0,1=26,2=0.000000
L 3.80128632 0.68278602 3.80315315 0.68070305 2 P 0 ;0,1=28,2=0.000000
L 3.80315315 0.68070305 3.80528652 0.67986998 2 P 0 ;0,1=28,2=0.000000
L 3.80528652 0.67986998 3.80741988 0.68070305 2 P 0 ;0,1=28,2=0.000000
L 3.80741988 0.68070305 3.80928661 0.68320256 2 P 0 ;0,1=28,2=0.000000
L 3.80928661 0.68320256 3.81062008 0.68695325 2 P 0 ;0,1=28,2=0.000000
L 3.81062008 0.68695325 3.81115335 0.69070325 2 P 0 ;0,1=28,2=0.000000
L 3.81115335 0.69070325 3.81115335 0.69528632 2 P 0 ;0,1=28,2=0.000000
L 3.81115335 0.69528632 3.81062008 0.69903632 2 P 0 ;0,1=28,2=0.000000
L 3.81062008 0.69903632 3.80928661 0.70236969 2 P 0 ;0,1=28,2=0.000000
L 3.80928661 0.70236969 3.80768642 0.70403681 2 P 0 ;0,1=28,2=0.000000
L 3.80768642 0.70403681 3.80581969 0.70486998 2 P 0 ;0,1=28,2=0.000000
L 3.80581969 0.70486998 3.80368632 0.70403681 2 P 0 ;0,1=28,2=0.000000
L 3.80368632 0.70403681 3.80208661 0.70236969 2 P 0 ;0,1=28,2=0.000000
L 3.80208661 0.70236969 3.80101978 0.69987028 2 P 0 ;0,1=28,2=0.000000
L 3.80101978 0.69987028 3.80048652 0.69653612 2 P 0 ;0,1=28,2=0.000000
L 3.80048652 0.69653612 3.80101978 0.69362008 2 P 0 ;0,1=28,2=0.000000
L 3.80101978 0.69362008 3.80235325 0.69070325 2 P 0 ;0,1=28,2=0.000000
L 3.80235325 0.69070325 3.80395344 0.68903612 2 P 0 ;0,1=28,2=0.000000
L 3.80395344 0.68903612 3.80581969 0.68861959 2 P 0 ;0,1=28,2=0.000000
L 3.80581969 0.68861959 3.80795305 0.68945276 2 P 0 ;0,1=28,2=0.000000
L 3.80795305 0.68945276 3.80955325 0.69153642 2 P 0 ;0,1=28,2=0.000000
L 3.80955325 0.69153642 3.81115335 0.69528632 2 P 0 ;0,1=28,2=0.000000
L 9.38275 0.64336998 9.36956004 0.64336998 3 P 0 
L 9.36956004 0.64336998 9.36956004 0.43548996 3 P 0 
L 9.36956004 0.43548996 9.38275 0.43548996 3 P 0 
L 9.63315 0.64336998 9.64633996 0.64336998 3 P 0 
L 9.64633996 0.64336998 9.64633996 0.43548996 3 P 0 
L 9.64633996 0.43548996 9.63315 0.43548996 3 P 0 
L 9.40795 0.69946998 9.38826004 0.72703002 3 P 0 
L 9.38826004 0.72703002 9.42763996 0.72703002 3 P 0 
L 9.42763996 0.72703002 9.40795 0.69946998 3 P 0 
L 9.40795 0.69946998 9.39613996 0.72308996 3 P 0 
L 9.39613996 0.72308996 9.41976004 0.72308996 3 P 0 
L 9.41976004 0.72308996 9.40795 0.69946998 3 P 0 
L 9.40795 0.69946998 9.40401004 0.71915 3 P 0 
L 9.40401004 0.71915 9.41581998 0.71915 3 P 0 
L 9.41581998 0.71915 9.40795 0.71128002 3 P 0 
L 9.30266654 0.70999961 9.3040001 0.70749941 2 P 0 ;0,1=268,2=0.000000
L 9.3040001 0.70749941 9.3055997 0.70583307 2 P 0 ;0,1=268,2=0.000000
L 9.3055997 0.70583307 9.30746654 0.705 2 P 0 ;0,1=268,2=0.000000
L 9.30746654 0.705 9.3095999 0.70583307 2 P 0 ;0,1=268,2=0.000000
L 9.3095999 0.70583307 9.3112 0.70749941 2 P 0 ;0,1=268,2=0.000000
L 9.3112 0.70749941 9.3128001 0.70999961 2 P 0 ;0,1=268,2=0.000000
L 9.3128001 0.70999961 9.31333337 0.71333307 2 P 0 ;0,1=268,2=0.000000
L 9.31333337 0.71333307 9.31333337 0.73 2 P 0 ;0,1=268,2=0.000000
L 9.3319997 0.705 9.3319997 0.73 2 P 0 ;0,1=268,2=0.000000
L 9.3319997 0.73 9.3287999 0.7250003 2 P 0 ;0,1=268,2=0.000000
L 9.3287999 0.705 9.33519951 0.705 2 P 0 ;0,1=268,2=0.000000
L 9.35546654 0.705 9.3559997 0.71041624 2 P 0 ;0,1=268,2=0.000000
L 9.3559997 0.71041624 9.3568 0.71499931 2 P 0 ;0,1=268,2=0.000000
L 9.3568 0.71499931 9.35786644 0.71916663 2 P 0 ;0,1=268,2=0.000000
L 9.35786644 0.71916663 9.3592 0.7237498 2 P 0 ;0,1=268,2=0.000000
L 9.3592 0.7237498 9.36133337 0.73 2 P 0 ;0,1=268,2=0.000000
L 9.36133337 0.73 9.35066654 0.73 2 P 0 ;0,1=268,2=0.000000
L 9.37293317 0.40083337 9.37453327 0.40333287 2 P 0 ;0,1=53,2=0.000000
L 9.37453327 0.40333287 9.3764 0.40458337 2 P 0 ;0,1=53,2=0.000000
L 9.3764 0.40458337 9.37853337 0.405 2 P 0 ;0,1=53,2=0.000000
L 9.37853337 0.405 9.3812 0.40416683 2 P 0 ;0,1=53,2=0.000000
L 9.3812 0.40416683 9.38306673 0.40208317 2 P 0 ;0,1=53,2=0.000000
L 9.38306673 0.40208317 9.3836 0.39958366 2 P 0 ;0,1=53,2=0.000000
L 9.3836 0.39958366 9.38333337 0.39708268 2 P 0 ;0,1=53,2=0.000000
L 9.38333337 0.39708268 9.38226644 0.3949998 2 P 0 ;0,1=53,2=0.000000
L 9.38226644 0.3949998 9.37693327 0.39083327 2 P 0 ;0,1=53,2=0.000000
L 9.37693327 0.39083327 9.37453327 0.38791644 2 P 0 ;0,1=53,2=0.000000
L 9.37453327 0.38791644 9.37293317 0.38374911 2 P 0 ;0,1=53,2=0.000000
L 9.37293317 0.38374911 9.3723999 0.38 2 P 0 ;0,1=53,2=0.000000
L 9.3723999 0.38 9.3836 0.38 2 P 0 ;0,1=53,2=0.000000
L 9.6429997 0.38 9.6429997 0.405 2 P 0 ;0,1=26,2=0.000000
L 9.6429997 0.405 9.6397999 0.4000003 2 P 0 ;0,1=26,2=0.000000
L 9.6397999 0.38 9.64619951 0.38 2 P 0 ;0,1=26,2=0.000000
L 9.6669997 0.405 9.66486634 0.40416683 2 P 0 ;0,1=26,2=0.000000
L 9.66486634 0.40416683 9.66326663 0.40208317 2 P 0 ;0,1=26,2=0.000000
L 9.66326663 0.40208317 9.6621998 0.39958366 2 P 0 ;0,1=26,2=0.000000
L 9.6621998 0.39958366 9.6613999 0.39624951 2 P 0 ;0,1=26,2=0.000000
L 9.6613999 0.39624951 9.66113327 0.39249961 2 P 0 ;0,1=26,2=0.000000
L 9.66113327 0.39249961 9.6613999 0.38874961 2 P 0 ;0,1=26,2=0.000000
L 9.6613999 0.38874961 9.6621998 0.38541624 2 P 0 ;0,1=26,2=0.000000
L 9.6621998 0.38541624 9.66326663 0.38291604 2 P 0 ;0,1=26,2=0.000000
L 9.66326663 0.38291604 9.66486634 0.38083307 2 P 0 ;0,1=26,2=0.000000
L 9.66486634 0.38083307 9.6669997 0.38 2 P 0 ;0,1=26,2=0.000000
L 9.6669997 0.38 9.66913307 0.38083307 2 P 0 ;0,1=26,2=0.000000
L 9.66913307 0.38083307 9.67073327 0.38291604 2 P 0 ;0,1=26,2=0.000000
L 9.67073327 0.38291604 9.6718001 0.38541624 2 P 0 ;0,1=26,2=0.000000
L 9.6718001 0.38541624 9.6726 0.38874961 2 P 0 ;0,1=26,2=0.000000
L 9.6726 0.38874961 9.67286663 0.39249961 2 P 0 ;0,1=26,2=0.000000
L 9.67286663 0.39249961 9.6726 0.39624951 2 P 0 ;0,1=26,2=0.000000
L 9.6726 0.39624951 9.6718001 0.39958366 2 P 0 ;0,1=26,2=0.000000
L 9.6718001 0.39958366 9.67073327 0.40208317 2 P 0 ;0,1=26,2=0.000000
L 9.67073327 0.40208317 9.66913307 0.40416683 2 P 0 ;0,1=26,2=0.000000
L 9.66913307 0.40416683 9.6669997 0.405 2 P 0 ;0,1=26,2=0.000000
L 9.59924636 0.70411604 9.60111319 0.70203307 2 P 0 ;0,1=28,2=0.000000
L 9.60111319 0.70203307 9.60324656 0.7012 2 P 0 ;0,1=28,2=0.000000
L 9.60324656 0.7012 9.60537992 0.70203307 2 P 0 ;0,1=28,2=0.000000
L 9.60537992 0.70203307 9.60724665 0.70453258 2 P 0 ;0,1=28,2=0.000000
L 9.60724665 0.70453258 9.60858012 0.70828327 2 P 0 ;0,1=28,2=0.000000
L 9.60858012 0.70828327 9.60911339 0.71203327 2 P 0 ;0,1=28,2=0.000000
L 9.60911339 0.71203327 9.60911339 0.71661634 2 P 0 ;0,1=28,2=0.000000
L 9.60911339 0.71661634 9.60858012 0.72036634 2 P 0 ;0,1=28,2=0.000000
L 9.60858012 0.72036634 9.60724665 0.7236997 2 P 0 ;0,1=28,2=0.000000
L 9.60724665 0.7236997 9.60564646 0.72536683 2 P 0 ;0,1=28,2=0.000000
L 9.60564646 0.72536683 9.60377972 0.7262 2 P 0 ;0,1=28,2=0.000000
L 9.60377972 0.7262 9.60164636 0.72536683 2 P 0 ;0,1=28,2=0.000000
L 9.60164636 0.72536683 9.60004665 0.7236997 2 P 0 ;0,1=28,2=0.000000
L 9.60004665 0.7236997 9.59897982 0.7212003 2 P 0 ;0,1=28,2=0.000000
L 9.59897982 0.7212003 9.59844656 0.71786614 2 P 0 ;0,1=28,2=0.000000
L 9.59844656 0.71786614 9.59897982 0.7149501 2 P 0 ;0,1=28,2=0.000000
L 9.59897982 0.7149501 9.60031329 0.71203327 2 P 0 ;0,1=28,2=0.000000
L 9.60031329 0.71203327 9.60191348 0.71036614 2 P 0 ;0,1=28,2=0.000000
L 9.60191348 0.71036614 9.60377972 0.70994961 2 P 0 ;0,1=28,2=0.000000
L 9.60377972 0.70994961 9.60591309 0.71078278 2 P 0 ;0,1=28,2=0.000000
L 9.60591309 0.71078278 9.60751329 0.71286644 2 P 0 ;0,1=28,2=0.000000
L 9.60751329 0.71286644 9.60911339 0.71661634 2 P 0 ;0,1=28,2=0.000000
L 0.63386004 5.49213002 0.66535 5.52361998 3 P 0 
L 0.69705 5.74803002 0.63386004 5.74803002 3 P 0 
L 0.63386004 5.74803002 0.63386004 5.49213002 3 P 0 
L 0.63386004 5.49213002 0.69705 5.49213002 3 P 0 
L 0.69705 5.52361998 0.66535 5.52361998 3 P 0 
L 0.66535 5.52361998 0.66535 5.57283996 3 P 0 
L 0.66535 5.57283996 0.63386004 5.57283996 3 P 0 
L 0.63386004 5.57283996 0.63386004 5.63583002 3 P 0 
L 0.63386004 5.63583002 0.66535 5.63583002 3 P 0 
L 0.66535 5.63583002 0.66535 5.71653996 3 P 0 
L 0.66535 5.71653996 0.69705 5.71653996 3 P 0 
L 0.63386004 5.74803002 0.66535 5.71653996 3 P 0 
L 1.54901004 5.74803002 1.6122 5.74803002 3 P 0 
L 1.6122 5.74803002 1.6122 5.49213002 3 P 0 
L 1.6122 5.49213002 1.54901004 5.49213002 3 P 0 
L 1.54901004 5.71653996 1.58071004 5.71653996 3 P 0 
L 1.58071004 5.71653996 1.58071004 5.66731998 3 P 0 
L 1.58071004 5.66731998 1.6122 5.66731998 3 P 0 
L 1.6122 5.66731998 1.6122 5.60433002 3 P 0 
L 1.6122 5.60433002 1.58071004 5.60433002 3 P 0 
L 1.58071004 5.60433002 1.58071004 5.52361998 3 P 0 
L 1.58071004 5.52361998 1.54901004 5.52361998 3 P 0 
L 1.58071004 5.52361998 1.6122 5.49213002 3 P 0 
L 1.58071004 5.71653996 1.6122 5.74803002 3 P 0 
L 0.76161004 5.71653996 0.77578996 5.71653996 3 P 0 
L 0.76161004 5.74803002 0.77578996 5.74803002 3 P 0 
L 0.84035 5.71653996 0.85453002 5.71653996 3 P 0 
L 0.84035 5.74803002 0.85453002 5.74803002 3 P 0 
L 0.91908996 5.71653996 0.93326998 5.71653996 3 P 0 
L 0.91908996 5.74803002 0.93326998 5.74803002 3 P 0 
L 0.99783002 5.71653996 1.01201004 5.71653996 3 P 0 
L 0.99783002 5.74803002 1.01201004 5.74803002 3 P 0 
L 1.07656998 5.71653996 1.09075 5.71653996 3 P 0 
L 1.07656998 5.74803002 1.09075 5.74803002 3 P 0 
L 1.15531004 5.71653996 1.16948996 5.71653996 3 P 0 
L 1.15531004 5.74803002 1.16948996 5.74803002 3 P 0 
L 1.23405 5.71653996 1.24823002 5.71653996 3 P 0 
L 1.23405 5.74803002 1.24823002 5.74803002 3 P 0 
L 1.31278996 5.71653996 1.32696998 5.71653996 3 P 0 
L 1.31278996 5.74803002 1.32696998 5.74803002 3 P 0 
L 1.39153002 5.71653996 1.40571004 5.71653996 3 P 0 
L 1.39153002 5.74803002 1.40571004 5.74803002 3 P 0 
L 1.47026998 5.71653996 1.48445 5.71653996 3 P 0 
L 1.47026998 5.74803002 1.48445 5.74803002 3 P 0 
L 0.76161004 5.49213002 0.77578996 5.49213002 3 P 0 
L 0.76161004 5.52361998 0.77578996 5.52361998 3 P 0 
L 0.84035 5.49213002 0.85453002 5.49213002 3 P 0 
L 0.84035 5.52361998 0.85453002 5.52361998 3 P 0 
L 0.91908996 5.49213002 0.93326998 5.49213002 3 P 0 
L 0.91908996 5.52361998 0.93326998 5.52361998 3 P 0 
L 0.99783002 5.49213002 1.01201004 5.49213002 3 P 0 
L 0.99783002 5.52361998 1.01201004 5.52361998 3 P 0 
L 1.07656998 5.49213002 1.09075 5.49213002 3 P 0 
L 1.07656998 5.52361998 1.09075 5.52361998 3 P 0 
L 1.31278996 5.49213002 1.32696998 5.49213002 3 P 0 
L 1.31278996 5.52361998 1.32696998 5.52361998 3 P 0 
L 1.39153002 5.49213002 1.40571004 5.49213002 3 P 0 
L 1.39153002 5.52361998 1.40571004 5.52361998 3 P 0 
L 1.47026998 5.49213002 1.48445 5.49213002 3 P 0 
L 1.47026998 5.52361998 1.48445 5.52361998 3 P 0 
L 0.72933002 5.46968996 0.70571004 5.44606004 3 P 0 
L 0.70571004 5.44606004 0.75295 5.44606004 3 P 0 
L 0.75295 5.44606004 0.72933002 5.46968996 3 P 0 
L 0.72933002 5.46968996 0.71751998 5.45788002 3 P 0 
L 0.71751998 5.45788002 0.71751998 5.45 3 P 0 
L 0.71751998 5.45 0.74508002 5.45 3 P 0 
L 0.74508002 5.45 0.74508002 5.45393996 3 P 0 
L 0.74508002 5.45393996 0.72933002 5.46968996 3 P 0 
L 0.72933002 5.46968996 0.72146004 5.46181004 3 P 0 
L 0.72146004 5.46181004 0.72146004 5.45393996 3 P 0 
L 0.72146004 5.45393996 0.74113996 5.45393996 3 P 0 
L 0.74113996 5.45393996 0.73326998 5.46181004 3 P 0 
L 0.73326998 5.46181004 0.72538996 5.46181004 3 P 0 
L 0.72538996 5.46181004 0.72538996 5.45788002 3 P 0 
L 0.72538996 5.45788002 0.7372 5.45788002 3 P 0 
L 0.7372 5.45788002 0.73326998 5.46181004 3 P 0 
L 0.73326998 5.46181004 0.72538996 5.46181004 3 P 0 
L 1.15531004 5.49213002 1.16948996 5.49213002 3 P 0 
L 1.15531004 5.52361998 1.16948996 5.52361998 3 P 0 
L 1.23405 5.49213002 1.24823002 5.49213002 3 P 0 
L 1.23405 5.52361998 1.24823002 5.52361998 3 P 0 
L 1.64883317 5.62639961 1.6507501 5.62319931 2 P 0 ;0,1=269,2=0.000000
L 1.6507501 5.62319931 1.65304961 5.62106644 2 P 0 ;0,1=269,2=0.000000
L 1.65304961 5.62106644 1.65573307 5.62 2 P 0 ;0,1=269,2=0.000000
L 1.65573307 5.62 1.6587998 5.62106644 2 P 0 ;0,1=269,2=0.000000
L 1.6587998 5.62106644 1.6611 5.62319931 2 P 0 ;0,1=269,2=0.000000
L 1.6611 5.62319931 1.6634002 5.62639961 2 P 0 ;0,1=269,2=0.000000
L 1.6634002 5.62639961 1.66416673 5.63066634 2 P 0 ;0,1=269,2=0.000000
L 1.66416673 5.63066634 1.66416673 5.652 2 P 0 ;0,1=269,2=0.000000
L 1.676 5.60933366 1.699 5.60933366 2 P 0 ;0,1=269,2=0.000000
L 1.7104499 5.62426575 1.71351663 5.62159961 2 P 0 ;0,1=269,2=0.000000
L 1.71351663 5.62159961 1.71696663 5.62 2 P 0 ;0,1=269,2=0.000000
L 1.71696663 5.62 1.72003327 5.62 2 P 0 ;0,1=269,2=0.000000
L 1.72003327 5.62 1.7231 5.62159961 2 P 0 ;0,1=269,2=0.000000
L 1.7231 5.62159961 1.7254002 5.62426575 2 P 0 ;0,1=269,2=0.000000
L 1.7254002 5.62426575 1.72655 5.6280002 2 P 0 ;0,1=269,2=0.000000
L 1.72655 5.6280002 1.72578346 5.63173278 2 P 0 ;0,1=269,2=0.000000
L 1.72578346 5.63173278 1.72386654 5.63493307 2 P 0 ;0,1=269,2=0.000000
L 1.72386654 5.63493307 1.72041654 5.63706683 2 P 0 ;0,1=269,2=0.000000
L 1.72041654 5.63706683 1.71581683 5.63813327 2 P 0 ;0,1=269,2=0.000000
L 1.71581683 5.63813327 1.71313337 5.64026624 2 P 0 ;0,1=269,2=0.000000
L 1.71313337 5.64026624 1.71198287 5.6439997 2 P 0 ;0,1=269,2=0.000000
L 1.71198287 5.6439997 1.7127501 5.64773327 2 P 0 ;0,1=269,2=0.000000
L 1.7127501 5.64773327 1.71466634 5.65039931 2 P 0 ;0,1=269,2=0.000000
L 1.71466634 5.65039931 1.7173498 5.652 2 P 0 ;0,1=269,2=0.000000
L 1.7173498 5.652 1.72003327 5.652 2 P 0 ;0,1=269,2=0.000000
L 1.72003327 5.652 1.72271673 5.65093346 2 P 0 ;0,1=269,2=0.000000
L 1.72271673 5.65093346 1.72501703 5.64826644 2 P 0 ;0,1=269,2=0.000000
L 1.7448999 5.652 1.75409931 5.652 2 P 0 ;0,1=269,2=0.000000
L 1.74949961 5.652 1.74949961 5.62 2 P 0 ;0,1=269,2=0.000000
L 1.7448999 5.62 1.75409931 5.62 2 P 0 ;0,1=269,2=0.000000
L 1.77206663 5.62 1.77206663 5.652 2 P 0 ;0,1=269,2=0.000000
L 1.77206663 5.652 1.77973307 5.652 2 P 0 ;0,1=269,2=0.000000
L 1.77973307 5.652 1.7827998 5.65039931 2 P 0 ;0,1=269,2=0.000000
L 1.7827998 5.65039931 1.7851 5.64826644 2 P 0 ;0,1=269,2=0.000000
L 1.7851 5.64826644 1.78701703 5.64506713 2 P 0 ;0,1=269,2=0.000000
L 1.78701703 5.64506713 1.78855 5.64133268 2 P 0 ;0,1=269,2=0.000000
L 1.78855 5.64133268 1.78893327 5.63599951 2 P 0 ;0,1=269,2=0.000000
L 1.78893327 5.63599951 1.78855 5.63066634 2 P 0 ;0,1=269,2=0.000000
L 1.78855 5.63066634 1.78701703 5.62693278 2 P 0 ;0,1=269,2=0.000000
L 1.78701703 5.62693278 1.7851 5.62373248 2 P 0 ;0,1=269,2=0.000000
L 1.7851 5.62373248 1.7827998 5.62159961 2 P 0 ;0,1=269,2=0.000000
L 1.7827998 5.62159961 1.77973307 5.62 2 P 0 ;0,1=269,2=0.000000
L 1.77973307 5.62 1.77206663 5.62 2 P 0 ;0,1=269,2=0.000000
L 1.81916673 5.62 1.80383317 5.62 2 P 0 ;0,1=269,2=0.000000
L 1.80383317 5.62 1.80383317 5.652 2 P 0 ;0,1=269,2=0.000000
L 1.80383317 5.652 1.81916673 5.652 2 P 0 ;0,1=269,2=0.000000
L 1.81303327 5.63653366 1.80383317 5.63653366 2 P 0 ;0,1=269,2=0.000000
L 1.84556634 5.63706683 1.8471 5.63866654 2 P 0 ;0,1=269,2=0.000000
L 1.8471 5.63866654 1.8482498 5.64133268 2 P 0 ;0,1=269,2=0.000000
L 1.8482498 5.64133268 1.84901703 5.64506713 2 P 0 ;0,1=269,2=0.000000
L 1.84901703 5.64506713 1.8482498 5.64826644 2 P 0 ;0,1=269,2=0.000000
L 1.8482498 5.64826644 1.84671673 5.65039931 2 P 0 ;0,1=269,2=0.000000
L 1.84671673 5.65039931 1.84403327 5.652 2 P 0 ;0,1=269,2=0.000000
L 1.84403327 5.652 1.83368337 5.652 2 P 0 ;0,1=269,2=0.000000
L 1.83368337 5.652 1.83368337 5.62 2 P 0 ;0,1=269,2=0.000000
L 1.83368337 5.62 1.84633356 5.62 2 P 0 ;0,1=269,2=0.000000
L 1.84633356 5.62 1.84901703 5.62213287 2 P 0 ;0,1=269,2=0.000000
L 1.84901703 5.62213287 1.85055 5.62533317 2 P 0 ;0,1=269,2=0.000000
L 1.85055 5.62533317 1.85131654 5.62906663 2 P 0 ;0,1=269,2=0.000000
L 1.85131654 5.62906663 1.85055 5.63279921 2 P 0 ;0,1=269,2=0.000000
L 1.85055 5.63279921 1.8482498 5.63599951 2 P 0 ;0,1=269,2=0.000000
L 1.8482498 5.63599951 1.84556634 5.63706683 2 P 0 ;0,1=269,2=0.000000
L 1.84556634 5.63706683 1.83368337 5.63706683 2 P 0 ;0,1=269,2=0.000000
L 1.86391624 5.62 1.87349961 5.652 2 P 0 ;0,1=269,2=0.000000
L 1.87349961 5.652 1.88308366 5.62 2 P 0 ;0,1=269,2=0.000000
L 1.87963307 5.63119951 1.86736614 5.63119951 2 P 0 ;0,1=269,2=0.000000
L 1.89568337 5.62 1.89568337 5.652 2 P 0 ;0,1=269,2=0.000000
L 1.89568337 5.652 1.91331654 5.62 2 P 0 ;0,1=269,2=0.000000
L 1.91331654 5.62 1.91331654 5.652 2 P 0 ;0,1=269,2=0.000000
L 1.92706663 5.62 1.92706663 5.652 2 P 0 ;0,1=269,2=0.000000
L 1.92706663 5.652 1.93473307 5.652 2 P 0 ;0,1=269,2=0.000000
L 1.93473307 5.652 1.9377998 5.65039931 2 P 0 ;0,1=269,2=0.000000
L 1.9377998 5.65039931 1.9401 5.64826644 2 P 0 ;0,1=269,2=0.000000
L 1.9401 5.64826644 1.94201703 5.64506713 2 P 0 ;0,1=269,2=0.000000
L 1.94201703 5.64506713 1.94355 5.64133268 2 P 0 ;0,1=269,2=0.000000
L 1.94355 5.64133268 1.94393327 5.63599951 2 P 0 ;0,1=269,2=0.000000
L 1.94393327 5.63599951 1.94355 5.63066634 2 P 0 ;0,1=269,2=0.000000
L 1.94355 5.63066634 1.94201703 5.62693278 2 P 0 ;0,1=269,2=0.000000
L 1.94201703 5.62693278 1.9401 5.62373248 2 P 0 ;0,1=269,2=0.000000
L 1.9401 5.62373248 1.9377998 5.62159961 2 P 0 ;0,1=269,2=0.000000
L 1.9377998 5.62159961 1.93473307 5.62 2 P 0 ;0,1=269,2=0.000000
L 1.93473307 5.62 1.92706663 5.62 2 P 0 ;0,1=269,2=0.000000
L 0.70293317 5.79083337 0.70453327 5.79333287 2 P 0 ;0,1=53,2=0.000000
L 0.70453327 5.79333287 0.7064 5.79458337 2 P 0 ;0,1=53,2=0.000000
L 0.7064 5.79458337 0.70853337 5.795 2 P 0 ;0,1=53,2=0.000000
L 0.70853337 5.795 0.7112 5.79416683 2 P 0 ;0,1=53,2=0.000000
L 0.7112 5.79416683 0.71306673 5.79208317 2 P 0 ;0,1=53,2=0.000000
L 0.71306673 5.79208317 0.7136 5.78958366 2 P 0 ;0,1=53,2=0.000000
L 0.7136 5.78958366 0.71333337 5.78708268 2 P 0 ;0,1=53,2=0.000000
L 0.71333337 5.78708268 0.71226644 5.7849998 2 P 0 ;0,1=53,2=0.000000
L 0.71226644 5.7849998 0.70693327 5.78083327 2 P 0 ;0,1=53,2=0.000000
L 0.70693327 5.78083327 0.70453327 5.77791644 2 P 0 ;0,1=53,2=0.000000
L 0.70453327 5.77791644 0.70293317 5.77374911 2 P 0 ;0,1=53,2=0.000000
L 0.70293317 5.77374911 0.7023999 5.77 2 P 0 ;0,1=53,2=0.000000
L 0.7023999 5.77 0.7136 5.77 2 P 0 ;0,1=53,2=0.000000
L 1.63293317 5.51083337 1.63453327 5.51333287 2 P 0 ;0,1=270,2=0.000000
L 1.63453327 5.51333287 1.6364 5.51458337 2 P 0 ;0,1=270,2=0.000000
L 1.6364 5.51458337 1.63853337 5.515 2 P 0 ;0,1=270,2=0.000000
L 1.63853337 5.515 1.6412 5.51416683 2 P 0 ;0,1=270,2=0.000000
L 1.6412 5.51416683 1.64306673 5.51208317 2 P 0 ;0,1=270,2=0.000000
L 1.64306673 5.51208317 1.6436 5.50958366 2 P 0 ;0,1=270,2=0.000000
L 1.6436 5.50958366 1.64333337 5.50708268 2 P 0 ;0,1=270,2=0.000000
L 1.64333337 5.50708268 1.64226644 5.5049998 2 P 0 ;0,1=270,2=0.000000
L 1.64226644 5.5049998 1.63693327 5.50083327 2 P 0 ;0,1=270,2=0.000000
L 1.63693327 5.50083327 1.63453327 5.49791644 2 P 0 ;0,1=270,2=0.000000
L 1.63453327 5.49791644 1.63293317 5.49374911 2 P 0 ;0,1=270,2=0.000000
L 1.63293317 5.49374911 1.6323999 5.49 2 P 0 ;0,1=270,2=0.000000
L 1.6323999 5.49 1.6436 5.49 2 P 0 ;0,1=270,2=0.000000
L 1.6619997 5.49 1.6619997 5.515 2 P 0 ;0,1=270,2=0.000000
L 1.6619997 5.515 1.6587999 5.5100003 2 P 0 ;0,1=270,2=0.000000
L 1.6587999 5.49 1.66519951 5.49 2 P 0 ;0,1=270,2=0.000000
L 1.53293317 5.79083337 1.53453327 5.79333287 2 P 0 ;0,1=271,2=0.000000
L 1.53453327 5.79333287 1.5364 5.79458337 2 P 0 ;0,1=271,2=0.000000
L 1.5364 5.79458337 1.53853337 5.795 2 P 0 ;0,1=271,2=0.000000
L 1.53853337 5.795 1.5412 5.79416683 2 P 0 ;0,1=271,2=0.000000
L 1.5412 5.79416683 1.54306673 5.79208317 2 P 0 ;0,1=271,2=0.000000
L 1.54306673 5.79208317 1.5436 5.78958366 2 P 0 ;0,1=271,2=0.000000
L 1.5436 5.78958366 1.54333337 5.78708268 2 P 0 ;0,1=271,2=0.000000
L 1.54333337 5.78708268 1.54226644 5.7849998 2 P 0 ;0,1=271,2=0.000000
L 1.54226644 5.7849998 1.53693327 5.78083327 2 P 0 ;0,1=271,2=0.000000
L 1.53693327 5.78083327 1.53453327 5.77791644 2 P 0 ;0,1=271,2=0.000000
L 1.53453327 5.77791644 1.53293317 5.77374911 2 P 0 ;0,1=271,2=0.000000
L 1.53293317 5.77374911 1.5323999 5.77 2 P 0 ;0,1=271,2=0.000000
L 1.5323999 5.77 1.5436 5.77 2 P 0 ;0,1=271,2=0.000000
L 1.55693317 5.79083337 1.55853327 5.79333287 2 P 0 ;0,1=271,2=0.000000
L 1.55853327 5.79333287 1.5604 5.79458337 2 P 0 ;0,1=271,2=0.000000
L 1.5604 5.79458337 1.56253337 5.795 2 P 0 ;0,1=271,2=0.000000
L 1.56253337 5.795 1.5652 5.79416683 2 P 0 ;0,1=271,2=0.000000
L 1.5652 5.79416683 1.56706673 5.79208317 2 P 0 ;0,1=271,2=0.000000
L 1.56706673 5.79208317 1.5676 5.78958366 2 P 0 ;0,1=271,2=0.000000
L 1.5676 5.78958366 1.56733337 5.78708268 2 P 0 ;0,1=271,2=0.000000
L 1.56733337 5.78708268 1.56626644 5.7849998 2 P 0 ;0,1=271,2=0.000000
L 1.56626644 5.7849998 1.56093327 5.78083327 2 P 0 ;0,1=271,2=0.000000
L 1.56093327 5.78083327 1.55853327 5.77791644 2 P 0 ;0,1=271,2=0.000000
L 1.55853327 5.77791644 1.55693317 5.77374911 2 P 0 ;0,1=271,2=0.000000
L 1.55693317 5.77374911 1.5563999 5.77 2 P 0 ;0,1=271,2=0.000000
L 1.5563999 5.77 1.5676 5.77 2 P 0 ;0,1=271,2=0.000000
L 2.09448996 1.7441 2.09448996 1.77953996 3 P 0 
L 2.09448996 1.77953996 1.9937 1.77953996 3 P 0 
A 1.9937 1.77953996 1.90078002 1.87246004 1.99328002 1.87203996 3 P 0 Y
L 1.90078002 1.87246004 1.90078002 3.85941004 3 P 0 
A 1.90078002 3.85941004 1.99415 3.95276004 1.9933002 3.86023996 3 P 0 Y
L 1.99415 3.95276004 2.13386004 3.95276004 3 P 0 
L 2.13386004 3.95276004 2.13386004 3.9882 3 P 0 
L 2.13386004 3.9882 2.35826004 3.9882 3 P 0 
L 2.35826004 3.9882 2.35826004 3.95276004 3 P 0 
L 2.35826004 3.95276004 2.4973 3.95276004 3 P 0 
A 2.4973 3.95276004 2.56400039 3.92590413 2.49880098 3.86023002 3 P 0 Y
A 2.56400039 3.92590413 2.59133996 3.8594 2.4988 3.86022884 3 P 0 Y
L 2.59133996 3.8594 2.59133996 1.87286004 3 P 0 
A 2.59133996 1.87286004 2.49801004 1.77953996 2.49882982 1.87205 3 P 0 Y
L 2.49801004 1.77953996 2.39763002 1.77953002 3 P 0 
L 2.39763002 1.77953002 2.39763002 1.7441 3 P 0 
L 2.39763002 1.7441 2.09448996 1.7441 3 P 0 
L 1.93796998 3.74115 1.92046998 3.7569 3 P 0 
L 1.92046998 3.7569 1.90476004 3.7569 3 P 0 
L 1.90476004 3.7569 1.9205 3.74115 3 P 0 
L 1.9205 3.74115 1.95593996 3.74115 3 P 0 
L 1.95593996 3.74115 1.95591004 3.5758 3 P 0 
L 1.95591004 3.5758 1.92046998 3.5758 3 P 0 
L 1.92046998 3.5758 1.90473002 3.56005 3 P 0 
L 1.90473002 3.56005 1.92046998 3.56005 3 P 0 
L 1.92046998 3.56005 1.92046998 2.96458002 3 P 0 
L 1.92046998 2.96458002 1.90473002 2.96458002 3 P 0 
L 1.90473002 2.96458002 1.92046998 2.94883996 3 P 0 
L 1.92046998 2.94883996 1.95591004 2.94883002 3 P 0 
L 1.95591004 2.94883002 1.95591004 2.78348002 3 P 0 
L 1.95591004 2.78348002 1.92046998 2.78348002 3 P 0 
L 1.92046998 2.78348002 1.90473002 2.76773002 3 P 0 
L 1.90473002 2.76773002 1.92046998 2.76773002 3 P 0 
L 1.92046998 2.76773002 1.92046998 2.17383002 3 P 0 
L 1.92046998 2.17383002 1.90473002 2.17383002 3 P 0 
L 1.90473002 2.17383002 1.92046998 2.15808002 3 P 0 
L 1.92046998 2.15808002 1.95591004 2.15808002 3 P 0 
L 1.95591004 2.15808002 1.95591004 1.99273002 3 P 0 
L 1.95591004 1.99273002 1.92046998 1.99273002 3 P 0 
L 1.92046998 1.99273002 1.90473002 1.97698002 3 P 0 
L 1.90473002 1.97698002 1.92046998 1.97698002 3 P 0 
L 1.92046998 1.97698002 1.93436998 1.99273002 3 P 0 
L 1.92046998 2.17383002 1.93621998 2.15808002 3 P 0 
L 1.93621998 2.15808002 1.93621998 2.78348002 3 P 0 
L 1.93621998 2.78348002 1.92046998 2.76773002 3 P 0 
L 1.92046998 2.78348002 1.92046998 2.94883002 2 P 0 
L 1.92046998 2.96458002 1.93621998 2.94883996 3 P 0 
L 1.93621998 2.94883996 1.93621998 3.5758 3 P 0 
L 1.93621998 3.5758 1.92046998 3.56005 3 P 0 
L 2.55628002 3.74115 2.57165 3.75688996 3 P 0 
L 2.57165 3.75688996 2.58738996 3.75688996 3 P 0 
L 2.58738996 3.75688996 2.57165 3.74115 3 P 0 
L 2.57165 3.74115 2.53621004 3.74115 3 P 0 
L 2.53621004 3.74115 2.53621004 3.5758 3 P 0 
L 2.53621004 3.5758 2.57165 3.5758 3 P 0 
L 2.57165 3.5758 2.58738996 3.56005 3 P 0 
L 2.58738996 3.56005 2.57165 3.56005 3 P 0 
L 2.57165 3.56005 2.57165 2.96456998 3 P 0 
L 2.57165 2.96456998 2.58738996 2.96456998 3 P 0 
L 2.58738996 2.96456998 2.57165 2.94883002 3 P 0 
L 2.57165 2.94883002 2.53621004 2.94883002 3 P 0 
L 2.53621004 2.94883002 2.53621004 2.78346998 3 P 0 
L 2.53621004 2.78346998 2.57165 2.78346998 3 P 0 
L 2.57165 2.78346998 2.58738996 2.76771998 3 P 0 
L 2.58738996 2.76771998 2.57165 2.76771998 3 P 0 
L 2.57165 2.76771998 2.57165 2.17383002 3 P 0 
L 2.57165 2.17383002 2.58738996 2.17383002 3 P 0 
L 2.58738996 2.17383002 2.57165 2.15808002 3 P 0 
L 2.57165 2.15808002 2.53621004 2.15808002 3 P 0 
L 2.53621004 2.15808002 2.53621004 1.99273002 3 P 0 
L 2.53621004 1.99273002 2.57165 1.99273002 3 P 0 
L 2.57165 1.99273002 2.58738996 1.97698002 3 P 0 
L 2.58738996 1.97698002 2.57165 1.97698002 3 P 0 
L 2.57165 1.97698002 2.55578996 1.99273002 3 P 0 
L 2.57165 3.56005 2.5559 3.5758 3 P 0 
L 2.5559 3.5758 2.55578996 2.94883002 3 P 0 
L 2.55578996 2.94883002 2.57165 2.96456998 3 P 0 
L 2.57165 2.94881998 2.57165 2.78346998 3 P 0 
L 2.57165 2.76771998 2.5559 2.78346998 3 P 0 
L 2.5559 2.78346998 2.5559 2.15808002 3 P 0 
L 2.5559 2.15808002 2.57163996 2.17383002 3 P 0 
L 2.57165 1.97698002 2.57165 1.87186004 3 P 0 
A 2.57165 1.87186004 2.49901004 1.79921998 2.49901004 1.87185994 3 P 0 Y
L 2.49901004 1.79921998 2.49881004 1.79921998 3 P 0 
L 2.49881004 1.79921998 2.37056998 1.79921998 3 P 0 
L 2.37056998 1.79921998 2.37056998 1.75788996 3 P 0 
L 2.37056998 1.75788996 2.12156004 1.75788996 3 P 0 
L 2.12156004 1.75788996 2.12156004 1.79921998 3 P 0 
L 2.12156004 1.79921998 1.9933 1.79921998 3 P 0 
L 1.9933 1.79921998 1.99311998 1.79921998 3 P 0 
A 1.99311998 1.79921998 1.92046998 1.87186004 1.99311004 1.87186004 3 P 0 Y
L 1.92046998 1.87186004 1.92046998 1.97708002 3 P 0 
A 2.55628002 3.86271004 2.53895719 3.90145246 2.4996 3.86061073 3 P 0 N
A 2.53895719 3.90145246 2.4996 3.91733002 2.49959921 3.86061004 3 P 0 N
L 2.4996 3.91733002 2.30561004 3.91733002 3 P 0 
L 2.30561004 3.91733002 2.30561004 3.95276004 3 P 0 
L 2.30561004 3.95276004 2.18651998 3.95276004 3 P 0 
L 2.18651998 3.95276004 2.18651998 3.91733002 3 P 0 
L 2.18651998 3.91733002 1.99331004 3.91733002 3 P 0 
A 1.99331004 3.91733002 1.93796998 3.86198996 1.99331004 3.86198996 3 P 0 N
L 1.93796998 3.86198996 1.93796998 3.74115 3 P 0 
L 2.16093002 3.93308002 2.17666998 3.91733002 3 P 0 
L 2.16338002 3.97245 2.18651998 3.95276004 3 P 0 
L 2.30561004 3.95276004 2.32873996 3.97245 3 P 0 
L 2.3312 3.93308002 2.31545 3.91733002 3 P 0 
L 2.18651998 3.91733002 2.18651998 3.90158002 3 P 0 
L 2.18651998 3.90158002 2.30561004 3.90158002 3 P 0 
L 2.30561004 3.90158002 2.30561004 3.91733002 3 P 0 
L 2.12156004 1.79921998 2.1373 1.81496998 3 P 0 
A 1.93431998 1.87186004 1.99121004 1.81496998 1.99121004 1.87186004 3 P 0 N
L 1.99121004 1.81496998 1.9933 1.81496998 3 P 0 
L 1.9933 1.81496998 2.14715 1.81498002 3 P 0 
L 2.14715 1.81498002 2.14713996 1.83071998 3 P 0 
L 2.14713996 1.83071998 2.14715 1.77953996 3 P 0 
L 2.14715 1.77953996 2.34498002 1.77953996 3 P 0 
L 2.34498002 1.77953996 2.34498002 1.81498002 3 P 0 
L 2.34498002 1.81498002 2.49881004 1.81496998 3 P 0 
L 2.49881004 1.81496998 2.49891998 1.81496998 3 P 0 
A 2.49891998 1.81496998 2.55578996 1.87183996 2.49891998 1.87183996 3 P 0 N
L 2.34498002 1.81498002 2.34498002 1.83071998 3 P 0 
L 2.34498002 1.83071998 2.3056 1.83071998 3 P 0 
L 2.3056 1.83071998 2.18651004 1.83071998 3 P 0 
L 2.18651004 1.83071998 2.14713996 1.83071998 3 P 0 
L 2.37056998 1.79921998 2.35483002 1.81496998 3 P 0 
L 2.14715 1.77953996 2.12401004 1.75985 3 P 0 
L 2.36811004 1.75985 2.34498002 1.77953996 3 P 0 
L 1.93436998 1.87178002 1.93436998 1.99295 3 P 0 
L 2.55578996 2.06861004 2.55578996 2.06868996 2 P 8191 
L 2.57165 2.86528002 2.57165 2.94898002 3 P 0 
L 2.57165 1.99273002 2.57165 2.15808002 3 P 0 
L 2.55578996 1.87183996 2.55578996 1.99273002 3 P 0 
L 2.55628002 3.74115 2.55628002 3.86271004 3 P 0 
L 1.92046998 1.99273002 1.92046998 2.15808002 3 P 0 
L 1.92046998 2.76631004 1.92046998 2.74745 3 P 0 
L 1.92046998 2.9478 1.92046998 2.78461004 3 P 0 
L 1.92046998 3.55888996 1.92046998 2.96508996 3 P 0 
L 1.92046998 3.73971004 1.92046998 3.57635 3 P 0 
L 2.57165 3.75658996 2.57165 3.86043996 3 P 0 
A 2.57165 3.86043996 2.499 3.93308002 2.49219085 3.85361998 3 P 0 N
L 2.499 3.93308002 2.3312 3.93308002 3 P 0 
L 2.3312 3.93308002 2.3312 3.97441998 3 P 0 
L 2.3312 3.97441998 2.16093002 3.97441998 3 P 0 
L 2.16093002 3.97441998 2.16093002 3.93308002 3 P 0 
L 2.16093002 3.93308002 1.99311004 3.93308002 3 P 0 
A 1.99311004 3.93308002 1.92046998 3.86043996 1.99168002 3.86186998 3 P 0 N
L 1.92046998 3.86043996 1.92046998 3.75903002 3 P 0 
L 2.57165 3.57576004 2.57165 3.73935 3 P 0 
L 2.57165 2.96475 2.57165 3.55796004 3 P 0 
L 2.46383317 1.64639961 2.4657501 1.64319931 2 P 0 ;0,1=272,2=0.000000
L 2.4657501 1.64319931 2.46804961 1.64106644 2 P 0 ;0,1=272,2=0.000000
L 2.46804961 1.64106644 2.47073307 1.64 2 P 0 ;0,1=272,2=0.000000
L 2.47073307 1.64 2.4737998 1.64106644 2 P 0 ;0,1=272,2=0.000000
L 2.4737998 1.64106644 2.4761 1.64319931 2 P 0 ;0,1=272,2=0.000000
L 2.4761 1.64319931 2.4784002 1.64639961 2 P 0 ;0,1=272,2=0.000000
L 2.4784002 1.64639961 2.47916673 1.65066634 2 P 0 ;0,1=272,2=0.000000
L 2.47916673 1.65066634 2.47916673 1.672 2 P 0 ;0,1=272,2=0.000000
L 2.491 1.62933366 2.514 1.62933366 2 P 0 ;0,1=272,2=0.000000
L 2.52468337 1.64 2.52468337 1.672 2 P 0 ;0,1=272,2=0.000000
L 2.52468337 1.672 2.54231654 1.64 2 P 0 ;0,1=272,2=0.000000
L 2.54231654 1.64 2.54231654 1.672 2 P 0 ;0,1=272,2=0.000000
L 2.55491624 1.672 2.56449961 1.64 2 P 0 ;0,1=272,2=0.000000
L 2.56449961 1.64 2.57408366 1.672 2 P 0 ;0,1=272,2=0.000000
L 2.58783317 1.672 2.58783317 1.64 2 P 0 ;0,1=272,2=0.000000
L 2.58783317 1.64 2.60316673 1.64 2 P 0 ;0,1=272,2=0.000000
L 2.6218999 1.672 2.63109931 1.672 2 P 0 ;0,1=272,2=0.000000
L 2.62649961 1.672 2.62649961 1.64 2 P 0 ;0,1=272,2=0.000000
L 2.6218999 1.64 2.63109931 1.64 2 P 0 ;0,1=272,2=0.000000
L 2.64868337 1.64 2.64868337 1.672 2 P 0 ;0,1=272,2=0.000000
L 2.64868337 1.672 2.66631654 1.64 2 P 0 ;0,1=272,2=0.000000
L 2.66631654 1.64 2.66631654 1.672 2 P 0 ;0,1=272,2=0.000000
L 2.68006663 1.64 2.68006663 1.672 2 P 0 ;0,1=272,2=0.000000
L 2.69463307 1.672 2.68006663 1.65226594 2 P 0 ;0,1=272,2=0.000000
L 2.69693327 1.64 2.68658337 1.66133268 2 P 0 ;0,1=272,2=0.000000
L 2.708 1.62933366 2.731 1.62933366 2 P 0 ;0,1=272,2=0.000000
L 2.7527998 1.65599951 2.76046693 1.65599951 2 P 0 ;0,1=272,2=0.000000
L 2.76046693 1.65599951 2.76046693 1.64639961 2 P 0 ;0,1=272,2=0.000000
L 2.76046693 1.64639961 2.75816673 1.64319931 2 P 0 ;0,1=272,2=0.000000
L 2.75816673 1.64319931 2.75548327 1.64106644 2 P 0 ;0,1=272,2=0.000000
L 2.75548327 1.64106644 2.7516501 1.64 2 P 0 ;0,1=272,2=0.000000
L 2.7516501 1.64 2.74781683 1.64106644 2 P 0 ;0,1=272,2=0.000000
L 2.74781683 1.64106644 2.74513337 1.64319931 2 P 0 ;0,1=272,2=0.000000
L 2.74513337 1.64319931 2.74283317 1.64639961 2 P 0 ;0,1=272,2=0.000000
L 2.74283317 1.64639961 2.74129951 1.65013307 2 P 0 ;0,1=272,2=0.000000
L 2.74129951 1.65013307 2.74053297 1.6543998 2 P 0 ;0,1=272,2=0.000000
L 2.74053297 1.6543998 2.74053297 1.65813327 2 P 0 ;0,1=272,2=0.000000
L 2.74053297 1.65813327 2.74129951 1.66133268 2 P 0 ;0,1=272,2=0.000000
L 2.74129951 1.66133268 2.74283317 1.66506713 2 P 0 ;0,1=272,2=0.000000
L 2.74283317 1.66506713 2.74513337 1.66826644 2 P 0 ;0,1=272,2=0.000000
L 2.74513337 1.66826644 2.74743287 1.67039931 2 P 0 ;0,1=272,2=0.000000
L 2.74743287 1.67039931 2.75049961 1.672 2 P 0 ;0,1=272,2=0.000000
L 2.75049961 1.672 2.75318307 1.672 2 P 0 ;0,1=272,2=0.000000
L 2.75318307 1.672 2.7562498 1.67093346 2 P 0 ;0,1=272,2=0.000000
L 2.7562498 1.67093346 2.75855 1.6687997 2 P 0 ;0,1=272,2=0.000000
L 2.77383317 1.64 2.77383317 1.672 2 P 0 ;0,1=272,2=0.000000
L 2.77383317 1.672 2.78303327 1.672 2 P 0 ;0,1=272,2=0.000000
L 2.78303327 1.672 2.7861 1.67039931 2 P 0 ;0,1=272,2=0.000000
L 2.7861 1.67039931 2.7884002 1.66666673 2 P 0 ;0,1=272,2=0.000000
L 2.7884002 1.66666673 2.78916673 1.6624 2 P 0 ;0,1=272,2=0.000000
L 2.78916673 1.6624 2.7884002 1.65813327 2 P 0 ;0,1=272,2=0.000000
L 2.7884002 1.65813327 2.78648327 1.65493307 2 P 0 ;0,1=272,2=0.000000
L 2.78648327 1.65493307 2.78303327 1.65333238 2 P 0 ;0,1=272,2=0.000000
L 2.78303327 1.65333238 2.77383317 1.65333238 2 P 0 ;0,1=272,2=0.000000
L 2.80406663 1.672 2.80406663 1.64906663 2 P 0 ;0,1=272,2=0.000000
L 2.80406663 1.64906663 2.8055997 1.64426575 2 P 0 ;0,1=272,2=0.000000
L 2.8055997 1.64426575 2.80866634 1.64106644 2 P 0 ;0,1=272,2=0.000000
L 2.80866634 1.64106644 2.81249961 1.64 2 P 0 ;0,1=272,2=0.000000
L 2.81249961 1.64 2.81633356 1.64106644 2 P 0 ;0,1=272,2=0.000000
L 2.81633356 1.64106644 2.8194002 1.64426575 2 P 0 ;0,1=272,2=0.000000
L 2.8194002 1.64426575 2.82093327 1.64906663 2 P 0 ;0,1=272,2=0.000000
L 2.82093327 1.64906663 2.82093327 1.672 2 P 0 ;0,1=272,2=0.000000
L 2.84349961 1.672 2.84043287 1.67093346 2 P 0 ;0,1=272,2=0.000000
L 2.84043287 1.67093346 2.83813337 1.66826644 2 P 0 ;0,1=272,2=0.000000
L 2.83813337 1.66826644 2.8365997 1.66506713 2 P 0 ;0,1=272,2=0.000000
L 2.8365997 1.66506713 2.8354499 1.66079941 2 P 0 ;0,1=272,2=0.000000
L 2.8354499 1.66079941 2.83506663 1.65599951 2 P 0 ;0,1=272,2=0.000000
L 2.83506663 1.65599951 2.8354499 1.65119951 2 P 0 ;0,1=272,2=0.000000
L 2.8354499 1.65119951 2.8365997 1.64693278 2 P 0 ;0,1=272,2=0.000000
L 2.8365997 1.64693278 2.83813337 1.64373248 2 P 0 ;0,1=272,2=0.000000
L 2.83813337 1.64373248 2.84043287 1.64106644 2 P 0 ;0,1=272,2=0.000000
L 2.84043287 1.64106644 2.84349961 1.64 2 P 0 ;0,1=272,2=0.000000
L 2.84349961 1.64 2.84656634 1.64106644 2 P 0 ;0,1=272,2=0.000000
L 2.84656634 1.64106644 2.84886654 1.64373248 2 P 0 ;0,1=272,2=0.000000
L 2.84886654 1.64373248 2.8504002 1.64693278 2 P 0 ;0,1=272,2=0.000000
L 2.8504002 1.64693278 2.85155 1.65119951 2 P 0 ;0,1=272,2=0.000000
L 2.85155 1.65119951 2.85193327 1.65599951 2 P 0 ;0,1=272,2=0.000000
L 2.85193327 1.65599951 2.85155 1.66079941 2 P 0 ;0,1=272,2=0.000000
L 2.85155 1.66079941 2.8504002 1.66506713 2 P 0 ;0,1=272,2=0.000000
L 2.8504002 1.66506713 2.84886654 1.66826644 2 P 0 ;0,1=272,2=0.000000
L 2.84886654 1.66826644 2.84656634 1.67093346 2 P 0 ;0,1=272,2=0.000000
L 2.84656634 1.67093346 2.84349961 1.672 2 P 0 ;0,1=272,2=0.000000
L 1.85677972 1.87671998 1.85677972 1.90171998 2 P 0 ;0,1=52,2=0.000000
L 1.85677972 1.90171998 1.85357992 1.89672028 2 P 0 ;0,1=52,2=0.000000
L 1.85357992 1.87671998 1.85997953 1.87671998 2 P 0 ;0,1=52,2=0.000000
L 1.85308317 1.95255335 1.85468327 1.95505285 2 P 0 ;0,1=53,2=0.000000
L 1.85468327 1.95505285 1.85655 1.95630335 2 P 0 ;0,1=53,2=0.000000
L 1.85655 1.95630335 1.85868337 1.95671998 2 P 0 ;0,1=53,2=0.000000
L 1.85868337 1.95671998 1.86135 1.95588681 2 P 0 ;0,1=53,2=0.000000
L 1.86135 1.95588681 1.86321673 1.95380315 2 P 0 ;0,1=53,2=0.000000
L 1.86321673 1.95380315 1.86375 1.95130364 2 P 0 ;0,1=53,2=0.000000
L 1.86375 1.95130364 1.86348337 1.94880266 2 P 0 ;0,1=53,2=0.000000
L 1.86348337 1.94880266 1.86241644 1.94671978 2 P 0 ;0,1=53,2=0.000000
L 1.86241644 1.94671978 1.85708327 1.94255325 2 P 0 ;0,1=53,2=0.000000
L 1.85708327 1.94255325 1.85468327 1.93963642 2 P 0 ;0,1=53,2=0.000000
L 1.85468327 1.93963642 1.85308317 1.93546909 2 P 0 ;0,1=53,2=0.000000
L 1.85308317 1.93546909 1.8525499 1.93171998 2 P 0 ;0,1=53,2=0.000000
L 1.8525499 1.93171998 1.86375 1.93171998 2 P 0 ;0,1=53,2=0.000000
L 1.85091329 1.98171959 1.85251299 1.97880285 2 P 0 ;0,1=57,2=0.000000
L 1.85251299 1.97880285 1.85464636 1.97713652 2 P 0 ;0,1=57,2=0.000000
L 1.85464636 1.97713652 1.85704685 1.97671998 2 P 0 ;0,1=57,2=0.000000
L 1.85704685 1.97671998 1.85918022 1.97713652 2 P 0 ;0,1=57,2=0.000000
L 1.85918022 1.97713652 1.86131358 1.97921939 2 P 0 ;0,1=57,2=0.000000
L 1.86131358 1.97921939 1.86264665 1.98171959 2 P 0 ;0,1=57,2=0.000000
L 1.86264665 1.98171959 1.86291319 1.98421988 2 P 0 ;0,1=57,2=0.000000
L 1.86291319 1.98421988 1.86238002 1.98713593 2 P 0 ;0,1=57,2=0.000000
L 1.86238002 1.98713593 1.86051329 1.98921959 2 P 0 ;0,1=57,2=0.000000
L 1.86051329 1.98921959 1.85864646 1.99005344 2 P 0 ;0,1=57,2=0.000000
L 1.85864646 1.99005344 1.85624656 1.99005344 2 P 0 ;0,1=57,2=0.000000
L 1.85864646 1.99005344 1.86024665 1.99130325 2 P 0 ;0,1=57,2=0.000000
L 1.86024665 1.99130325 1.86158012 1.99338612 2 P 0 ;0,1=57,2=0.000000
L 1.86158012 1.99338612 1.86211339 1.99588632 2 P 0 ;0,1=57,2=0.000000
L 1.86211339 1.99588632 1.86158012 1.99838652 2 P 0 ;0,1=57,2=0.000000
L 1.86158012 1.99838652 1.86024665 2.00046939 2 P 0 ;0,1=57,2=0.000000
L 1.86024665 2.00046939 1.85784665 2.00171998 2 P 0 ;0,1=57,2=0.000000
L 1.85784665 2.00171998 1.85544665 2.00130335 2 P 0 ;0,1=57,2=0.000000
L 1.85544665 2.00130335 1.85304665 1.99963632 2 P 0 ;0,1=57,2=0.000000
L 1.86135 2.03171998 1.86135 2.05671998 2 P 0 ;0,1=58,2=0.000000
L 1.86135 2.05671998 1.85148297 2.03880325 2 P 0 ;0,1=58,2=0.000000
L 1.85148297 2.03880325 1.86481693 2.03880325 2 P 0 ;0,1=58,2=0.000000
L 1.85091329 2.08046909 1.85251299 2.07838622 2 P 0 ;0,1=273,2=0.000000
L 1.85251299 2.07838622 1.85437972 2.07713652 2 P 0 ;0,1=273,2=0.000000
L 1.85437972 2.07713652 1.85677972 2.07671998 2 P 0 ;0,1=273,2=0.000000
L 1.85677972 2.07671998 1.85918022 2.07755305 2 P 0 ;0,1=273,2=0.000000
L 1.85918022 2.07755305 1.86104646 2.07921939 2 P 0 ;0,1=273,2=0.000000
L 1.86104646 2.07921939 1.86238002 2.08213622 2 P 0 ;0,1=273,2=0.000000
L 1.86238002 2.08213622 1.86264665 2.08546959 2 P 0 ;0,1=273,2=0.000000
L 1.86264665 2.08546959 1.86211339 2.08880295 2 P 0 ;0,1=273,2=0.000000
L 1.86211339 2.08880295 1.86077982 2.09088661 2 P 0 ;0,1=273,2=0.000000
L 1.86077982 2.09088661 1.85891309 2.09255295 2 P 0 ;0,1=273,2=0.000000
L 1.85891309 2.09255295 1.85704685 2.09296949 2 P 0 ;0,1=273,2=0.000000
L 1.85704685 2.09296949 1.85518002 2.09255295 2 P 0 ;0,1=273,2=0.000000
L 1.85518002 2.09255295 1.85278012 2.09088661 2 P 0 ;0,1=273,2=0.000000
L 1.85278012 2.09088661 1.85357992 2.10171998 2 P 0 ;0,1=273,2=0.000000
L 1.85357992 2.10171998 1.86077982 2.10171998 2 P 0 ;0,1=273,2=0.000000
L 1.85308317 2.14213593 1.8549499 2.14505344 2 P 0 ;0,1=274,2=0.000000
L 1.8549499 2.14505344 1.85655 2.14671978 2 P 0 ;0,1=274,2=0.000000
L 1.85655 2.14671978 1.85868337 2.14755295 2 P 0 ;0,1=274,2=0.000000
L 1.85868337 2.14755295 1.8605502 2.14671978 2 P 0 ;0,1=274,2=0.000000
L 1.8605502 2.14671978 1.86188327 2.14505344 2 P 0 ;0,1=274,2=0.000000
L 1.86188327 2.14505344 1.8629501 2.14255325 2 P 0 ;0,1=274,2=0.000000
L 1.8629501 2.14255325 1.86321673 2.13963642 2 P 0 ;0,1=274,2=0.000000
L 1.86321673 2.13963642 1.8629501 2.13713622 2 P 0 ;0,1=274,2=0.000000
L 1.8629501 2.13713622 1.86188327 2.13463602 2 P 0 ;0,1=274,2=0.000000
L 1.86188327 2.13463602 1.86028307 2.13255305 2 P 0 ;0,1=274,2=0.000000
L 1.86028307 2.13255305 1.85841683 2.13171998 2 P 0 ;0,1=274,2=0.000000
L 1.85841683 2.13171998 1.85628346 2.13255305 2 P 0 ;0,1=274,2=0.000000
L 1.85628346 2.13255305 1.85441663 2.13505256 2 P 0 ;0,1=274,2=0.000000
L 1.85441663 2.13505256 1.8533498 2.13880325 2 P 0 ;0,1=274,2=0.000000
L 1.8533498 2.13880325 1.85308317 2.14296978 2 P 0 ;0,1=274,2=0.000000
L 1.85308317 2.14296978 1.85361634 2.14838612 2 P 0 ;0,1=274,2=0.000000
L 1.85361634 2.14838612 1.85441663 2.15130364 2 P 0 ;0,1=274,2=0.000000
L 1.85441663 2.15130364 1.8557497 2.15421969 2 P 0 ;0,1=274,2=0.000000
L 1.8557497 2.15421969 1.85761654 2.15630335 2 P 0 ;0,1=274,2=0.000000
L 1.85761654 2.15630335 1.85948327 2.15671998 2 P 0 ;0,1=274,2=0.000000
L 1.85948327 2.15671998 1.86135 2.15588681 2 P 0 ;0,1=274,2=0.000000
L 1.86135 2.15588681 1.86268356 2.15380315 2 P 0 ;0,1=274,2=0.000000
L 1.85624656 2.17671998 1.85677972 2.18213622 2 P 0 ;0,1=275,2=0.000000
L 1.85677972 2.18213622 1.85758002 2.18671929 2 P 0 ;0,1=275,2=0.000000
L 1.85758002 2.18671929 1.85864646 2.19088661 2 P 0 ;0,1=275,2=0.000000
L 1.85864646 2.19088661 1.85998002 2.19546978 2 P 0 ;0,1=275,2=0.000000
L 1.85998002 2.19546978 1.86211339 2.20171998 2 P 0 ;0,1=275,2=0.000000
L 1.86211339 2.20171998 1.85144656 2.20171998 2 P 0 ;0,1=275,2=0.000000
L 1.8581497 2.23171998 1.86001644 2.23213652 2 P 0 ;0,1=276,2=0.000000
L 1.86001644 2.23213652 1.8621498 2.23338622 2 P 0 ;0,1=276,2=0.000000
L 1.8621498 2.23338622 1.86348337 2.23546909 2 P 0 ;0,1=276,2=0.000000
L 1.86348337 2.23546909 1.86401663 2.23838671 2 P 0 ;0,1=276,2=0.000000
L 1.86401663 2.23838671 1.86348337 2.24130276 2 P 0 ;0,1=276,2=0.000000
L 1.86348337 2.24130276 1.86188327 2.24380295 2 P 0 ;0,1=276,2=0.000000
L 1.86188327 2.24380295 1.85948327 2.24505344 2 P 0 ;0,1=276,2=0.000000
L 1.85948327 2.24505344 1.85681663 2.24505344 2 P 0 ;0,1=276,2=0.000000
L 1.85681663 2.24505344 1.85521654 2.24588661 2 P 0 ;0,1=276,2=0.000000
L 1.85521654 2.24588661 1.85388297 2.24796949 2 P 0 ;0,1=276,2=0.000000
L 1.85388297 2.24796949 1.8533498 2.25088632 2 P 0 ;0,1=276,2=0.000000
L 1.8533498 2.25088632 1.8541501 2.25380315 2 P 0 ;0,1=276,2=0.000000
L 1.8541501 2.25380315 1.85601634 2.25588681 2 P 0 ;0,1=276,2=0.000000
L 1.85601634 2.25588681 1.8581497 2.25671998 2 P 0 ;0,1=276,2=0.000000
L 1.8581497 2.25671998 1.86028307 2.25588681 2 P 0 ;0,1=276,2=0.000000
L 1.86028307 2.25588681 1.8621498 2.25380315 2 P 0 ;0,1=276,2=0.000000
L 1.8621498 2.25380315 1.8629501 2.25088632 2 P 0 ;0,1=276,2=0.000000
L 1.8629501 2.25088632 1.86241644 2.24796949 2 P 0 ;0,1=276,2=0.000000
L 1.86241644 2.24796949 1.86108337 2.24588661 2 P 0 ;0,1=276,2=0.000000
L 1.86108337 2.24588661 1.85948327 2.24505344 2 P 0 ;0,1=276,2=0.000000
L 1.85948327 2.24505344 1.85681663 2.24505344 2 P 0 ;0,1=276,2=0.000000
L 1.85681663 2.24505344 1.85441663 2.24380295 2 P 0 ;0,1=276,2=0.000000
L 1.85441663 2.24380295 1.85281654 2.24130276 2 P 0 ;0,1=276,2=0.000000
L 1.85281654 2.24130276 1.85228327 2.23838671 2 P 0 ;0,1=276,2=0.000000
L 1.85228327 2.23838671 1.85281654 2.23546909 2 P 0 ;0,1=276,2=0.000000
L 1.85281654 2.23546909 1.8541501 2.23338622 2 P 0 ;0,1=276,2=0.000000
L 1.8541501 2.23338622 1.85628346 2.23213652 2 P 0 ;0,1=276,2=0.000000
L 1.85628346 2.23213652 1.8581497 2.23171998 2 P 0 ;0,1=276,2=0.000000
L 1.85224636 2.27963602 1.85411319 2.27755305 2 P 0 ;0,1=28,2=0.000000
L 1.85411319 2.27755305 1.85624656 2.27671998 2 P 0 ;0,1=28,2=0.000000
L 1.85624656 2.27671998 1.85837992 2.27755305 2 P 0 ;0,1=28,2=0.000000
L 1.85837992 2.27755305 1.86024665 2.28005256 2 P 0 ;0,1=28,2=0.000000
L 1.86024665 2.28005256 1.86158012 2.28380325 2 P 0 ;0,1=28,2=0.000000
L 1.86158012 2.28380325 1.86211339 2.28755325 2 P 0 ;0,1=28,2=0.000000
L 1.86211339 2.28755325 1.86211339 2.29213632 2 P 0 ;0,1=28,2=0.000000
L 1.86211339 2.29213632 1.86158012 2.29588632 2 P 0 ;0,1=28,2=0.000000
L 1.86158012 2.29588632 1.86024665 2.29921969 2 P 0 ;0,1=28,2=0.000000
L 1.86024665 2.29921969 1.85864646 2.30088681 2 P 0 ;0,1=28,2=0.000000
L 1.85864646 2.30088681 1.85677972 2.30171998 2 P 0 ;0,1=28,2=0.000000
L 1.85677972 2.30171998 1.85464636 2.30088681 2 P 0 ;0,1=28,2=0.000000
L 1.85464636 2.30088681 1.85304665 2.29921969 2 P 0 ;0,1=28,2=0.000000
L 1.85304665 2.29921969 1.85197982 2.29672028 2 P 0 ;0,1=28,2=0.000000
L 1.85197982 2.29672028 1.85144656 2.29338612 2 P 0 ;0,1=28,2=0.000000
L 1.85144656 2.29338612 1.85197982 2.29047008 2 P 0 ;0,1=28,2=0.000000
L 1.85197982 2.29047008 1.85331329 2.28755325 2 P 0 ;0,1=28,2=0.000000
L 1.85331329 2.28755325 1.85491348 2.28588612 2 P 0 ;0,1=28,2=0.000000
L 1.85491348 2.28588612 1.85677972 2.28546959 2 P 0 ;0,1=28,2=0.000000
L 1.85677972 2.28546959 1.85891309 2.28630276 2 P 0 ;0,1=28,2=0.000000
L 1.85891309 2.28630276 1.86051329 2.28838642 2 P 0 ;0,1=28,2=0.000000
L 1.86051329 2.28838642 1.86211339 2.29213632 2 P 0 ;0,1=28,2=0.000000
L 1.8531497 2.31671998 1.8531497 2.34171998 2 P 0 ;0,1=26,2=0.000000
L 1.8531497 2.34171998 1.8499499 2.33672028 2 P 0 ;0,1=26,2=0.000000
L 1.8499499 2.31671998 1.85634951 2.31671998 2 P 0 ;0,1=26,2=0.000000
L 1.8771497 2.34171998 1.87501634 2.34088681 2 P 0 ;0,1=26,2=0.000000
L 1.87501634 2.34088681 1.87341663 2.33880315 2 P 0 ;0,1=26,2=0.000000
L 1.87341663 2.33880315 1.8723498 2.33630364 2 P 0 ;0,1=26,2=0.000000
L 1.8723498 2.33630364 1.8715499 2.33296949 2 P 0 ;0,1=26,2=0.000000
L 1.8715499 2.33296949 1.87128327 2.32921959 2 P 0 ;0,1=26,2=0.000000
L 1.87128327 2.32921959 1.8715499 2.32546959 2 P 0 ;0,1=26,2=0.000000
L 1.8715499 2.32546959 1.8723498 2.32213622 2 P 0 ;0,1=26,2=0.000000
L 1.8723498 2.32213622 1.87341663 2.31963602 2 P 0 ;0,1=26,2=0.000000
L 1.87341663 2.31963602 1.87501634 2.31755305 2 P 0 ;0,1=26,2=0.000000
L 1.87501634 2.31755305 1.8771497 2.31671998 2 P 0 ;0,1=26,2=0.000000
L 1.8771497 2.31671998 1.87928307 2.31755305 2 P 0 ;0,1=26,2=0.000000
L 1.87928307 2.31755305 1.88088327 2.31963602 2 P 0 ;0,1=26,2=0.000000
L 1.88088327 2.31963602 1.8819501 2.32213622 2 P 0 ;0,1=26,2=0.000000
L 1.8819501 2.32213622 1.88275 2.32546959 2 P 0 ;0,1=26,2=0.000000
L 1.88275 2.32546959 1.88301663 2.32921959 2 P 0 ;0,1=26,2=0.000000
L 1.88301663 2.32921959 1.88275 2.33296949 2 P 0 ;0,1=26,2=0.000000
L 1.88275 2.33296949 1.8819501 2.33630364 2 P 0 ;0,1=26,2=0.000000
L 1.8819501 2.33630364 1.88088327 2.33880315 2 P 0 ;0,1=26,2=0.000000
L 1.88088327 2.33880315 1.87928307 2.34088681 2 P 0 ;0,1=26,2=0.000000
L 1.87928307 2.34088681 1.8771497 2.34171998 2 P 0 ;0,1=26,2=0.000000
L 1.85677972 2.36671998 1.85677972 2.39171998 2 P 0 ;0,1=277,2=0.000000
L 1.85677972 2.39171998 1.85357992 2.38672028 2 P 0 ;0,1=277,2=0.000000
L 1.85357992 2.36671998 1.85997953 2.36671998 2 P 0 ;0,1=277,2=0.000000
L 1.88077972 2.36671998 1.88077972 2.39171998 2 P 0 ;0,1=277,2=0.000000
L 1.88077972 2.39171998 1.87757992 2.38672028 2 P 0 ;0,1=277,2=0.000000
L 1.87757992 2.36671998 1.88397953 2.36671998 2 P 0 ;0,1=277,2=0.000000
L 1.8531497 2.41671998 1.8531497 2.44171998 2 P 0 ;0,1=278,2=0.000000
L 1.8531497 2.44171998 1.8499499 2.43672028 2 P 0 ;0,1=278,2=0.000000
L 1.8499499 2.41671998 1.85634951 2.41671998 2 P 0 ;0,1=278,2=0.000000
L 1.87208317 2.43755335 1.87368327 2.44005285 2 P 0 ;0,1=278,2=0.000000
L 1.87368327 2.44005285 1.87555 2.44130335 2 P 0 ;0,1=278,2=0.000000
L 1.87555 2.44130335 1.87768337 2.44171998 2 P 0 ;0,1=278,2=0.000000
L 1.87768337 2.44171998 1.88035 2.44088681 2 P 0 ;0,1=278,2=0.000000
L 1.88035 2.44088681 1.88221673 2.43880315 2 P 0 ;0,1=278,2=0.000000
L 1.88221673 2.43880315 1.88275 2.43630364 2 P 0 ;0,1=278,2=0.000000
L 1.88275 2.43630364 1.88248337 2.43380266 2 P 0 ;0,1=278,2=0.000000
L 1.88248337 2.43380266 1.88141644 2.43171978 2 P 0 ;0,1=278,2=0.000000
L 1.88141644 2.43171978 1.87608327 2.42755325 2 P 0 ;0,1=278,2=0.000000
L 1.87608327 2.42755325 1.87368327 2.42463642 2 P 0 ;0,1=278,2=0.000000
L 1.87368327 2.42463642 1.87208317 2.42046909 2 P 0 ;0,1=278,2=0.000000
L 1.87208317 2.42046909 1.8715499 2.41671998 2 P 0 ;0,1=278,2=0.000000
L 1.8715499 2.41671998 1.88275 2.41671998 2 P 0 ;0,1=278,2=0.000000
L 1.85677972 2.46671998 1.85677972 2.49171998 2 P 0 ;0,1=279,2=0.000000
L 1.85677972 2.49171998 1.85357992 2.48672028 2 P 0 ;0,1=279,2=0.000000
L 1.85357992 2.46671998 1.85997953 2.46671998 2 P 0 ;0,1=279,2=0.000000
L 1.87491329 2.47171959 1.87651299 2.46880285 2 P 0 ;0,1=279,2=0.000000
L 1.87651299 2.46880285 1.87864636 2.46713652 2 P 0 ;0,1=279,2=0.000000
L 1.87864636 2.46713652 1.88104685 2.46671998 2 P 0 ;0,1=279,2=0.000000
L 1.88104685 2.46671998 1.88318022 2.46713652 2 P 0 ;0,1=279,2=0.000000
L 1.88318022 2.46713652 1.88531358 2.46921939 2 P 0 ;0,1=279,2=0.000000
L 1.88531358 2.46921939 1.88664665 2.47171959 2 P 0 ;0,1=279,2=0.000000
L 1.88664665 2.47171959 1.88691319 2.47421988 2 P 0 ;0,1=279,2=0.000000
L 1.88691319 2.47421988 1.88638002 2.47713593 2 P 0 ;0,1=279,2=0.000000
L 1.88638002 2.47713593 1.88451329 2.47921959 2 P 0 ;0,1=279,2=0.000000
L 1.88451329 2.47921959 1.88264646 2.48005344 2 P 0 ;0,1=279,2=0.000000
L 1.88264646 2.48005344 1.88024656 2.48005344 2 P 0 ;0,1=279,2=0.000000
L 1.88264646 2.48005344 1.88424665 2.48130325 2 P 0 ;0,1=279,2=0.000000
L 1.88424665 2.48130325 1.88558012 2.48338612 2 P 0 ;0,1=279,2=0.000000
L 1.88558012 2.48338612 1.88611339 2.48588632 2 P 0 ;0,1=279,2=0.000000
L 1.88611339 2.48588632 1.88558012 2.48838652 2 P 0 ;0,1=279,2=0.000000
L 1.88558012 2.48838652 1.88424665 2.49046939 2 P 0 ;0,1=279,2=0.000000
L 1.88424665 2.49046939 1.88184665 2.49171998 2 P 0 ;0,1=279,2=0.000000
L 1.88184665 2.49171998 1.87944665 2.49130335 2 P 0 ;0,1=279,2=0.000000
L 1.87944665 2.49130335 1.87704665 2.48963632 2 P 0 ;0,1=279,2=0.000000
L 1.8531497 2.51671998 1.8531497 2.54171998 2 P 0 ;0,1=63,2=0.000000
L 1.8531497 2.54171998 1.8499499 2.53672028 2 P 0 ;0,1=63,2=0.000000
L 1.8499499 2.51671998 1.85634951 2.51671998 2 P 0 ;0,1=63,2=0.000000
L 1.88035 2.51671998 1.88035 2.54171998 2 P 0 ;0,1=63,2=0.000000
L 1.88035 2.54171998 1.87048297 2.52380325 2 P 0 ;0,1=63,2=0.000000
L 1.87048297 2.52380325 1.88381693 2.52380325 2 P 0 ;0,1=63,2=0.000000
L 1.85677972 2.56671998 1.85677972 2.59171998 2 P 0 ;0,1=280,2=0.000000
L 1.85677972 2.59171998 1.85357992 2.58672028 2 P 0 ;0,1=280,2=0.000000
L 1.85357992 2.56671998 1.85997953 2.56671998 2 P 0 ;0,1=280,2=0.000000
L 1.87491329 2.57046909 1.87651299 2.56838622 2 P 0 ;0,1=280,2=0.000000
L 1.87651299 2.56838622 1.87837972 2.56713652 2 P 0 ;0,1=280,2=0.000000
L 1.87837972 2.56713652 1.88077972 2.56671998 2 P 0 ;0,1=280,2=0.000000
L 1.88077972 2.56671998 1.88318022 2.56755305 2 P 0 ;0,1=280,2=0.000000
L 1.88318022 2.56755305 1.88504646 2.56921939 2 P 0 ;0,1=280,2=0.000000
L 1.88504646 2.56921939 1.88638002 2.57213622 2 P 0 ;0,1=280,2=0.000000
L 1.88638002 2.57213622 1.88664665 2.57546959 2 P 0 ;0,1=280,2=0.000000
L 1.88664665 2.57546959 1.88611339 2.57880295 2 P 0 ;0,1=280,2=0.000000
L 1.88611339 2.57880295 1.88477982 2.58088661 2 P 0 ;0,1=280,2=0.000000
L 1.88477982 2.58088661 1.88291309 2.58255295 2 P 0 ;0,1=280,2=0.000000
L 1.88291309 2.58255295 1.88104685 2.58296949 2 P 0 ;0,1=280,2=0.000000
L 1.88104685 2.58296949 1.87918002 2.58255295 2 P 0 ;0,1=280,2=0.000000
L 1.87918002 2.58255295 1.87678012 2.58088661 2 P 0 ;0,1=280,2=0.000000
L 1.87678012 2.58088661 1.87757992 2.59171998 2 P 0 ;0,1=280,2=0.000000
L 1.87757992 2.59171998 1.88477982 2.59171998 2 P 0 ;0,1=280,2=0.000000
L 1.8531497 2.61671998 1.8531497 2.64171998 2 P 0 ;0,1=281,2=0.000000
L 1.8531497 2.64171998 1.8499499 2.63672028 2 P 0 ;0,1=281,2=0.000000
L 1.8499499 2.61671998 1.85634951 2.61671998 2 P 0 ;0,1=281,2=0.000000
L 1.87208317 2.62713593 1.8739499 2.63005344 2 P 0 ;0,1=281,2=0.000000
L 1.8739499 2.63005344 1.87555 2.63171978 2 P 0 ;0,1=281,2=0.000000
L 1.87555 2.63171978 1.87768337 2.63255295 2 P 0 ;0,1=281,2=0.000000
L 1.87768337 2.63255295 1.8795502 2.63171978 2 P 0 ;0,1=281,2=0.000000
L 1.8795502 2.63171978 1.88088327 2.63005344 2 P 0 ;0,1=281,2=0.000000
L 1.88088327 2.63005344 1.8819501 2.62755325 2 P 0 ;0,1=281,2=0.000000
L 1.8819501 2.62755325 1.88221673 2.62463642 2 P 0 ;0,1=281,2=0.000000
L 1.88221673 2.62463642 1.8819501 2.62213622 2 P 0 ;0,1=281,2=0.000000
L 1.8819501 2.62213622 1.88088327 2.61963602 2 P 0 ;0,1=281,2=0.000000
L 1.88088327 2.61963602 1.87928307 2.61755305 2 P 0 ;0,1=281,2=0.000000
L 1.87928307 2.61755305 1.87741683 2.61671998 2 P 0 ;0,1=281,2=0.000000
L 1.87741683 2.61671998 1.87528346 2.61755305 2 P 0 ;0,1=281,2=0.000000
L 1.87528346 2.61755305 1.87341663 2.62005256 2 P 0 ;0,1=281,2=0.000000
L 1.87341663 2.62005256 1.8723498 2.62380325 2 P 0 ;0,1=281,2=0.000000
L 1.8723498 2.62380325 1.87208317 2.62796978 2 P 0 ;0,1=281,2=0.000000
L 1.87208317 2.62796978 1.87261634 2.63338612 2 P 0 ;0,1=281,2=0.000000
L 1.87261634 2.63338612 1.87341663 2.63630364 2 P 0 ;0,1=281,2=0.000000
L 1.87341663 2.63630364 1.8747497 2.63921969 2 P 0 ;0,1=281,2=0.000000
L 1.8747497 2.63921969 1.87661654 2.64130335 2 P 0 ;0,1=281,2=0.000000
L 1.87661654 2.64130335 1.87848327 2.64171998 2 P 0 ;0,1=281,2=0.000000
L 1.87848327 2.64171998 1.88035 2.64088681 2 P 0 ;0,1=281,2=0.000000
L 1.88035 2.64088681 1.88168356 2.63880315 2 P 0 ;0,1=281,2=0.000000
L 1.85677972 2.66671998 1.85677972 2.69171998 2 P 0 ;0,1=282,2=0.000000
L 1.85677972 2.69171998 1.85357992 2.68672028 2 P 0 ;0,1=282,2=0.000000
L 1.85357992 2.66671998 1.85997953 2.66671998 2 P 0 ;0,1=282,2=0.000000
L 1.88024656 2.66671998 1.88077972 2.67213622 2 P 0 ;0,1=282,2=0.000000
L 1.88077972 2.67213622 1.88158002 2.67671929 2 P 0 ;0,1=282,2=0.000000
L 1.88158002 2.67671929 1.88264646 2.68088661 2 P 0 ;0,1=282,2=0.000000
L 1.88264646 2.68088661 1.88398002 2.68546978 2 P 0 ;0,1=282,2=0.000000
L 1.88398002 2.68546978 1.88611339 2.69171998 2 P 0 ;0,1=282,2=0.000000
L 1.88611339 2.69171998 1.87544656 2.69171998 2 P 0 ;0,1=282,2=0.000000
L 1.8531497 2.71671998 1.8531497 2.74171998 2 P 0 ;0,1=27,2=0.000000
L 1.8531497 2.74171998 1.8499499 2.73672028 2 P 0 ;0,1=27,2=0.000000
L 1.8499499 2.71671998 1.85634951 2.71671998 2 P 0 ;0,1=27,2=0.000000
L 1.8771497 2.71671998 1.87901644 2.71713652 2 P 0 ;0,1=27,2=0.000000
L 1.87901644 2.71713652 1.8811498 2.71838622 2 P 0 ;0,1=27,2=0.000000
L 1.8811498 2.71838622 1.88248337 2.72046909 2 P 0 ;0,1=27,2=0.000000
L 1.88248337 2.72046909 1.88301663 2.72338671 2 P 0 ;0,1=27,2=0.000000
L 1.88301663 2.72338671 1.88248337 2.72630276 2 P 0 ;0,1=27,2=0.000000
L 1.88248337 2.72630276 1.88088327 2.72880295 2 P 0 ;0,1=27,2=0.000000
L 1.88088327 2.72880295 1.87848327 2.73005344 2 P 0 ;0,1=27,2=0.000000
L 1.87848327 2.73005344 1.87581663 2.73005344 2 P 0 ;0,1=27,2=0.000000
L 1.87581663 2.73005344 1.87421654 2.73088661 2 P 0 ;0,1=27,2=0.000000
L 1.87421654 2.73088661 1.87288297 2.73296949 2 P 0 ;0,1=27,2=0.000000
L 1.87288297 2.73296949 1.8723498 2.73588632 2 P 0 ;0,1=27,2=0.000000
L 1.8723498 2.73588632 1.8731501 2.73880315 2 P 0 ;0,1=27,2=0.000000
L 1.8731501 2.73880315 1.87501634 2.74088681 2 P 0 ;0,1=27,2=0.000000
L 1.87501634 2.74088681 1.8771497 2.74171998 2 P 0 ;0,1=27,2=0.000000
L 1.8771497 2.74171998 1.87928307 2.74088681 2 P 0 ;0,1=27,2=0.000000
L 1.87928307 2.74088681 1.8811498 2.73880315 2 P 0 ;0,1=27,2=0.000000
L 1.8811498 2.73880315 1.8819501 2.73588632 2 P 0 ;0,1=27,2=0.000000
L 1.8819501 2.73588632 1.88141644 2.73296949 2 P 0 ;0,1=27,2=0.000000
L 1.88141644 2.73296949 1.88008337 2.73088661 2 P 0 ;0,1=27,2=0.000000
L 1.88008337 2.73088661 1.87848327 2.73005344 2 P 0 ;0,1=27,2=0.000000
L 1.87848327 2.73005344 1.87581663 2.73005344 2 P 0 ;0,1=27,2=0.000000
L 1.87581663 2.73005344 1.87341663 2.72880295 2 P 0 ;0,1=27,2=0.000000
L 1.87341663 2.72880295 1.87181654 2.72630276 2 P 0 ;0,1=27,2=0.000000
L 1.87181654 2.72630276 1.87128327 2.72338671 2 P 0 ;0,1=27,2=0.000000
L 1.87128327 2.72338671 1.87181654 2.72046909 2 P 0 ;0,1=27,2=0.000000
L 1.87181654 2.72046909 1.8731501 2.71838622 2 P 0 ;0,1=27,2=0.000000
L 1.8731501 2.71838622 1.87528346 2.71713652 2 P 0 ;0,1=27,2=0.000000
L 1.87528346 2.71713652 1.8771497 2.71671998 2 P 0 ;0,1=27,2=0.000000
L 1.85677972 2.76671998 1.85677972 2.79171998 2 P 0 ;0,1=283,2=0.000000
L 1.85677972 2.79171998 1.85357992 2.78672028 2 P 0 ;0,1=283,2=0.000000
L 1.85357992 2.76671998 1.85997953 2.76671998 2 P 0 ;0,1=283,2=0.000000
L 1.87624636 2.76963602 1.87811319 2.76755305 2 P 0 ;0,1=283,2=0.000000
L 1.87811319 2.76755305 1.88024656 2.76671998 2 P 0 ;0,1=283,2=0.000000
L 1.88024656 2.76671998 1.88237992 2.76755305 2 P 0 ;0,1=283,2=0.000000
L 1.88237992 2.76755305 1.88424665 2.77005256 2 P 0 ;0,1=283,2=0.000000
L 1.88424665 2.77005256 1.88558012 2.77380325 2 P 0 ;0,1=283,2=0.000000
L 1.88558012 2.77380325 1.88611339 2.77755325 2 P 0 ;0,1=283,2=0.000000
L 1.88611339 2.77755325 1.88611339 2.78213632 2 P 0 ;0,1=283,2=0.000000
L 1.88611339 2.78213632 1.88558012 2.78588632 2 P 0 ;0,1=283,2=0.000000
L 1.88558012 2.78588632 1.88424665 2.78921969 2 P 0 ;0,1=283,2=0.000000
L 1.88424665 2.78921969 1.88264646 2.79088681 2 P 0 ;0,1=283,2=0.000000
L 1.88264646 2.79088681 1.88077972 2.79171998 2 P 0 ;0,1=283,2=0.000000
L 1.88077972 2.79171998 1.87864636 2.79088681 2 P 0 ;0,1=283,2=0.000000
L 1.87864636 2.79088681 1.87704665 2.78921969 2 P 0 ;0,1=283,2=0.000000
L 1.87704665 2.78921969 1.87597982 2.78672028 2 P 0 ;0,1=283,2=0.000000
L 1.87597982 2.78672028 1.87544656 2.78338612 2 P 0 ;0,1=283,2=0.000000
L 1.87544656 2.78338612 1.87597982 2.78047008 2 P 0 ;0,1=283,2=0.000000
L 1.87597982 2.78047008 1.87731329 2.77755325 2 P 0 ;0,1=283,2=0.000000
L 1.87731329 2.77755325 1.87891348 2.77588612 2 P 0 ;0,1=283,2=0.000000
L 1.87891348 2.77588612 1.88077972 2.77546959 2 P 0 ;0,1=283,2=0.000000
L 1.88077972 2.77546959 1.88291309 2.77630276 2 P 0 ;0,1=283,2=0.000000
L 1.88291309 2.77630276 1.88451329 2.77838642 2 P 0 ;0,1=283,2=0.000000
L 1.88451329 2.77838642 1.88611339 2.78213632 2 P 0 ;0,1=283,2=0.000000
L 1.84808317 2.83755335 1.84968327 2.84005285 2 P 0 ;0,1=284,2=0.000000
L 1.84968327 2.84005285 1.85155 2.84130335 2 P 0 ;0,1=284,2=0.000000
L 1.85155 2.84130335 1.85368337 2.84171998 2 P 0 ;0,1=284,2=0.000000
L 1.85368337 2.84171998 1.85635 2.84088681 2 P 0 ;0,1=284,2=0.000000
L 1.85635 2.84088681 1.85821673 2.83880315 2 P 0 ;0,1=284,2=0.000000
L 1.85821673 2.83880315 1.85875 2.83630364 2 P 0 ;0,1=284,2=0.000000
L 1.85875 2.83630364 1.85848337 2.83380266 2 P 0 ;0,1=284,2=0.000000
L 1.85848337 2.83380266 1.85741644 2.83171978 2 P 0 ;0,1=284,2=0.000000
L 1.85741644 2.83171978 1.85208327 2.82755325 2 P 0 ;0,1=284,2=0.000000
L 1.85208327 2.82755325 1.84968327 2.82463642 2 P 0 ;0,1=284,2=0.000000
L 1.84968327 2.82463642 1.84808317 2.82046909 2 P 0 ;0,1=284,2=0.000000
L 1.84808317 2.82046909 1.8475499 2.81671998 2 P 0 ;0,1=284,2=0.000000
L 1.8475499 2.81671998 1.85875 2.81671998 2 P 0 ;0,1=284,2=0.000000
L 1.8771497 2.84171998 1.87501634 2.84088681 2 P 0 ;0,1=284,2=0.000000
L 1.87501634 2.84088681 1.87341663 2.83880315 2 P 0 ;0,1=284,2=0.000000
L 1.87341663 2.83880315 1.8723498 2.83630364 2 P 0 ;0,1=284,2=0.000000
L 1.8723498 2.83630364 1.8715499 2.83296949 2 P 0 ;0,1=284,2=0.000000
L 1.8715499 2.83296949 1.87128327 2.82921959 2 P 0 ;0,1=284,2=0.000000
L 1.87128327 2.82921959 1.8715499 2.82546959 2 P 0 ;0,1=284,2=0.000000
L 1.8715499 2.82546959 1.8723498 2.82213622 2 P 0 ;0,1=284,2=0.000000
L 1.8723498 2.82213622 1.87341663 2.81963602 2 P 0 ;0,1=284,2=0.000000
L 1.87341663 2.81963602 1.87501634 2.81755305 2 P 0 ;0,1=284,2=0.000000
L 1.87501634 2.81755305 1.8771497 2.81671998 2 P 0 ;0,1=284,2=0.000000
L 1.8771497 2.81671998 1.87928307 2.81755305 2 P 0 ;0,1=284,2=0.000000
L 1.87928307 2.81755305 1.88088327 2.81963602 2 P 0 ;0,1=284,2=0.000000
L 1.88088327 2.81963602 1.8819501 2.82213622 2 P 0 ;0,1=284,2=0.000000
L 1.8819501 2.82213622 1.88275 2.82546959 2 P 0 ;0,1=284,2=0.000000
L 1.88275 2.82546959 1.88301663 2.82921959 2 P 0 ;0,1=284,2=0.000000
L 1.88301663 2.82921959 1.88275 2.83296949 2 P 0 ;0,1=284,2=0.000000
L 1.88275 2.83296949 1.8819501 2.83630364 2 P 0 ;0,1=284,2=0.000000
L 1.8819501 2.83630364 1.88088327 2.83880315 2 P 0 ;0,1=284,2=0.000000
L 1.88088327 2.83880315 1.87928307 2.84088681 2 P 0 ;0,1=284,2=0.000000
L 1.87928307 2.84088681 1.8771497 2.84171998 2 P 0 ;0,1=284,2=0.000000
L 2.03391998 1.71381299 2.00891998 1.72047972 2 P 0 ;0,1=48,2=270.000000
L 2.00891998 1.72047972 2.03391998 1.72714695 2 P 0 ;0,1=48,2=270.000000
L 2.02517037 1.72474646 2.02517037 1.71621299 2 P 0 ;0,1=48,2=270.000000
L 2.07058652 1.72261309 2.06933671 1.72368002 2 P 0 ;0,1=285,2=270.000000
L 2.06933671 1.72368002 2.06725384 1.72447982 2 P 0 ;0,1=285,2=270.000000
L 2.06725384 1.72447982 2.06433632 1.72501358 2 P 0 ;0,1=285,2=270.000000
L 2.06433632 1.72501358 2.06183681 1.72447982 2 P 0 ;0,1=285,2=270.000000
L 2.06183681 1.72447982 2.06017057 1.72341339 2 P 0 ;0,1=285,2=270.000000
L 2.06017057 1.72341339 2.05891998 1.72154665 2 P 0 ;0,1=285,2=270.000000
L 2.05891998 1.72154665 2.05891998 1.71434675 2 P 0 ;0,1=285,2=270.000000
L 2.05891998 1.71434675 2.08391998 1.71434675 2 P 0 ;0,1=285,2=270.000000
L 2.08391998 1.71434675 2.08391998 1.72314675 2 P 0 ;0,1=285,2=270.000000
L 2.08391998 1.72314675 2.08225374 1.72501358 2 P 0 ;0,1=285,2=270.000000
L 2.08225374 1.72501358 2.07975344 1.72608002 2 P 0 ;0,1=285,2=270.000000
L 2.07975344 1.72608002 2.07683671 1.72661319 2 P 0 ;0,1=285,2=270.000000
L 2.07683671 1.72661319 2.07392067 1.72608002 2 P 0 ;0,1=285,2=270.000000
L 2.07392067 1.72608002 2.07142037 1.72447982 2 P 0 ;0,1=285,2=270.000000
L 2.07142037 1.72447982 2.07058652 1.72261309 2 P 0 ;0,1=285,2=270.000000
L 2.07058652 1.72261309 2.07058652 1.71434675 2 P 0 ;0,1=285,2=270.000000
L 2.11100364 1.72634665 2.10975315 1.72474646 2 P 0 ;0,1=49,2=270.000000
L 2.10975315 1.72474646 2.10891998 1.72288022 2 P 0 ;0,1=49,2=270.000000
L 2.10891998 1.72288022 2.10891998 1.72074685 2 P 0 ;0,1=49,2=270.000000
L 2.10891998 1.72074685 2.11017057 1.71834636 2 P 0 ;0,1=49,2=270.000000
L 2.11017057 1.71834636 2.11225344 1.71648012 2 P 0 ;0,1=49,2=270.000000
L 2.11225344 1.71648012 2.11475364 1.71514656 2 P 0 ;0,1=49,2=270.000000
L 2.11475364 1.71514656 2.11892018 1.71407963 2 P 0 ;0,1=49,2=270.000000
L 2.11892018 1.71407963 2.12267018 1.71381299 2 P 0 ;0,1=49,2=270.000000
L 2.12267018 1.71381299 2.12642008 1.71434675 2 P 0 ;0,1=49,2=270.000000
L 2.12642008 1.71434675 2.12892037 1.71514656 2 P 0 ;0,1=49,2=270.000000
L 2.12892037 1.71514656 2.13142057 1.71674665 2 P 0 ;0,1=49,2=270.000000
L 2.13142057 1.71674665 2.13308691 1.71861348 2 P 0 ;0,1=49,2=270.000000
L 2.13308691 1.71861348 2.13391998 1.72047972 2 P 0 ;0,1=49,2=270.000000
L 2.13391998 1.72047972 2.13391998 1.72234646 2 P 0 ;0,1=49,2=270.000000
L 2.13391998 1.72234646 2.13308691 1.72421329 2 P 0 ;0,1=49,2=270.000000
L 2.13308691 1.72421329 2.13183711 1.72581339 2 P 0 ;0,1=49,2=270.000000
L 2.13183711 1.72581339 2.13017087 1.72714695 2 P 0 ;0,1=49,2=270.000000
L 2.18391998 1.72461329 2.15891998 1.72461329 2 P 0 ;0,1=255,2=270.000000
L 2.15891998 1.72461329 2.15891998 1.72994656 2 P 0 ;0,1=255,2=270.000000
L 2.15891998 1.72994656 2.16017057 1.73207992 2 P 0 ;0,1=255,2=270.000000
L 2.16017057 1.73207992 2.16183681 1.73368002 2 P 0 ;0,1=255,2=270.000000
L 2.16183681 1.73368002 2.16433632 1.73501358 2 P 0 ;0,1=255,2=270.000000
L 2.16433632 1.73501358 2.16725384 1.73608002 2 P 0 ;0,1=255,2=270.000000
L 2.16725384 1.73608002 2.17142037 1.73634665 2 P 0 ;0,1=255,2=270.000000
L 2.17142037 1.73634665 2.17558691 1.73608002 2 P 0 ;0,1=255,2=270.000000
L 2.17558691 1.73608002 2.17850374 1.73501358 2 P 0 ;0,1=255,2=270.000000
L 2.17850374 1.73501358 2.18100394 1.73368002 2 P 0 ;0,1=255,2=270.000000
L 2.18100394 1.73368002 2.18267028 1.73207992 2 P 0 ;0,1=255,2=270.000000
L 2.18267028 1.73207992 2.18391998 1.72994656 2 P 0 ;0,1=255,2=270.000000
L 2.18391998 1.72994656 2.18391998 1.72461329 2 P 0 ;0,1=255,2=270.000000
L 2.23391998 1.73581339 2.23391998 1.72514656 2 P 0 ;0,1=286,2=270.000000
L 2.23391998 1.72514656 2.20891998 1.72514656 2 P 0 ;0,1=286,2=270.000000
L 2.20891998 1.72514656 2.20891998 1.73581339 2 P 0 ;0,1=286,2=270.000000
L 2.22100305 1.73154665 2.22100305 1.72514656 2 P 0 ;0,1=286,2=270.000000
L 2.28391998 1.72541319 2.25891998 1.72541319 2 P 0 ;0,1=287,2=270.000000
L 2.25891998 1.72541319 2.25891998 1.73554675 2 P 0 ;0,1=287,2=270.000000
L 2.27100305 1.73181329 2.27100305 1.72541319 2 P 0 ;0,1=287,2=270.000000
L 2.32142037 1.72207992 2.32142037 1.72741348 2 P 0 ;0,1=256,2=270.000000
L 2.32142037 1.72741348 2.32892037 1.72741348 2 P 0 ;0,1=256,2=270.000000
L 2.32892037 1.72741348 2.33142057 1.72581339 2 P 0 ;0,1=256,2=270.000000
L 2.33142057 1.72581339 2.33308691 1.72394665 2 P 0 ;0,1=256,2=270.000000
L 2.33308691 1.72394665 2.33391998 1.72128002 2 P 0 ;0,1=256,2=270.000000
L 2.33391998 1.72128002 2.33308691 1.71861348 2 P 0 ;0,1=256,2=270.000000
L 2.33308691 1.71861348 2.33142057 1.71674665 2 P 0 ;0,1=256,2=270.000000
L 2.33142057 1.71674665 2.32892037 1.71514656 2 P 0 ;0,1=256,2=270.000000
L 2.32892037 1.71514656 2.32600354 1.71407963 2 P 0 ;0,1=256,2=270.000000
L 2.32600354 1.71407963 2.32267018 1.71354646 2 P 0 ;0,1=256,2=270.000000
L 2.32267018 1.71354646 2.31975335 1.71354646 2 P 0 ;0,1=256,2=270.000000
L 2.31975335 1.71354646 2.31725384 1.71407963 2 P 0 ;0,1=256,2=270.000000
L 2.31725384 1.71407963 2.31433632 1.71514656 2 P 0 ;0,1=256,2=270.000000
L 2.31433632 1.71514656 2.31183681 1.71674665 2 P 0 ;0,1=256,2=270.000000
L 2.31183681 1.71674665 2.31017057 1.71834636 2 P 0 ;0,1=256,2=270.000000
L 2.31017057 1.71834636 2.30891998 1.72047972 2 P 0 ;0,1=256,2=270.000000
L 2.30891998 1.72047972 2.30891998 1.72234646 2 P 0 ;0,1=256,2=270.000000
L 2.30891998 1.72234646 2.30975315 1.72447982 2 P 0 ;0,1=256,2=270.000000
L 2.30975315 1.72447982 2.31142028 1.72608002 2 P 0 ;0,1=256,2=270.000000
L 2.38391998 1.71487992 2.35891998 1.71487992 2 P 0 ;0,1=288,2=270.000000
L 2.35891998 1.72608002 2.38391998 1.72608002 2 P 0 ;0,1=288,2=270.000000
L 2.37142037 1.72608002 2.37142037 1.71487992 2 P 0 ;0,1=288,2=270.000000
L 2.42892037 1.71514656 2.43142057 1.71648012 2 P 0 ;0,1=289,2=270.000000
L 2.43142057 1.71648012 2.43308691 1.71807972 2 P 0 ;0,1=289,2=270.000000
L 2.43308691 1.71807972 2.43391998 1.71994656 2 P 0 ;0,1=289,2=270.000000
L 2.43391998 1.71994656 2.43308691 1.72207992 2 P 0 ;0,1=289,2=270.000000
L 2.43308691 1.72207992 2.43142057 1.72368002 2 P 0 ;0,1=289,2=270.000000
L 2.43142057 1.72368002 2.42892037 1.72528012 2 P 0 ;0,1=289,2=270.000000
L 2.42892037 1.72528012 2.42558691 1.72581339 2 P 0 ;0,1=289,2=270.000000
L 2.42558691 1.72581339 2.40891998 1.72581339 2 P 0 ;0,1=289,2=270.000000
L 2.48391998 1.71461329 2.45891998 1.71461329 2 P 0 ;0,1=290,2=270.000000
L 2.45891998 1.72474646 2.4743372 1.71461329 2 P 0 ;0,1=290,2=270.000000
L 2.48391998 1.72634665 2.46725384 1.71914665 2 P 0 ;0,1=290,2=270.000000
L 1.85171319 2.88755335 1.85331329 2.89005285 2 P 0 ;0,1=270,2=0.000000
L 1.85331329 2.89005285 1.85518002 2.89130335 2 P 0 ;0,1=270,2=0.000000
L 1.85518002 2.89130335 1.85731339 2.89171998 2 P 0 ;0,1=270,2=0.000000
L 1.85731339 2.89171998 1.85998002 2.89088681 2 P 0 ;0,1=270,2=0.000000
L 1.85998002 2.89088681 1.86184675 2.88880315 2 P 0 ;0,1=270,2=0.000000
L 1.86184675 2.88880315 1.86238002 2.88630364 2 P 0 ;0,1=270,2=0.000000
L 1.86238002 2.88630364 1.86211339 2.88380266 2 P 0 ;0,1=270,2=0.000000
L 1.86211339 2.88380266 1.86104646 2.88171978 2 P 0 ;0,1=270,2=0.000000
L 1.86104646 2.88171978 1.85571329 2.87755325 2 P 0 ;0,1=270,2=0.000000
L 1.85571329 2.87755325 1.85331329 2.87463642 2 P 0 ;0,1=270,2=0.000000
L 1.85331329 2.87463642 1.85171319 2.87046909 2 P 0 ;0,1=270,2=0.000000
L 1.85171319 2.87046909 1.85117992 2.86671998 2 P 0 ;0,1=270,2=0.000000
L 1.85117992 2.86671998 1.86238002 2.86671998 2 P 0 ;0,1=270,2=0.000000
L 1.88077972 2.86671998 1.88077972 2.89171998 2 P 0 ;0,1=270,2=0.000000
L 1.88077972 2.89171998 1.87757992 2.88672028 2 P 0 ;0,1=270,2=0.000000
L 1.87757992 2.86671998 1.88397953 2.86671998 2 P 0 ;0,1=270,2=0.000000
L 1.84808317 2.93755335 1.84968327 2.94005285 2 P 0 ;0,1=271,2=0.000000
L 1.84968327 2.94005285 1.85155 2.94130335 2 P 0 ;0,1=271,2=0.000000
L 1.85155 2.94130335 1.85368337 2.94171998 2 P 0 ;0,1=271,2=0.000000
L 1.85368337 2.94171998 1.85635 2.94088681 2 P 0 ;0,1=271,2=0.000000
L 1.85635 2.94088681 1.85821673 2.93880315 2 P 0 ;0,1=271,2=0.000000
L 1.85821673 2.93880315 1.85875 2.93630364 2 P 0 ;0,1=271,2=0.000000
L 1.85875 2.93630364 1.85848337 2.93380266 2 P 0 ;0,1=271,2=0.000000
L 1.85848337 2.93380266 1.85741644 2.93171978 2 P 0 ;0,1=271,2=0.000000
L 1.85741644 2.93171978 1.85208327 2.92755325 2 P 0 ;0,1=271,2=0.000000
L 1.85208327 2.92755325 1.84968327 2.92463642 2 P 0 ;0,1=271,2=0.000000
L 1.84968327 2.92463642 1.84808317 2.92046909 2 P 0 ;0,1=271,2=0.000000
L 1.84808317 2.92046909 1.8475499 2.91671998 2 P 0 ;0,1=271,2=0.000000
L 1.8475499 2.91671998 1.85875 2.91671998 2 P 0 ;0,1=271,2=0.000000
L 1.87208317 2.93755335 1.87368327 2.94005285 2 P 0 ;0,1=271,2=0.000000
L 1.87368327 2.94005285 1.87555 2.94130335 2 P 0 ;0,1=271,2=0.000000
L 1.87555 2.94130335 1.87768337 2.94171998 2 P 0 ;0,1=271,2=0.000000
L 1.87768337 2.94171998 1.88035 2.94088681 2 P 0 ;0,1=271,2=0.000000
L 1.88035 2.94088681 1.88221673 2.93880315 2 P 0 ;0,1=271,2=0.000000
L 1.88221673 2.93880315 1.88275 2.93630364 2 P 0 ;0,1=271,2=0.000000
L 1.88275 2.93630364 1.88248337 2.93380266 2 P 0 ;0,1=271,2=0.000000
L 1.88248337 2.93380266 1.88141644 2.93171978 2 P 0 ;0,1=271,2=0.000000
L 1.88141644 2.93171978 1.87608327 2.92755325 2 P 0 ;0,1=271,2=0.000000
L 1.87608327 2.92755325 1.87368327 2.92463642 2 P 0 ;0,1=271,2=0.000000
L 1.87368327 2.92463642 1.87208317 2.92046909 2 P 0 ;0,1=271,2=0.000000
L 1.87208317 2.92046909 1.8715499 2.91671998 2 P 0 ;0,1=271,2=0.000000
L 1.8715499 2.91671998 1.88275 2.91671998 2 P 0 ;0,1=271,2=0.000000
L 1.85171319 2.98755335 1.85331329 2.99005285 2 P 0 ;0,1=64,2=0.000000
L 1.85331329 2.99005285 1.85518002 2.99130335 2 P 0 ;0,1=64,2=0.000000
L 1.85518002 2.99130335 1.85731339 2.99171998 2 P 0 ;0,1=64,2=0.000000
L 1.85731339 2.99171998 1.85998002 2.99088681 2 P 0 ;0,1=64,2=0.000000
L 1.85998002 2.99088681 1.86184675 2.98880315 2 P 0 ;0,1=64,2=0.000000
L 1.86184675 2.98880315 1.86238002 2.98630364 2 P 0 ;0,1=64,2=0.000000
L 1.86238002 2.98630364 1.86211339 2.98380266 2 P 0 ;0,1=64,2=0.000000
L 1.86211339 2.98380266 1.86104646 2.98171978 2 P 0 ;0,1=64,2=0.000000
L 1.86104646 2.98171978 1.85571329 2.97755325 2 P 0 ;0,1=64,2=0.000000
L 1.85571329 2.97755325 1.85331329 2.97463642 2 P 0 ;0,1=64,2=0.000000
L 1.85331329 2.97463642 1.85171319 2.97046909 2 P 0 ;0,1=64,2=0.000000
L 1.85171319 2.97046909 1.85117992 2.96671998 2 P 0 ;0,1=64,2=0.000000
L 1.85117992 2.96671998 1.86238002 2.96671998 2 P 0 ;0,1=64,2=0.000000
L 1.87491329 2.97171959 1.87651299 2.96880285 2 P 0 ;0,1=64,2=0.000000
L 1.87651299 2.96880285 1.87864636 2.96713652 2 P 0 ;0,1=64,2=0.000000
L 1.87864636 2.96713652 1.88104685 2.96671998 2 P 0 ;0,1=64,2=0.000000
L 1.88104685 2.96671998 1.88318022 2.96713652 2 P 0 ;0,1=64,2=0.000000
L 1.88318022 2.96713652 1.88531358 2.96921939 2 P 0 ;0,1=64,2=0.000000
L 1.88531358 2.96921939 1.88664665 2.97171959 2 P 0 ;0,1=64,2=0.000000
L 1.88664665 2.97171959 1.88691319 2.97421988 2 P 0 ;0,1=64,2=0.000000
L 1.88691319 2.97421988 1.88638002 2.97713593 2 P 0 ;0,1=64,2=0.000000
L 1.88638002 2.97713593 1.88451329 2.97921959 2 P 0 ;0,1=64,2=0.000000
L 1.88451329 2.97921959 1.88264646 2.98005344 2 P 0 ;0,1=64,2=0.000000
L 1.88264646 2.98005344 1.88024656 2.98005344 2 P 0 ;0,1=64,2=0.000000
L 1.88264646 2.98005344 1.88424665 2.98130325 2 P 0 ;0,1=64,2=0.000000
L 1.88424665 2.98130325 1.88558012 2.98338612 2 P 0 ;0,1=64,2=0.000000
L 1.88558012 2.98338612 1.88611339 2.98588632 2 P 0 ;0,1=64,2=0.000000
L 1.88611339 2.98588632 1.88558012 2.98838652 2 P 0 ;0,1=64,2=0.000000
L 1.88558012 2.98838652 1.88424665 2.99046939 2 P 0 ;0,1=64,2=0.000000
L 1.88424665 2.99046939 1.88184665 2.99171998 2 P 0 ;0,1=64,2=0.000000
L 1.88184665 2.99171998 1.87944665 2.99130335 2 P 0 ;0,1=64,2=0.000000
L 1.87944665 2.99130335 1.87704665 2.98963632 2 P 0 ;0,1=64,2=0.000000
L 1.84808317 3.03755335 1.84968327 3.04005285 2 P 0 ;0,1=65,2=0.000000
L 1.84968327 3.04005285 1.85155 3.04130335 2 P 0 ;0,1=65,2=0.000000
L 1.85155 3.04130335 1.85368337 3.04171998 2 P 0 ;0,1=65,2=0.000000
L 1.85368337 3.04171998 1.85635 3.04088681 2 P 0 ;0,1=65,2=0.000000
L 1.85635 3.04088681 1.85821673 3.03880315 2 P 0 ;0,1=65,2=0.000000
L 1.85821673 3.03880315 1.85875 3.03630364 2 P 0 ;0,1=65,2=0.000000
L 1.85875 3.03630364 1.85848337 3.03380266 2 P 0 ;0,1=65,2=0.000000
L 1.85848337 3.03380266 1.85741644 3.03171978 2 P 0 ;0,1=65,2=0.000000
L 1.85741644 3.03171978 1.85208327 3.02755325 2 P 0 ;0,1=65,2=0.000000
L 1.85208327 3.02755325 1.84968327 3.02463642 2 P 0 ;0,1=65,2=0.000000
L 1.84968327 3.02463642 1.84808317 3.02046909 2 P 0 ;0,1=65,2=0.000000
L 1.84808317 3.02046909 1.8475499 3.01671998 2 P 0 ;0,1=65,2=0.000000
L 1.8475499 3.01671998 1.85875 3.01671998 2 P 0 ;0,1=65,2=0.000000
L 1.88035 3.01671998 1.88035 3.04171998 2 P 0 ;0,1=65,2=0.000000
L 1.88035 3.04171998 1.87048297 3.02380325 2 P 0 ;0,1=65,2=0.000000
L 1.87048297 3.02380325 1.88381693 3.02380325 2 P 0 ;0,1=65,2=0.000000
L 1.85171319 3.08755335 1.85331329 3.09005285 2 P 0 ;0,1=291,2=0.000000
L 1.85331329 3.09005285 1.85518002 3.09130335 2 P 0 ;0,1=291,2=0.000000
L 1.85518002 3.09130335 1.85731339 3.09171998 2 P 0 ;0,1=291,2=0.000000
L 1.85731339 3.09171998 1.85998002 3.09088681 2 P 0 ;0,1=291,2=0.000000
L 1.85998002 3.09088681 1.86184675 3.08880315 2 P 0 ;0,1=291,2=0.000000
L 1.86184675 3.08880315 1.86238002 3.08630364 2 P 0 ;0,1=291,2=0.000000
L 1.86238002 3.08630364 1.86211339 3.08380266 2 P 0 ;0,1=291,2=0.000000
L 1.86211339 3.08380266 1.86104646 3.08171978 2 P 0 ;0,1=291,2=0.000000
L 1.86104646 3.08171978 1.85571329 3.07755325 2 P 0 ;0,1=291,2=0.000000
L 1.85571329 3.07755325 1.85331329 3.07463642 2 P 0 ;0,1=291,2=0.000000
L 1.85331329 3.07463642 1.85171319 3.07046909 2 P 0 ;0,1=291,2=0.000000
L 1.85171319 3.07046909 1.85117992 3.06671998 2 P 0 ;0,1=291,2=0.000000
L 1.85117992 3.06671998 1.86238002 3.06671998 2 P 0 ;0,1=291,2=0.000000
L 1.87491329 3.07046909 1.87651299 3.06838622 2 P 0 ;0,1=291,2=0.000000
L 1.87651299 3.06838622 1.87837972 3.06713652 2 P 0 ;0,1=291,2=0.000000
L 1.87837972 3.06713652 1.88077972 3.06671998 2 P 0 ;0,1=291,2=0.000000
L 1.88077972 3.06671998 1.88318022 3.06755305 2 P 0 ;0,1=291,2=0.000000
L 1.88318022 3.06755305 1.88504646 3.06921939 2 P 0 ;0,1=291,2=0.000000
L 1.88504646 3.06921939 1.88638002 3.07213622 2 P 0 ;0,1=291,2=0.000000
L 1.88638002 3.07213622 1.88664665 3.07546959 2 P 0 ;0,1=291,2=0.000000
L 1.88664665 3.07546959 1.88611339 3.07880295 2 P 0 ;0,1=291,2=0.000000
L 1.88611339 3.07880295 1.88477982 3.08088661 2 P 0 ;0,1=291,2=0.000000
L 1.88477982 3.08088661 1.88291309 3.08255295 2 P 0 ;0,1=291,2=0.000000
L 1.88291309 3.08255295 1.88104685 3.08296949 2 P 0 ;0,1=291,2=0.000000
L 1.88104685 3.08296949 1.87918002 3.08255295 2 P 0 ;0,1=291,2=0.000000
L 1.87918002 3.08255295 1.87678012 3.08088661 2 P 0 ;0,1=291,2=0.000000
L 1.87678012 3.08088661 1.87757992 3.09171998 2 P 0 ;0,1=291,2=0.000000
L 1.87757992 3.09171998 1.88477982 3.09171998 2 P 0 ;0,1=291,2=0.000000
L 1.84808317 3.13755335 1.84968327 3.14005285 2 P 0 ;0,1=292,2=0.000000
L 1.84968327 3.14005285 1.85155 3.14130335 2 P 0 ;0,1=292,2=0.000000
L 1.85155 3.14130335 1.85368337 3.14171998 2 P 0 ;0,1=292,2=0.000000
L 1.85368337 3.14171998 1.85635 3.14088681 2 P 0 ;0,1=292,2=0.000000
L 1.85635 3.14088681 1.85821673 3.13880315 2 P 0 ;0,1=292,2=0.000000
L 1.85821673 3.13880315 1.85875 3.13630364 2 P 0 ;0,1=292,2=0.000000
L 1.85875 3.13630364 1.85848337 3.13380266 2 P 0 ;0,1=292,2=0.000000
L 1.85848337 3.13380266 1.85741644 3.13171978 2 P 0 ;0,1=292,2=0.000000
L 1.85741644 3.13171978 1.85208327 3.12755325 2 P 0 ;0,1=292,2=0.000000
L 1.85208327 3.12755325 1.84968327 3.12463642 2 P 0 ;0,1=292,2=0.000000
L 1.84968327 3.12463642 1.84808317 3.12046909 2 P 0 ;0,1=292,2=0.000000
L 1.84808317 3.12046909 1.8475499 3.11671998 2 P 0 ;0,1=292,2=0.000000
L 1.8475499 3.11671998 1.85875 3.11671998 2 P 0 ;0,1=292,2=0.000000
L 1.87208317 3.12713593 1.8739499 3.13005344 2 P 0 ;0,1=292,2=0.000000
L 1.8739499 3.13005344 1.87555 3.13171978 2 P 0 ;0,1=292,2=0.000000
L 1.87555 3.13171978 1.87768337 3.13255295 2 P 0 ;0,1=292,2=0.000000
L 1.87768337 3.13255295 1.8795502 3.13171978 2 P 0 ;0,1=292,2=0.000000
L 1.8795502 3.13171978 1.88088327 3.13005344 2 P 0 ;0,1=292,2=0.000000
L 1.88088327 3.13005344 1.8819501 3.12755325 2 P 0 ;0,1=292,2=0.000000
L 1.8819501 3.12755325 1.88221673 3.12463642 2 P 0 ;0,1=292,2=0.000000
L 1.88221673 3.12463642 1.8819501 3.12213622 2 P 0 ;0,1=292,2=0.000000
L 1.8819501 3.12213622 1.88088327 3.11963602 2 P 0 ;0,1=292,2=0.000000
L 1.88088327 3.11963602 1.87928307 3.11755305 2 P 0 ;0,1=292,2=0.000000
L 1.87928307 3.11755305 1.87741683 3.11671998 2 P 0 ;0,1=292,2=0.000000
L 1.87741683 3.11671998 1.87528346 3.11755305 2 P 0 ;0,1=292,2=0.000000
L 1.87528346 3.11755305 1.87341663 3.12005256 2 P 0 ;0,1=292,2=0.000000
L 1.87341663 3.12005256 1.8723498 3.12380325 2 P 0 ;0,1=292,2=0.000000
L 1.8723498 3.12380325 1.87208317 3.12796978 2 P 0 ;0,1=292,2=0.000000
L 1.87208317 3.12796978 1.87261634 3.13338612 2 P 0 ;0,1=292,2=0.000000
L 1.87261634 3.13338612 1.87341663 3.13630364 2 P 0 ;0,1=292,2=0.000000
L 1.87341663 3.13630364 1.8747497 3.13921969 2 P 0 ;0,1=292,2=0.000000
L 1.8747497 3.13921969 1.87661654 3.14130335 2 P 0 ;0,1=292,2=0.000000
L 1.87661654 3.14130335 1.87848327 3.14171998 2 P 0 ;0,1=292,2=0.000000
L 1.87848327 3.14171998 1.88035 3.14088681 2 P 0 ;0,1=292,2=0.000000
L 1.88035 3.14088681 1.88168356 3.13880315 2 P 0 ;0,1=292,2=0.000000
L 1.85171319 3.18755335 1.85331329 3.19005285 2 P 0 ;0,1=293,2=0.000000
L 1.85331329 3.19005285 1.85518002 3.19130335 2 P 0 ;0,1=293,2=0.000000
L 1.85518002 3.19130335 1.85731339 3.19171998 2 P 0 ;0,1=293,2=0.000000
L 1.85731339 3.19171998 1.85998002 3.19088681 2 P 0 ;0,1=293,2=0.000000
L 1.85998002 3.19088681 1.86184675 3.18880315 2 P 0 ;0,1=293,2=0.000000
L 1.86184675 3.18880315 1.86238002 3.18630364 2 P 0 ;0,1=293,2=0.000000
L 1.86238002 3.18630364 1.86211339 3.18380266 2 P 0 ;0,1=293,2=0.000000
L 1.86211339 3.18380266 1.86104646 3.18171978 2 P 0 ;0,1=293,2=0.000000
L 1.86104646 3.18171978 1.85571329 3.17755325 2 P 0 ;0,1=293,2=0.000000
L 1.85571329 3.17755325 1.85331329 3.17463642 2 P 0 ;0,1=293,2=0.000000
L 1.85331329 3.17463642 1.85171319 3.17046909 2 P 0 ;0,1=293,2=0.000000
L 1.85171319 3.17046909 1.85117992 3.16671998 2 P 0 ;0,1=293,2=0.000000
L 1.85117992 3.16671998 1.86238002 3.16671998 2 P 0 ;0,1=293,2=0.000000
L 1.88024656 3.16671998 1.88077972 3.17213622 2 P 0 ;0,1=293,2=0.000000
L 1.88077972 3.17213622 1.88158002 3.17671929 2 P 0 ;0,1=293,2=0.000000
L 1.88158002 3.17671929 1.88264646 3.18088661 2 P 0 ;0,1=293,2=0.000000
L 1.88264646 3.18088661 1.88398002 3.18546978 2 P 0 ;0,1=293,2=0.000000
L 1.88398002 3.18546978 1.88611339 3.19171998 2 P 0 ;0,1=293,2=0.000000
L 1.88611339 3.19171998 1.87544656 3.19171998 2 P 0 ;0,1=293,2=0.000000
L 1.84808317 3.23755335 1.84968327 3.24005285 2 P 0 ;0,1=66,2=0.000000
L 1.84968327 3.24005285 1.85155 3.24130335 2 P 0 ;0,1=66,2=0.000000
L 1.85155 3.24130335 1.85368337 3.24171998 2 P 0 ;0,1=66,2=0.000000
L 1.85368337 3.24171998 1.85635 3.24088681 2 P 0 ;0,1=66,2=0.000000
L 1.85635 3.24088681 1.85821673 3.23880315 2 P 0 ;0,1=66,2=0.000000
L 1.85821673 3.23880315 1.85875 3.23630364 2 P 0 ;0,1=66,2=0.000000
L 1.85875 3.23630364 1.85848337 3.23380266 2 P 0 ;0,1=66,2=0.000000
L 1.85848337 3.23380266 1.85741644 3.23171978 2 P 0 ;0,1=66,2=0.000000
L 1.85741644 3.23171978 1.85208327 3.22755325 2 P 0 ;0,1=66,2=0.000000
L 1.85208327 3.22755325 1.84968327 3.22463642 2 P 0 ;0,1=66,2=0.000000
L 1.84968327 3.22463642 1.84808317 3.22046909 2 P 0 ;0,1=66,2=0.000000
L 1.84808317 3.22046909 1.8475499 3.21671998 2 P 0 ;0,1=66,2=0.000000
L 1.8475499 3.21671998 1.85875 3.21671998 2 P 0 ;0,1=66,2=0.000000
L 1.8771497 3.21671998 1.87901644 3.21713652 2 P 0 ;0,1=66,2=0.000000
L 1.87901644 3.21713652 1.8811498 3.21838622 2 P 0 ;0,1=66,2=0.000000
L 1.8811498 3.21838622 1.88248337 3.22046909 2 P 0 ;0,1=66,2=0.000000
L 1.88248337 3.22046909 1.88301663 3.22338671 2 P 0 ;0,1=66,2=0.000000
L 1.88301663 3.22338671 1.88248337 3.22630276 2 P 0 ;0,1=66,2=0.000000
L 1.88248337 3.22630276 1.88088327 3.22880295 2 P 0 ;0,1=66,2=0.000000
L 1.88088327 3.22880295 1.87848327 3.23005344 2 P 0 ;0,1=66,2=0.000000
L 1.87848327 3.23005344 1.87581663 3.23005344 2 P 0 ;0,1=66,2=0.000000
L 1.87581663 3.23005344 1.87421654 3.23088661 2 P 0 ;0,1=66,2=0.000000
L 1.87421654 3.23088661 1.87288297 3.23296949 2 P 0 ;0,1=66,2=0.000000
L 1.87288297 3.23296949 1.8723498 3.23588632 2 P 0 ;0,1=66,2=0.000000
L 1.8723498 3.23588632 1.8731501 3.23880315 2 P 0 ;0,1=66,2=0.000000
L 1.8731501 3.23880315 1.87501634 3.24088681 2 P 0 ;0,1=66,2=0.000000
L 1.87501634 3.24088681 1.8771497 3.24171998 2 P 0 ;0,1=66,2=0.000000
L 1.8771497 3.24171998 1.87928307 3.24088681 2 P 0 ;0,1=66,2=0.000000
L 1.87928307 3.24088681 1.8811498 3.23880315 2 P 0 ;0,1=66,2=0.000000
L 1.8811498 3.23880315 1.8819501 3.23588632 2 P 0 ;0,1=66,2=0.000000
L 1.8819501 3.23588632 1.88141644 3.23296949 2 P 0 ;0,1=66,2=0.000000
L 1.88141644 3.23296949 1.88008337 3.23088661 2 P 0 ;0,1=66,2=0.000000
L 1.88008337 3.23088661 1.87848327 3.23005344 2 P 0 ;0,1=66,2=0.000000
L 1.87848327 3.23005344 1.87581663 3.23005344 2 P 0 ;0,1=66,2=0.000000
L 1.87581663 3.23005344 1.87341663 3.22880295 2 P 0 ;0,1=66,2=0.000000
L 1.87341663 3.22880295 1.87181654 3.22630276 2 P 0 ;0,1=66,2=0.000000
L 1.87181654 3.22630276 1.87128327 3.22338671 2 P 0 ;0,1=66,2=0.000000
L 1.87128327 3.22338671 1.87181654 3.22046909 2 P 0 ;0,1=66,2=0.000000
L 1.87181654 3.22046909 1.8731501 3.21838622 2 P 0 ;0,1=66,2=0.000000
L 1.8731501 3.21838622 1.87528346 3.21713652 2 P 0 ;0,1=66,2=0.000000
L 1.87528346 3.21713652 1.8771497 3.21671998 2 P 0 ;0,1=66,2=0.000000
L 1.85171319 3.28755335 1.85331329 3.29005285 2 P 0 ;0,1=294,2=0.000000
L 1.85331329 3.29005285 1.85518002 3.29130335 2 P 0 ;0,1=294,2=0.000000
L 1.85518002 3.29130335 1.85731339 3.29171998 2 P 0 ;0,1=294,2=0.000000
L 1.85731339 3.29171998 1.85998002 3.29088681 2 P 0 ;0,1=294,2=0.000000
L 1.85998002 3.29088681 1.86184675 3.28880315 2 P 0 ;0,1=294,2=0.000000
L 1.86184675 3.28880315 1.86238002 3.28630364 2 P 0 ;0,1=294,2=0.000000
L 1.86238002 3.28630364 1.86211339 3.28380266 2 P 0 ;0,1=294,2=0.000000
L 1.86211339 3.28380266 1.86104646 3.28171978 2 P 0 ;0,1=294,2=0.000000
L 1.86104646 3.28171978 1.85571329 3.27755325 2 P 0 ;0,1=294,2=0.000000
L 1.85571329 3.27755325 1.85331329 3.27463642 2 P 0 ;0,1=294,2=0.000000
L 1.85331329 3.27463642 1.85171319 3.27046909 2 P 0 ;0,1=294,2=0.000000
L 1.85171319 3.27046909 1.85117992 3.26671998 2 P 0 ;0,1=294,2=0.000000
L 1.85117992 3.26671998 1.86238002 3.26671998 2 P 0 ;0,1=294,2=0.000000
L 1.87624636 3.26963602 1.87811319 3.26755305 2 P 0 ;0,1=294,2=0.000000
L 1.87811319 3.26755305 1.88024656 3.26671998 2 P 0 ;0,1=294,2=0.000000
L 1.88024656 3.26671998 1.88237992 3.26755305 2 P 0 ;0,1=294,2=0.000000
L 1.88237992 3.26755305 1.88424665 3.27005256 2 P 0 ;0,1=294,2=0.000000
L 1.88424665 3.27005256 1.88558012 3.27380325 2 P 0 ;0,1=294,2=0.000000
L 1.88558012 3.27380325 1.88611339 3.27755325 2 P 0 ;0,1=294,2=0.000000
L 1.88611339 3.27755325 1.88611339 3.28213632 2 P 0 ;0,1=294,2=0.000000
L 1.88611339 3.28213632 1.88558012 3.28588632 2 P 0 ;0,1=294,2=0.000000
L 1.88558012 3.28588632 1.88424665 3.28921969 2 P 0 ;0,1=294,2=0.000000
L 1.88424665 3.28921969 1.88264646 3.29088681 2 P 0 ;0,1=294,2=0.000000
L 1.88264646 3.29088681 1.88077972 3.29171998 2 P 0 ;0,1=294,2=0.000000
L 1.88077972 3.29171998 1.87864636 3.29088681 2 P 0 ;0,1=294,2=0.000000
L 1.87864636 3.29088681 1.87704665 3.28921969 2 P 0 ;0,1=294,2=0.000000
L 1.87704665 3.28921969 1.87597982 3.28672028 2 P 0 ;0,1=294,2=0.000000
L 1.87597982 3.28672028 1.87544656 3.28338612 2 P 0 ;0,1=294,2=0.000000
L 1.87544656 3.28338612 1.87597982 3.28047008 2 P 0 ;0,1=294,2=0.000000
L 1.87597982 3.28047008 1.87731329 3.27755325 2 P 0 ;0,1=294,2=0.000000
L 1.87731329 3.27755325 1.87891348 3.27588612 2 P 0 ;0,1=294,2=0.000000
L 1.87891348 3.27588612 1.88077972 3.27546959 2 P 0 ;0,1=294,2=0.000000
L 1.88077972 3.27546959 1.88291309 3.27630276 2 P 0 ;0,1=294,2=0.000000
L 1.88291309 3.27630276 1.88451329 3.27838642 2 P 0 ;0,1=294,2=0.000000
L 1.88451329 3.27838642 1.88611339 3.28213632 2 P 0 ;0,1=294,2=0.000000
L 1.84728327 3.32171959 1.84888297 3.31880285 2 P 0 ;0,1=295,2=0.000000
L 1.84888297 3.31880285 1.85101634 3.31713652 2 P 0 ;0,1=295,2=0.000000
L 1.85101634 3.31713652 1.85341683 3.31671998 2 P 0 ;0,1=295,2=0.000000
L 1.85341683 3.31671998 1.8555502 3.31713652 2 P 0 ;0,1=295,2=0.000000
L 1.8555502 3.31713652 1.85768356 3.31921939 2 P 0 ;0,1=295,2=0.000000
L 1.85768356 3.31921939 1.85901663 3.32171959 2 P 0 ;0,1=295,2=0.000000
L 1.85901663 3.32171959 1.85928317 3.32421988 2 P 0 ;0,1=295,2=0.000000
L 1.85928317 3.32421988 1.85875 3.32713593 2 P 0 ;0,1=295,2=0.000000
L 1.85875 3.32713593 1.85688327 3.32921959 2 P 0 ;0,1=295,2=0.000000
L 1.85688327 3.32921959 1.85501644 3.33005344 2 P 0 ;0,1=295,2=0.000000
L 1.85501644 3.33005344 1.85261654 3.33005344 2 P 0 ;0,1=295,2=0.000000
L 1.85501644 3.33005344 1.85661663 3.33130325 2 P 0 ;0,1=295,2=0.000000
L 1.85661663 3.33130325 1.8579501 3.33338612 2 P 0 ;0,1=295,2=0.000000
L 1.8579501 3.33338612 1.85848337 3.33588632 2 P 0 ;0,1=295,2=0.000000
L 1.85848337 3.33588632 1.8579501 3.33838652 2 P 0 ;0,1=295,2=0.000000
L 1.8579501 3.33838652 1.85661663 3.34046939 2 P 0 ;0,1=295,2=0.000000
L 1.85661663 3.34046939 1.85421663 3.34171998 2 P 0 ;0,1=295,2=0.000000
L 1.85421663 3.34171998 1.85181663 3.34130335 2 P 0 ;0,1=295,2=0.000000
L 1.85181663 3.34130335 1.84941663 3.33963632 2 P 0 ;0,1=295,2=0.000000
L 1.8771497 3.34171998 1.87501634 3.34088681 2 P 0 ;0,1=295,2=0.000000
L 1.87501634 3.34088681 1.87341663 3.33880315 2 P 0 ;0,1=295,2=0.000000
L 1.87341663 3.33880315 1.8723498 3.33630364 2 P 0 ;0,1=295,2=0.000000
L 1.8723498 3.33630364 1.8715499 3.33296949 2 P 0 ;0,1=295,2=0.000000
L 1.8715499 3.33296949 1.87128327 3.32921959 2 P 0 ;0,1=295,2=0.000000
L 1.87128327 3.32921959 1.8715499 3.32546959 2 P 0 ;0,1=295,2=0.000000
L 1.8715499 3.32546959 1.8723498 3.32213622 2 P 0 ;0,1=295,2=0.000000
L 1.8723498 3.32213622 1.87341663 3.31963602 2 P 0 ;0,1=295,2=0.000000
L 1.87341663 3.31963602 1.87501634 3.31755305 2 P 0 ;0,1=295,2=0.000000
L 1.87501634 3.31755305 1.8771497 3.31671998 2 P 0 ;0,1=295,2=0.000000
L 1.8771497 3.31671998 1.87928307 3.31755305 2 P 0 ;0,1=295,2=0.000000
L 1.87928307 3.31755305 1.88088327 3.31963602 2 P 0 ;0,1=295,2=0.000000
L 1.88088327 3.31963602 1.8819501 3.32213622 2 P 0 ;0,1=295,2=0.000000
L 1.8819501 3.32213622 1.88275 3.32546959 2 P 0 ;0,1=295,2=0.000000
L 1.88275 3.32546959 1.88301663 3.32921959 2 P 0 ;0,1=295,2=0.000000
L 1.88301663 3.32921959 1.88275 3.33296949 2 P 0 ;0,1=295,2=0.000000
L 1.88275 3.33296949 1.8819501 3.33630364 2 P 0 ;0,1=295,2=0.000000
L 1.8819501 3.33630364 1.88088327 3.33880315 2 P 0 ;0,1=295,2=0.000000
L 1.88088327 3.33880315 1.87928307 3.34088681 2 P 0 ;0,1=295,2=0.000000
L 1.87928307 3.34088681 1.8771497 3.34171998 2 P 0 ;0,1=295,2=0.000000
L 1.85091329 3.37171959 1.85251299 3.36880285 2 P 0 ;0,1=296,2=0.000000
L 1.85251299 3.36880285 1.85464636 3.36713652 2 P 0 ;0,1=296,2=0.000000
L 1.85464636 3.36713652 1.85704685 3.36671998 2 P 0 ;0,1=296,2=0.000000
L 1.85704685 3.36671998 1.85918022 3.36713652 2 P 0 ;0,1=296,2=0.000000
L 1.85918022 3.36713652 1.86131358 3.36921939 2 P 0 ;0,1=296,2=0.000000
L 1.86131358 3.36921939 1.86264665 3.37171959 2 P 0 ;0,1=296,2=0.000000
L 1.86264665 3.37171959 1.86291319 3.37421988 2 P 0 ;0,1=296,2=0.000000
L 1.86291319 3.37421988 1.86238002 3.37713593 2 P 0 ;0,1=296,2=0.000000
L 1.86238002 3.37713593 1.86051329 3.37921959 2 P 0 ;0,1=296,2=0.000000
L 1.86051329 3.37921959 1.85864646 3.38005344 2 P 0 ;0,1=296,2=0.000000
L 1.85864646 3.38005344 1.85624656 3.38005344 2 P 0 ;0,1=296,2=0.000000
L 1.85864646 3.38005344 1.86024665 3.38130325 2 P 0 ;0,1=296,2=0.000000
L 1.86024665 3.38130325 1.86158012 3.38338612 2 P 0 ;0,1=296,2=0.000000
L 1.86158012 3.38338612 1.86211339 3.38588632 2 P 0 ;0,1=296,2=0.000000
L 1.86211339 3.38588632 1.86158012 3.38838652 2 P 0 ;0,1=296,2=0.000000
L 1.86158012 3.38838652 1.86024665 3.39046939 2 P 0 ;0,1=296,2=0.000000
L 1.86024665 3.39046939 1.85784665 3.39171998 2 P 0 ;0,1=296,2=0.000000
L 1.85784665 3.39171998 1.85544665 3.39130335 2 P 0 ;0,1=296,2=0.000000
L 1.85544665 3.39130335 1.85304665 3.38963632 2 P 0 ;0,1=296,2=0.000000
L 1.88077972 3.36671998 1.88077972 3.39171998 2 P 0 ;0,1=296,2=0.000000
L 1.88077972 3.39171998 1.87757992 3.38672028 2 P 0 ;0,1=296,2=0.000000
L 1.87757992 3.36671998 1.88397953 3.36671998 2 P 0 ;0,1=296,2=0.000000
L 1.84728327 3.42171959 1.84888297 3.41880285 2 P 0 ;0,1=297,2=0.000000
L 1.84888297 3.41880285 1.85101634 3.41713652 2 P 0 ;0,1=297,2=0.000000
L 1.85101634 3.41713652 1.85341683 3.41671998 2 P 0 ;0,1=297,2=0.000000
L 1.85341683 3.41671998 1.8555502 3.41713652 2 P 0 ;0,1=297,2=0.000000
L 1.8555502 3.41713652 1.85768356 3.41921939 2 P 0 ;0,1=297,2=0.000000
L 1.85768356 3.41921939 1.85901663 3.42171959 2 P 0 ;0,1=297,2=0.000000
L 1.85901663 3.42171959 1.85928317 3.42421988 2 P 0 ;0,1=297,2=0.000000
L 1.85928317 3.42421988 1.85875 3.42713593 2 P 0 ;0,1=297,2=0.000000
L 1.85875 3.42713593 1.85688327 3.42921959 2 P 0 ;0,1=297,2=0.000000
L 1.85688327 3.42921959 1.85501644 3.43005344 2 P 0 ;0,1=297,2=0.000000
L 1.85501644 3.43005344 1.85261654 3.43005344 2 P 0 ;0,1=297,2=0.000000
L 1.85501644 3.43005344 1.85661663 3.43130325 2 P 0 ;0,1=297,2=0.000000
L 1.85661663 3.43130325 1.8579501 3.43338612 2 P 0 ;0,1=297,2=0.000000
L 1.8579501 3.43338612 1.85848337 3.43588632 2 P 0 ;0,1=297,2=0.000000
L 1.85848337 3.43588632 1.8579501 3.43838652 2 P 0 ;0,1=297,2=0.000000
L 1.8579501 3.43838652 1.85661663 3.44046939 2 P 0 ;0,1=297,2=0.000000
L 1.85661663 3.44046939 1.85421663 3.44171998 2 P 0 ;0,1=297,2=0.000000
L 1.85421663 3.44171998 1.85181663 3.44130335 2 P 0 ;0,1=297,2=0.000000
L 1.85181663 3.44130335 1.84941663 3.43963632 2 P 0 ;0,1=297,2=0.000000
L 1.87208317 3.43755335 1.87368327 3.44005285 2 P 0 ;0,1=297,2=0.000000
L 1.87368327 3.44005285 1.87555 3.44130335 2 P 0 ;0,1=297,2=0.000000
L 1.87555 3.44130335 1.87768337 3.44171998 2 P 0 ;0,1=297,2=0.000000
L 1.87768337 3.44171998 1.88035 3.44088681 2 P 0 ;0,1=297,2=0.000000
L 1.88035 3.44088681 1.88221673 3.43880315 2 P 0 ;0,1=297,2=0.000000
L 1.88221673 3.43880315 1.88275 3.43630364 2 P 0 ;0,1=297,2=0.000000
L 1.88275 3.43630364 1.88248337 3.43380266 2 P 0 ;0,1=297,2=0.000000
L 1.88248337 3.43380266 1.88141644 3.43171978 2 P 0 ;0,1=297,2=0.000000
L 1.88141644 3.43171978 1.87608327 3.42755325 2 P 0 ;0,1=297,2=0.000000
L 1.87608327 3.42755325 1.87368327 3.42463642 2 P 0 ;0,1=297,2=0.000000
L 1.87368327 3.42463642 1.87208317 3.42046909 2 P 0 ;0,1=297,2=0.000000
L 1.87208317 3.42046909 1.8715499 3.41671998 2 P 0 ;0,1=297,2=0.000000
L 1.8715499 3.41671998 1.88275 3.41671998 2 P 0 ;0,1=297,2=0.000000
L 1.85091329 3.47171959 1.85251299 3.46880285 2 P 0 ;0,1=298,2=0.000000
L 1.85251299 3.46880285 1.85464636 3.46713652 2 P 0 ;0,1=298,2=0.000000
L 1.85464636 3.46713652 1.85704685 3.46671998 2 P 0 ;0,1=298,2=0.000000
L 1.85704685 3.46671998 1.85918022 3.46713652 2 P 0 ;0,1=298,2=0.000000
L 1.85918022 3.46713652 1.86131358 3.46921939 2 P 0 ;0,1=298,2=0.000000
L 1.86131358 3.46921939 1.86264665 3.47171959 2 P 0 ;0,1=298,2=0.000000
L 1.86264665 3.47171959 1.86291319 3.47421988 2 P 0 ;0,1=298,2=0.000000
L 1.86291319 3.47421988 1.86238002 3.47713593 2 P 0 ;0,1=298,2=0.000000
L 1.86238002 3.47713593 1.86051329 3.47921959 2 P 0 ;0,1=298,2=0.000000
L 1.86051329 3.47921959 1.85864646 3.48005344 2 P 0 ;0,1=298,2=0.000000
L 1.85864646 3.48005344 1.85624656 3.48005344 2 P 0 ;0,1=298,2=0.000000
L 1.85864646 3.48005344 1.86024665 3.48130325 2 P 0 ;0,1=298,2=0.000000
L 1.86024665 3.48130325 1.86158012 3.48338612 2 P 0 ;0,1=298,2=0.000000
L 1.86158012 3.48338612 1.86211339 3.48588632 2 P 0 ;0,1=298,2=0.000000
L 1.86211339 3.48588632 1.86158012 3.48838652 2 P 0 ;0,1=298,2=0.000000
L 1.86158012 3.48838652 1.86024665 3.49046939 2 P 0 ;0,1=298,2=0.000000
L 1.86024665 3.49046939 1.85784665 3.49171998 2 P 0 ;0,1=298,2=0.000000
L 1.85784665 3.49171998 1.85544665 3.49130335 2 P 0 ;0,1=298,2=0.000000
L 1.85544665 3.49130335 1.85304665 3.48963632 2 P 0 ;0,1=298,2=0.000000
L 1.87491329 3.47171959 1.87651299 3.46880285 2 P 0 ;0,1=298,2=0.000000
L 1.87651299 3.46880285 1.87864636 3.46713652 2 P 0 ;0,1=298,2=0.000000
L 1.87864636 3.46713652 1.88104685 3.46671998 2 P 0 ;0,1=298,2=0.000000
L 1.88104685 3.46671998 1.88318022 3.46713652 2 P 0 ;0,1=298,2=0.000000
L 1.88318022 3.46713652 1.88531358 3.46921939 2 P 0 ;0,1=298,2=0.000000
L 1.88531358 3.46921939 1.88664665 3.47171959 2 P 0 ;0,1=298,2=0.000000
L 1.88664665 3.47171959 1.88691319 3.47421988 2 P 0 ;0,1=298,2=0.000000
L 1.88691319 3.47421988 1.88638002 3.47713593 2 P 0 ;0,1=298,2=0.000000
L 1.88638002 3.47713593 1.88451329 3.47921959 2 P 0 ;0,1=298,2=0.000000
L 1.88451329 3.47921959 1.88264646 3.48005344 2 P 0 ;0,1=298,2=0.000000
L 1.88264646 3.48005344 1.88024656 3.48005344 2 P 0 ;0,1=298,2=0.000000
L 1.88264646 3.48005344 1.88424665 3.48130325 2 P 0 ;0,1=298,2=0.000000
L 1.88424665 3.48130325 1.88558012 3.48338612 2 P 0 ;0,1=298,2=0.000000
L 1.88558012 3.48338612 1.88611339 3.48588632 2 P 0 ;0,1=298,2=0.000000
L 1.88611339 3.48588632 1.88558012 3.48838652 2 P 0 ;0,1=298,2=0.000000
L 1.88558012 3.48838652 1.88424665 3.49046939 2 P 0 ;0,1=298,2=0.000000
L 1.88424665 3.49046939 1.88184665 3.49171998 2 P 0 ;0,1=298,2=0.000000
L 1.88184665 3.49171998 1.87944665 3.49130335 2 P 0 ;0,1=298,2=0.000000
L 1.87944665 3.49130335 1.87704665 3.48963632 2 P 0 ;0,1=298,2=0.000000
L 1.84728327 3.52171959 1.84888297 3.51880285 2 P 0 ;0,1=299,2=0.000000
L 1.84888297 3.51880285 1.85101634 3.51713652 2 P 0 ;0,1=299,2=0.000000
L 1.85101634 3.51713652 1.85341683 3.51671998 2 P 0 ;0,1=299,2=0.000000
L 1.85341683 3.51671998 1.8555502 3.51713652 2 P 0 ;0,1=299,2=0.000000
L 1.8555502 3.51713652 1.85768356 3.51921939 2 P 0 ;0,1=299,2=0.000000
L 1.85768356 3.51921939 1.85901663 3.52171959 2 P 0 ;0,1=299,2=0.000000
L 1.85901663 3.52171959 1.85928317 3.52421988 2 P 0 ;0,1=299,2=0.000000
L 1.85928317 3.52421988 1.85875 3.52713593 2 P 0 ;0,1=299,2=0.000000
L 1.85875 3.52713593 1.85688327 3.52921959 2 P 0 ;0,1=299,2=0.000000
L 1.85688327 3.52921959 1.85501644 3.53005344 2 P 0 ;0,1=299,2=0.000000
L 1.85501644 3.53005344 1.85261654 3.53005344 2 P 0 ;0,1=299,2=0.000000
L 1.85501644 3.53005344 1.85661663 3.53130325 2 P 0 ;0,1=299,2=0.000000
L 1.85661663 3.53130325 1.8579501 3.53338612 2 P 0 ;0,1=299,2=0.000000
L 1.8579501 3.53338612 1.85848337 3.53588632 2 P 0 ;0,1=299,2=0.000000
L 1.85848337 3.53588632 1.8579501 3.53838652 2 P 0 ;0,1=299,2=0.000000
L 1.8579501 3.53838652 1.85661663 3.54046939 2 P 0 ;0,1=299,2=0.000000
L 1.85661663 3.54046939 1.85421663 3.54171998 2 P 0 ;0,1=299,2=0.000000
L 1.85421663 3.54171998 1.85181663 3.54130335 2 P 0 ;0,1=299,2=0.000000
L 1.85181663 3.54130335 1.84941663 3.53963632 2 P 0 ;0,1=299,2=0.000000
L 1.88035 3.51671998 1.88035 3.54171998 2 P 0 ;0,1=299,2=0.000000
L 1.88035 3.54171998 1.87048297 3.52380325 2 P 0 ;0,1=299,2=0.000000
L 1.87048297 3.52380325 1.88381693 3.52380325 2 P 0 ;0,1=299,2=0.000000
L 1.85091329 3.57171959 1.85251299 3.56880285 2 P 0 ;0,1=300,2=0.000000
L 1.85251299 3.56880285 1.85464636 3.56713652 2 P 0 ;0,1=300,2=0.000000
L 1.85464636 3.56713652 1.85704685 3.56671998 2 P 0 ;0,1=300,2=0.000000
L 1.85704685 3.56671998 1.85918022 3.56713652 2 P 0 ;0,1=300,2=0.000000
L 1.85918022 3.56713652 1.86131358 3.56921939 2 P 0 ;0,1=300,2=0.000000
L 1.86131358 3.56921939 1.86264665 3.57171959 2 P 0 ;0,1=300,2=0.000000
L 1.86264665 3.57171959 1.86291319 3.57421988 2 P 0 ;0,1=300,2=0.000000
L 1.86291319 3.57421988 1.86238002 3.57713593 2 P 0 ;0,1=300,2=0.000000
L 1.86238002 3.57713593 1.86051329 3.57921959 2 P 0 ;0,1=300,2=0.000000
L 1.86051329 3.57921959 1.85864646 3.58005344 2 P 0 ;0,1=300,2=0.000000
L 1.85864646 3.58005344 1.85624656 3.58005344 2 P 0 ;0,1=300,2=0.000000
L 1.85864646 3.58005344 1.86024665 3.58130325 2 P 0 ;0,1=300,2=0.000000
L 1.86024665 3.58130325 1.86158012 3.58338612 2 P 0 ;0,1=300,2=0.000000
L 1.86158012 3.58338612 1.86211339 3.58588632 2 P 0 ;0,1=300,2=0.000000
L 1.86211339 3.58588632 1.86158012 3.58838652 2 P 0 ;0,1=300,2=0.000000
L 1.86158012 3.58838652 1.86024665 3.59046939 2 P 0 ;0,1=300,2=0.000000
L 1.86024665 3.59046939 1.85784665 3.59171998 2 P 0 ;0,1=300,2=0.000000
L 1.85784665 3.59171998 1.85544665 3.59130335 2 P 0 ;0,1=300,2=0.000000
L 1.85544665 3.59130335 1.85304665 3.58963632 2 P 0 ;0,1=300,2=0.000000
L 1.87491329 3.57046909 1.87651299 3.56838622 2 P 0 ;0,1=300,2=0.000000
L 1.87651299 3.56838622 1.87837972 3.56713652 2 P 0 ;0,1=300,2=0.000000
L 1.87837972 3.56713652 1.88077972 3.56671998 2 P 0 ;0,1=300,2=0.000000
L 1.88077972 3.56671998 1.88318022 3.56755305 2 P 0 ;0,1=300,2=0.000000
L 1.88318022 3.56755305 1.88504646 3.56921939 2 P 0 ;0,1=300,2=0.000000
L 1.88504646 3.56921939 1.88638002 3.57213622 2 P 0 ;0,1=300,2=0.000000
L 1.88638002 3.57213622 1.88664665 3.57546959 2 P 0 ;0,1=300,2=0.000000
L 1.88664665 3.57546959 1.88611339 3.57880295 2 P 0 ;0,1=300,2=0.000000
L 1.88611339 3.57880295 1.88477982 3.58088661 2 P 0 ;0,1=300,2=0.000000
L 1.88477982 3.58088661 1.88291309 3.58255295 2 P 0 ;0,1=300,2=0.000000
L 1.88291309 3.58255295 1.88104685 3.58296949 2 P 0 ;0,1=300,2=0.000000
L 1.88104685 3.58296949 1.87918002 3.58255295 2 P 0 ;0,1=300,2=0.000000
L 1.87918002 3.58255295 1.87678012 3.58088661 2 P 0 ;0,1=300,2=0.000000
L 1.87678012 3.58088661 1.87757992 3.59171998 2 P 0 ;0,1=300,2=0.000000
L 1.87757992 3.59171998 1.88477982 3.59171998 2 P 0 ;0,1=300,2=0.000000
L 1.84728327 3.62171959 1.84888297 3.61880285 2 P 0 ;0,1=301,2=0.000000
L 1.84888297 3.61880285 1.85101634 3.61713652 2 P 0 ;0,1=301,2=0.000000
L 1.85101634 3.61713652 1.85341683 3.61671998 2 P 0 ;0,1=301,2=0.000000
L 1.85341683 3.61671998 1.8555502 3.61713652 2 P 0 ;0,1=301,2=0.000000
L 1.8555502 3.61713652 1.85768356 3.61921939 2 P 0 ;0,1=301,2=0.000000
L 1.85768356 3.61921939 1.85901663 3.62171959 2 P 0 ;0,1=301,2=0.000000
L 1.85901663 3.62171959 1.85928317 3.62421988 2 P 0 ;0,1=301,2=0.000000
L 1.85928317 3.62421988 1.85875 3.62713593 2 P 0 ;0,1=301,2=0.000000
L 1.85875 3.62713593 1.85688327 3.62921959 2 P 0 ;0,1=301,2=0.000000
L 1.85688327 3.62921959 1.85501644 3.63005344 2 P 0 ;0,1=301,2=0.000000
L 1.85501644 3.63005344 1.85261654 3.63005344 2 P 0 ;0,1=301,2=0.000000
L 1.85501644 3.63005344 1.85661663 3.63130325 2 P 0 ;0,1=301,2=0.000000
L 1.85661663 3.63130325 1.8579501 3.63338612 2 P 0 ;0,1=301,2=0.000000
L 1.8579501 3.63338612 1.85848337 3.63588632 2 P 0 ;0,1=301,2=0.000000
L 1.85848337 3.63588632 1.8579501 3.63838652 2 P 0 ;0,1=301,2=0.000000
L 1.8579501 3.63838652 1.85661663 3.64046939 2 P 0 ;0,1=301,2=0.000000
L 1.85661663 3.64046939 1.85421663 3.64171998 2 P 0 ;0,1=301,2=0.000000
L 1.85421663 3.64171998 1.85181663 3.64130335 2 P 0 ;0,1=301,2=0.000000
L 1.85181663 3.64130335 1.84941663 3.63963632 2 P 0 ;0,1=301,2=0.000000
L 1.87208317 3.62713593 1.8739499 3.63005344 2 P 0 ;0,1=301,2=0.000000
L 1.8739499 3.63005344 1.87555 3.63171978 2 P 0 ;0,1=301,2=0.000000
L 1.87555 3.63171978 1.87768337 3.63255295 2 P 0 ;0,1=301,2=0.000000
L 1.87768337 3.63255295 1.8795502 3.63171978 2 P 0 ;0,1=301,2=0.000000
L 1.8795502 3.63171978 1.88088327 3.63005344 2 P 0 ;0,1=301,2=0.000000
L 1.88088327 3.63005344 1.8819501 3.62755325 2 P 0 ;0,1=301,2=0.000000
L 1.8819501 3.62755325 1.88221673 3.62463642 2 P 0 ;0,1=301,2=0.000000
L 1.88221673 3.62463642 1.8819501 3.62213622 2 P 0 ;0,1=301,2=0.000000
L 1.8819501 3.62213622 1.88088327 3.61963602 2 P 0 ;0,1=301,2=0.000000
L 1.88088327 3.61963602 1.87928307 3.61755305 2 P 0 ;0,1=301,2=0.000000
L 1.87928307 3.61755305 1.87741683 3.61671998 2 P 0 ;0,1=301,2=0.000000
L 1.87741683 3.61671998 1.87528346 3.61755305 2 P 0 ;0,1=301,2=0.000000
L 1.87528346 3.61755305 1.87341663 3.62005256 2 P 0 ;0,1=301,2=0.000000
L 1.87341663 3.62005256 1.8723498 3.62380325 2 P 0 ;0,1=301,2=0.000000
L 1.8723498 3.62380325 1.87208317 3.62796978 2 P 0 ;0,1=301,2=0.000000
L 1.87208317 3.62796978 1.87261634 3.63338612 2 P 0 ;0,1=301,2=0.000000
L 1.87261634 3.63338612 1.87341663 3.63630364 2 P 0 ;0,1=301,2=0.000000
L 1.87341663 3.63630364 1.8747497 3.63921969 2 P 0 ;0,1=301,2=0.000000
L 1.8747497 3.63921969 1.87661654 3.64130335 2 P 0 ;0,1=301,2=0.000000
L 1.87661654 3.64130335 1.87848327 3.64171998 2 P 0 ;0,1=301,2=0.000000
L 1.87848327 3.64171998 1.88035 3.64088681 2 P 0 ;0,1=301,2=0.000000
L 1.88035 3.64088681 1.88168356 3.63880315 2 P 0 ;0,1=301,2=0.000000
L 1.85091329 3.67171959 1.85251299 3.66880285 2 P 0 ;0,1=302,2=0.000000
L 1.85251299 3.66880285 1.85464636 3.66713652 2 P 0 ;0,1=302,2=0.000000
L 1.85464636 3.66713652 1.85704685 3.66671998 2 P 0 ;0,1=302,2=0.000000
L 1.85704685 3.66671998 1.85918022 3.66713652 2 P 0 ;0,1=302,2=0.000000
L 1.85918022 3.66713652 1.86131358 3.66921939 2 P 0 ;0,1=302,2=0.000000
L 1.86131358 3.66921939 1.86264665 3.67171959 2 P 0 ;0,1=302,2=0.000000
L 1.86264665 3.67171959 1.86291319 3.67421988 2 P 0 ;0,1=302,2=0.000000
L 1.86291319 3.67421988 1.86238002 3.67713593 2 P 0 ;0,1=302,2=0.000000
L 1.86238002 3.67713593 1.86051329 3.67921959 2 P 0 ;0,1=302,2=0.000000
L 1.86051329 3.67921959 1.85864646 3.68005344 2 P 0 ;0,1=302,2=0.000000
L 1.85864646 3.68005344 1.85624656 3.68005344 2 P 0 ;0,1=302,2=0.000000
L 1.85864646 3.68005344 1.86024665 3.68130325 2 P 0 ;0,1=302,2=0.000000
L 1.86024665 3.68130325 1.86158012 3.68338612 2 P 0 ;0,1=302,2=0.000000
L 1.86158012 3.68338612 1.86211339 3.68588632 2 P 0 ;0,1=302,2=0.000000
L 1.86211339 3.68588632 1.86158012 3.68838652 2 P 0 ;0,1=302,2=0.000000
L 1.86158012 3.68838652 1.86024665 3.69046939 2 P 0 ;0,1=302,2=0.000000
L 1.86024665 3.69046939 1.85784665 3.69171998 2 P 0 ;0,1=302,2=0.000000
L 1.85784665 3.69171998 1.85544665 3.69130335 2 P 0 ;0,1=302,2=0.000000
L 1.85544665 3.69130335 1.85304665 3.68963632 2 P 0 ;0,1=302,2=0.000000
L 1.88024656 3.66671998 1.88077972 3.67213622 2 P 0 ;0,1=302,2=0.000000
L 1.88077972 3.67213622 1.88158002 3.67671929 2 P 0 ;0,1=302,2=0.000000
L 1.88158002 3.67671929 1.88264646 3.68088661 2 P 0 ;0,1=302,2=0.000000
L 1.88264646 3.68088661 1.88398002 3.68546978 2 P 0 ;0,1=302,2=0.000000
L 1.88398002 3.68546978 1.88611339 3.69171998 2 P 0 ;0,1=302,2=0.000000
L 1.88611339 3.69171998 1.87544656 3.69171998 2 P 0 ;0,1=302,2=0.000000
L 1.84728327 3.72171959 1.84888297 3.71880285 2 P 0 ;0,1=303,2=0.000000
L 1.84888297 3.71880285 1.85101634 3.71713652 2 P 0 ;0,1=303,2=0.000000
L 1.85101634 3.71713652 1.85341683 3.71671998 2 P 0 ;0,1=303,2=0.000000
L 1.85341683 3.71671998 1.8555502 3.71713652 2 P 0 ;0,1=303,2=0.000000
L 1.8555502 3.71713652 1.85768356 3.71921939 2 P 0 ;0,1=303,2=0.000000
L 1.85768356 3.71921939 1.85901663 3.72171959 2 P 0 ;0,1=303,2=0.000000
L 1.85901663 3.72171959 1.85928317 3.72421988 2 P 0 ;0,1=303,2=0.000000
L 1.85928317 3.72421988 1.85875 3.72713593 2 P 0 ;0,1=303,2=0.000000
L 1.85875 3.72713593 1.85688327 3.72921959 2 P 0 ;0,1=303,2=0.000000
L 1.85688327 3.72921959 1.85501644 3.73005344 2 P 0 ;0,1=303,2=0.000000
L 1.85501644 3.73005344 1.85261654 3.73005344 2 P 0 ;0,1=303,2=0.000000
L 1.85501644 3.73005344 1.85661663 3.73130325 2 P 0 ;0,1=303,2=0.000000
L 1.85661663 3.73130325 1.8579501 3.73338612 2 P 0 ;0,1=303,2=0.000000
L 1.8579501 3.73338612 1.85848337 3.73588632 2 P 0 ;0,1=303,2=0.000000
L 1.85848337 3.73588632 1.8579501 3.73838652 2 P 0 ;0,1=303,2=0.000000
L 1.8579501 3.73838652 1.85661663 3.74046939 2 P 0 ;0,1=303,2=0.000000
L 1.85661663 3.74046939 1.85421663 3.74171998 2 P 0 ;0,1=303,2=0.000000
L 1.85421663 3.74171998 1.85181663 3.74130335 2 P 0 ;0,1=303,2=0.000000
L 1.85181663 3.74130335 1.84941663 3.73963632 2 P 0 ;0,1=303,2=0.000000
L 1.8771497 3.71671998 1.87901644 3.71713652 2 P 0 ;0,1=303,2=0.000000
L 1.87901644 3.71713652 1.8811498 3.71838622 2 P 0 ;0,1=303,2=0.000000
L 1.8811498 3.71838622 1.88248337 3.72046909 2 P 0 ;0,1=303,2=0.000000
L 1.88248337 3.72046909 1.88301663 3.72338671 2 P 0 ;0,1=303,2=0.000000
L 1.88301663 3.72338671 1.88248337 3.72630276 2 P 0 ;0,1=303,2=0.000000
L 1.88248337 3.72630276 1.88088327 3.72880295 2 P 0 ;0,1=303,2=0.000000
L 1.88088327 3.72880295 1.87848327 3.73005344 2 P 0 ;0,1=303,2=0.000000
L 1.87848327 3.73005344 1.87581663 3.73005344 2 P 0 ;0,1=303,2=0.000000
L 1.87581663 3.73005344 1.87421654 3.73088661 2 P 0 ;0,1=303,2=0.000000
L 1.87421654 3.73088661 1.87288297 3.73296949 2 P 0 ;0,1=303,2=0.000000
L 1.87288297 3.73296949 1.8723498 3.73588632 2 P 0 ;0,1=303,2=0.000000
L 1.8723498 3.73588632 1.8731501 3.73880315 2 P 0 ;0,1=303,2=0.000000
L 1.8731501 3.73880315 1.87501634 3.74088681 2 P 0 ;0,1=303,2=0.000000
L 1.87501634 3.74088681 1.8771497 3.74171998 2 P 0 ;0,1=303,2=0.000000
L 1.8771497 3.74171998 1.87928307 3.74088681 2 P 0 ;0,1=303,2=0.000000
L 1.87928307 3.74088681 1.8811498 3.73880315 2 P 0 ;0,1=303,2=0.000000
L 1.8811498 3.73880315 1.8819501 3.73588632 2 P 0 ;0,1=303,2=0.000000
L 1.8819501 3.73588632 1.88141644 3.73296949 2 P 0 ;0,1=303,2=0.000000
L 1.88141644 3.73296949 1.88008337 3.73088661 2 P 0 ;0,1=303,2=0.000000
L 1.88008337 3.73088661 1.87848327 3.73005344 2 P 0 ;0,1=303,2=0.000000
L 1.87848327 3.73005344 1.87581663 3.73005344 2 P 0 ;0,1=303,2=0.000000
L 1.87581663 3.73005344 1.87341663 3.72880295 2 P 0 ;0,1=303,2=0.000000
L 1.87341663 3.72880295 1.87181654 3.72630276 2 P 0 ;0,1=303,2=0.000000
L 1.87181654 3.72630276 1.87128327 3.72338671 2 P 0 ;0,1=303,2=0.000000
L 1.87128327 3.72338671 1.87181654 3.72046909 2 P 0 ;0,1=303,2=0.000000
L 1.87181654 3.72046909 1.8731501 3.71838622 2 P 0 ;0,1=303,2=0.000000
L 1.8731501 3.71838622 1.87528346 3.71713652 2 P 0 ;0,1=303,2=0.000000
L 1.87528346 3.71713652 1.8771497 3.71671998 2 P 0 ;0,1=303,2=0.000000
L 1.85091329 3.77171959 1.85251299 3.76880285 2 P 0 ;0,1=304,2=0.000000
L 1.85251299 3.76880285 1.85464636 3.76713652 2 P 0 ;0,1=304,2=0.000000
L 1.85464636 3.76713652 1.85704685 3.76671998 2 P 0 ;0,1=304,2=0.000000
L 1.85704685 3.76671998 1.85918022 3.76713652 2 P 0 ;0,1=304,2=0.000000
L 1.85918022 3.76713652 1.86131358 3.76921939 2 P 0 ;0,1=304,2=0.000000
L 1.86131358 3.76921939 1.86264665 3.77171959 2 P 0 ;0,1=304,2=0.000000
L 1.86264665 3.77171959 1.86291319 3.77421988 2 P 0 ;0,1=304,2=0.000000
L 1.86291319 3.77421988 1.86238002 3.77713593 2 P 0 ;0,1=304,2=0.000000
L 1.86238002 3.77713593 1.86051329 3.77921959 2 P 0 ;0,1=304,2=0.000000
L 1.86051329 3.77921959 1.85864646 3.78005344 2 P 0 ;0,1=304,2=0.000000
L 1.85864646 3.78005344 1.85624656 3.78005344 2 P 0 ;0,1=304,2=0.000000
L 1.85864646 3.78005344 1.86024665 3.78130325 2 P 0 ;0,1=304,2=0.000000
L 1.86024665 3.78130325 1.86158012 3.78338612 2 P 0 ;0,1=304,2=0.000000
L 1.86158012 3.78338612 1.86211339 3.78588632 2 P 0 ;0,1=304,2=0.000000
L 1.86211339 3.78588632 1.86158012 3.78838652 2 P 0 ;0,1=304,2=0.000000
L 1.86158012 3.78838652 1.86024665 3.79046939 2 P 0 ;0,1=304,2=0.000000
L 1.86024665 3.79046939 1.85784665 3.79171998 2 P 0 ;0,1=304,2=0.000000
L 1.85784665 3.79171998 1.85544665 3.79130335 2 P 0 ;0,1=304,2=0.000000
L 1.85544665 3.79130335 1.85304665 3.78963632 2 P 0 ;0,1=304,2=0.000000
L 1.87624636 3.76963602 1.87811319 3.76755305 2 P 0 ;0,1=304,2=0.000000
L 1.87811319 3.76755305 1.88024656 3.76671998 2 P 0 ;0,1=304,2=0.000000
L 1.88024656 3.76671998 1.88237992 3.76755305 2 P 0 ;0,1=304,2=0.000000
L 1.88237992 3.76755305 1.88424665 3.77005256 2 P 0 ;0,1=304,2=0.000000
L 1.88424665 3.77005256 1.88558012 3.77380325 2 P 0 ;0,1=304,2=0.000000
L 1.88558012 3.77380325 1.88611339 3.77755325 2 P 0 ;0,1=304,2=0.000000
L 1.88611339 3.77755325 1.88611339 3.78213632 2 P 0 ;0,1=304,2=0.000000
L 1.88611339 3.78213632 1.88558012 3.78588632 2 P 0 ;0,1=304,2=0.000000
L 1.88558012 3.78588632 1.88424665 3.78921969 2 P 0 ;0,1=304,2=0.000000
L 1.88424665 3.78921969 1.88264646 3.79088681 2 P 0 ;0,1=304,2=0.000000
L 1.88264646 3.79088681 1.88077972 3.79171998 2 P 0 ;0,1=304,2=0.000000
L 1.88077972 3.79171998 1.87864636 3.79088681 2 P 0 ;0,1=304,2=0.000000
L 1.87864636 3.79088681 1.87704665 3.78921969 2 P 0 ;0,1=304,2=0.000000
L 1.87704665 3.78921969 1.87597982 3.78672028 2 P 0 ;0,1=304,2=0.000000
L 1.87597982 3.78672028 1.87544656 3.78338612 2 P 0 ;0,1=304,2=0.000000
L 1.87544656 3.78338612 1.87597982 3.78047008 2 P 0 ;0,1=304,2=0.000000
L 1.87597982 3.78047008 1.87731329 3.77755325 2 P 0 ;0,1=304,2=0.000000
L 1.87731329 3.77755325 1.87891348 3.77588612 2 P 0 ;0,1=304,2=0.000000
L 1.87891348 3.77588612 1.88077972 3.77546959 2 P 0 ;0,1=304,2=0.000000
L 1.88077972 3.77546959 1.88291309 3.77630276 2 P 0 ;0,1=304,2=0.000000
L 1.88291309 3.77630276 1.88451329 3.77838642 2 P 0 ;0,1=304,2=0.000000
L 1.88451329 3.77838642 1.88611339 3.78213632 2 P 0 ;0,1=304,2=0.000000
L 1.85635 3.81671998 1.85635 3.84171998 2 P 0 ;0,1=305,2=0.000000
L 1.85635 3.84171998 1.84648297 3.82380325 2 P 0 ;0,1=305,2=0.000000
L 1.84648297 3.82380325 1.85981693 3.82380325 2 P 0 ;0,1=305,2=0.000000
L 1.8771497 3.84171998 1.87501634 3.84088681 2 P 0 ;0,1=305,2=0.000000
L 1.87501634 3.84088681 1.87341663 3.83880315 2 P 0 ;0,1=305,2=0.000000
L 1.87341663 3.83880315 1.8723498 3.83630364 2 P 0 ;0,1=305,2=0.000000
L 1.8723498 3.83630364 1.8715499 3.83296949 2 P 0 ;0,1=305,2=0.000000
L 1.8715499 3.83296949 1.87128327 3.82921959 2 P 0 ;0,1=305,2=0.000000
L 1.87128327 3.82921959 1.8715499 3.82546959 2 P 0 ;0,1=305,2=0.000000
L 1.8715499 3.82546959 1.8723498 3.82213622 2 P 0 ;0,1=305,2=0.000000
L 1.8723498 3.82213622 1.87341663 3.81963602 2 P 0 ;0,1=305,2=0.000000
L 1.87341663 3.81963602 1.87501634 3.81755305 2 P 0 ;0,1=305,2=0.000000
L 1.87501634 3.81755305 1.8771497 3.81671998 2 P 0 ;0,1=305,2=0.000000
L 1.8771497 3.81671998 1.87928307 3.81755305 2 P 0 ;0,1=305,2=0.000000
L 1.87928307 3.81755305 1.88088327 3.81963602 2 P 0 ;0,1=305,2=0.000000
L 1.88088327 3.81963602 1.8819501 3.82213622 2 P 0 ;0,1=305,2=0.000000
L 1.8819501 3.82213622 1.88275 3.82546959 2 P 0 ;0,1=305,2=0.000000
L 1.88275 3.82546959 1.88301663 3.82921959 2 P 0 ;0,1=305,2=0.000000
L 1.88301663 3.82921959 1.88275 3.83296949 2 P 0 ;0,1=305,2=0.000000
L 1.88275 3.83296949 1.8819501 3.83630364 2 P 0 ;0,1=305,2=0.000000
L 1.8819501 3.83630364 1.88088327 3.83880315 2 P 0 ;0,1=305,2=0.000000
L 1.88088327 3.83880315 1.87928307 3.84088681 2 P 0 ;0,1=305,2=0.000000
L 1.87928307 3.84088681 1.8771497 3.84171998 2 P 0 ;0,1=305,2=0.000000
L 8.09843002 1.7441 8.09843002 1.77953996 3 P 0 
L 8.09843002 1.77953996 7.99763996 1.77953996 3 P 0 
A 7.99763996 1.77953996 7.90471998 1.87246004 7.99721998 1.87203996 3 P 0 Y
L 7.90471998 1.87246004 7.90471998 3.85941004 3 P 0 
A 7.90471998 3.85941004 7.99808996 3.95276004 7.99724016 3.86023996 3 P 0 Y
L 7.99808996 3.95276004 8.1378 3.95276004 3 P 0 
L 8.1378 3.95276004 8.1378 3.9882 3 P 0 
L 8.1378 3.9882 8.3622 3.9882 3 P 0 
L 8.3622 3.9882 8.3622 3.95276004 3 P 0 
L 8.3622 3.95276004 8.50123996 3.95276004 3 P 0 
A 8.50123996 3.95276004 8.56794035 3.92590423 8.50274104 3.86023002 3 P 0 Y
A 8.56794035 3.92590423 8.59528002 3.8594 8.50273996 3.86022884 3 P 0 Y
L 8.59528002 3.8594 8.59528002 1.87286004 3 P 0 
A 8.59528002 1.87286004 8.50195 1.77953996 8.50276988 1.87205 3 P 0 Y
L 8.50195 1.77953996 8.40156998 1.77953002 3 P 0 
L 8.40156998 1.77953002 8.40156998 1.7441 3 P 0 
L 8.40156998 1.7441 8.09843002 1.7441 3 P 0 
L 7.94191004 3.74115 7.92441004 3.7569 3 P 0 
L 7.92441004 3.7569 7.9087 3.7569 3 P 0 
L 7.9087 3.7569 7.92443996 3.74115 3 P 0 
L 7.92443996 3.74115 7.95988002 3.74115 3 P 0 
L 7.95988002 3.74115 7.95985 3.5758 3 P 0 
L 7.95985 3.5758 7.92441004 3.5758 3 P 0 
L 7.92441004 3.5758 7.90866998 3.56005 3 P 0 
L 7.90866998 3.56005 7.92441004 3.56005 3 P 0 
L 7.92441004 3.56005 7.92441004 2.96458002 3 P 0 
L 7.92441004 2.96458002 7.90866998 2.96458002 3 P 0 
L 7.90866998 2.96458002 7.92441004 2.94883996 3 P 0 
L 7.92441004 2.94883996 7.95985 2.94883002 3 P 0 
L 7.95985 2.94883002 7.95985 2.78348002 3 P 0 
L 7.95985 2.78348002 7.92441004 2.78348002 3 P 0 
L 7.92441004 2.78348002 7.90866998 2.76773002 3 P 0 
L 7.90866998 2.76773002 7.92441004 2.76773002 3 P 0 
L 7.92441004 2.76773002 7.92441004 2.17383002 3 P 0 
L 7.92441004 2.17383002 7.90866998 2.17383002 3 P 0 
L 7.90866998 2.17383002 7.92441004 2.15808002 3 P 0 
L 7.92441004 2.15808002 7.95985 2.15808002 3 P 0 
L 7.95985 2.15808002 7.95985 1.99273002 3 P 0 
L 7.95985 1.99273002 7.92441004 1.99273002 3 P 0 
L 7.92441004 1.99273002 7.90866998 1.97698002 3 P 0 
L 7.90866998 1.97698002 7.92441004 1.97698002 3 P 0 
L 7.92441004 1.97698002 7.93831004 1.99273002 3 P 0 
L 7.92441004 2.17383002 7.94016004 2.15808002 3 P 0 
L 7.94016004 2.15808002 7.94016004 2.78348002 3 P 0 
L 7.94016004 2.78348002 7.92441004 2.76773002 3 P 0 
L 7.92441004 2.78348002 7.92441004 2.94883002 2 P 0 
L 7.92441004 2.96458002 7.94016004 2.94883996 3 P 0 
L 7.94016004 2.94883996 7.94016004 3.5758 3 P 0 
L 7.94016004 3.5758 7.92441004 3.56005 3 P 0 
L 8.56021998 3.74115 8.57558996 3.75688996 3 P 0 
L 8.57558996 3.75688996 8.59133002 3.75688996 3 P 0 
L 8.59133002 3.75688996 8.57558996 3.74115 3 P 0 
L 8.57558996 3.74115 8.54015 3.74115 3 P 0 
L 8.54015 3.74115 8.54015 3.5758 3 P 0 
L 8.54015 3.5758 8.57558996 3.5758 3 P 0 
L 8.57558996 3.5758 8.59133002 3.56005 3 P 0 
L 8.59133002 3.56005 8.57558996 3.56005 3 P 0 
L 8.57558996 3.56005 8.57558996 2.96456998 3 P 0 
L 8.57558996 2.96456998 8.59133002 2.96456998 3 P 0 
L 8.59133002 2.96456998 8.57558996 2.94883002 3 P 0 
L 8.57558996 2.94883002 8.54015 2.94883002 3 P 0 
L 8.54015 2.94883002 8.54015 2.78346998 3 P 0 
L 8.54015 2.78346998 8.57558996 2.78346998 3 P 0 
L 8.57558996 2.78346998 8.59133002 2.76771998 3 P 0 
L 8.59133002 2.76771998 8.57558996 2.76771998 3 P 0 
L 8.57558996 2.76771998 8.57558996 2.17383002 3 P 0 
L 8.57558996 2.17383002 8.59133002 2.17383002 3 P 0 
L 8.59133002 2.17383002 8.57558996 2.15808002 3 P 0 
L 8.57558996 2.15808002 8.54015 2.15808002 3 P 0 
L 8.54015 2.15808002 8.54015 1.99273002 3 P 0 
L 8.54015 1.99273002 8.57558996 1.99273002 3 P 0 
L 8.57558996 1.99273002 8.59133002 1.97698002 3 P 0 
L 8.59133002 1.97698002 8.57558996 1.97698002 3 P 0 
L 8.57558996 1.97698002 8.55973002 1.99273002 3 P 0 
L 8.57558996 3.56005 8.55983996 3.5758 3 P 0 
L 8.55983996 3.5758 8.55973002 2.94883002 3 P 0 
L 8.55973002 2.94883002 8.57558996 2.96456998 3 P 0 
L 8.57558996 2.94881998 8.57558996 2.78346998 3 P 0 
L 8.57558996 2.76771998 8.55983996 2.78346998 3 P 0 
L 8.55983996 2.78346998 8.55983996 2.15808002 3 P 0 
L 8.55983996 2.15808002 8.57558002 2.17383002 3 P 0 
L 8.57558996 1.97698002 8.57558996 1.87186004 3 P 0 
A 8.57558996 1.87186004 8.50295 1.79921998 8.50295 1.87185994 3 P 0 Y
L 8.50295 1.79921998 8.50275 1.79921998 3 P 0 
L 8.50275 1.79921998 8.37451004 1.79921998 3 P 0 
L 8.37451004 1.79921998 8.37451004 1.75788996 3 P 0 
L 8.37451004 1.75788996 8.1255 1.75788996 3 P 0 
L 8.1255 1.75788996 8.1255 1.79921998 3 P 0 
L 8.1255 1.79921998 7.99723996 1.79921998 3 P 0 
L 7.99723996 1.79921998 7.99706004 1.79921998 3 P 0 
A 7.99706004 1.79921998 7.92441004 1.87186004 7.9970501 1.87186004 3 P 0 Y
L 7.92441004 1.87186004 7.92441004 1.97708002 3 P 0 
A 8.56021998 3.86271004 8.54289715 3.90145246 8.50353996 3.86061073 3 P 0 N
A 8.54289715 3.90145246 8.50353996 3.91733002 8.50353917 3.86061004 3 P 0 N
L 8.50353996 3.91733002 8.30955 3.91733002 3 P 0 
L 8.30955 3.91733002 8.30955 3.95276004 3 P 0 
L 8.30955 3.95276004 8.19046004 3.95276004 3 P 0 
L 8.19046004 3.95276004 8.19046004 3.91733002 3 P 0 
L 8.19046004 3.91733002 7.99725 3.91733002 3 P 0 
A 7.99725 3.91733002 7.94191004 3.86198996 7.99725 3.86199006 3 P 0 N
L 7.94191004 3.86198996 7.94191004 3.74115 3 P 0 
L 8.16486998 3.93308002 8.18061004 3.91733002 3 P 0 
L 8.16731998 3.97245 8.19046004 3.95276004 3 P 0 
L 8.30955 3.95276004 8.33268002 3.97245 3 P 0 
L 8.33513996 3.93308002 8.31938996 3.91733002 3 P 0 
L 8.19046004 3.91733002 8.19046004 3.90158002 3 P 0 
L 8.19046004 3.90158002 8.30955 3.90158002 3 P 0 
L 8.30955 3.90158002 8.30955 3.91733002 3 P 0 
L 8.1255 1.79921998 8.14123996 1.81496998 3 P 0 
A 7.93826004 1.87186004 7.99515 1.81496998 7.99515 1.87185994 3 P 0 N
L 7.99515 1.81496998 7.99723996 1.81496998 3 P 0 
L 7.99723996 1.81496998 8.15108996 1.81498002 3 P 0 
L 8.15108996 1.81498002 8.15108002 1.83071998 3 P 0 
L 8.15108002 1.83071998 8.15108996 1.77953996 3 P 0 
L 8.15108996 1.77953996 8.34891998 1.77953996 3 P 0 
L 8.34891998 1.77953996 8.34891998 1.81498002 3 P 0 
L 8.34891998 1.81498002 8.50275 1.81496998 3 P 0 
L 8.50275 1.81496998 8.50286004 1.81496998 3 P 0 
A 8.50286004 1.81496998 8.55973002 1.87183996 8.50286004 1.87183996 3 P 0 N
L 8.34891998 1.81498002 8.34891998 1.83071998 3 P 0 
L 8.34891998 1.83071998 8.30953996 1.83071998 3 P 0 
L 8.30953996 1.83071998 8.19045 1.83071998 3 P 0 
L 8.19045 1.83071998 8.15108002 1.83071998 3 P 0 
L 8.37451004 1.79921998 8.35876998 1.81496998 3 P 0 
L 8.15108996 1.77953996 8.12795 1.75985 3 P 0 
L 8.37205 1.75985 8.34891998 1.77953996 3 P 0 
L 7.93831004 1.87178002 7.93831004 1.99295 3 P 0 
L 8.55973002 2.06861004 8.55973002 2.06868996 2 P 8191 
L 8.57558996 2.86528002 8.57558996 2.94898002 3 P 0 
L 8.57558996 1.99273002 8.57558996 2.15808002 3 P 0 
L 8.55973002 1.87183996 8.55973002 1.99273002 3 P 0 
L 8.56021998 3.74115 8.56021998 3.86271004 3 P 0 
L 7.92441004 1.99273002 7.92441004 2.15808002 3 P 0 
L 7.92441004 2.76631004 7.92441004 2.74745 3 P 0 
L 7.92441004 2.9478 7.92441004 2.78461004 3 P 0 
L 7.92441004 3.55888996 7.92441004 2.96508996 3 P 0 
L 7.92441004 3.73971004 7.92441004 3.57635 3 P 0 
L 8.57558996 3.75658996 8.57558996 3.86043996 3 P 0 
A 8.57558996 3.86043996 8.50293996 3.93308002 8.49613081 3.85361998 3 P 0 N
L 8.50293996 3.93308002 8.33513996 3.93308002 3 P 0 
L 8.33513996 3.93308002 8.33513996 3.97441998 3 P 0 
L 8.33513996 3.97441998 8.16486998 3.97441998 3 P 0 
L 8.16486998 3.97441998 8.16486998 3.93308002 3 P 0 
L 8.16486998 3.93308002 7.99705 3.93308002 3 P 0 
A 7.99705 3.93308002 7.92441004 3.86043996 7.99561998 3.86186998 3 P 0 N
L 7.92441004 3.86043996 7.92441004 3.75903002 3 P 0 
L 8.57558996 3.57576004 8.57558996 3.73935 3 P 0 
L 8.57558996 2.96475 8.57558996 3.55796004 3 P 0 
L 8.54883317 1.74639961 8.5507501 1.74319931 2 P 0 ;0,1=306,2=0.000000
L 8.5507501 1.74319931 8.55304961 1.74106644 2 P 0 ;0,1=306,2=0.000000
L 8.55304961 1.74106644 8.55573307 1.74 2 P 0 ;0,1=306,2=0.000000
L 8.55573307 1.74 8.5587998 1.74106644 2 P 0 ;0,1=306,2=0.000000
L 8.5587998 1.74106644 8.5611 1.74319931 2 P 0 ;0,1=306,2=0.000000
L 8.5611 1.74319931 8.5634002 1.74639961 2 P 0 ;0,1=306,2=0.000000
L 8.5634002 1.74639961 8.56416673 1.75066634 2 P 0 ;0,1=306,2=0.000000
L 8.56416673 1.75066634 8.56416673 1.772 2 P 0 ;0,1=306,2=0.000000
L 8.576 1.72933366 8.599 1.72933366 2 P 0 ;0,1=306,2=0.000000
L 8.60968337 1.74 8.60968337 1.772 2 P 0 ;0,1=306,2=0.000000
L 8.60968337 1.772 8.62731654 1.74 2 P 0 ;0,1=306,2=0.000000
L 8.62731654 1.74 8.62731654 1.772 2 P 0 ;0,1=306,2=0.000000
L 8.63991624 1.772 8.64949961 1.74 2 P 0 ;0,1=306,2=0.000000
L 8.64949961 1.74 8.65908366 1.772 2 P 0 ;0,1=306,2=0.000000
L 8.67283317 1.772 8.67283317 1.74 2 P 0 ;0,1=306,2=0.000000
L 8.67283317 1.74 8.68816673 1.74 2 P 0 ;0,1=306,2=0.000000
L 8.7068999 1.772 8.71609931 1.772 2 P 0 ;0,1=306,2=0.000000
L 8.71149961 1.772 8.71149961 1.74 2 P 0 ;0,1=306,2=0.000000
L 8.7068999 1.74 8.71609931 1.74 2 P 0 ;0,1=306,2=0.000000
L 8.73368337 1.74 8.73368337 1.772 2 P 0 ;0,1=306,2=0.000000
L 8.73368337 1.772 8.75131654 1.74 2 P 0 ;0,1=306,2=0.000000
L 8.75131654 1.74 8.75131654 1.772 2 P 0 ;0,1=306,2=0.000000
L 8.76506663 1.74 8.76506663 1.772 2 P 0 ;0,1=306,2=0.000000
L 8.77963307 1.772 8.76506663 1.75226594 2 P 0 ;0,1=306,2=0.000000
L 8.78193327 1.74 8.77158337 1.76133268 2 P 0 ;0,1=306,2=0.000000
L 8.793 1.72933366 8.816 1.72933366 2 P 0 ;0,1=306,2=0.000000
L 8.8377998 1.75599951 8.84546693 1.75599951 2 P 0 ;0,1=306,2=0.000000
L 8.84546693 1.75599951 8.84546693 1.74639961 2 P 0 ;0,1=306,2=0.000000
L 8.84546693 1.74639961 8.84316673 1.74319931 2 P 0 ;0,1=306,2=0.000000
L 8.84316673 1.74319931 8.84048327 1.74106644 2 P 0 ;0,1=306,2=0.000000
L 8.84048327 1.74106644 8.8366501 1.74 2 P 0 ;0,1=306,2=0.000000
L 8.8366501 1.74 8.83281683 1.74106644 2 P 0 ;0,1=306,2=0.000000
L 8.83281683 1.74106644 8.83013337 1.74319931 2 P 0 ;0,1=306,2=0.000000
L 8.83013337 1.74319931 8.82783317 1.74639961 2 P 0 ;0,1=306,2=0.000000
L 8.82783317 1.74639961 8.82629951 1.75013307 2 P 0 ;0,1=306,2=0.000000
L 8.82629951 1.75013307 8.82553297 1.7543998 2 P 0 ;0,1=306,2=0.000000
L 8.82553297 1.7543998 8.82553297 1.75813327 2 P 0 ;0,1=306,2=0.000000
L 8.82553297 1.75813327 8.82629951 1.76133268 2 P 0 ;0,1=306,2=0.000000
L 8.82629951 1.76133268 8.82783317 1.76506713 2 P 0 ;0,1=306,2=0.000000
L 8.82783317 1.76506713 8.83013337 1.76826644 2 P 0 ;0,1=306,2=0.000000
L 8.83013337 1.76826644 8.83243287 1.77039931 2 P 0 ;0,1=306,2=0.000000
L 8.83243287 1.77039931 8.83549961 1.772 2 P 0 ;0,1=306,2=0.000000
L 8.83549961 1.772 8.83818307 1.772 2 P 0 ;0,1=306,2=0.000000
L 8.83818307 1.772 8.8412498 1.77093346 2 P 0 ;0,1=306,2=0.000000
L 8.8412498 1.77093346 8.84355 1.7687997 2 P 0 ;0,1=306,2=0.000000
L 8.85883317 1.74 8.85883317 1.772 2 P 0 ;0,1=306,2=0.000000
L 8.85883317 1.772 8.86803327 1.772 2 P 0 ;0,1=306,2=0.000000
L 8.86803327 1.772 8.8711 1.77039931 2 P 0 ;0,1=306,2=0.000000
L 8.8711 1.77039931 8.8734002 1.76666673 2 P 0 ;0,1=306,2=0.000000
L 8.8734002 1.76666673 8.87416673 1.7624 2 P 0 ;0,1=306,2=0.000000
L 8.87416673 1.7624 8.8734002 1.75813327 2 P 0 ;0,1=306,2=0.000000
L 8.8734002 1.75813327 8.87148327 1.75493307 2 P 0 ;0,1=306,2=0.000000
L 8.87148327 1.75493307 8.86803327 1.75333238 2 P 0 ;0,1=306,2=0.000000
L 8.86803327 1.75333238 8.85883317 1.75333238 2 P 0 ;0,1=306,2=0.000000
L 8.88906663 1.772 8.88906663 1.74906663 2 P 0 ;0,1=306,2=0.000000
L 8.88906663 1.74906663 8.8905997 1.74426575 2 P 0 ;0,1=306,2=0.000000
L 8.8905997 1.74426575 8.89366634 1.74106644 2 P 0 ;0,1=306,2=0.000000
L 8.89366634 1.74106644 8.89749961 1.74 2 P 0 ;0,1=306,2=0.000000
L 8.89749961 1.74 8.90133356 1.74106644 2 P 0 ;0,1=306,2=0.000000
L 8.90133356 1.74106644 8.9044002 1.74426575 2 P 0 ;0,1=306,2=0.000000
L 8.9044002 1.74426575 8.90593327 1.74906663 2 P 0 ;0,1=306,2=0.000000
L 8.90593327 1.74906663 8.90593327 1.772 2 P 0 ;0,1=306,2=0.000000
L 8.92849961 1.74 8.92849961 1.772 2 P 0 ;0,1=306,2=0.000000
L 8.92849961 1.772 8.9238999 1.7656003 2 P 0 ;0,1=306,2=0.000000
L 8.9238999 1.74 8.93309931 1.74 2 P 0 ;0,1=306,2=0.000000
L 7.84571969 1.88171998 7.84571969 1.90671998 2 P 0 ;0,1=52,2=0.000000
L 7.84571969 1.90671998 7.84251988 1.90172028 2 P 0 ;0,1=52,2=0.000000
L 7.84251988 1.88171998 7.84891949 1.88171998 2 P 0 ;0,1=52,2=0.000000
L 7.87202313 1.95255335 7.87362323 1.95505285 2 P 0 ;0,1=53,2=0.000000
L 7.87362323 1.95505285 7.87548996 1.95630335 2 P 0 ;0,1=53,2=0.000000
L 7.87548996 1.95630335 7.87762333 1.95671998 2 P 0 ;0,1=53,2=0.000000
L 7.87762333 1.95671998 7.88028996 1.95588681 2 P 0 ;0,1=53,2=0.000000
L 7.88028996 1.95588681 7.88215669 1.95380315 2 P 0 ;0,1=53,2=0.000000
L 7.88215669 1.95380315 7.88268996 1.95130364 2 P 0 ;0,1=53,2=0.000000
L 7.88268996 1.95130364 7.88242333 1.94880266 2 P 0 ;0,1=53,2=0.000000
L 7.88242333 1.94880266 7.8813564 1.94671978 2 P 0 ;0,1=53,2=0.000000
L 7.8813564 1.94671978 7.87602323 1.94255325 2 P 0 ;0,1=53,2=0.000000
L 7.87602323 1.94255325 7.87362323 1.93963642 2 P 0 ;0,1=53,2=0.000000
L 7.87362323 1.93963642 7.87202313 1.93546909 2 P 0 ;0,1=53,2=0.000000
L 7.87202313 1.93546909 7.87148986 1.93171998 2 P 0 ;0,1=53,2=0.000000
L 7.87148986 1.93171998 7.88268996 1.93171998 2 P 0 ;0,1=53,2=0.000000
L 7.83985325 1.98671959 7.84145295 1.98380285 2 P 0 ;0,1=57,2=0.000000
L 7.84145295 1.98380285 7.84358632 1.98213652 2 P 0 ;0,1=57,2=0.000000
L 7.84358632 1.98213652 7.84598681 1.98171998 2 P 0 ;0,1=57,2=0.000000
L 7.84598681 1.98171998 7.84812018 1.98213652 2 P 0 ;0,1=57,2=0.000000
L 7.84812018 1.98213652 7.85025354 1.98421939 2 P 0 ;0,1=57,2=0.000000
L 7.85025354 1.98421939 7.85158661 1.98671959 2 P 0 ;0,1=57,2=0.000000
L 7.85158661 1.98671959 7.85185315 1.98921988 2 P 0 ;0,1=57,2=0.000000
L 7.85185315 1.98921988 7.85131998 1.99213593 2 P 0 ;0,1=57,2=0.000000
L 7.85131998 1.99213593 7.84945325 1.99421959 2 P 0 ;0,1=57,2=0.000000
L 7.84945325 1.99421959 7.84758642 1.99505344 2 P 0 ;0,1=57,2=0.000000
L 7.84758642 1.99505344 7.84518652 1.99505344 2 P 0 ;0,1=57,2=0.000000
L 7.84758642 1.99505344 7.84918661 1.99630325 2 P 0 ;0,1=57,2=0.000000
L 7.84918661 1.99630325 7.85052008 1.99838612 2 P 0 ;0,1=57,2=0.000000
L 7.85052008 1.99838612 7.85105335 2.00088632 2 P 0 ;0,1=57,2=0.000000
L 7.85105335 2.00088632 7.85052008 2.00338652 2 P 0 ;0,1=57,2=0.000000
L 7.85052008 2.00338652 7.84918661 2.00546939 2 P 0 ;0,1=57,2=0.000000
L 7.84918661 2.00546939 7.84678661 2.00671998 2 P 0 ;0,1=57,2=0.000000
L 7.84678661 2.00671998 7.84438661 2.00630335 2 P 0 ;0,1=57,2=0.000000
L 7.84438661 2.00630335 7.84198661 2.00463632 2 P 0 ;0,1=57,2=0.000000
L 7.88028996 2.03171998 7.88028996 2.05671998 2 P 0 ;0,1=58,2=0.000000
L 7.88028996 2.05671998 7.87042293 2.03880325 2 P 0 ;0,1=58,2=0.000000
L 7.87042293 2.03880325 7.88375689 2.03880325 2 P 0 ;0,1=58,2=0.000000
L 7.83985325 2.08546909 7.84145295 2.08338622 2 P 0 ;0,1=273,2=0.000000
L 7.84145295 2.08338622 7.84331969 2.08213652 2 P 0 ;0,1=273,2=0.000000
L 7.84331969 2.08213652 7.84571969 2.08171998 2 P 0 ;0,1=273,2=0.000000
L 7.84571969 2.08171998 7.84812018 2.08255305 2 P 0 ;0,1=273,2=0.000000
L 7.84812018 2.08255305 7.84998642 2.08421939 2 P 0 ;0,1=273,2=0.000000
L 7.84998642 2.08421939 7.85131998 2.08713622 2 P 0 ;0,1=273,2=0.000000
L 7.85131998 2.08713622 7.85158661 2.09046959 2 P 0 ;0,1=273,2=0.000000
L 7.85158661 2.09046959 7.85105335 2.09380295 2 P 0 ;0,1=273,2=0.000000
L 7.85105335 2.09380295 7.84971978 2.09588661 2 P 0 ;0,1=273,2=0.000000
L 7.84971978 2.09588661 7.84785305 2.09755295 2 P 0 ;0,1=273,2=0.000000
L 7.84785305 2.09755295 7.84598681 2.09796949 2 P 0 ;0,1=273,2=0.000000
L 7.84598681 2.09796949 7.84411998 2.09755295 2 P 0 ;0,1=273,2=0.000000
L 7.84411998 2.09755295 7.84172008 2.09588661 2 P 0 ;0,1=273,2=0.000000
L 7.84172008 2.09588661 7.84251988 2.10671998 2 P 0 ;0,1=273,2=0.000000
L 7.84251988 2.10671998 7.84971978 2.10671998 2 P 0 ;0,1=273,2=0.000000
L 7.87202313 2.14213593 7.87388986 2.14505344 2 P 0 ;0,1=274,2=0.000000
L 7.87388986 2.14505344 7.87548996 2.14671978 2 P 0 ;0,1=274,2=0.000000
L 7.87548996 2.14671978 7.87762333 2.14755295 2 P 0 ;0,1=274,2=0.000000
L 7.87762333 2.14755295 7.87949016 2.14671978 2 P 0 ;0,1=274,2=0.000000
L 7.87949016 2.14671978 7.88082323 2.14505344 2 P 0 ;0,1=274,2=0.000000
L 7.88082323 2.14505344 7.88189006 2.14255325 2 P 0 ;0,1=274,2=0.000000
L 7.88189006 2.14255325 7.88215669 2.13963642 2 P 0 ;0,1=274,2=0.000000
L 7.88215669 2.13963642 7.88189006 2.13713622 2 P 0 ;0,1=274,2=0.000000
L 7.88189006 2.13713622 7.88082323 2.13463602 2 P 0 ;0,1=274,2=0.000000
L 7.88082323 2.13463602 7.87922303 2.13255305 2 P 0 ;0,1=274,2=0.000000
L 7.87922303 2.13255305 7.87735679 2.13171998 2 P 0 ;0,1=274,2=0.000000
L 7.87735679 2.13171998 7.87522343 2.13255305 2 P 0 ;0,1=274,2=0.000000
L 7.87522343 2.13255305 7.87335659 2.13505256 2 P 0 ;0,1=274,2=0.000000
L 7.87335659 2.13505256 7.87228976 2.13880325 2 P 0 ;0,1=274,2=0.000000
L 7.87228976 2.13880325 7.87202313 2.14296978 2 P 0 ;0,1=274,2=0.000000
L 7.87202313 2.14296978 7.8725563 2.14838612 2 P 0 ;0,1=274,2=0.000000
L 7.8725563 2.14838612 7.87335659 2.15130364 2 P 0 ;0,1=274,2=0.000000
L 7.87335659 2.15130364 7.87468967 2.15421969 2 P 0 ;0,1=274,2=0.000000
L 7.87468967 2.15421969 7.8765565 2.15630335 2 P 0 ;0,1=274,2=0.000000
L 7.8765565 2.15630335 7.87842323 2.15671998 2 P 0 ;0,1=274,2=0.000000
L 7.87842323 2.15671998 7.88028996 2.15588681 2 P 0 ;0,1=274,2=0.000000
L 7.88028996 2.15588681 7.88162352 2.15380315 2 P 0 ;0,1=274,2=0.000000
L 7.84518652 2.18171998 7.84571969 2.18713622 2 P 0 ;0,1=275,2=0.000000
L 7.84571969 2.18713622 7.84651998 2.19171929 2 P 0 ;0,1=275,2=0.000000
L 7.84651998 2.19171929 7.84758642 2.19588661 2 P 0 ;0,1=275,2=0.000000
L 7.84758642 2.19588661 7.84891998 2.20046978 2 P 0 ;0,1=275,2=0.000000
L 7.84891998 2.20046978 7.85105335 2.20671998 2 P 0 ;0,1=275,2=0.000000
L 7.85105335 2.20671998 7.84038652 2.20671998 2 P 0 ;0,1=275,2=0.000000
L 7.8779997 2.235 7.87986644 2.23541654 2 P 0 ;0,1=276,2=0.000000
L 7.87986644 2.23541654 7.8819998 2.23666624 2 P 0 ;0,1=276,2=0.000000
L 7.8819998 2.23666624 7.88333337 2.23874911 2 P 0 ;0,1=276,2=0.000000
L 7.88333337 2.23874911 7.88386663 2.24166673 2 P 0 ;0,1=276,2=0.000000
L 7.88386663 2.24166673 7.88333337 2.24458278 2 P 0 ;0,1=276,2=0.000000
L 7.88333337 2.24458278 7.88173327 2.24708297 2 P 0 ;0,1=276,2=0.000000
L 7.88173327 2.24708297 7.87933327 2.24833346 2 P 0 ;0,1=276,2=0.000000
L 7.87933327 2.24833346 7.87666663 2.24833346 2 P 0 ;0,1=276,2=0.000000
L 7.87666663 2.24833346 7.87506654 2.24916663 2 P 0 ;0,1=276,2=0.000000
L 7.87506654 2.24916663 7.87373297 2.25124951 2 P 0 ;0,1=276,2=0.000000
L 7.87373297 2.25124951 7.8731998 2.25416634 2 P 0 ;0,1=276,2=0.000000
L 7.8731998 2.25416634 7.8740001 2.25708317 2 P 0 ;0,1=276,2=0.000000
L 7.8740001 2.25708317 7.87586634 2.25916683 2 P 0 ;0,1=276,2=0.000000
L 7.87586634 2.25916683 7.8779997 2.26 2 P 0 ;0,1=276,2=0.000000
L 7.8779997 2.26 7.88013307 2.25916683 2 P 0 ;0,1=276,2=0.000000
L 7.88013307 2.25916683 7.8819998 2.25708317 2 P 0 ;0,1=276,2=0.000000
L 7.8819998 2.25708317 7.8828001 2.25416634 2 P 0 ;0,1=276,2=0.000000
L 7.8828001 2.25416634 7.88226644 2.25124951 2 P 0 ;0,1=276,2=0.000000
L 7.88226644 2.25124951 7.88093337 2.24916663 2 P 0 ;0,1=276,2=0.000000
L 7.88093337 2.24916663 7.87933327 2.24833346 2 P 0 ;0,1=276,2=0.000000
L 7.87933327 2.24833346 7.87666663 2.24833346 2 P 0 ;0,1=276,2=0.000000
L 7.87666663 2.24833346 7.87426663 2.24708297 2 P 0 ;0,1=276,2=0.000000
L 7.87426663 2.24708297 7.87266654 2.24458278 2 P 0 ;0,1=276,2=0.000000
L 7.87266654 2.24458278 7.87213327 2.24166673 2 P 0 ;0,1=276,2=0.000000
L 7.87213327 2.24166673 7.87266654 2.23874911 2 P 0 ;0,1=276,2=0.000000
L 7.87266654 2.23874911 7.8740001 2.23666624 2 P 0 ;0,1=276,2=0.000000
L 7.8740001 2.23666624 7.87613346 2.23541654 2 P 0 ;0,1=276,2=0.000000
L 7.87613346 2.23541654 7.8779997 2.235 2 P 0 ;0,1=276,2=0.000000
L 7.87346634 2.28291604 7.87533317 2.28083307 2 P 0 ;0,1=28,2=0.000000
L 7.87533317 2.28083307 7.87746654 2.28 2 P 0 ;0,1=28,2=0.000000
L 7.87746654 2.28 7.8795999 2.28083307 2 P 0 ;0,1=28,2=0.000000
L 7.8795999 2.28083307 7.88146663 2.28333258 2 P 0 ;0,1=28,2=0.000000
L 7.88146663 2.28333258 7.8828001 2.28708327 2 P 0 ;0,1=28,2=0.000000
L 7.8828001 2.28708327 7.88333337 2.29083327 2 P 0 ;0,1=28,2=0.000000
L 7.88333337 2.29083327 7.88333337 2.29541634 2 P 0 ;0,1=28,2=0.000000
L 7.88333337 2.29541634 7.8828001 2.29916634 2 P 0 ;0,1=28,2=0.000000
L 7.8828001 2.29916634 7.88146663 2.3024997 2 P 0 ;0,1=28,2=0.000000
L 7.88146663 2.3024997 7.87986644 2.30416683 2 P 0 ;0,1=28,2=0.000000
L 7.87986644 2.30416683 7.8779997 2.305 2 P 0 ;0,1=28,2=0.000000
L 7.8779997 2.305 7.87586634 2.30416683 2 P 0 ;0,1=28,2=0.000000
L 7.87586634 2.30416683 7.87426663 2.3024997 2 P 0 ;0,1=28,2=0.000000
L 7.87426663 2.3024997 7.8731998 2.3000003 2 P 0 ;0,1=28,2=0.000000
L 7.8731998 2.3000003 7.87266654 2.29666614 2 P 0 ;0,1=28,2=0.000000
L 7.87266654 2.29666614 7.8731998 2.2937501 2 P 0 ;0,1=28,2=0.000000
L 7.8731998 2.2937501 7.87453327 2.29083327 2 P 0 ;0,1=28,2=0.000000
L 7.87453327 2.29083327 7.87613346 2.28916614 2 P 0 ;0,1=28,2=0.000000
L 7.87613346 2.28916614 7.8779997 2.28874961 2 P 0 ;0,1=28,2=0.000000
L 7.8779997 2.28874961 7.88013307 2.28958278 2 P 0 ;0,1=28,2=0.000000
L 7.88013307 2.28958278 7.88173327 2.29166644 2 P 0 ;0,1=28,2=0.000000
L 7.88173327 2.29166644 7.88333337 2.29541634 2 P 0 ;0,1=28,2=0.000000
L 7.8429997 2.325 7.8429997 2.35 2 P 0 ;0,1=26,2=0.000000
L 7.8429997 2.35 7.8397999 2.3450003 2 P 0 ;0,1=26,2=0.000000
L 7.8397999 2.325 7.84619951 2.325 2 P 0 ;0,1=26,2=0.000000
L 7.8669997 2.35 7.86486634 2.34916683 2 P 0 ;0,1=26,2=0.000000
L 7.86486634 2.34916683 7.86326663 2.34708317 2 P 0 ;0,1=26,2=0.000000
L 7.86326663 2.34708317 7.8621998 2.34458366 2 P 0 ;0,1=26,2=0.000000
L 7.8621998 2.34458366 7.8613999 2.34124951 2 P 0 ;0,1=26,2=0.000000
L 7.8613999 2.34124951 7.86113327 2.33749961 2 P 0 ;0,1=26,2=0.000000
L 7.86113327 2.33749961 7.8613999 2.33374961 2 P 0 ;0,1=26,2=0.000000
L 7.8613999 2.33374961 7.8621998 2.33041624 2 P 0 ;0,1=26,2=0.000000
L 7.8621998 2.33041624 7.86326663 2.32791604 2 P 0 ;0,1=26,2=0.000000
L 7.86326663 2.32791604 7.86486634 2.32583307 2 P 0 ;0,1=26,2=0.000000
L 7.86486634 2.32583307 7.8669997 2.325 2 P 0 ;0,1=26,2=0.000000
L 7.8669997 2.325 7.86913307 2.32583307 2 P 0 ;0,1=26,2=0.000000
L 7.86913307 2.32583307 7.87073327 2.32791604 2 P 0 ;0,1=26,2=0.000000
L 7.87073327 2.32791604 7.8718001 2.33041624 2 P 0 ;0,1=26,2=0.000000
L 7.8718001 2.33041624 7.8726 2.33374961 2 P 0 ;0,1=26,2=0.000000
L 7.8726 2.33374961 7.87286663 2.33749961 2 P 0 ;0,1=26,2=0.000000
L 7.87286663 2.33749961 7.8726 2.34124951 2 P 0 ;0,1=26,2=0.000000
L 7.8726 2.34124951 7.8718001 2.34458366 2 P 0 ;0,1=26,2=0.000000
L 7.8718001 2.34458366 7.87073327 2.34708317 2 P 0 ;0,1=26,2=0.000000
L 7.87073327 2.34708317 7.86913307 2.34916683 2 P 0 ;0,1=26,2=0.000000
L 7.86913307 2.34916683 7.8669997 2.35 2 P 0 ;0,1=26,2=0.000000
L 7.84571969 2.37171998 7.84571969 2.39671998 2 P 0 ;0,1=277,2=0.000000
L 7.84571969 2.39671998 7.84251988 2.39172028 2 P 0 ;0,1=277,2=0.000000
L 7.84251988 2.37171998 7.84891949 2.37171998 2 P 0 ;0,1=277,2=0.000000
L 7.86971969 2.37171998 7.86971969 2.39671998 2 P 0 ;0,1=277,2=0.000000
L 7.86971969 2.39671998 7.86651988 2.39172028 2 P 0 ;0,1=277,2=0.000000
L 7.86651988 2.37171998 7.87291949 2.37171998 2 P 0 ;0,1=277,2=0.000000
L 7.8429997 2.425 7.8429997 2.45 2 P 0 ;0,1=278,2=0.000000
L 7.8429997 2.45 7.8397999 2.4450003 2 P 0 ;0,1=278,2=0.000000
L 7.8397999 2.425 7.84619951 2.425 2 P 0 ;0,1=278,2=0.000000
L 7.86193317 2.44583337 7.86353327 2.44833287 2 P 0 ;0,1=278,2=0.000000
L 7.86353327 2.44833287 7.8654 2.44958337 2 P 0 ;0,1=278,2=0.000000
L 7.8654 2.44958337 7.86753337 2.45 2 P 0 ;0,1=278,2=0.000000
L 7.86753337 2.45 7.8702 2.44916683 2 P 0 ;0,1=278,2=0.000000
L 7.8702 2.44916683 7.87206673 2.44708317 2 P 0 ;0,1=278,2=0.000000
L 7.87206673 2.44708317 7.8726 2.44458366 2 P 0 ;0,1=278,2=0.000000
L 7.8726 2.44458366 7.87233337 2.44208268 2 P 0 ;0,1=278,2=0.000000
L 7.87233337 2.44208268 7.87126644 2.4399998 2 P 0 ;0,1=278,2=0.000000
L 7.87126644 2.4399998 7.86593327 2.43583327 2 P 0 ;0,1=278,2=0.000000
L 7.86593327 2.43583327 7.86353327 2.43291644 2 P 0 ;0,1=278,2=0.000000
L 7.86353327 2.43291644 7.86193317 2.42874911 2 P 0 ;0,1=278,2=0.000000
L 7.86193317 2.42874911 7.8613999 2.425 2 P 0 ;0,1=278,2=0.000000
L 7.8613999 2.425 7.8726 2.425 2 P 0 ;0,1=278,2=0.000000
L 7.84571969 2.47171998 7.84571969 2.49671998 2 P 0 ;0,1=279,2=0.000000
L 7.84571969 2.49671998 7.84251988 2.49172028 2 P 0 ;0,1=279,2=0.000000
L 7.84251988 2.47171998 7.84891949 2.47171998 2 P 0 ;0,1=279,2=0.000000
L 7.86385325 2.47671959 7.86545295 2.47380285 2 P 0 ;0,1=279,2=0.000000
L 7.86545295 2.47380285 7.86758632 2.47213652 2 P 0 ;0,1=279,2=0.000000
L 7.86758632 2.47213652 7.86998681 2.47171998 2 P 0 ;0,1=279,2=0.000000
L 7.86998681 2.47171998 7.87212018 2.47213652 2 P 0 ;0,1=279,2=0.000000
L 7.87212018 2.47213652 7.87425354 2.47421939 2 P 0 ;0,1=279,2=0.000000
L 7.87425354 2.47421939 7.87558661 2.47671959 2 P 0 ;0,1=279,2=0.000000
L 7.87558661 2.47671959 7.87585315 2.47921988 2 P 0 ;0,1=279,2=0.000000
L 7.87585315 2.47921988 7.87531998 2.48213593 2 P 0 ;0,1=279,2=0.000000
L 7.87531998 2.48213593 7.87345325 2.48421959 2 P 0 ;0,1=279,2=0.000000
L 7.87345325 2.48421959 7.87158642 2.48505344 2 P 0 ;0,1=279,2=0.000000
L 7.87158642 2.48505344 7.86918652 2.48505344 2 P 0 ;0,1=279,2=0.000000
L 7.87158642 2.48505344 7.87318661 2.48630325 2 P 0 ;0,1=279,2=0.000000
L 7.87318661 2.48630325 7.87452008 2.48838612 2 P 0 ;0,1=279,2=0.000000
L 7.87452008 2.48838612 7.87505335 2.49088632 2 P 0 ;0,1=279,2=0.000000
L 7.87505335 2.49088632 7.87452008 2.49338652 2 P 0 ;0,1=279,2=0.000000
L 7.87452008 2.49338652 7.87318661 2.49546939 2 P 0 ;0,1=279,2=0.000000
L 7.87318661 2.49546939 7.87078661 2.49671998 2 P 0 ;0,1=279,2=0.000000
L 7.87078661 2.49671998 7.86838661 2.49630335 2 P 0 ;0,1=279,2=0.000000
L 7.86838661 2.49630335 7.86598661 2.49463632 2 P 0 ;0,1=279,2=0.000000
L 7.84708967 2.52171998 7.84708967 2.54671998 2 P 0 ;0,1=63,2=0.000000
L 7.84708967 2.54671998 7.84388986 2.54172028 2 P 0 ;0,1=63,2=0.000000
L 7.84388986 2.52171998 7.85028947 2.52171998 2 P 0 ;0,1=63,2=0.000000
L 7.87428996 2.52171998 7.87428996 2.54671998 2 P 0 ;0,1=63,2=0.000000
L 7.87428996 2.54671998 7.86442293 2.52880325 2 P 0 ;0,1=63,2=0.000000
L 7.86442293 2.52880325 7.87775689 2.52880325 2 P 0 ;0,1=63,2=0.000000
L 7.84571969 2.57171998 7.84571969 2.59671998 2 P 0 ;0,1=280,2=0.000000
L 7.84571969 2.59671998 7.84251988 2.59172028 2 P 0 ;0,1=280,2=0.000000
L 7.84251988 2.57171998 7.84891949 2.57171998 2 P 0 ;0,1=280,2=0.000000
L 7.86385325 2.57546909 7.86545295 2.57338622 2 P 0 ;0,1=280,2=0.000000
L 7.86545295 2.57338622 7.86731969 2.57213652 2 P 0 ;0,1=280,2=0.000000
L 7.86731969 2.57213652 7.86971969 2.57171998 2 P 0 ;0,1=280,2=0.000000
L 7.86971969 2.57171998 7.87212018 2.57255305 2 P 0 ;0,1=280,2=0.000000
L 7.87212018 2.57255305 7.87398642 2.57421939 2 P 0 ;0,1=280,2=0.000000
L 7.87398642 2.57421939 7.87531998 2.57713622 2 P 0 ;0,1=280,2=0.000000
L 7.87531998 2.57713622 7.87558661 2.58046959 2 P 0 ;0,1=280,2=0.000000
L 7.87558661 2.58046959 7.87505335 2.58380295 2 P 0 ;0,1=280,2=0.000000
L 7.87505335 2.58380295 7.87371978 2.58588661 2 P 0 ;0,1=280,2=0.000000
L 7.87371978 2.58588661 7.87185305 2.58755295 2 P 0 ;0,1=280,2=0.000000
L 7.87185305 2.58755295 7.86998681 2.58796949 2 P 0 ;0,1=280,2=0.000000
L 7.86998681 2.58796949 7.86811998 2.58755295 2 P 0 ;0,1=280,2=0.000000
L 7.86811998 2.58755295 7.86572008 2.58588661 2 P 0 ;0,1=280,2=0.000000
L 7.86572008 2.58588661 7.86651988 2.59671998 2 P 0 ;0,1=280,2=0.000000
L 7.86651988 2.59671998 7.87371978 2.59671998 2 P 0 ;0,1=280,2=0.000000
L 7.84708967 2.62171998 7.84708967 2.64671998 2 P 0 ;0,1=281,2=0.000000
L 7.84708967 2.64671998 7.84388986 2.64172028 2 P 0 ;0,1=281,2=0.000000
L 7.84388986 2.62171998 7.85028947 2.62171998 2 P 0 ;0,1=281,2=0.000000
L 7.86602313 2.63213593 7.86788986 2.63505344 2 P 0 ;0,1=281,2=0.000000
L 7.86788986 2.63505344 7.86948996 2.63671978 2 P 0 ;0,1=281,2=0.000000
L 7.86948996 2.63671978 7.87162333 2.63755295 2 P 0 ;0,1=281,2=0.000000
L 7.87162333 2.63755295 7.87349016 2.63671978 2 P 0 ;0,1=281,2=0.000000
L 7.87349016 2.63671978 7.87482323 2.63505344 2 P 0 ;0,1=281,2=0.000000
L 7.87482323 2.63505344 7.87589006 2.63255325 2 P 0 ;0,1=281,2=0.000000
L 7.87589006 2.63255325 7.87615669 2.62963642 2 P 0 ;0,1=281,2=0.000000
L 7.87615669 2.62963642 7.87589006 2.62713622 2 P 0 ;0,1=281,2=0.000000
L 7.87589006 2.62713622 7.87482323 2.62463602 2 P 0 ;0,1=281,2=0.000000
L 7.87482323 2.62463602 7.87322303 2.62255305 2 P 0 ;0,1=281,2=0.000000
L 7.87322303 2.62255305 7.87135679 2.62171998 2 P 0 ;0,1=281,2=0.000000
L 7.87135679 2.62171998 7.86922343 2.62255305 2 P 0 ;0,1=281,2=0.000000
L 7.86922343 2.62255305 7.86735659 2.62505256 2 P 0 ;0,1=281,2=0.000000
L 7.86735659 2.62505256 7.86628976 2.62880325 2 P 0 ;0,1=281,2=0.000000
L 7.86628976 2.62880325 7.86602313 2.63296978 2 P 0 ;0,1=281,2=0.000000
L 7.86602313 2.63296978 7.8665563 2.63838612 2 P 0 ;0,1=281,2=0.000000
L 7.8665563 2.63838612 7.86735659 2.64130364 2 P 0 ;0,1=281,2=0.000000
L 7.86735659 2.64130364 7.86868967 2.64421969 2 P 0 ;0,1=281,2=0.000000
L 7.86868967 2.64421969 7.8705565 2.64630335 2 P 0 ;0,1=281,2=0.000000
L 7.8705565 2.64630335 7.87242323 2.64671998 2 P 0 ;0,1=281,2=0.000000
L 7.87242323 2.64671998 7.87428996 2.64588681 2 P 0 ;0,1=281,2=0.000000
L 7.87428996 2.64588681 7.87562352 2.64380315 2 P 0 ;0,1=281,2=0.000000
L 7.84571969 2.67171998 7.84571969 2.69671998 2 P 0 ;0,1=282,2=0.000000
L 7.84571969 2.69671998 7.84251988 2.69172028 2 P 0 ;0,1=282,2=0.000000
L 7.84251988 2.67171998 7.84891949 2.67171998 2 P 0 ;0,1=282,2=0.000000
L 7.86918652 2.67171998 7.86971969 2.67713622 2 P 0 ;0,1=282,2=0.000000
L 7.86971969 2.67713622 7.87051998 2.68171929 2 P 0 ;0,1=282,2=0.000000
L 7.87051998 2.68171929 7.87158642 2.68588661 2 P 0 ;0,1=282,2=0.000000
L 7.87158642 2.68588661 7.87291998 2.69046978 2 P 0 ;0,1=282,2=0.000000
L 7.87291998 2.69046978 7.87505335 2.69671998 2 P 0 ;0,1=282,2=0.000000
L 7.87505335 2.69671998 7.86438652 2.69671998 2 P 0 ;0,1=282,2=0.000000
L 7.84708967 2.72171998 7.84708967 2.74671998 2 P 0 ;0,1=27,2=0.000000
L 7.84708967 2.74671998 7.84388986 2.74172028 2 P 0 ;0,1=27,2=0.000000
L 7.84388986 2.72171998 7.85028947 2.72171998 2 P 0 ;0,1=27,2=0.000000
L 7.87108967 2.72171998 7.8729564 2.72213652 2 P 0 ;0,1=27,2=0.000000
L 7.8729564 2.72213652 7.87508976 2.72338622 2 P 0 ;0,1=27,2=0.000000
L 7.87508976 2.72338622 7.87642333 2.72546909 2 P 0 ;0,1=27,2=0.000000
L 7.87642333 2.72546909 7.87695659 2.72838671 2 P 0 ;0,1=27,2=0.000000
L 7.87695659 2.72838671 7.87642333 2.73130276 2 P 0 ;0,1=27,2=0.000000
L 7.87642333 2.73130276 7.87482323 2.73380295 2 P 0 ;0,1=27,2=0.000000
L 7.87482323 2.73380295 7.87242323 2.73505344 2 P 0 ;0,1=27,2=0.000000
L 7.87242323 2.73505344 7.86975659 2.73505344 2 P 0 ;0,1=27,2=0.000000
L 7.86975659 2.73505344 7.8681565 2.73588661 2 P 0 ;0,1=27,2=0.000000
L 7.8681565 2.73588661 7.86682293 2.73796949 2 P 0 ;0,1=27,2=0.000000
L 7.86682293 2.73796949 7.86628976 2.74088632 2 P 0 ;0,1=27,2=0.000000
L 7.86628976 2.74088632 7.86709006 2.74380315 2 P 0 ;0,1=27,2=0.000000
L 7.86709006 2.74380315 7.8689563 2.74588681 2 P 0 ;0,1=27,2=0.000000
L 7.8689563 2.74588681 7.87108967 2.74671998 2 P 0 ;0,1=27,2=0.000000
L 7.87108967 2.74671998 7.87322303 2.74588681 2 P 0 ;0,1=27,2=0.000000
L 7.87322303 2.74588681 7.87508976 2.74380315 2 P 0 ;0,1=27,2=0.000000
L 7.87508976 2.74380315 7.87589006 2.74088632 2 P 0 ;0,1=27,2=0.000000
L 7.87589006 2.74088632 7.8753564 2.73796949 2 P 0 ;0,1=27,2=0.000000
L 7.8753564 2.73796949 7.87402333 2.73588661 2 P 0 ;0,1=27,2=0.000000
L 7.87402333 2.73588661 7.87242323 2.73505344 2 P 0 ;0,1=27,2=0.000000
L 7.87242323 2.73505344 7.86975659 2.73505344 2 P 0 ;0,1=27,2=0.000000
L 7.86975659 2.73505344 7.86735659 2.73380295 2 P 0 ;0,1=27,2=0.000000
L 7.86735659 2.73380295 7.8657565 2.73130276 2 P 0 ;0,1=27,2=0.000000
L 7.8657565 2.73130276 7.86522323 2.72838671 2 P 0 ;0,1=27,2=0.000000
L 7.86522323 2.72838671 7.8657565 2.72546909 2 P 0 ;0,1=27,2=0.000000
L 7.8657565 2.72546909 7.86709006 2.72338622 2 P 0 ;0,1=27,2=0.000000
L 7.86709006 2.72338622 7.86922343 2.72213652 2 P 0 ;0,1=27,2=0.000000
L 7.86922343 2.72213652 7.87108967 2.72171998 2 P 0 ;0,1=27,2=0.000000
L 7.84571969 2.77171998 7.84571969 2.79671998 2 P 0 ;0,1=283,2=0.000000
L 7.84571969 2.79671998 7.84251988 2.79172028 2 P 0 ;0,1=283,2=0.000000
L 7.84251988 2.77171998 7.84891949 2.77171998 2 P 0 ;0,1=283,2=0.000000
L 7.86518632 2.77463602 7.86705315 2.77255305 2 P 0 ;0,1=283,2=0.000000
L 7.86705315 2.77255305 7.86918652 2.77171998 2 P 0 ;0,1=283,2=0.000000
L 7.86918652 2.77171998 7.87131988 2.77255305 2 P 0 ;0,1=283,2=0.000000
L 7.87131988 2.77255305 7.87318661 2.77505256 2 P 0 ;0,1=283,2=0.000000
L 7.87318661 2.77505256 7.87452008 2.77880325 2 P 0 ;0,1=283,2=0.000000
L 7.87452008 2.77880325 7.87505335 2.78255325 2 P 0 ;0,1=283,2=0.000000
L 7.87505335 2.78255325 7.87505335 2.78713632 2 P 0 ;0,1=283,2=0.000000
L 7.87505335 2.78713632 7.87452008 2.79088632 2 P 0 ;0,1=283,2=0.000000
L 7.87452008 2.79088632 7.87318661 2.79421969 2 P 0 ;0,1=283,2=0.000000
L 7.87318661 2.79421969 7.87158642 2.79588681 2 P 0 ;0,1=283,2=0.000000
L 7.87158642 2.79588681 7.86971969 2.79671998 2 P 0 ;0,1=283,2=0.000000
L 7.86971969 2.79671998 7.86758632 2.79588681 2 P 0 ;0,1=283,2=0.000000
L 7.86758632 2.79588681 7.86598661 2.79421969 2 P 0 ;0,1=283,2=0.000000
L 7.86598661 2.79421969 7.86491978 2.79172028 2 P 0 ;0,1=283,2=0.000000
L 7.86491978 2.79172028 7.86438652 2.78838612 2 P 0 ;0,1=283,2=0.000000
L 7.86438652 2.78838612 7.86491978 2.78547008 2 P 0 ;0,1=283,2=0.000000
L 7.86491978 2.78547008 7.86625325 2.78255325 2 P 0 ;0,1=283,2=0.000000
L 7.86625325 2.78255325 7.86785344 2.78088612 2 P 0 ;0,1=283,2=0.000000
L 7.86785344 2.78088612 7.86971969 2.78046959 2 P 0 ;0,1=283,2=0.000000
L 7.86971969 2.78046959 7.87185305 2.78130276 2 P 0 ;0,1=283,2=0.000000
L 7.87185305 2.78130276 7.87345325 2.78338642 2 P 0 ;0,1=283,2=0.000000
L 7.87345325 2.78338642 7.87505335 2.78713632 2 P 0 ;0,1=283,2=0.000000
L 7.84202313 2.84255335 7.84362323 2.84505285 2 P 0 ;0,1=284,2=0.000000
L 7.84362323 2.84505285 7.84548996 2.84630335 2 P 0 ;0,1=284,2=0.000000
L 7.84548996 2.84630335 7.84762333 2.84671998 2 P 0 ;0,1=284,2=0.000000
L 7.84762333 2.84671998 7.85028996 2.84588681 2 P 0 ;0,1=284,2=0.000000
L 7.85028996 2.84588681 7.85215669 2.84380315 2 P 0 ;0,1=284,2=0.000000
L 7.85215669 2.84380315 7.85268996 2.84130364 2 P 0 ;0,1=284,2=0.000000
L 7.85268996 2.84130364 7.85242333 2.83880266 2 P 0 ;0,1=284,2=0.000000
L 7.85242333 2.83880266 7.8513564 2.83671978 2 P 0 ;0,1=284,2=0.000000
L 7.8513564 2.83671978 7.84602323 2.83255325 2 P 0 ;0,1=284,2=0.000000
L 7.84602323 2.83255325 7.84362323 2.82963642 2 P 0 ;0,1=284,2=0.000000
L 7.84362323 2.82963642 7.84202313 2.82546909 2 P 0 ;0,1=284,2=0.000000
L 7.84202313 2.82546909 7.84148986 2.82171998 2 P 0 ;0,1=284,2=0.000000
L 7.84148986 2.82171998 7.85268996 2.82171998 2 P 0 ;0,1=284,2=0.000000
L 7.87108967 2.84671998 7.8689563 2.84588681 2 P 0 ;0,1=284,2=0.000000
L 7.8689563 2.84588681 7.86735659 2.84380315 2 P 0 ;0,1=284,2=0.000000
L 7.86735659 2.84380315 7.86628976 2.84130364 2 P 0 ;0,1=284,2=0.000000
L 7.86628976 2.84130364 7.86548986 2.83796949 2 P 0 ;0,1=284,2=0.000000
L 7.86548986 2.83796949 7.86522323 2.83421959 2 P 0 ;0,1=284,2=0.000000
L 7.86522323 2.83421959 7.86548986 2.83046959 2 P 0 ;0,1=284,2=0.000000
L 7.86548986 2.83046959 7.86628976 2.82713622 2 P 0 ;0,1=284,2=0.000000
L 7.86628976 2.82713622 7.86735659 2.82463602 2 P 0 ;0,1=284,2=0.000000
L 7.86735659 2.82463602 7.8689563 2.82255305 2 P 0 ;0,1=284,2=0.000000
L 7.8689563 2.82255305 7.87108967 2.82171998 2 P 0 ;0,1=284,2=0.000000
L 7.87108967 2.82171998 7.87322303 2.82255305 2 P 0 ;0,1=284,2=0.000000
L 7.87322303 2.82255305 7.87482323 2.82463602 2 P 0 ;0,1=284,2=0.000000
L 7.87482323 2.82463602 7.87589006 2.82713622 2 P 0 ;0,1=284,2=0.000000
L 7.87589006 2.82713622 7.87668996 2.83046959 2 P 0 ;0,1=284,2=0.000000
L 7.87668996 2.83046959 7.87695659 2.83421959 2 P 0 ;0,1=284,2=0.000000
L 7.87695659 2.83421959 7.87668996 2.83796949 2 P 0 ;0,1=284,2=0.000000
L 7.87668996 2.83796949 7.87589006 2.84130364 2 P 0 ;0,1=284,2=0.000000
L 7.87589006 2.84130364 7.87482323 2.84380315 2 P 0 ;0,1=284,2=0.000000
L 7.87482323 2.84380315 7.87322303 2.84588681 2 P 0 ;0,1=284,2=0.000000
L 7.87322303 2.84588681 7.87108967 2.84671998 2 P 0 ;0,1=284,2=0.000000
L 8.03786004 1.71381299 8.01286004 1.72047972 2 P 0 ;0,1=48,2=270.000000
L 8.01286004 1.72047972 8.03786004 1.72714695 2 P 0 ;0,1=48,2=270.000000
L 8.02911043 1.72474646 8.02911043 1.71621299 2 P 0 ;0,1=48,2=270.000000
L 8.07452657 1.72261309 8.07327677 1.72368002 2 P 0 ;0,1=285,2=270.000000
L 8.07327677 1.72368002 8.0711939 1.72447982 2 P 0 ;0,1=285,2=270.000000
L 8.0711939 1.72447982 8.06827638 1.72501358 2 P 0 ;0,1=285,2=270.000000
L 8.06827638 1.72501358 8.06577687 1.72447982 2 P 0 ;0,1=285,2=270.000000
L 8.06577687 1.72447982 8.06411063 1.72341339 2 P 0 ;0,1=285,2=270.000000
L 8.06411063 1.72341339 8.06286004 1.72154665 2 P 0 ;0,1=285,2=270.000000
L 8.06286004 1.72154665 8.06286004 1.71434675 2 P 0 ;0,1=285,2=270.000000
L 8.06286004 1.71434675 8.08786004 1.71434675 2 P 0 ;0,1=285,2=270.000000
L 8.08786004 1.71434675 8.08786004 1.72314675 2 P 0 ;0,1=285,2=270.000000
L 8.08786004 1.72314675 8.0861938 1.72501358 2 P 0 ;0,1=285,2=270.000000
L 8.0861938 1.72501358 8.0836935 1.72608002 2 P 0 ;0,1=285,2=270.000000
L 8.0836935 1.72608002 8.08077677 1.72661319 2 P 0 ;0,1=285,2=270.000000
L 8.08077677 1.72661319 8.07786073 1.72608002 2 P 0 ;0,1=285,2=270.000000
L 8.07786073 1.72608002 8.07536043 1.72447982 2 P 0 ;0,1=285,2=270.000000
L 8.07536043 1.72447982 8.07452657 1.72261309 2 P 0 ;0,1=285,2=270.000000
L 8.07452657 1.72261309 8.07452657 1.71434675 2 P 0 ;0,1=285,2=270.000000
L 8.1149437 1.72634665 8.11369321 1.72474646 2 P 0 ;0,1=49,2=270.000000
L 8.11369321 1.72474646 8.11286004 1.72288022 2 P 0 ;0,1=49,2=270.000000
L 8.11286004 1.72288022 8.11286004 1.72074685 2 P 0 ;0,1=49,2=270.000000
L 8.11286004 1.72074685 8.11411063 1.71834636 2 P 0 ;0,1=49,2=270.000000
L 8.11411063 1.71834636 8.1161935 1.71648012 2 P 0 ;0,1=49,2=270.000000
L 8.1161935 1.71648012 8.1186937 1.71514656 2 P 0 ;0,1=49,2=270.000000
L 8.1186937 1.71514656 8.12286024 1.71407963 2 P 0 ;0,1=49,2=270.000000
L 8.12286024 1.71407963 8.12661024 1.71381299 2 P 0 ;0,1=49,2=270.000000
L 8.12661024 1.71381299 8.13036014 1.71434675 2 P 0 ;0,1=49,2=270.000000
L 8.13036014 1.71434675 8.13286043 1.71514656 2 P 0 ;0,1=49,2=270.000000
L 8.13286043 1.71514656 8.13536063 1.71674665 2 P 0 ;0,1=49,2=270.000000
L 8.13536063 1.71674665 8.13702697 1.71861348 2 P 0 ;0,1=49,2=270.000000
L 8.13702697 1.71861348 8.13786004 1.72047972 2 P 0 ;0,1=49,2=270.000000
L 8.13786004 1.72047972 8.13786004 1.72234646 2 P 0 ;0,1=49,2=270.000000
L 8.13786004 1.72234646 8.13702697 1.72421329 2 P 0 ;0,1=49,2=270.000000
L 8.13702697 1.72421329 8.13577717 1.72581339 2 P 0 ;0,1=49,2=270.000000
L 8.13577717 1.72581339 8.13411093 1.72714695 2 P 0 ;0,1=49,2=270.000000
L 8.18786004 1.72461329 8.16286004 1.72461329 2 P 0 ;0,1=255,2=270.000000
L 8.16286004 1.72461329 8.16286004 1.72994656 2 P 0 ;0,1=255,2=270.000000
L 8.16286004 1.72994656 8.16411063 1.73207992 2 P 0 ;0,1=255,2=270.000000
L 8.16411063 1.73207992 8.16577687 1.73368002 2 P 0 ;0,1=255,2=270.000000
L 8.16577687 1.73368002 8.16827638 1.73501358 2 P 0 ;0,1=255,2=270.000000
L 8.16827638 1.73501358 8.1711939 1.73608002 2 P 0 ;0,1=255,2=270.000000
L 8.1711939 1.73608002 8.17536043 1.73634665 2 P 0 ;0,1=255,2=270.000000
L 8.17536043 1.73634665 8.17952697 1.73608002 2 P 0 ;0,1=255,2=270.000000
L 8.17952697 1.73608002 8.1824438 1.73501358 2 P 0 ;0,1=255,2=270.000000
L 8.1824438 1.73501358 8.184944 1.73368002 2 P 0 ;0,1=255,2=270.000000
L 8.184944 1.73368002 8.18661033 1.73207992 2 P 0 ;0,1=255,2=270.000000
L 8.18661033 1.73207992 8.18786004 1.72994656 2 P 0 ;0,1=255,2=270.000000
L 8.18786004 1.72994656 8.18786004 1.72461329 2 P 0 ;0,1=255,2=270.000000
L 8.23786004 1.73581339 8.23786004 1.72514656 2 P 0 ;0,1=286,2=270.000000
L 8.23786004 1.72514656 8.21286004 1.72514656 2 P 0 ;0,1=286,2=270.000000
L 8.21286004 1.72514656 8.21286004 1.73581339 2 P 0 ;0,1=286,2=270.000000
L 8.22494311 1.73154665 8.22494311 1.72514656 2 P 0 ;0,1=286,2=270.000000
L 8.28786004 1.72541319 8.26286004 1.72541319 2 P 0 ;0,1=287,2=270.000000
L 8.26286004 1.72541319 8.26286004 1.73554675 2 P 0 ;0,1=287,2=270.000000
L 8.27494311 1.73181329 8.27494311 1.72541319 2 P 0 ;0,1=287,2=270.000000
L 8.32536043 1.72207992 8.32536043 1.72741348 2 P 0 ;0,1=256,2=270.000000
L 8.32536043 1.72741348 8.33286043 1.72741348 2 P 0 ;0,1=256,2=270.000000
L 8.33286043 1.72741348 8.33536063 1.72581339 2 P 0 ;0,1=256,2=270.000000
L 8.33536063 1.72581339 8.33702697 1.72394665 2 P 0 ;0,1=256,2=270.000000
L 8.33702697 1.72394665 8.33786004 1.72128002 2 P 0 ;0,1=256,2=270.000000
L 8.33786004 1.72128002 8.33702697 1.71861348 2 P 0 ;0,1=256,2=270.000000
L 8.33702697 1.71861348 8.33536063 1.71674665 2 P 0 ;0,1=256,2=270.000000
L 8.33536063 1.71674665 8.33286043 1.71514656 2 P 0 ;0,1=256,2=270.000000
L 8.33286043 1.71514656 8.3299436 1.71407963 2 P 0 ;0,1=256,2=270.000000
L 8.3299436 1.71407963 8.32661024 1.71354646 2 P 0 ;0,1=256,2=270.000000
L 8.32661024 1.71354646 8.32369341 1.71354646 2 P 0 ;0,1=256,2=270.000000
L 8.32369341 1.71354646 8.3211939 1.71407963 2 P 0 ;0,1=256,2=270.000000
L 8.3211939 1.71407963 8.31827638 1.71514656 2 P 0 ;0,1=256,2=270.000000
L 8.31827638 1.71514656 8.31577687 1.71674665 2 P 0 ;0,1=256,2=270.000000
L 8.31577687 1.71674665 8.31411063 1.71834636 2 P 0 ;0,1=256,2=270.000000
L 8.31411063 1.71834636 8.31286004 1.72047972 2 P 0 ;0,1=256,2=270.000000
L 8.31286004 1.72047972 8.31286004 1.72234646 2 P 0 ;0,1=256,2=270.000000
L 8.31286004 1.72234646 8.31369321 1.72447982 2 P 0 ;0,1=256,2=270.000000
L 8.31369321 1.72447982 8.31536033 1.72608002 2 P 0 ;0,1=256,2=270.000000
L 8.38786004 1.71487992 8.36286004 1.71487992 2 P 0 ;0,1=288,2=270.000000
L 8.36286004 1.72608002 8.38786004 1.72608002 2 P 0 ;0,1=288,2=270.000000
L 8.37536043 1.72608002 8.37536043 1.71487992 2 P 0 ;0,1=288,2=270.000000
L 8.43286043 1.71514656 8.43536063 1.71648012 2 P 0 ;0,1=289,2=270.000000
L 8.43536063 1.71648012 8.43702697 1.71807972 2 P 0 ;0,1=289,2=270.000000
L 8.43702697 1.71807972 8.43786004 1.71994656 2 P 0 ;0,1=289,2=270.000000
L 8.43786004 1.71994656 8.43702697 1.72207992 2 P 0 ;0,1=289,2=270.000000
L 8.43702697 1.72207992 8.43536063 1.72368002 2 P 0 ;0,1=289,2=270.000000
L 8.43536063 1.72368002 8.43286043 1.72528012 2 P 0 ;0,1=289,2=270.000000
L 8.43286043 1.72528012 8.42952697 1.72581339 2 P 0 ;0,1=289,2=270.000000
L 8.42952697 1.72581339 8.41286004 1.72581339 2 P 0 ;0,1=289,2=270.000000
L 8.48786004 1.71461329 8.46286004 1.71461329 2 P 0 ;0,1=290,2=270.000000
L 8.46286004 1.72474646 8.47827726 1.71461329 2 P 0 ;0,1=290,2=270.000000
L 8.48786004 1.72634665 8.4711939 1.71914665 2 P 0 ;0,1=290,2=270.000000
L 7.84065315 2.89255335 7.84225325 2.89505285 2 P 0 ;0,1=270,2=0.000000
L 7.84225325 2.89505285 7.84411998 2.89630335 2 P 0 ;0,1=270,2=0.000000
L 7.84411998 2.89630335 7.84625335 2.89671998 2 P 0 ;0,1=270,2=0.000000
L 7.84625335 2.89671998 7.84891998 2.89588681 2 P 0 ;0,1=270,2=0.000000
L 7.84891998 2.89588681 7.85078671 2.89380315 2 P 0 ;0,1=270,2=0.000000
L 7.85078671 2.89380315 7.85131998 2.89130364 2 P 0 ;0,1=270,2=0.000000
L 7.85131998 2.89130364 7.85105335 2.88880266 2 P 0 ;0,1=270,2=0.000000
L 7.85105335 2.88880266 7.84998642 2.88671978 2 P 0 ;0,1=270,2=0.000000
L 7.84998642 2.88671978 7.84465325 2.88255325 2 P 0 ;0,1=270,2=0.000000
L 7.84465325 2.88255325 7.84225325 2.87963642 2 P 0 ;0,1=270,2=0.000000
L 7.84225325 2.87963642 7.84065315 2.87546909 2 P 0 ;0,1=270,2=0.000000
L 7.84065315 2.87546909 7.84011988 2.87171998 2 P 0 ;0,1=270,2=0.000000
L 7.84011988 2.87171998 7.85131998 2.87171998 2 P 0 ;0,1=270,2=0.000000
L 7.86971969 2.87171998 7.86971969 2.89671998 2 P 0 ;0,1=270,2=0.000000
L 7.86971969 2.89671998 7.86651988 2.89172028 2 P 0 ;0,1=270,2=0.000000
L 7.86651988 2.87171998 7.87291949 2.87171998 2 P 0 ;0,1=270,2=0.000000
L 7.84202313 2.94255335 7.84362323 2.94505285 2 P 0 ;0,1=271,2=0.000000
L 7.84362323 2.94505285 7.84548996 2.94630335 2 P 0 ;0,1=271,2=0.000000
L 7.84548996 2.94630335 7.84762333 2.94671998 2 P 0 ;0,1=271,2=0.000000
L 7.84762333 2.94671998 7.85028996 2.94588681 2 P 0 ;0,1=271,2=0.000000
L 7.85028996 2.94588681 7.85215669 2.94380315 2 P 0 ;0,1=271,2=0.000000
L 7.85215669 2.94380315 7.85268996 2.94130364 2 P 0 ;0,1=271,2=0.000000
L 7.85268996 2.94130364 7.85242333 2.93880266 2 P 0 ;0,1=271,2=0.000000
L 7.85242333 2.93880266 7.8513564 2.93671978 2 P 0 ;0,1=271,2=0.000000
L 7.8513564 2.93671978 7.84602323 2.93255325 2 P 0 ;0,1=271,2=0.000000
L 7.84602323 2.93255325 7.84362323 2.92963642 2 P 0 ;0,1=271,2=0.000000
L 7.84362323 2.92963642 7.84202313 2.92546909 2 P 0 ;0,1=271,2=0.000000
L 7.84202313 2.92546909 7.84148986 2.92171998 2 P 0 ;0,1=271,2=0.000000
L 7.84148986 2.92171998 7.85268996 2.92171998 2 P 0 ;0,1=271,2=0.000000
L 7.86602313 2.94255335 7.86762323 2.94505285 2 P 0 ;0,1=271,2=0.000000
L 7.86762323 2.94505285 7.86948996 2.94630335 2 P 0 ;0,1=271,2=0.000000
L 7.86948996 2.94630335 7.87162333 2.94671998 2 P 0 ;0,1=271,2=0.000000
L 7.87162333 2.94671998 7.87428996 2.94588681 2 P 0 ;0,1=271,2=0.000000
L 7.87428996 2.94588681 7.87615669 2.94380315 2 P 0 ;0,1=271,2=0.000000
L 7.87615669 2.94380315 7.87668996 2.94130364 2 P 0 ;0,1=271,2=0.000000
L 7.87668996 2.94130364 7.87642333 2.93880266 2 P 0 ;0,1=271,2=0.000000
L 7.87642333 2.93880266 7.8753564 2.93671978 2 P 0 ;0,1=271,2=0.000000
L 7.8753564 2.93671978 7.87002323 2.93255325 2 P 0 ;0,1=271,2=0.000000
L 7.87002323 2.93255325 7.86762323 2.92963642 2 P 0 ;0,1=271,2=0.000000
L 7.86762323 2.92963642 7.86602313 2.92546909 2 P 0 ;0,1=271,2=0.000000
L 7.86602313 2.92546909 7.86548986 2.92171998 2 P 0 ;0,1=271,2=0.000000
L 7.86548986 2.92171998 7.87668996 2.92171998 2 P 0 ;0,1=271,2=0.000000
L 7.84065315 2.99255335 7.84225325 2.99505285 2 P 0 ;0,1=64,2=0.000000
L 7.84225325 2.99505285 7.84411998 2.99630335 2 P 0 ;0,1=64,2=0.000000
L 7.84411998 2.99630335 7.84625335 2.99671998 2 P 0 ;0,1=64,2=0.000000
L 7.84625335 2.99671998 7.84891998 2.99588681 2 P 0 ;0,1=64,2=0.000000
L 7.84891998 2.99588681 7.85078671 2.99380315 2 P 0 ;0,1=64,2=0.000000
L 7.85078671 2.99380315 7.85131998 2.99130364 2 P 0 ;0,1=64,2=0.000000
L 7.85131998 2.99130364 7.85105335 2.98880266 2 P 0 ;0,1=64,2=0.000000
L 7.85105335 2.98880266 7.84998642 2.98671978 2 P 0 ;0,1=64,2=0.000000
L 7.84998642 2.98671978 7.84465325 2.98255325 2 P 0 ;0,1=64,2=0.000000
L 7.84465325 2.98255325 7.84225325 2.97963642 2 P 0 ;0,1=64,2=0.000000
L 7.84225325 2.97963642 7.84065315 2.97546909 2 P 0 ;0,1=64,2=0.000000
L 7.84065315 2.97546909 7.84011988 2.97171998 2 P 0 ;0,1=64,2=0.000000
L 7.84011988 2.97171998 7.85131998 2.97171998 2 P 0 ;0,1=64,2=0.000000
L 7.86385325 2.97671959 7.86545295 2.97380285 2 P 0 ;0,1=64,2=0.000000
L 7.86545295 2.97380285 7.86758632 2.97213652 2 P 0 ;0,1=64,2=0.000000
L 7.86758632 2.97213652 7.86998681 2.97171998 2 P 0 ;0,1=64,2=0.000000
L 7.86998681 2.97171998 7.87212018 2.97213652 2 P 0 ;0,1=64,2=0.000000
L 7.87212018 2.97213652 7.87425354 2.97421939 2 P 0 ;0,1=64,2=0.000000
L 7.87425354 2.97421939 7.87558661 2.97671959 2 P 0 ;0,1=64,2=0.000000
L 7.87558661 2.97671959 7.87585315 2.97921988 2 P 0 ;0,1=64,2=0.000000
L 7.87585315 2.97921988 7.87531998 2.98213593 2 P 0 ;0,1=64,2=0.000000
L 7.87531998 2.98213593 7.87345325 2.98421959 2 P 0 ;0,1=64,2=0.000000
L 7.87345325 2.98421959 7.87158642 2.98505344 2 P 0 ;0,1=64,2=0.000000
L 7.87158642 2.98505344 7.86918652 2.98505344 2 P 0 ;0,1=64,2=0.000000
L 7.87158642 2.98505344 7.87318661 2.98630325 2 P 0 ;0,1=64,2=0.000000
L 7.87318661 2.98630325 7.87452008 2.98838612 2 P 0 ;0,1=64,2=0.000000
L 7.87452008 2.98838612 7.87505335 2.99088632 2 P 0 ;0,1=64,2=0.000000
L 7.87505335 2.99088632 7.87452008 2.99338652 2 P 0 ;0,1=64,2=0.000000
L 7.87452008 2.99338652 7.87318661 2.99546939 2 P 0 ;0,1=64,2=0.000000
L 7.87318661 2.99546939 7.87078661 2.99671998 2 P 0 ;0,1=64,2=0.000000
L 7.87078661 2.99671998 7.86838661 2.99630335 2 P 0 ;0,1=64,2=0.000000
L 7.86838661 2.99630335 7.86598661 2.99463632 2 P 0 ;0,1=64,2=0.000000
L 7.84202313 3.04255335 7.84362323 3.04505285 2 P 0 ;0,1=65,2=0.000000
L 7.84362323 3.04505285 7.84548996 3.04630335 2 P 0 ;0,1=65,2=0.000000
L 7.84548996 3.04630335 7.84762333 3.04671998 2 P 0 ;0,1=65,2=0.000000
L 7.84762333 3.04671998 7.85028996 3.04588681 2 P 0 ;0,1=65,2=0.000000
L 7.85028996 3.04588681 7.85215669 3.04380315 2 P 0 ;0,1=65,2=0.000000
L 7.85215669 3.04380315 7.85268996 3.04130364 2 P 0 ;0,1=65,2=0.000000
L 7.85268996 3.04130364 7.85242333 3.03880266 2 P 0 ;0,1=65,2=0.000000
L 7.85242333 3.03880266 7.8513564 3.03671978 2 P 0 ;0,1=65,2=0.000000
L 7.8513564 3.03671978 7.84602323 3.03255325 2 P 0 ;0,1=65,2=0.000000
L 7.84602323 3.03255325 7.84362323 3.02963642 2 P 0 ;0,1=65,2=0.000000
L 7.84362323 3.02963642 7.84202313 3.02546909 2 P 0 ;0,1=65,2=0.000000
L 7.84202313 3.02546909 7.84148986 3.02171998 2 P 0 ;0,1=65,2=0.000000
L 7.84148986 3.02171998 7.85268996 3.02171998 2 P 0 ;0,1=65,2=0.000000
L 7.87428996 3.02171998 7.87428996 3.04671998 2 P 0 ;0,1=65,2=0.000000
L 7.87428996 3.04671998 7.86442293 3.02880325 2 P 0 ;0,1=65,2=0.000000
L 7.86442293 3.02880325 7.87775689 3.02880325 2 P 0 ;0,1=65,2=0.000000
L 7.84065315 3.09255335 7.84225325 3.09505285 2 P 0 ;0,1=291,2=0.000000
L 7.84225325 3.09505285 7.84411998 3.09630335 2 P 0 ;0,1=291,2=0.000000
L 7.84411998 3.09630335 7.84625335 3.09671998 2 P 0 ;0,1=291,2=0.000000
L 7.84625335 3.09671998 7.84891998 3.09588681 2 P 0 ;0,1=291,2=0.000000
L 7.84891998 3.09588681 7.85078671 3.09380315 2 P 0 ;0,1=291,2=0.000000
L 7.85078671 3.09380315 7.85131998 3.09130364 2 P 0 ;0,1=291,2=0.000000
L 7.85131998 3.09130364 7.85105335 3.08880266 2 P 0 ;0,1=291,2=0.000000
L 7.85105335 3.08880266 7.84998642 3.08671978 2 P 0 ;0,1=291,2=0.000000
L 7.84998642 3.08671978 7.84465325 3.08255325 2 P 0 ;0,1=291,2=0.000000
L 7.84465325 3.08255325 7.84225325 3.07963642 2 P 0 ;0,1=291,2=0.000000
L 7.84225325 3.07963642 7.84065315 3.07546909 2 P 0 ;0,1=291,2=0.000000
L 7.84065315 3.07546909 7.84011988 3.07171998 2 P 0 ;0,1=291,2=0.000000
L 7.84011988 3.07171998 7.85131998 3.07171998 2 P 0 ;0,1=291,2=0.000000
L 7.86385325 3.07546909 7.86545295 3.07338622 2 P 0 ;0,1=291,2=0.000000
L 7.86545295 3.07338622 7.86731969 3.07213652 2 P 0 ;0,1=291,2=0.000000
L 7.86731969 3.07213652 7.86971969 3.07171998 2 P 0 ;0,1=291,2=0.000000
L 7.86971969 3.07171998 7.87212018 3.07255305 2 P 0 ;0,1=291,2=0.000000
L 7.87212018 3.07255305 7.87398642 3.07421939 2 P 0 ;0,1=291,2=0.000000
L 7.87398642 3.07421939 7.87531998 3.07713622 2 P 0 ;0,1=291,2=0.000000
L 7.87531998 3.07713622 7.87558661 3.08046959 2 P 0 ;0,1=291,2=0.000000
L 7.87558661 3.08046959 7.87505335 3.08380295 2 P 0 ;0,1=291,2=0.000000
L 7.87505335 3.08380295 7.87371978 3.08588661 2 P 0 ;0,1=291,2=0.000000
L 7.87371978 3.08588661 7.87185305 3.08755295 2 P 0 ;0,1=291,2=0.000000
L 7.87185305 3.08755295 7.86998681 3.08796949 2 P 0 ;0,1=291,2=0.000000
L 7.86998681 3.08796949 7.86811998 3.08755295 2 P 0 ;0,1=291,2=0.000000
L 7.86811998 3.08755295 7.86572008 3.08588661 2 P 0 ;0,1=291,2=0.000000
L 7.86572008 3.08588661 7.86651988 3.09671998 2 P 0 ;0,1=291,2=0.000000
L 7.86651988 3.09671998 7.87371978 3.09671998 2 P 0 ;0,1=291,2=0.000000
L 7.84202313 3.14255335 7.84362323 3.14505285 2 P 0 ;0,1=292,2=0.000000
L 7.84362323 3.14505285 7.84548996 3.14630335 2 P 0 ;0,1=292,2=0.000000
L 7.84548996 3.14630335 7.84762333 3.14671998 2 P 0 ;0,1=292,2=0.000000
L 7.84762333 3.14671998 7.85028996 3.14588681 2 P 0 ;0,1=292,2=0.000000
L 7.85028996 3.14588681 7.85215669 3.14380315 2 P 0 ;0,1=292,2=0.000000
L 7.85215669 3.14380315 7.85268996 3.14130364 2 P 0 ;0,1=292,2=0.000000
L 7.85268996 3.14130364 7.85242333 3.13880266 2 P 0 ;0,1=292,2=0.000000
L 7.85242333 3.13880266 7.8513564 3.13671978 2 P 0 ;0,1=292,2=0.000000
L 7.8513564 3.13671978 7.84602323 3.13255325 2 P 0 ;0,1=292,2=0.000000
L 7.84602323 3.13255325 7.84362323 3.12963642 2 P 0 ;0,1=292,2=0.000000
L 7.84362323 3.12963642 7.84202313 3.12546909 2 P 0 ;0,1=292,2=0.000000
L 7.84202313 3.12546909 7.84148986 3.12171998 2 P 0 ;0,1=292,2=0.000000
L 7.84148986 3.12171998 7.85268996 3.12171998 2 P 0 ;0,1=292,2=0.000000
L 7.86602313 3.13213593 7.86788986 3.13505344 2 P 0 ;0,1=292,2=0.000000
L 7.86788986 3.13505344 7.86948996 3.13671978 2 P 0 ;0,1=292,2=0.000000
L 7.86948996 3.13671978 7.87162333 3.13755295 2 P 0 ;0,1=292,2=0.000000
L 7.87162333 3.13755295 7.87349016 3.13671978 2 P 0 ;0,1=292,2=0.000000
L 7.87349016 3.13671978 7.87482323 3.13505344 2 P 0 ;0,1=292,2=0.000000
L 7.87482323 3.13505344 7.87589006 3.13255325 2 P 0 ;0,1=292,2=0.000000
L 7.87589006 3.13255325 7.87615669 3.12963642 2 P 0 ;0,1=292,2=0.000000
L 7.87615669 3.12963642 7.87589006 3.12713622 2 P 0 ;0,1=292,2=0.000000
L 7.87589006 3.12713622 7.87482323 3.12463602 2 P 0 ;0,1=292,2=0.000000
L 7.87482323 3.12463602 7.87322303 3.12255305 2 P 0 ;0,1=292,2=0.000000
L 7.87322303 3.12255305 7.87135679 3.12171998 2 P 0 ;0,1=292,2=0.000000
L 7.87135679 3.12171998 7.86922343 3.12255305 2 P 0 ;0,1=292,2=0.000000
L 7.86922343 3.12255305 7.86735659 3.12505256 2 P 0 ;0,1=292,2=0.000000
L 7.86735659 3.12505256 7.86628976 3.12880325 2 P 0 ;0,1=292,2=0.000000
L 7.86628976 3.12880325 7.86602313 3.13296978 2 P 0 ;0,1=292,2=0.000000
L 7.86602313 3.13296978 7.8665563 3.13838612 2 P 0 ;0,1=292,2=0.000000
L 7.8665563 3.13838612 7.86735659 3.14130364 2 P 0 ;0,1=292,2=0.000000
L 7.86735659 3.14130364 7.86868967 3.14421969 2 P 0 ;0,1=292,2=0.000000
L 7.86868967 3.14421969 7.8705565 3.14630335 2 P 0 ;0,1=292,2=0.000000
L 7.8705565 3.14630335 7.87242323 3.14671998 2 P 0 ;0,1=292,2=0.000000
L 7.87242323 3.14671998 7.87428996 3.14588681 2 P 0 ;0,1=292,2=0.000000
L 7.87428996 3.14588681 7.87562352 3.14380315 2 P 0 ;0,1=292,2=0.000000
L 7.84065315 3.19255335 7.84225325 3.19505285 2 P 0 ;0,1=293,2=0.000000
L 7.84225325 3.19505285 7.84411998 3.19630335 2 P 0 ;0,1=293,2=0.000000
L 7.84411998 3.19630335 7.84625335 3.19671998 2 P 0 ;0,1=293,2=0.000000
L 7.84625335 3.19671998 7.84891998 3.19588681 2 P 0 ;0,1=293,2=0.000000
L 7.84891998 3.19588681 7.85078671 3.19380315 2 P 0 ;0,1=293,2=0.000000
L 7.85078671 3.19380315 7.85131998 3.19130364 2 P 0 ;0,1=293,2=0.000000
L 7.85131998 3.19130364 7.85105335 3.18880266 2 P 0 ;0,1=293,2=0.000000
L 7.85105335 3.18880266 7.84998642 3.18671978 2 P 0 ;0,1=293,2=0.000000
L 7.84998642 3.18671978 7.84465325 3.18255325 2 P 0 ;0,1=293,2=0.000000
L 7.84465325 3.18255325 7.84225325 3.17963642 2 P 0 ;0,1=293,2=0.000000
L 7.84225325 3.17963642 7.84065315 3.17546909 2 P 0 ;0,1=293,2=0.000000
L 7.84065315 3.17546909 7.84011988 3.17171998 2 P 0 ;0,1=293,2=0.000000
L 7.84011988 3.17171998 7.85131998 3.17171998 2 P 0 ;0,1=293,2=0.000000
L 7.86918652 3.17171998 7.86971969 3.17713622 2 P 0 ;0,1=293,2=0.000000
L 7.86971969 3.17713622 7.87051998 3.18171929 2 P 0 ;0,1=293,2=0.000000
L 7.87051998 3.18171929 7.87158642 3.18588661 2 P 0 ;0,1=293,2=0.000000
L 7.87158642 3.18588661 7.87291998 3.19046978 2 P 0 ;0,1=293,2=0.000000
L 7.87291998 3.19046978 7.87505335 3.19671998 2 P 0 ;0,1=293,2=0.000000
L 7.87505335 3.19671998 7.86438652 3.19671998 2 P 0 ;0,1=293,2=0.000000
L 7.84202313 3.24255335 7.84362323 3.24505285 2 P 0 ;0,1=66,2=0.000000
L 7.84362323 3.24505285 7.84548996 3.24630335 2 P 0 ;0,1=66,2=0.000000
L 7.84548996 3.24630335 7.84762333 3.24671998 2 P 0 ;0,1=66,2=0.000000
L 7.84762333 3.24671998 7.85028996 3.24588681 2 P 0 ;0,1=66,2=0.000000
L 7.85028996 3.24588681 7.85215669 3.24380315 2 P 0 ;0,1=66,2=0.000000
L 7.85215669 3.24380315 7.85268996 3.24130364 2 P 0 ;0,1=66,2=0.000000
L 7.85268996 3.24130364 7.85242333 3.23880266 2 P 0 ;0,1=66,2=0.000000
L 7.85242333 3.23880266 7.8513564 3.23671978 2 P 0 ;0,1=66,2=0.000000
L 7.8513564 3.23671978 7.84602323 3.23255325 2 P 0 ;0,1=66,2=0.000000
L 7.84602323 3.23255325 7.84362323 3.22963642 2 P 0 ;0,1=66,2=0.000000
L 7.84362323 3.22963642 7.84202313 3.22546909 2 P 0 ;0,1=66,2=0.000000
L 7.84202313 3.22546909 7.84148986 3.22171998 2 P 0 ;0,1=66,2=0.000000
L 7.84148986 3.22171998 7.85268996 3.22171998 2 P 0 ;0,1=66,2=0.000000
L 7.87108967 3.22171998 7.8729564 3.22213652 2 P 0 ;0,1=66,2=0.000000
L 7.8729564 3.22213652 7.87508976 3.22338622 2 P 0 ;0,1=66,2=0.000000
L 7.87508976 3.22338622 7.87642333 3.22546909 2 P 0 ;0,1=66,2=0.000000
L 7.87642333 3.22546909 7.87695659 3.22838671 2 P 0 ;0,1=66,2=0.000000
L 7.87695659 3.22838671 7.87642333 3.23130276 2 P 0 ;0,1=66,2=0.000000
L 7.87642333 3.23130276 7.87482323 3.23380295 2 P 0 ;0,1=66,2=0.000000
L 7.87482323 3.23380295 7.87242323 3.23505344 2 P 0 ;0,1=66,2=0.000000
L 7.87242323 3.23505344 7.86975659 3.23505344 2 P 0 ;0,1=66,2=0.000000
L 7.86975659 3.23505344 7.8681565 3.23588661 2 P 0 ;0,1=66,2=0.000000
L 7.8681565 3.23588661 7.86682293 3.23796949 2 P 0 ;0,1=66,2=0.000000
L 7.86682293 3.23796949 7.86628976 3.24088632 2 P 0 ;0,1=66,2=0.000000
L 7.86628976 3.24088632 7.86709006 3.24380315 2 P 0 ;0,1=66,2=0.000000
L 7.86709006 3.24380315 7.8689563 3.24588681 2 P 0 ;0,1=66,2=0.000000
L 7.8689563 3.24588681 7.87108967 3.24671998 2 P 0 ;0,1=66,2=0.000000
L 7.87108967 3.24671998 7.87322303 3.24588681 2 P 0 ;0,1=66,2=0.000000
L 7.87322303 3.24588681 7.87508976 3.24380315 2 P 0 ;0,1=66,2=0.000000
L 7.87508976 3.24380315 7.87589006 3.24088632 2 P 0 ;0,1=66,2=0.000000
L 7.87589006 3.24088632 7.8753564 3.23796949 2 P 0 ;0,1=66,2=0.000000
L 7.8753564 3.23796949 7.87402333 3.23588661 2 P 0 ;0,1=66,2=0.000000
L 7.87402333 3.23588661 7.87242323 3.23505344 2 P 0 ;0,1=66,2=0.000000
L 7.87242323 3.23505344 7.86975659 3.23505344 2 P 0 ;0,1=66,2=0.000000
L 7.86975659 3.23505344 7.86735659 3.23380295 2 P 0 ;0,1=66,2=0.000000
L 7.86735659 3.23380295 7.8657565 3.23130276 2 P 0 ;0,1=66,2=0.000000
L 7.8657565 3.23130276 7.86522323 3.22838671 2 P 0 ;0,1=66,2=0.000000
L 7.86522323 3.22838671 7.8657565 3.22546909 2 P 0 ;0,1=66,2=0.000000
L 7.8657565 3.22546909 7.86709006 3.22338622 2 P 0 ;0,1=66,2=0.000000
L 7.86709006 3.22338622 7.86922343 3.22213652 2 P 0 ;0,1=66,2=0.000000
L 7.86922343 3.22213652 7.87108967 3.22171998 2 P 0 ;0,1=66,2=0.000000
L 7.84065315 3.29255335 7.84225325 3.29505285 2 P 0 ;0,1=294,2=0.000000
L 7.84225325 3.29505285 7.84411998 3.29630335 2 P 0 ;0,1=294,2=0.000000
L 7.84411998 3.29630335 7.84625335 3.29671998 2 P 0 ;0,1=294,2=0.000000
L 7.84625335 3.29671998 7.84891998 3.29588681 2 P 0 ;0,1=294,2=0.000000
L 7.84891998 3.29588681 7.85078671 3.29380315 2 P 0 ;0,1=294,2=0.000000
L 7.85078671 3.29380315 7.85131998 3.29130364 2 P 0 ;0,1=294,2=0.000000
L 7.85131998 3.29130364 7.85105335 3.28880266 2 P 0 ;0,1=294,2=0.000000
L 7.85105335 3.28880266 7.84998642 3.28671978 2 P 0 ;0,1=294,2=0.000000
L 7.84998642 3.28671978 7.84465325 3.28255325 2 P 0 ;0,1=294,2=0.000000
L 7.84465325 3.28255325 7.84225325 3.27963642 2 P 0 ;0,1=294,2=0.000000
L 7.84225325 3.27963642 7.84065315 3.27546909 2 P 0 ;0,1=294,2=0.000000
L 7.84065315 3.27546909 7.84011988 3.27171998 2 P 0 ;0,1=294,2=0.000000
L 7.84011988 3.27171998 7.85131998 3.27171998 2 P 0 ;0,1=294,2=0.000000
L 7.86518632 3.27463602 7.86705315 3.27255305 2 P 0 ;0,1=294,2=0.000000
L 7.86705315 3.27255305 7.86918652 3.27171998 2 P 0 ;0,1=294,2=0.000000
L 7.86918652 3.27171998 7.87131988 3.27255305 2 P 0 ;0,1=294,2=0.000000
L 7.87131988 3.27255305 7.87318661 3.27505256 2 P 0 ;0,1=294,2=0.000000
L 7.87318661 3.27505256 7.87452008 3.27880325 2 P 0 ;0,1=294,2=0.000000
L 7.87452008 3.27880325 7.87505335 3.28255325 2 P 0 ;0,1=294,2=0.000000
L 7.87505335 3.28255325 7.87505335 3.28713632 2 P 0 ;0,1=294,2=0.000000
L 7.87505335 3.28713632 7.87452008 3.29088632 2 P 0 ;0,1=294,2=0.000000
L 7.87452008 3.29088632 7.87318661 3.29421969 2 P 0 ;0,1=294,2=0.000000
L 7.87318661 3.29421969 7.87158642 3.29588681 2 P 0 ;0,1=294,2=0.000000
L 7.87158642 3.29588681 7.86971969 3.29671998 2 P 0 ;0,1=294,2=0.000000
L 7.86971969 3.29671998 7.86758632 3.29588681 2 P 0 ;0,1=294,2=0.000000
L 7.86758632 3.29588681 7.86598661 3.29421969 2 P 0 ;0,1=294,2=0.000000
L 7.86598661 3.29421969 7.86491978 3.29172028 2 P 0 ;0,1=294,2=0.000000
L 7.86491978 3.29172028 7.86438652 3.28838612 2 P 0 ;0,1=294,2=0.000000
L 7.86438652 3.28838612 7.86491978 3.28547008 2 P 0 ;0,1=294,2=0.000000
L 7.86491978 3.28547008 7.86625325 3.28255325 2 P 0 ;0,1=294,2=0.000000
L 7.86625325 3.28255325 7.86785344 3.28088612 2 P 0 ;0,1=294,2=0.000000
L 7.86785344 3.28088612 7.86971969 3.28046959 2 P 0 ;0,1=294,2=0.000000
L 7.86971969 3.28046959 7.87185305 3.28130276 2 P 0 ;0,1=294,2=0.000000
L 7.87185305 3.28130276 7.87345325 3.28338642 2 P 0 ;0,1=294,2=0.000000
L 7.87345325 3.28338642 7.87505335 3.28713632 2 P 0 ;0,1=294,2=0.000000
L 7.84122323 3.32671959 7.84282293 3.32380285 2 P 0 ;0,1=295,2=0.000000
L 7.84282293 3.32380285 7.8449563 3.32213652 2 P 0 ;0,1=295,2=0.000000
L 7.8449563 3.32213652 7.84735679 3.32171998 2 P 0 ;0,1=295,2=0.000000
L 7.84735679 3.32171998 7.84949016 3.32213652 2 P 0 ;0,1=295,2=0.000000
L 7.84949016 3.32213652 7.85162352 3.32421939 2 P 0 ;0,1=295,2=0.000000
L 7.85162352 3.32421939 7.85295659 3.32671959 2 P 0 ;0,1=295,2=0.000000
L 7.85295659 3.32671959 7.85322313 3.32921988 2 P 0 ;0,1=295,2=0.000000
L 7.85322313 3.32921988 7.85268996 3.33213593 2 P 0 ;0,1=295,2=0.000000
L 7.85268996 3.33213593 7.85082323 3.33421959 2 P 0 ;0,1=295,2=0.000000
L 7.85082323 3.33421959 7.8489564 3.33505344 2 P 0 ;0,1=295,2=0.000000
L 7.8489564 3.33505344 7.8465565 3.33505344 2 P 0 ;0,1=295,2=0.000000
L 7.8489564 3.33505344 7.85055659 3.33630325 2 P 0 ;0,1=295,2=0.000000
L 7.85055659 3.33630325 7.85189006 3.33838612 2 P 0 ;0,1=295,2=0.000000
L 7.85189006 3.33838612 7.85242333 3.34088632 2 P 0 ;0,1=295,2=0.000000
L 7.85242333 3.34088632 7.85189006 3.34338652 2 P 0 ;0,1=295,2=0.000000
L 7.85189006 3.34338652 7.85055659 3.34546939 2 P 0 ;0,1=295,2=0.000000
L 7.85055659 3.34546939 7.84815659 3.34671998 2 P 0 ;0,1=295,2=0.000000
L 7.84815659 3.34671998 7.84575659 3.34630335 2 P 0 ;0,1=295,2=0.000000
L 7.84575659 3.34630335 7.84335659 3.34463632 2 P 0 ;0,1=295,2=0.000000
L 7.87108967 3.34671998 7.8689563 3.34588681 2 P 0 ;0,1=295,2=0.000000
L 7.8689563 3.34588681 7.86735659 3.34380315 2 P 0 ;0,1=295,2=0.000000
L 7.86735659 3.34380315 7.86628976 3.34130364 2 P 0 ;0,1=295,2=0.000000
L 7.86628976 3.34130364 7.86548986 3.33796949 2 P 0 ;0,1=295,2=0.000000
L 7.86548986 3.33796949 7.86522323 3.33421959 2 P 0 ;0,1=295,2=0.000000
L 7.86522323 3.33421959 7.86548986 3.33046959 2 P 0 ;0,1=295,2=0.000000
L 7.86548986 3.33046959 7.86628976 3.32713622 2 P 0 ;0,1=295,2=0.000000
L 7.86628976 3.32713622 7.86735659 3.32463602 2 P 0 ;0,1=295,2=0.000000
L 7.86735659 3.32463602 7.8689563 3.32255305 2 P 0 ;0,1=295,2=0.000000
L 7.8689563 3.32255305 7.87108967 3.32171998 2 P 0 ;0,1=295,2=0.000000
L 7.87108967 3.32171998 7.87322303 3.32255305 2 P 0 ;0,1=295,2=0.000000
L 7.87322303 3.32255305 7.87482323 3.32463602 2 P 0 ;0,1=295,2=0.000000
L 7.87482323 3.32463602 7.87589006 3.32713622 2 P 0 ;0,1=295,2=0.000000
L 7.87589006 3.32713622 7.87668996 3.33046959 2 P 0 ;0,1=295,2=0.000000
L 7.87668996 3.33046959 7.87695659 3.33421959 2 P 0 ;0,1=295,2=0.000000
L 7.87695659 3.33421959 7.87668996 3.33796949 2 P 0 ;0,1=295,2=0.000000
L 7.87668996 3.33796949 7.87589006 3.34130364 2 P 0 ;0,1=295,2=0.000000
L 7.87589006 3.34130364 7.87482323 3.34380315 2 P 0 ;0,1=295,2=0.000000
L 7.87482323 3.34380315 7.87322303 3.34588681 2 P 0 ;0,1=295,2=0.000000
L 7.87322303 3.34588681 7.87108967 3.34671998 2 P 0 ;0,1=295,2=0.000000
L 7.83985325 3.37671959 7.84145295 3.37380285 2 P 0 ;0,1=296,2=0.000000
L 7.84145295 3.37380285 7.84358632 3.37213652 2 P 0 ;0,1=296,2=0.000000
L 7.84358632 3.37213652 7.84598681 3.37171998 2 P 0 ;0,1=296,2=0.000000
L 7.84598681 3.37171998 7.84812018 3.37213652 2 P 0 ;0,1=296,2=0.000000
L 7.84812018 3.37213652 7.85025354 3.37421939 2 P 0 ;0,1=296,2=0.000000
L 7.85025354 3.37421939 7.85158661 3.37671959 2 P 0 ;0,1=296,2=0.000000
L 7.85158661 3.37671959 7.85185315 3.37921988 2 P 0 ;0,1=296,2=0.000000
L 7.85185315 3.37921988 7.85131998 3.38213593 2 P 0 ;0,1=296,2=0.000000
L 7.85131998 3.38213593 7.84945325 3.38421959 2 P 0 ;0,1=296,2=0.000000
L 7.84945325 3.38421959 7.84758642 3.38505344 2 P 0 ;0,1=296,2=0.000000
L 7.84758642 3.38505344 7.84518652 3.38505344 2 P 0 ;0,1=296,2=0.000000
L 7.84758642 3.38505344 7.84918661 3.38630325 2 P 0 ;0,1=296,2=0.000000
L 7.84918661 3.38630325 7.85052008 3.38838612 2 P 0 ;0,1=296,2=0.000000
L 7.85052008 3.38838612 7.85105335 3.39088632 2 P 0 ;0,1=296,2=0.000000
L 7.85105335 3.39088632 7.85052008 3.39338652 2 P 0 ;0,1=296,2=0.000000
L 7.85052008 3.39338652 7.84918661 3.39546939 2 P 0 ;0,1=296,2=0.000000
L 7.84918661 3.39546939 7.84678661 3.39671998 2 P 0 ;0,1=296,2=0.000000
L 7.84678661 3.39671998 7.84438661 3.39630335 2 P 0 ;0,1=296,2=0.000000
L 7.84438661 3.39630335 7.84198661 3.39463632 2 P 0 ;0,1=296,2=0.000000
L 7.86971969 3.37171998 7.86971969 3.39671998 2 P 0 ;0,1=296,2=0.000000
L 7.86971969 3.39671998 7.86651988 3.39172028 2 P 0 ;0,1=296,2=0.000000
L 7.86651988 3.37171998 7.87291949 3.37171998 2 P 0 ;0,1=296,2=0.000000
L 7.84122323 3.42671959 7.84282293 3.42380285 2 P 0 ;0,1=297,2=0.000000
L 7.84282293 3.42380285 7.8449563 3.42213652 2 P 0 ;0,1=297,2=0.000000
L 7.8449563 3.42213652 7.84735679 3.42171998 2 P 0 ;0,1=297,2=0.000000
L 7.84735679 3.42171998 7.84949016 3.42213652 2 P 0 ;0,1=297,2=0.000000
L 7.84949016 3.42213652 7.85162352 3.42421939 2 P 0 ;0,1=297,2=0.000000
L 7.85162352 3.42421939 7.85295659 3.42671959 2 P 0 ;0,1=297,2=0.000000
L 7.85295659 3.42671959 7.85322313 3.42921988 2 P 0 ;0,1=297,2=0.000000
L 7.85322313 3.42921988 7.85268996 3.43213593 2 P 0 ;0,1=297,2=0.000000
L 7.85268996 3.43213593 7.85082323 3.43421959 2 P 0 ;0,1=297,2=0.000000
L 7.85082323 3.43421959 7.8489564 3.43505344 2 P 0 ;0,1=297,2=0.000000
L 7.8489564 3.43505344 7.8465565 3.43505344 2 P 0 ;0,1=297,2=0.000000
L 7.8489564 3.43505344 7.85055659 3.43630325 2 P 0 ;0,1=297,2=0.000000
L 7.85055659 3.43630325 7.85189006 3.43838612 2 P 0 ;0,1=297,2=0.000000
L 7.85189006 3.43838612 7.85242333 3.44088632 2 P 0 ;0,1=297,2=0.000000
L 7.85242333 3.44088632 7.85189006 3.44338652 2 P 0 ;0,1=297,2=0.000000
L 7.85189006 3.44338652 7.85055659 3.44546939 2 P 0 ;0,1=297,2=0.000000
L 7.85055659 3.44546939 7.84815659 3.44671998 2 P 0 ;0,1=297,2=0.000000
L 7.84815659 3.44671998 7.84575659 3.44630335 2 P 0 ;0,1=297,2=0.000000
L 7.84575659 3.44630335 7.84335659 3.44463632 2 P 0 ;0,1=297,2=0.000000
L 7.86602313 3.44255335 7.86762323 3.44505285 2 P 0 ;0,1=297,2=0.000000
L 7.86762323 3.44505285 7.86948996 3.44630335 2 P 0 ;0,1=297,2=0.000000
L 7.86948996 3.44630335 7.87162333 3.44671998 2 P 0 ;0,1=297,2=0.000000
L 7.87162333 3.44671998 7.87428996 3.44588681 2 P 0 ;0,1=297,2=0.000000
L 7.87428996 3.44588681 7.87615669 3.44380315 2 P 0 ;0,1=297,2=0.000000
L 7.87615669 3.44380315 7.87668996 3.44130364 2 P 0 ;0,1=297,2=0.000000
L 7.87668996 3.44130364 7.87642333 3.43880266 2 P 0 ;0,1=297,2=0.000000
L 7.87642333 3.43880266 7.8753564 3.43671978 2 P 0 ;0,1=297,2=0.000000
L 7.8753564 3.43671978 7.87002323 3.43255325 2 P 0 ;0,1=297,2=0.000000
L 7.87002323 3.43255325 7.86762323 3.42963642 2 P 0 ;0,1=297,2=0.000000
L 7.86762323 3.42963642 7.86602313 3.42546909 2 P 0 ;0,1=297,2=0.000000
L 7.86602313 3.42546909 7.86548986 3.42171998 2 P 0 ;0,1=297,2=0.000000
L 7.86548986 3.42171998 7.87668996 3.42171998 2 P 0 ;0,1=297,2=0.000000
L 7.83985325 3.47671959 7.84145295 3.47380285 2 P 0 ;0,1=298,2=0.000000
L 7.84145295 3.47380285 7.84358632 3.47213652 2 P 0 ;0,1=298,2=0.000000
L 7.84358632 3.47213652 7.84598681 3.47171998 2 P 0 ;0,1=298,2=0.000000
L 7.84598681 3.47171998 7.84812018 3.47213652 2 P 0 ;0,1=298,2=0.000000
L 7.84812018 3.47213652 7.85025354 3.47421939 2 P 0 ;0,1=298,2=0.000000
L 7.85025354 3.47421939 7.85158661 3.47671959 2 P 0 ;0,1=298,2=0.000000
L 7.85158661 3.47671959 7.85185315 3.47921988 2 P 0 ;0,1=298,2=0.000000
L 7.85185315 3.47921988 7.85131998 3.48213593 2 P 0 ;0,1=298,2=0.000000
L 7.85131998 3.48213593 7.84945325 3.48421959 2 P 0 ;0,1=298,2=0.000000
L 7.84945325 3.48421959 7.84758642 3.48505344 2 P 0 ;0,1=298,2=0.000000
L 7.84758642 3.48505344 7.84518652 3.48505344 2 P 0 ;0,1=298,2=0.000000
L 7.84758642 3.48505344 7.84918661 3.48630325 2 P 0 ;0,1=298,2=0.000000
L 7.84918661 3.48630325 7.85052008 3.48838612 2 P 0 ;0,1=298,2=0.000000
L 7.85052008 3.48838612 7.85105335 3.49088632 2 P 0 ;0,1=298,2=0.000000
L 7.85105335 3.49088632 7.85052008 3.49338652 2 P 0 ;0,1=298,2=0.000000
L 7.85052008 3.49338652 7.84918661 3.49546939 2 P 0 ;0,1=298,2=0.000000
L 7.84918661 3.49546939 7.84678661 3.49671998 2 P 0 ;0,1=298,2=0.000000
L 7.84678661 3.49671998 7.84438661 3.49630335 2 P 0 ;0,1=298,2=0.000000
L 7.84438661 3.49630335 7.84198661 3.49463632 2 P 0 ;0,1=298,2=0.000000
L 7.86385325 3.47671959 7.86545295 3.47380285 2 P 0 ;0,1=298,2=0.000000
L 7.86545295 3.47380285 7.86758632 3.47213652 2 P 0 ;0,1=298,2=0.000000
L 7.86758632 3.47213652 7.86998681 3.47171998 2 P 0 ;0,1=298,2=0.000000
L 7.86998681 3.47171998 7.87212018 3.47213652 2 P 0 ;0,1=298,2=0.000000
L 7.87212018 3.47213652 7.87425354 3.47421939 2 P 0 ;0,1=298,2=0.000000
L 7.87425354 3.47421939 7.87558661 3.47671959 2 P 0 ;0,1=298,2=0.000000
L 7.87558661 3.47671959 7.87585315 3.47921988 2 P 0 ;0,1=298,2=0.000000
L 7.87585315 3.47921988 7.87531998 3.48213593 2 P 0 ;0,1=298,2=0.000000
L 7.87531998 3.48213593 7.87345325 3.48421959 2 P 0 ;0,1=298,2=0.000000
L 7.87345325 3.48421959 7.87158642 3.48505344 2 P 0 ;0,1=298,2=0.000000
L 7.87158642 3.48505344 7.86918652 3.48505344 2 P 0 ;0,1=298,2=0.000000
L 7.87158642 3.48505344 7.87318661 3.48630325 2 P 0 ;0,1=298,2=0.000000
L 7.87318661 3.48630325 7.87452008 3.48838612 2 P 0 ;0,1=298,2=0.000000
L 7.87452008 3.48838612 7.87505335 3.49088632 2 P 0 ;0,1=298,2=0.000000
L 7.87505335 3.49088632 7.87452008 3.49338652 2 P 0 ;0,1=298,2=0.000000
L 7.87452008 3.49338652 7.87318661 3.49546939 2 P 0 ;0,1=298,2=0.000000
L 7.87318661 3.49546939 7.87078661 3.49671998 2 P 0 ;0,1=298,2=0.000000
L 7.87078661 3.49671998 7.86838661 3.49630335 2 P 0 ;0,1=298,2=0.000000
L 7.86838661 3.49630335 7.86598661 3.49463632 2 P 0 ;0,1=298,2=0.000000
L 7.84122323 3.52671959 7.84282293 3.52380285 2 P 0 ;0,1=299,2=0.000000
L 7.84282293 3.52380285 7.8449563 3.52213652 2 P 0 ;0,1=299,2=0.000000
L 7.8449563 3.52213652 7.84735679 3.52171998 2 P 0 ;0,1=299,2=0.000000
L 7.84735679 3.52171998 7.84949016 3.52213652 2 P 0 ;0,1=299,2=0.000000
L 7.84949016 3.52213652 7.85162352 3.52421939 2 P 0 ;0,1=299,2=0.000000
L 7.85162352 3.52421939 7.85295659 3.52671959 2 P 0 ;0,1=299,2=0.000000
L 7.85295659 3.52671959 7.85322313 3.52921988 2 P 0 ;0,1=299,2=0.000000
L 7.85322313 3.52921988 7.85268996 3.53213593 2 P 0 ;0,1=299,2=0.000000
L 7.85268996 3.53213593 7.85082323 3.53421959 2 P 0 ;0,1=299,2=0.000000
L 7.85082323 3.53421959 7.8489564 3.53505344 2 P 0 ;0,1=299,2=0.000000
L 7.8489564 3.53505344 7.8465565 3.53505344 2 P 0 ;0,1=299,2=0.000000
L 7.8489564 3.53505344 7.85055659 3.53630325 2 P 0 ;0,1=299,2=0.000000
L 7.85055659 3.53630325 7.85189006 3.53838612 2 P 0 ;0,1=299,2=0.000000
L 7.85189006 3.53838612 7.85242333 3.54088632 2 P 0 ;0,1=299,2=0.000000
L 7.85242333 3.54088632 7.85189006 3.54338652 2 P 0 ;0,1=299,2=0.000000
L 7.85189006 3.54338652 7.85055659 3.54546939 2 P 0 ;0,1=299,2=0.000000
L 7.85055659 3.54546939 7.84815659 3.54671998 2 P 0 ;0,1=299,2=0.000000
L 7.84815659 3.54671998 7.84575659 3.54630335 2 P 0 ;0,1=299,2=0.000000
L 7.84575659 3.54630335 7.84335659 3.54463632 2 P 0 ;0,1=299,2=0.000000
L 7.87428996 3.52171998 7.87428996 3.54671998 2 P 0 ;0,1=299,2=0.000000
L 7.87428996 3.54671998 7.86442293 3.52880325 2 P 0 ;0,1=299,2=0.000000
L 7.86442293 3.52880325 7.87775689 3.52880325 2 P 0 ;0,1=299,2=0.000000
L 7.83985325 3.57671959 7.84145295 3.57380285 2 P 0 ;0,1=300,2=0.000000
L 7.84145295 3.57380285 7.84358632 3.57213652 2 P 0 ;0,1=300,2=0.000000
L 7.84358632 3.57213652 7.84598681 3.57171998 2 P 0 ;0,1=300,2=0.000000
L 7.84598681 3.57171998 7.84812018 3.57213652 2 P 0 ;0,1=300,2=0.000000
L 7.84812018 3.57213652 7.85025354 3.57421939 2 P 0 ;0,1=300,2=0.000000
L 7.85025354 3.57421939 7.85158661 3.57671959 2 P 0 ;0,1=300,2=0.000000
L 7.85158661 3.57671959 7.85185315 3.57921988 2 P 0 ;0,1=300,2=0.000000
L 7.85185315 3.57921988 7.85131998 3.58213593 2 P 0 ;0,1=300,2=0.000000
L 7.85131998 3.58213593 7.84945325 3.58421959 2 P 0 ;0,1=300,2=0.000000
L 7.84945325 3.58421959 7.84758642 3.58505344 2 P 0 ;0,1=300,2=0.000000
L 7.84758642 3.58505344 7.84518652 3.58505344 2 P 0 ;0,1=300,2=0.000000
L 7.84758642 3.58505344 7.84918661 3.58630325 2 P 0 ;0,1=300,2=0.000000
L 7.84918661 3.58630325 7.85052008 3.58838612 2 P 0 ;0,1=300,2=0.000000
L 7.85052008 3.58838612 7.85105335 3.59088632 2 P 0 ;0,1=300,2=0.000000
L 7.85105335 3.59088632 7.85052008 3.59338652 2 P 0 ;0,1=300,2=0.000000
L 7.85052008 3.59338652 7.84918661 3.59546939 2 P 0 ;0,1=300,2=0.000000
L 7.84918661 3.59546939 7.84678661 3.59671998 2 P 0 ;0,1=300,2=0.000000
L 7.84678661 3.59671998 7.84438661 3.59630335 2 P 0 ;0,1=300,2=0.000000
L 7.84438661 3.59630335 7.84198661 3.59463632 2 P 0 ;0,1=300,2=0.000000
L 7.86385325 3.57546909 7.86545295 3.57338622 2 P 0 ;0,1=300,2=0.000000
L 7.86545295 3.57338622 7.86731969 3.57213652 2 P 0 ;0,1=300,2=0.000000
L 7.86731969 3.57213652 7.86971969 3.57171998 2 P 0 ;0,1=300,2=0.000000
L 7.86971969 3.57171998 7.87212018 3.57255305 2 P 0 ;0,1=300,2=0.000000
L 7.87212018 3.57255305 7.87398642 3.57421939 2 P 0 ;0,1=300,2=0.000000
L 7.87398642 3.57421939 7.87531998 3.57713622 2 P 0 ;0,1=300,2=0.000000
L 7.87531998 3.57713622 7.87558661 3.58046959 2 P 0 ;0,1=300,2=0.000000
L 7.87558661 3.58046959 7.87505335 3.58380295 2 P 0 ;0,1=300,2=0.000000
L 7.87505335 3.58380295 7.87371978 3.58588661 2 P 0 ;0,1=300,2=0.000000
L 7.87371978 3.58588661 7.87185305 3.58755295 2 P 0 ;0,1=300,2=0.000000
L 7.87185305 3.58755295 7.86998681 3.58796949 2 P 0 ;0,1=300,2=0.000000
L 7.86998681 3.58796949 7.86811998 3.58755295 2 P 0 ;0,1=300,2=0.000000
L 7.86811998 3.58755295 7.86572008 3.58588661 2 P 0 ;0,1=300,2=0.000000
L 7.86572008 3.58588661 7.86651988 3.59671998 2 P 0 ;0,1=300,2=0.000000
L 7.86651988 3.59671998 7.87371978 3.59671998 2 P 0 ;0,1=300,2=0.000000
L 7.84122323 3.62671959 7.84282293 3.62380285 2 P 0 ;0,1=301,2=0.000000
L 7.84282293 3.62380285 7.8449563 3.62213652 2 P 0 ;0,1=301,2=0.000000
L 7.8449563 3.62213652 7.84735679 3.62171998 2 P 0 ;0,1=301,2=0.000000
L 7.84735679 3.62171998 7.84949016 3.62213652 2 P 0 ;0,1=301,2=0.000000
L 7.84949016 3.62213652 7.85162352 3.62421939 2 P 0 ;0,1=301,2=0.000000
L 7.85162352 3.62421939 7.85295659 3.62671959 2 P 0 ;0,1=301,2=0.000000
L 7.85295659 3.62671959 7.85322313 3.62921988 2 P 0 ;0,1=301,2=0.000000
L 7.85322313 3.62921988 7.85268996 3.63213593 2 P 0 ;0,1=301,2=0.000000
L 7.85268996 3.63213593 7.85082323 3.63421959 2 P 0 ;0,1=301,2=0.000000
L 7.85082323 3.63421959 7.8489564 3.63505344 2 P 0 ;0,1=301,2=0.000000
L 7.8489564 3.63505344 7.8465565 3.63505344 2 P 0 ;0,1=301,2=0.000000
L 7.8489564 3.63505344 7.85055659 3.63630325 2 P 0 ;0,1=301,2=0.000000
L 7.85055659 3.63630325 7.85189006 3.63838612 2 P 0 ;0,1=301,2=0.000000
L 7.85189006 3.63838612 7.85242333 3.64088632 2 P 0 ;0,1=301,2=0.000000
L 7.85242333 3.64088632 7.85189006 3.64338652 2 P 0 ;0,1=301,2=0.000000
L 7.85189006 3.64338652 7.85055659 3.64546939 2 P 0 ;0,1=301,2=0.000000
L 7.85055659 3.64546939 7.84815659 3.64671998 2 P 0 ;0,1=301,2=0.000000
L 7.84815659 3.64671998 7.84575659 3.64630335 2 P 0 ;0,1=301,2=0.000000
L 7.84575659 3.64630335 7.84335659 3.64463632 2 P 0 ;0,1=301,2=0.000000
L 7.86602313 3.63213593 7.86788986 3.63505344 2 P 0 ;0,1=301,2=0.000000
L 7.86788986 3.63505344 7.86948996 3.63671978 2 P 0 ;0,1=301,2=0.000000
L 7.86948996 3.63671978 7.87162333 3.63755295 2 P 0 ;0,1=301,2=0.000000
L 7.87162333 3.63755295 7.87349016 3.63671978 2 P 0 ;0,1=301,2=0.000000
L 7.87349016 3.63671978 7.87482323 3.63505344 2 P 0 ;0,1=301,2=0.000000
L 7.87482323 3.63505344 7.87589006 3.63255325 2 P 0 ;0,1=301,2=0.000000
L 7.87589006 3.63255325 7.87615669 3.62963642 2 P 0 ;0,1=301,2=0.000000
L 7.87615669 3.62963642 7.87589006 3.62713622 2 P 0 ;0,1=301,2=0.000000
L 7.87589006 3.62713622 7.87482323 3.62463602 2 P 0 ;0,1=301,2=0.000000
L 7.87482323 3.62463602 7.87322303 3.62255305 2 P 0 ;0,1=301,2=0.000000
L 7.87322303 3.62255305 7.87135679 3.62171998 2 P 0 ;0,1=301,2=0.000000
L 7.87135679 3.62171998 7.86922343 3.62255305 2 P 0 ;0,1=301,2=0.000000
L 7.86922343 3.62255305 7.86735659 3.62505256 2 P 0 ;0,1=301,2=0.000000
L 7.86735659 3.62505256 7.86628976 3.62880325 2 P 0 ;0,1=301,2=0.000000
L 7.86628976 3.62880325 7.86602313 3.63296978 2 P 0 ;0,1=301,2=0.000000
L 7.86602313 3.63296978 7.8665563 3.63838612 2 P 0 ;0,1=301,2=0.000000
L 7.8665563 3.63838612 7.86735659 3.64130364 2 P 0 ;0,1=301,2=0.000000
L 7.86735659 3.64130364 7.86868967 3.64421969 2 P 0 ;0,1=301,2=0.000000
L 7.86868967 3.64421969 7.8705565 3.64630335 2 P 0 ;0,1=301,2=0.000000
L 7.8705565 3.64630335 7.87242323 3.64671998 2 P 0 ;0,1=301,2=0.000000
L 7.87242323 3.64671998 7.87428996 3.64588681 2 P 0 ;0,1=301,2=0.000000
L 7.87428996 3.64588681 7.87562352 3.64380315 2 P 0 ;0,1=301,2=0.000000
L 7.83985325 3.67671959 7.84145295 3.67380285 2 P 0 ;0,1=302,2=0.000000
L 7.84145295 3.67380285 7.84358632 3.67213652 2 P 0 ;0,1=302,2=0.000000
L 7.84358632 3.67213652 7.84598681 3.67171998 2 P 0 ;0,1=302,2=0.000000
L 7.84598681 3.67171998 7.84812018 3.67213652 2 P 0 ;0,1=302,2=0.000000
L 7.84812018 3.67213652 7.85025354 3.67421939 2 P 0 ;0,1=302,2=0.000000
L 7.85025354 3.67421939 7.85158661 3.67671959 2 P 0 ;0,1=302,2=0.000000
L 7.85158661 3.67671959 7.85185315 3.67921988 2 P 0 ;0,1=302,2=0.000000
L 7.85185315 3.67921988 7.85131998 3.68213593 2 P 0 ;0,1=302,2=0.000000
L 7.85131998 3.68213593 7.84945325 3.68421959 2 P 0 ;0,1=302,2=0.000000
L 7.84945325 3.68421959 7.84758642 3.68505344 2 P 0 ;0,1=302,2=0.000000
L 7.84758642 3.68505344 7.84518652 3.68505344 2 P 0 ;0,1=302,2=0.000000
L 7.84758642 3.68505344 7.84918661 3.68630325 2 P 0 ;0,1=302,2=0.000000
L 7.84918661 3.68630325 7.85052008 3.68838612 2 P 0 ;0,1=302,2=0.000000
L 7.85052008 3.68838612 7.85105335 3.69088632 2 P 0 ;0,1=302,2=0.000000
L 7.85105335 3.69088632 7.85052008 3.69338652 2 P 0 ;0,1=302,2=0.000000
L 7.85052008 3.69338652 7.84918661 3.69546939 2 P 0 ;0,1=302,2=0.000000
L 7.84918661 3.69546939 7.84678661 3.69671998 2 P 0 ;0,1=302,2=0.000000
L 7.84678661 3.69671998 7.84438661 3.69630335 2 P 0 ;0,1=302,2=0.000000
L 7.84438661 3.69630335 7.84198661 3.69463632 2 P 0 ;0,1=302,2=0.000000
L 7.86918652 3.67171998 7.86971969 3.67713622 2 P 0 ;0,1=302,2=0.000000
L 7.86971969 3.67713622 7.87051998 3.68171929 2 P 0 ;0,1=302,2=0.000000
L 7.87051998 3.68171929 7.87158642 3.68588661 2 P 0 ;0,1=302,2=0.000000
L 7.87158642 3.68588661 7.87291998 3.69046978 2 P 0 ;0,1=302,2=0.000000
L 7.87291998 3.69046978 7.87505335 3.69671998 2 P 0 ;0,1=302,2=0.000000
L 7.87505335 3.69671998 7.86438652 3.69671998 2 P 0 ;0,1=302,2=0.000000
L 7.84122323 3.72671959 7.84282293 3.72380285 2 P 0 ;0,1=303,2=0.000000
L 7.84282293 3.72380285 7.8449563 3.72213652 2 P 0 ;0,1=303,2=0.000000
L 7.8449563 3.72213652 7.84735679 3.72171998 2 P 0 ;0,1=303,2=0.000000
L 7.84735679 3.72171998 7.84949016 3.72213652 2 P 0 ;0,1=303,2=0.000000
L 7.84949016 3.72213652 7.85162352 3.72421939 2 P 0 ;0,1=303,2=0.000000
L 7.85162352 3.72421939 7.85295659 3.72671959 2 P 0 ;0,1=303,2=0.000000
L 7.85295659 3.72671959 7.85322313 3.72921988 2 P 0 ;0,1=303,2=0.000000
L 7.85322313 3.72921988 7.85268996 3.73213593 2 P 0 ;0,1=303,2=0.000000
L 7.85268996 3.73213593 7.85082323 3.73421959 2 P 0 ;0,1=303,2=0.000000
L 7.85082323 3.73421959 7.8489564 3.73505344 2 P 0 ;0,1=303,2=0.000000
L 7.8489564 3.73505344 7.8465565 3.73505344 2 P 0 ;0,1=303,2=0.000000
L 7.8489564 3.73505344 7.85055659 3.73630325 2 P 0 ;0,1=303,2=0.000000
L 7.85055659 3.73630325 7.85189006 3.73838612 2 P 0 ;0,1=303,2=0.000000
L 7.85189006 3.73838612 7.85242333 3.74088632 2 P 0 ;0,1=303,2=0.000000
L 7.85242333 3.74088632 7.85189006 3.74338652 2 P 0 ;0,1=303,2=0.000000
L 7.85189006 3.74338652 7.85055659 3.74546939 2 P 0 ;0,1=303,2=0.000000
L 7.85055659 3.74546939 7.84815659 3.74671998 2 P 0 ;0,1=303,2=0.000000
L 7.84815659 3.74671998 7.84575659 3.74630335 2 P 0 ;0,1=303,2=0.000000
L 7.84575659 3.74630335 7.84335659 3.74463632 2 P 0 ;0,1=303,2=0.000000
L 7.87108967 3.72171998 7.8729564 3.72213652 2 P 0 ;0,1=303,2=0.000000
L 7.8729564 3.72213652 7.87508976 3.72338622 2 P 0 ;0,1=303,2=0.000000
L 7.87508976 3.72338622 7.87642333 3.72546909 2 P 0 ;0,1=303,2=0.000000
L 7.87642333 3.72546909 7.87695659 3.72838671 2 P 0 ;0,1=303,2=0.000000
L 7.87695659 3.72838671 7.87642333 3.73130276 2 P 0 ;0,1=303,2=0.000000
L 7.87642333 3.73130276 7.87482323 3.73380295 2 P 0 ;0,1=303,2=0.000000
L 7.87482323 3.73380295 7.87242323 3.73505344 2 P 0 ;0,1=303,2=0.000000
L 7.87242323 3.73505344 7.86975659 3.73505344 2 P 0 ;0,1=303,2=0.000000
L 7.86975659 3.73505344 7.8681565 3.73588661 2 P 0 ;0,1=303,2=0.000000
L 7.8681565 3.73588661 7.86682293 3.73796949 2 P 0 ;0,1=303,2=0.000000
L 7.86682293 3.73796949 7.86628976 3.74088632 2 P 0 ;0,1=303,2=0.000000
L 7.86628976 3.74088632 7.86709006 3.74380315 2 P 0 ;0,1=303,2=0.000000
L 7.86709006 3.74380315 7.8689563 3.74588681 2 P 0 ;0,1=303,2=0.000000
L 7.8689563 3.74588681 7.87108967 3.74671998 2 P 0 ;0,1=303,2=0.000000
L 7.87108967 3.74671998 7.87322303 3.74588681 2 P 0 ;0,1=303,2=0.000000
L 7.87322303 3.74588681 7.87508976 3.74380315 2 P 0 ;0,1=303,2=0.000000
L 7.87508976 3.74380315 7.87589006 3.74088632 2 P 0 ;0,1=303,2=0.000000
L 7.87589006 3.74088632 7.8753564 3.73796949 2 P 0 ;0,1=303,2=0.000000
L 7.8753564 3.73796949 7.87402333 3.73588661 2 P 0 ;0,1=303,2=0.000000
L 7.87402333 3.73588661 7.87242323 3.73505344 2 P 0 ;0,1=303,2=0.000000
L 7.87242323 3.73505344 7.86975659 3.73505344 2 P 0 ;0,1=303,2=0.000000
L 7.86975659 3.73505344 7.86735659 3.73380295 2 P 0 ;0,1=303,2=0.000000
L 7.86735659 3.73380295 7.8657565 3.73130276 2 P 0 ;0,1=303,2=0.000000
L 7.8657565 3.73130276 7.86522323 3.72838671 2 P 0 ;0,1=303,2=0.000000
L 7.86522323 3.72838671 7.8657565 3.72546909 2 P 0 ;0,1=303,2=0.000000
L 7.8657565 3.72546909 7.86709006 3.72338622 2 P 0 ;0,1=303,2=0.000000
L 7.86709006 3.72338622 7.86922343 3.72213652 2 P 0 ;0,1=303,2=0.000000
L 7.86922343 3.72213652 7.87108967 3.72171998 2 P 0 ;0,1=303,2=0.000000
L 7.83985325 3.77671959 7.84145295 3.77380285 2 P 0 ;0,1=304,2=0.000000
L 7.84145295 3.77380285 7.84358632 3.77213652 2 P 0 ;0,1=304,2=0.000000
L 7.84358632 3.77213652 7.84598681 3.77171998 2 P 0 ;0,1=304,2=0.000000
L 7.84598681 3.77171998 7.84812018 3.77213652 2 P 0 ;0,1=304,2=0.000000
L 7.84812018 3.77213652 7.85025354 3.77421939 2 P 0 ;0,1=304,2=0.000000
L 7.85025354 3.77421939 7.85158661 3.77671959 2 P 0 ;0,1=304,2=0.000000
L 7.85158661 3.77671959 7.85185315 3.77921988 2 P 0 ;0,1=304,2=0.000000
L 7.85185315 3.77921988 7.85131998 3.78213593 2 P 0 ;0,1=304,2=0.000000
L 7.85131998 3.78213593 7.84945325 3.78421959 2 P 0 ;0,1=304,2=0.000000
L 7.84945325 3.78421959 7.84758642 3.78505344 2 P 0 ;0,1=304,2=0.000000
L 7.84758642 3.78505344 7.84518652 3.78505344 2 P 0 ;0,1=304,2=0.000000
L 7.84758642 3.78505344 7.84918661 3.78630325 2 P 0 ;0,1=304,2=0.000000
L 7.84918661 3.78630325 7.85052008 3.78838612 2 P 0 ;0,1=304,2=0.000000
L 7.85052008 3.78838612 7.85105335 3.79088632 2 P 0 ;0,1=304,2=0.000000
L 7.85105335 3.79088632 7.85052008 3.79338652 2 P 0 ;0,1=304,2=0.000000
L 7.85052008 3.79338652 7.84918661 3.79546939 2 P 0 ;0,1=304,2=0.000000
L 7.84918661 3.79546939 7.84678661 3.79671998 2 P 0 ;0,1=304,2=0.000000
L 7.84678661 3.79671998 7.84438661 3.79630335 2 P 0 ;0,1=304,2=0.000000
L 7.84438661 3.79630335 7.84198661 3.79463632 2 P 0 ;0,1=304,2=0.000000
L 7.86518632 3.77463602 7.86705315 3.77255305 2 P 0 ;0,1=304,2=0.000000
L 7.86705315 3.77255305 7.86918652 3.77171998 2 P 0 ;0,1=304,2=0.000000
L 7.86918652 3.77171998 7.87131988 3.77255305 2 P 0 ;0,1=304,2=0.000000
L 7.87131988 3.77255305 7.87318661 3.77505256 2 P 0 ;0,1=304,2=0.000000
L 7.87318661 3.77505256 7.87452008 3.77880325 2 P 0 ;0,1=304,2=0.000000
L 7.87452008 3.77880325 7.87505335 3.78255325 2 P 0 ;0,1=304,2=0.000000
L 7.87505335 3.78255325 7.87505335 3.78713632 2 P 0 ;0,1=304,2=0.000000
L 7.87505335 3.78713632 7.87452008 3.79088632 2 P 0 ;0,1=304,2=0.000000
L 7.87452008 3.79088632 7.87318661 3.79421969 2 P 0 ;0,1=304,2=0.000000
L 7.87318661 3.79421969 7.87158642 3.79588681 2 P 0 ;0,1=304,2=0.000000
L 7.87158642 3.79588681 7.86971969 3.79671998 2 P 0 ;0,1=304,2=0.000000
L 7.86971969 3.79671998 7.86758632 3.79588681 2 P 0 ;0,1=304,2=0.000000
L 7.86758632 3.79588681 7.86598661 3.79421969 2 P 0 ;0,1=304,2=0.000000
L 7.86598661 3.79421969 7.86491978 3.79172028 2 P 0 ;0,1=304,2=0.000000
L 7.86491978 3.79172028 7.86438652 3.78838612 2 P 0 ;0,1=304,2=0.000000
L 7.86438652 3.78838612 7.86491978 3.78547008 2 P 0 ;0,1=304,2=0.000000
L 7.86491978 3.78547008 7.86625325 3.78255325 2 P 0 ;0,1=304,2=0.000000
L 7.86625325 3.78255325 7.86785344 3.78088612 2 P 0 ;0,1=304,2=0.000000
L 7.86785344 3.78088612 7.86971969 3.78046959 2 P 0 ;0,1=304,2=0.000000
L 7.86971969 3.78046959 7.87185305 3.78130276 2 P 0 ;0,1=304,2=0.000000
L 7.87185305 3.78130276 7.87345325 3.78338642 2 P 0 ;0,1=304,2=0.000000
L 7.87345325 3.78338642 7.87505335 3.78713632 2 P 0 ;0,1=304,2=0.000000
L 7.85028996 3.82171998 7.85028996 3.84671998 2 P 0 ;0,1=305,2=0.000000
L 7.85028996 3.84671998 7.84042293 3.82880325 2 P 0 ;0,1=305,2=0.000000
L 7.84042293 3.82880325 7.85375689 3.82880325 2 P 0 ;0,1=305,2=0.000000
L 7.87108967 3.84671998 7.8689563 3.84588681 2 P 0 ;0,1=305,2=0.000000
L 7.8689563 3.84588681 7.86735659 3.84380315 2 P 0 ;0,1=305,2=0.000000
L 7.86735659 3.84380315 7.86628976 3.84130364 2 P 0 ;0,1=305,2=0.000000
L 7.86628976 3.84130364 7.86548986 3.83796949 2 P 0 ;0,1=305,2=0.000000
L 7.86548986 3.83796949 7.86522323 3.83421959 2 P 0 ;0,1=305,2=0.000000
L 7.86522323 3.83421959 7.86548986 3.83046959 2 P 0 ;0,1=305,2=0.000000
L 7.86548986 3.83046959 7.86628976 3.82713622 2 P 0 ;0,1=305,2=0.000000
L 7.86628976 3.82713622 7.86735659 3.82463602 2 P 0 ;0,1=305,2=0.000000
L 7.86735659 3.82463602 7.8689563 3.82255305 2 P 0 ;0,1=305,2=0.000000
L 7.8689563 3.82255305 7.87108967 3.82171998 2 P 0 ;0,1=305,2=0.000000
L 7.87108967 3.82171998 7.87322303 3.82255305 2 P 0 ;0,1=305,2=0.000000
L 7.87322303 3.82255305 7.87482323 3.82463602 2 P 0 ;0,1=305,2=0.000000
L 7.87482323 3.82463602 7.87589006 3.82713622 2 P 0 ;0,1=305,2=0.000000
L 7.87589006 3.82713622 7.87668996 3.83046959 2 P 0 ;0,1=305,2=0.000000
L 7.87668996 3.83046959 7.87695659 3.83421959 2 P 0 ;0,1=305,2=0.000000
L 7.87695659 3.83421959 7.87668996 3.83796949 2 P 0 ;0,1=305,2=0.000000
L 7.87668996 3.83796949 7.87589006 3.84130364 2 P 0 ;0,1=305,2=0.000000
L 7.87589006 3.84130364 7.87482323 3.84380315 2 P 0 ;0,1=305,2=0.000000
L 7.87482323 3.84380315 7.87322303 3.84588681 2 P 0 ;0,1=305,2=0.000000
L 7.87322303 3.84588681 7.87108967 3.84671998 2 P 0 ;0,1=305,2=0.000000
L 4.68111004 1.7441 4.68111004 1.77953996 3 P 0 
L 4.68111004 1.77953996 4.58031998 1.77953996 3 P 0 
A 4.58031998 1.77953996 4.4874 1.87246004 4.5799 1.87203996 3 P 0 Y
L 4.4874 1.87246004 4.4874 3.85941004 3 P 0 
A 4.4874 3.85941004 4.58076998 3.95276004 4.57992018 3.86023996 3 P 0 Y
L 4.58076998 3.95276004 4.72048002 3.95276004 3 P 0 
L 4.72048002 3.95276004 4.72048002 3.9882 3 P 0 
L 4.72048002 3.9882 4.94488002 3.9882 3 P 0 
L 4.94488002 3.9882 4.94488002 3.95276004 3 P 0 
L 4.94488002 3.95276004 5.08391998 3.95276004 3 P 0 
A 5.08391998 3.95276004 5.15062037 3.92590423 5.08542106 3.86023002 3 P 0 Y
A 5.15062037 3.92590423 5.17796004 3.8594 5.08541998 3.86022884 3 P 0 Y
L 5.17796004 3.8594 5.17796004 1.87286004 3 P 0 
A 5.17796004 1.87286004 5.08463002 1.77953996 5.0854499 1.87205 3 P 0 Y
L 5.08463002 1.77953996 4.98425 1.77953002 3 P 0 
L 4.98425 1.77953002 4.98425 1.7441 3 P 0 
L 4.98425 1.7441 4.68111004 1.7441 3 P 0 
L 4.52458996 3.74115 4.50708996 3.7569 3 P 0 
L 4.50708996 3.7569 4.49138002 3.7569 3 P 0 
L 4.49138002 3.7569 4.50711998 3.74115 3 P 0 
L 4.50711998 3.74115 4.54256004 3.74115 3 P 0 
L 4.54256004 3.74115 4.54253002 3.5758 3 P 0 
L 4.54253002 3.5758 4.50708996 3.5758 3 P 0 
L 4.50708996 3.5758 4.49135 3.56005 3 P 0 
L 4.49135 3.56005 4.50708996 3.56005 3 P 0 
L 4.50708996 3.56005 4.50708996 2.96458002 3 P 0 
L 4.50708996 2.96458002 4.49135 2.96458002 3 P 0 
L 4.49135 2.96458002 4.50708996 2.94883996 3 P 0 
L 4.50708996 2.94883996 4.54253002 2.94883002 3 P 0 
L 4.54253002 2.94883002 4.54253002 2.78348002 3 P 0 
L 4.54253002 2.78348002 4.50708996 2.78348002 3 P 0 
L 4.50708996 2.78348002 4.49135 2.76773002 3 P 0 
L 4.49135 2.76773002 4.50708996 2.76773002 3 P 0 
L 4.50708996 2.76773002 4.50708996 2.17383002 3 P 0 
L 4.50708996 2.17383002 4.49135 2.17383002 3 P 0 
L 4.49135 2.17383002 4.50708996 2.15808002 3 P 0 
L 4.50708996 2.15808002 4.54253002 2.15808002 3 P 0 
L 4.54253002 2.15808002 4.54253002 1.99273002 3 P 0 
L 4.54253002 1.99273002 4.50708996 1.99273002 3 P 0 
L 4.50708996 1.99273002 4.49135 1.97698002 3 P 0 
L 4.49135 1.97698002 4.50708996 1.97698002 3 P 0 
L 4.50708996 1.97698002 4.52098996 1.99273002 3 P 0 
L 4.50708996 2.17383002 4.52283996 2.15808002 3 P 0 
L 4.52283996 2.15808002 4.52283996 2.78348002 3 P 0 
L 4.52283996 2.78348002 4.50708996 2.76773002 3 P 0 
L 4.50708996 2.78348002 4.50708996 2.94883002 2 P 0 
L 4.50708996 2.96458002 4.52283996 2.94883996 3 P 0 
L 4.52283996 2.94883996 4.52283996 3.5758 3 P 0 
L 4.52283996 3.5758 4.50708996 3.56005 3 P 0 
L 5.1429 3.74115 5.15826998 3.75688996 3 P 0 
L 5.15826998 3.75688996 5.17401004 3.75688996 3 P 0 
L 5.17401004 3.75688996 5.15826998 3.74115 3 P 0 
L 5.15826998 3.74115 5.12283002 3.74115 3 P 0 
L 5.12283002 3.74115 5.12283002 3.5758 3 P 0 
L 5.12283002 3.5758 5.15826998 3.5758 3 P 0 
L 5.15826998 3.5758 5.17401004 3.56005 3 P 0 
L 5.17401004 3.56005 5.15826998 3.56005 3 P 0 
L 5.15826998 3.56005 5.15826998 2.96456998 3 P 0 
L 5.15826998 2.96456998 5.17401004 2.96456998 3 P 0 
L 5.17401004 2.96456998 5.15826998 2.94883002 3 P 0 
L 5.15826998 2.94883002 5.12283002 2.94883002 3 P 0 
L 5.12283002 2.94883002 5.12283002 2.78346998 3 P 0 
L 5.12283002 2.78346998 5.15826998 2.78346998 3 P 0 
L 5.15826998 2.78346998 5.17401004 2.76771998 3 P 0 
L 5.17401004 2.76771998 5.15826998 2.76771998 3 P 0 
L 5.15826998 2.76771998 5.15826998 2.17383002 3 P 0 
L 5.15826998 2.17383002 5.17401004 2.17383002 3 P 0 
L 5.17401004 2.17383002 5.15826998 2.15808002 3 P 0 
L 5.15826998 2.15808002 5.12283002 2.15808002 3 P 0 
L 5.12283002 2.15808002 5.12283002 1.99273002 3 P 0 
L 5.12283002 1.99273002 5.15826998 1.99273002 3 P 0 
L 5.15826998 1.99273002 5.17401004 1.97698002 3 P 0 
L 5.17401004 1.97698002 5.15826998 1.97698002 3 P 0 
L 5.15826998 1.97698002 5.14241004 1.99273002 3 P 0 
L 5.15826998 3.56005 5.14251998 3.5758 3 P 0 
L 5.14251998 3.5758 5.14241004 2.94883002 3 P 0 
L 5.14241004 2.94883002 5.15826998 2.96456998 3 P 0 
L 5.15826998 2.94881998 5.15826998 2.78346998 3 P 0 
L 5.15826998 2.76771998 5.14251998 2.78346998 3 P 0 
L 5.14251998 2.78346998 5.14251998 2.15808002 3 P 0 
L 5.14251998 2.15808002 5.15826004 2.17383002 3 P 0 
L 5.15826998 1.97698002 5.15826998 1.87186004 3 P 0 
A 5.15826998 1.87186004 5.08563002 1.79921998 5.08563002 1.87185994 3 P 0 Y
L 5.08563002 1.79921998 5.08543002 1.79921998 3 P 0 
L 5.08543002 1.79921998 4.95718996 1.79921998 3 P 0 
L 4.95718996 1.79921998 4.95718996 1.75788996 3 P 0 
L 4.95718996 1.75788996 4.70818002 1.75788996 3 P 0 
L 4.70818002 1.75788996 4.70818002 1.79921998 3 P 0 
L 4.70818002 1.79921998 4.57991998 1.79921998 3 P 0 
L 4.57991998 1.79921998 4.57973996 1.79921998 3 P 0 
A 4.57973996 1.79921998 4.50708996 1.87186004 4.57973002 1.87186004 3 P 0 Y
L 4.50708996 1.87186004 4.50708996 1.97708002 3 P 0 
A 5.1429 3.86271004 5.12557717 3.90145246 5.08621998 3.86061073 3 P 0 N
A 5.12557717 3.90145246 5.08621998 3.91733002 5.08621919 3.86061004 3 P 0 N
L 5.08621998 3.91733002 4.89223002 3.91733002 3 P 0 
L 4.89223002 3.91733002 4.89223002 3.95276004 3 P 0 
L 4.89223002 3.95276004 4.77313996 3.95276004 3 P 0 
L 4.77313996 3.95276004 4.77313996 3.91733002 3 P 0 
L 4.77313996 3.91733002 4.57993002 3.91733002 3 P 0 
A 4.57993002 3.91733002 4.52458996 3.86198996 4.57993002 3.86198996 3 P 0 N
L 4.52458996 3.86198996 4.52458996 3.74115 3 P 0 
L 4.74755 3.93308002 4.76328996 3.91733002 3 P 0 
L 4.75 3.97245 4.77313996 3.95276004 3 P 0 
L 4.89223002 3.95276004 4.91536004 3.97245 3 P 0 
L 4.91781998 3.93308002 4.90206998 3.91733002 3 P 0 
L 4.77313996 3.91733002 4.77313996 3.90158002 3 P 0 
L 4.77313996 3.90158002 4.89223002 3.90158002 3 P 0 
L 4.89223002 3.90158002 4.89223002 3.91733002 3 P 0 
L 4.70818002 1.79921998 4.72391998 1.81496998 3 P 0 
A 4.52093996 1.87186004 4.57783002 1.81496998 4.57783002 1.87186004 3 P 0 N
L 4.57783002 1.81496998 4.57991998 1.81496998 3 P 0 
L 4.57991998 1.81496998 4.73376998 1.81498002 3 P 0 
L 4.73376998 1.81498002 4.73376004 1.83071998 3 P 0 
L 4.73376004 1.83071998 4.73376998 1.77953996 3 P 0 
L 4.73376998 1.77953996 4.9316 1.77953996 3 P 0 
L 4.9316 1.77953996 4.9316 1.81498002 3 P 0 
L 4.9316 1.81498002 5.08543002 1.81496998 3 P 0 
L 5.08543002 1.81496998 5.08553996 1.81496998 3 P 0 
A 5.08553996 1.81496998 5.14241004 1.87183996 5.08554006 1.87183996 3 P 0 N
L 4.9316 1.81498002 4.9316 1.83071998 3 P 0 
L 4.9316 1.83071998 4.89221998 1.83071998 3 P 0 
L 4.89221998 1.83071998 4.77313002 1.83071998 3 P 0 
L 4.77313002 1.83071998 4.73376004 1.83071998 3 P 0 
L 4.95718996 1.79921998 4.94145 1.81496998 3 P 0 
L 4.73376998 1.77953996 4.71063002 1.75985 3 P 0 
L 4.95473002 1.75985 4.9316 1.77953996 3 P 0 
L 4.52098996 1.87178002 4.52098996 1.99295 3 P 0 
L 5.14241004 2.06861004 5.14241004 2.06868996 2 P 8191 
L 5.15826998 2.86528002 5.15826998 2.94898002 3 P 0 
L 5.15826998 1.99273002 5.15826998 2.15808002 3 P 0 
L 5.14241004 1.87183996 5.14241004 1.99273002 3 P 0 
L 5.1429 3.74115 5.1429 3.86271004 3 P 0 
L 4.50708996 1.99273002 4.50708996 2.15808002 3 P 0 
L 4.50708996 2.76631004 4.50708996 2.74745 3 P 0 
L 4.50708996 2.9478 4.50708996 2.78461004 3 P 0 
L 4.50708996 3.55888996 4.50708996 2.96508996 3 P 0 
L 4.50708996 3.73971004 4.50708996 3.57635 3 P 0 
L 5.15826998 3.75658996 5.15826998 3.86043996 3 P 0 
A 5.15826998 3.86043996 5.08561998 3.93308002 5.07881083 3.85361998 3 P 0 N
L 5.08561998 3.93308002 4.91781998 3.93308002 3 P 0 
L 4.91781998 3.93308002 4.91781998 3.97441998 3 P 0 
L 4.91781998 3.97441998 4.74755 3.97441998 3 P 0 
L 4.74755 3.97441998 4.74755 3.93308002 3 P 0 
L 4.74755 3.93308002 4.57973002 3.93308002 3 P 0 
A 4.57973002 3.93308002 4.50708996 3.86043996 4.5783 3.86186998 3 P 0 N
L 4.50708996 3.86043996 4.50708996 3.75903002 3 P 0 
L 5.15826998 3.57576004 5.15826998 3.73935 3 P 0 
L 5.15826998 2.96475 5.15826998 3.55796004 3 P 0 
L 5.01383317 1.65139961 5.0157501 1.64819931 2 P 0 ;0,1=307,2=0.000000
L 5.0157501 1.64819931 5.01804961 1.64606644 2 P 0 ;0,1=307,2=0.000000
L 5.01804961 1.64606644 5.02073307 1.645 2 P 0 ;0,1=307,2=0.000000
L 5.02073307 1.645 5.0237998 1.64606644 2 P 0 ;0,1=307,2=0.000000
L 5.0237998 1.64606644 5.0261 1.64819931 2 P 0 ;0,1=307,2=0.000000
L 5.0261 1.64819931 5.0284002 1.65139961 2 P 0 ;0,1=307,2=0.000000
L 5.0284002 1.65139961 5.02916673 1.65566634 2 P 0 ;0,1=307,2=0.000000
L 5.02916673 1.65566634 5.02916673 1.677 2 P 0 ;0,1=307,2=0.000000
L 5.041 1.63433366 5.064 1.63433366 2 P 0 ;0,1=307,2=0.000000
L 5.07583317 1.645 5.07583317 1.677 2 P 0 ;0,1=307,2=0.000000
L 5.07583317 1.677 5.08503327 1.677 2 P 0 ;0,1=307,2=0.000000
L 5.08503327 1.677 5.0881 1.67539931 2 P 0 ;0,1=307,2=0.000000
L 5.0881 1.67539931 5.0904002 1.67166673 2 P 0 ;0,1=307,2=0.000000
L 5.0904002 1.67166673 5.09116673 1.6674 2 P 0 ;0,1=307,2=0.000000
L 5.09116673 1.6674 5.0904002 1.66313327 2 P 0 ;0,1=307,2=0.000000
L 5.0904002 1.66313327 5.08848327 1.65993307 2 P 0 ;0,1=307,2=0.000000
L 5.08848327 1.65993307 5.08503327 1.65833238 2 P 0 ;0,1=307,2=0.000000
L 5.08503327 1.65833238 5.07583317 1.65833238 2 P 0 ;0,1=307,2=0.000000
L 5.12216673 1.645 5.10683317 1.645 2 P 0 ;0,1=307,2=0.000000
L 5.10683317 1.645 5.10683317 1.677 2 P 0 ;0,1=307,2=0.000000
L 5.10683317 1.677 5.12216673 1.677 2 P 0 ;0,1=307,2=0.000000
L 5.11603327 1.66153366 5.10683317 1.66153366 2 P 0 ;0,1=307,2=0.000000
L 5.1374499 1.645 5.15355 1.677 2 P 0 ;0,1=307,2=0.000000
L 5.1374499 1.677 5.15355 1.645 2 P 0 ;0,1=307,2=0.000000
L 5.165 1.63433366 5.188 1.63433366 2 P 0 ;0,1=307,2=0.000000
L 5.2097998 1.66099951 5.21746693 1.66099951 2 P 0 ;0,1=307,2=0.000000
L 5.21746693 1.66099951 5.21746693 1.65139961 2 P 0 ;0,1=307,2=0.000000
L 5.21746693 1.65139961 5.21516673 1.64819931 2 P 0 ;0,1=307,2=0.000000
L 5.21516673 1.64819931 5.21248327 1.64606644 2 P 0 ;0,1=307,2=0.000000
L 5.21248327 1.64606644 5.2086501 1.645 2 P 0 ;0,1=307,2=0.000000
L 5.2086501 1.645 5.20481683 1.64606644 2 P 0 ;0,1=307,2=0.000000
L 5.20481683 1.64606644 5.20213337 1.64819931 2 P 0 ;0,1=307,2=0.000000
L 5.20213337 1.64819931 5.19983317 1.65139961 2 P 0 ;0,1=307,2=0.000000
L 5.19983317 1.65139961 5.19829951 1.65513307 2 P 0 ;0,1=307,2=0.000000
L 5.19829951 1.65513307 5.19753297 1.6593998 2 P 0 ;0,1=307,2=0.000000
L 5.19753297 1.6593998 5.19753297 1.66313327 2 P 0 ;0,1=307,2=0.000000
L 5.19753297 1.66313327 5.19829951 1.66633268 2 P 0 ;0,1=307,2=0.000000
L 5.19829951 1.66633268 5.19983317 1.67006713 2 P 0 ;0,1=307,2=0.000000
L 5.19983317 1.67006713 5.20213337 1.67326644 2 P 0 ;0,1=307,2=0.000000
L 5.20213337 1.67326644 5.20443287 1.67539931 2 P 0 ;0,1=307,2=0.000000
L 5.20443287 1.67539931 5.20749961 1.677 2 P 0 ;0,1=307,2=0.000000
L 5.20749961 1.677 5.21018307 1.677 2 P 0 ;0,1=307,2=0.000000
L 5.21018307 1.677 5.2132498 1.67593346 2 P 0 ;0,1=307,2=0.000000
L 5.2132498 1.67593346 5.21555 1.6737997 2 P 0 ;0,1=307,2=0.000000
L 5.23083317 1.645 5.23083317 1.677 2 P 0 ;0,1=307,2=0.000000
L 5.23083317 1.677 5.24003327 1.677 2 P 0 ;0,1=307,2=0.000000
L 5.24003327 1.677 5.2431 1.67539931 2 P 0 ;0,1=307,2=0.000000
L 5.2431 1.67539931 5.2454002 1.67166673 2 P 0 ;0,1=307,2=0.000000
L 5.2454002 1.67166673 5.24616673 1.6674 2 P 0 ;0,1=307,2=0.000000
L 5.24616673 1.6674 5.2454002 1.66313327 2 P 0 ;0,1=307,2=0.000000
L 5.2454002 1.66313327 5.24348327 1.65993307 2 P 0 ;0,1=307,2=0.000000
L 5.24348327 1.65993307 5.24003327 1.65833238 2 P 0 ;0,1=307,2=0.000000
L 5.24003327 1.65833238 5.23083317 1.65833238 2 P 0 ;0,1=307,2=0.000000
L 5.26106663 1.677 5.26106663 1.65406663 2 P 0 ;0,1=307,2=0.000000
L 5.26106663 1.65406663 5.2625997 1.64926575 2 P 0 ;0,1=307,2=0.000000
L 5.2625997 1.64926575 5.26566634 1.64606644 2 P 0 ;0,1=307,2=0.000000
L 5.26566634 1.64606644 5.26949961 1.645 2 P 0 ;0,1=307,2=0.000000
L 5.26949961 1.645 5.27333356 1.64606644 2 P 0 ;0,1=307,2=0.000000
L 5.27333356 1.64606644 5.2764002 1.64926575 2 P 0 ;0,1=307,2=0.000000
L 5.2764002 1.64926575 5.27793327 1.65406663 2 P 0 ;0,1=307,2=0.000000
L 5.27793327 1.65406663 5.27793327 1.677 2 P 0 ;0,1=307,2=0.000000
L 5.30049961 1.677 5.29743287 1.67593346 2 P 0 ;0,1=307,2=0.000000
L 5.29743287 1.67593346 5.29513337 1.67326644 2 P 0 ;0,1=307,2=0.000000
L 5.29513337 1.67326644 5.2935997 1.67006713 2 P 0 ;0,1=307,2=0.000000
L 5.2935997 1.67006713 5.2924499 1.66579941 2 P 0 ;0,1=307,2=0.000000
L 5.2924499 1.66579941 5.29206663 1.66099951 2 P 0 ;0,1=307,2=0.000000
L 5.29206663 1.66099951 5.2924499 1.65619951 2 P 0 ;0,1=307,2=0.000000
L 5.2924499 1.65619951 5.2935997 1.65193278 2 P 0 ;0,1=307,2=0.000000
L 5.2935997 1.65193278 5.29513337 1.64873248 2 P 0 ;0,1=307,2=0.000000
L 5.29513337 1.64873248 5.29743287 1.64606644 2 P 0 ;0,1=307,2=0.000000
L 5.29743287 1.64606644 5.30049961 1.645 2 P 0 ;0,1=307,2=0.000000
L 5.30049961 1.645 5.30356634 1.64606644 2 P 0 ;0,1=307,2=0.000000
L 5.30356634 1.64606644 5.30586654 1.64873248 2 P 0 ;0,1=307,2=0.000000
L 5.30586654 1.64873248 5.3074002 1.65193278 2 P 0 ;0,1=307,2=0.000000
L 5.3074002 1.65193278 5.30855 1.65619951 2 P 0 ;0,1=307,2=0.000000
L 5.30855 1.65619951 5.30893327 1.66099951 2 P 0 ;0,1=307,2=0.000000
L 5.30893327 1.66099951 5.30855 1.66579941 2 P 0 ;0,1=307,2=0.000000
L 5.30855 1.66579941 5.3074002 1.67006713 2 P 0 ;0,1=307,2=0.000000
L 5.3074002 1.67006713 5.30586654 1.67326644 2 P 0 ;0,1=307,2=0.000000
L 5.30586654 1.67326644 5.30356634 1.67593346 2 P 0 ;0,1=307,2=0.000000
L 5.30356634 1.67593346 5.30049961 1.677 2 P 0 ;0,1=307,2=0.000000
L 5.2333997 1.88171998 5.2333997 1.90671998 2 P 0 ;0,1=52,2=0.000000
L 5.2333997 1.90671998 5.2301999 1.90172028 2 P 0 ;0,1=52,2=0.000000
L 5.2301999 1.88171998 5.23659951 1.88171998 2 P 0 ;0,1=52,2=0.000000
L 5.20470315 1.95255335 5.20630325 1.95505285 2 P 0 ;0,1=53,2=0.000000
L 5.20630325 1.95505285 5.20816998 1.95630335 2 P 0 ;0,1=53,2=0.000000
L 5.20816998 1.95630335 5.21030335 1.95671998 2 P 0 ;0,1=53,2=0.000000
L 5.21030335 1.95671998 5.21296998 1.95588681 2 P 0 ;0,1=53,2=0.000000
L 5.21296998 1.95588681 5.21483671 1.95380315 2 P 0 ;0,1=53,2=0.000000
L 5.21483671 1.95380315 5.21536998 1.95130364 2 P 0 ;0,1=53,2=0.000000
L 5.21536998 1.95130364 5.21510335 1.94880266 2 P 0 ;0,1=53,2=0.000000
L 5.21510335 1.94880266 5.21403642 1.94671978 2 P 0 ;0,1=53,2=0.000000
L 5.21403642 1.94671978 5.20870325 1.94255325 2 P 0 ;0,1=53,2=0.000000
L 5.20870325 1.94255325 5.20630325 1.93963642 2 P 0 ;0,1=53,2=0.000000
L 5.20630325 1.93963642 5.20470315 1.93546909 2 P 0 ;0,1=53,2=0.000000
L 5.20470315 1.93546909 5.20416988 1.93171998 2 P 0 ;0,1=53,2=0.000000
L 5.20416988 1.93171998 5.21536998 1.93171998 2 P 0 ;0,1=53,2=0.000000
L 5.22753327 1.98671959 5.22913297 1.98380285 2 P 0 ;0,1=57,2=0.000000
L 5.22913297 1.98380285 5.23126634 1.98213652 2 P 0 ;0,1=57,2=0.000000
L 5.23126634 1.98213652 5.23366683 1.98171998 2 P 0 ;0,1=57,2=0.000000
L 5.23366683 1.98171998 5.2358002 1.98213652 2 P 0 ;0,1=57,2=0.000000
L 5.2358002 1.98213652 5.23793356 1.98421939 2 P 0 ;0,1=57,2=0.000000
L 5.23793356 1.98421939 5.23926663 1.98671959 2 P 0 ;0,1=57,2=0.000000
L 5.23926663 1.98671959 5.23953317 1.98921988 2 P 0 ;0,1=57,2=0.000000
L 5.23953317 1.98921988 5.239 1.99213593 2 P 0 ;0,1=57,2=0.000000
L 5.239 1.99213593 5.23713327 1.99421959 2 P 0 ;0,1=57,2=0.000000
L 5.23713327 1.99421959 5.23526644 1.99505344 2 P 0 ;0,1=57,2=0.000000
L 5.23526644 1.99505344 5.23286654 1.99505344 2 P 0 ;0,1=57,2=0.000000
L 5.23526644 1.99505344 5.23686663 1.99630325 2 P 0 ;0,1=57,2=0.000000
L 5.23686663 1.99630325 5.2382001 1.99838612 2 P 0 ;0,1=57,2=0.000000
L 5.2382001 1.99838612 5.23873337 2.00088632 2 P 0 ;0,1=57,2=0.000000
L 5.23873337 2.00088632 5.2382001 2.00338652 2 P 0 ;0,1=57,2=0.000000
L 5.2382001 2.00338652 5.23686663 2.00546939 2 P 0 ;0,1=57,2=0.000000
L 5.23686663 2.00546939 5.23446663 2.00671998 2 P 0 ;0,1=57,2=0.000000
L 5.23446663 2.00671998 5.23206663 2.00630335 2 P 0 ;0,1=57,2=0.000000
L 5.23206663 2.00630335 5.22966663 2.00463632 2 P 0 ;0,1=57,2=0.000000
L 5.21296998 2.03171998 5.21296998 2.05671998 2 P 0 ;0,1=58,2=0.000000
L 5.21296998 2.05671998 5.20310295 2.03880325 2 P 0 ;0,1=58,2=0.000000
L 5.20310295 2.03880325 5.21643691 2.03880325 2 P 0 ;0,1=58,2=0.000000
L 5.22753327 2.08546909 5.22913297 2.08338622 2 P 0 ;0,1=273,2=0.000000
L 5.22913297 2.08338622 5.2309997 2.08213652 2 P 0 ;0,1=273,2=0.000000
L 5.2309997 2.08213652 5.2333997 2.08171998 2 P 0 ;0,1=273,2=0.000000
L 5.2333997 2.08171998 5.2358002 2.08255305 2 P 0 ;0,1=273,2=0.000000
L 5.2358002 2.08255305 5.23766644 2.08421939 2 P 0 ;0,1=273,2=0.000000
L 5.23766644 2.08421939 5.239 2.08713622 2 P 0 ;0,1=273,2=0.000000
L 5.239 2.08713622 5.23926663 2.09046959 2 P 0 ;0,1=273,2=0.000000
L 5.23926663 2.09046959 5.23873337 2.09380295 2 P 0 ;0,1=273,2=0.000000
L 5.23873337 2.09380295 5.2373998 2.09588661 2 P 0 ;0,1=273,2=0.000000
L 5.2373998 2.09588661 5.23553307 2.09755295 2 P 0 ;0,1=273,2=0.000000
L 5.23553307 2.09755295 5.23366683 2.09796949 2 P 0 ;0,1=273,2=0.000000
L 5.23366683 2.09796949 5.2318 2.09755295 2 P 0 ;0,1=273,2=0.000000
L 5.2318 2.09755295 5.2294001 2.09588661 2 P 0 ;0,1=273,2=0.000000
L 5.2294001 2.09588661 5.2301999 2.10671998 2 P 0 ;0,1=273,2=0.000000
L 5.2301999 2.10671998 5.2373998 2.10671998 2 P 0 ;0,1=273,2=0.000000
L 5.20470315 2.14213593 5.20656988 2.14505344 2 P 0 ;0,1=274,2=0.000000
L 5.20656988 2.14505344 5.20816998 2.14671978 2 P 0 ;0,1=274,2=0.000000
L 5.20816998 2.14671978 5.21030335 2.14755295 2 P 0 ;0,1=274,2=0.000000
L 5.21030335 2.14755295 5.21217018 2.14671978 2 P 0 ;0,1=274,2=0.000000
L 5.21217018 2.14671978 5.21350325 2.14505344 2 P 0 ;0,1=274,2=0.000000
L 5.21350325 2.14505344 5.21457008 2.14255325 2 P 0 ;0,1=274,2=0.000000
L 5.21457008 2.14255325 5.21483671 2.13963642 2 P 0 ;0,1=274,2=0.000000
L 5.21483671 2.13963642 5.21457008 2.13713622 2 P 0 ;0,1=274,2=0.000000
L 5.21457008 2.13713622 5.21350325 2.13463602 2 P 0 ;0,1=274,2=0.000000
L 5.21350325 2.13463602 5.21190305 2.13255305 2 P 0 ;0,1=274,2=0.000000
L 5.21190305 2.13255305 5.21003681 2.13171998 2 P 0 ;0,1=274,2=0.000000
L 5.21003681 2.13171998 5.20790344 2.13255305 2 P 0 ;0,1=274,2=0.000000
L 5.20790344 2.13255305 5.20603661 2.13505256 2 P 0 ;0,1=274,2=0.000000
L 5.20603661 2.13505256 5.20496978 2.13880325 2 P 0 ;0,1=274,2=0.000000
L 5.20496978 2.13880325 5.20470315 2.14296978 2 P 0 ;0,1=274,2=0.000000
L 5.20470315 2.14296978 5.20523632 2.14838612 2 P 0 ;0,1=274,2=0.000000
L 5.20523632 2.14838612 5.20603661 2.15130364 2 P 0 ;0,1=274,2=0.000000
L 5.20603661 2.15130364 5.20736969 2.15421969 2 P 0 ;0,1=274,2=0.000000
L 5.20736969 2.15421969 5.20923652 2.15630335 2 P 0 ;0,1=274,2=0.000000
L 5.20923652 2.15630335 5.21110325 2.15671998 2 P 0 ;0,1=274,2=0.000000
L 5.21110325 2.15671998 5.21296998 2.15588681 2 P 0 ;0,1=274,2=0.000000
L 5.21296998 2.15588681 5.21430354 2.15380315 2 P 0 ;0,1=274,2=0.000000
L 5.23286654 2.18171998 5.2333997 2.18713622 2 P 0 ;0,1=275,2=0.000000
L 5.2333997 2.18713622 5.2342 2.19171929 2 P 0 ;0,1=275,2=0.000000
L 5.2342 2.19171929 5.23526644 2.19588661 2 P 0 ;0,1=275,2=0.000000
L 5.23526644 2.19588661 5.2366 2.20046978 2 P 0 ;0,1=275,2=0.000000
L 5.2366 2.20046978 5.23873337 2.20671998 2 P 0 ;0,1=275,2=0.000000
L 5.23873337 2.20671998 5.22806654 2.20671998 2 P 0 ;0,1=275,2=0.000000
L 5.20976969 2.23171998 5.21163642 2.23213652 2 P 0 ;0,1=276,2=0.000000
L 5.21163642 2.23213652 5.21376978 2.23338622 2 P 0 ;0,1=276,2=0.000000
L 5.21376978 2.23338622 5.21510335 2.23546909 2 P 0 ;0,1=276,2=0.000000
L 5.21510335 2.23546909 5.21563661 2.23838671 2 P 0 ;0,1=276,2=0.000000
L 5.21563661 2.23838671 5.21510335 2.24130276 2 P 0 ;0,1=276,2=0.000000
L 5.21510335 2.24130276 5.21350325 2.24380295 2 P 0 ;0,1=276,2=0.000000
L 5.21350325 2.24380295 5.21110325 2.24505344 2 P 0 ;0,1=276,2=0.000000
L 5.21110325 2.24505344 5.20843661 2.24505344 2 P 0 ;0,1=276,2=0.000000
L 5.20843661 2.24505344 5.20683652 2.24588661 2 P 0 ;0,1=276,2=0.000000
L 5.20683652 2.24588661 5.20550295 2.24796949 2 P 0 ;0,1=276,2=0.000000
L 5.20550295 2.24796949 5.20496978 2.25088632 2 P 0 ;0,1=276,2=0.000000
L 5.20496978 2.25088632 5.20577008 2.25380315 2 P 0 ;0,1=276,2=0.000000
L 5.20577008 2.25380315 5.20763632 2.25588681 2 P 0 ;0,1=276,2=0.000000
L 5.20763632 2.25588681 5.20976969 2.25671998 2 P 0 ;0,1=276,2=0.000000
L 5.20976969 2.25671998 5.21190305 2.25588681 2 P 0 ;0,1=276,2=0.000000
L 5.21190305 2.25588681 5.21376978 2.25380315 2 P 0 ;0,1=276,2=0.000000
L 5.21376978 2.25380315 5.21457008 2.25088632 2 P 0 ;0,1=276,2=0.000000
L 5.21457008 2.25088632 5.21403642 2.24796949 2 P 0 ;0,1=276,2=0.000000
L 5.21403642 2.24796949 5.21270335 2.24588661 2 P 0 ;0,1=276,2=0.000000
L 5.21270335 2.24588661 5.21110325 2.24505344 2 P 0 ;0,1=276,2=0.000000
L 5.21110325 2.24505344 5.20843661 2.24505344 2 P 0 ;0,1=276,2=0.000000
L 5.20843661 2.24505344 5.20603661 2.24380295 2 P 0 ;0,1=276,2=0.000000
L 5.20603661 2.24380295 5.20443652 2.24130276 2 P 0 ;0,1=276,2=0.000000
L 5.20443652 2.24130276 5.20390325 2.23838671 2 P 0 ;0,1=276,2=0.000000
L 5.20390325 2.23838671 5.20443652 2.23546909 2 P 0 ;0,1=276,2=0.000000
L 5.20443652 2.23546909 5.20577008 2.23338622 2 P 0 ;0,1=276,2=0.000000
L 5.20577008 2.23338622 5.20790344 2.23213652 2 P 0 ;0,1=276,2=0.000000
L 5.20790344 2.23213652 5.20976969 2.23171998 2 P 0 ;0,1=276,2=0.000000
L 5.22886634 2.28463602 5.23073317 2.28255305 2 P 0 ;0,1=28,2=0.000000
L 5.23073317 2.28255305 5.23286654 2.28171998 2 P 0 ;0,1=28,2=0.000000
L 5.23286654 2.28171998 5.2349999 2.28255305 2 P 0 ;0,1=28,2=0.000000
L 5.2349999 2.28255305 5.23686663 2.28505256 2 P 0 ;0,1=28,2=0.000000
L 5.23686663 2.28505256 5.2382001 2.28880325 2 P 0 ;0,1=28,2=0.000000
L 5.2382001 2.28880325 5.23873337 2.29255325 2 P 0 ;0,1=28,2=0.000000
L 5.23873337 2.29255325 5.23873337 2.29713632 2 P 0 ;0,1=28,2=0.000000
L 5.23873337 2.29713632 5.2382001 2.30088632 2 P 0 ;0,1=28,2=0.000000
L 5.2382001 2.30088632 5.23686663 2.30421969 2 P 0 ;0,1=28,2=0.000000
L 5.23686663 2.30421969 5.23526644 2.30588681 2 P 0 ;0,1=28,2=0.000000
L 5.23526644 2.30588681 5.2333997 2.30671998 2 P 0 ;0,1=28,2=0.000000
L 5.2333997 2.30671998 5.23126634 2.30588681 2 P 0 ;0,1=28,2=0.000000
L 5.23126634 2.30588681 5.22966663 2.30421969 2 P 0 ;0,1=28,2=0.000000
L 5.22966663 2.30421969 5.2285998 2.30172028 2 P 0 ;0,1=28,2=0.000000
L 5.2285998 2.30172028 5.22806654 2.29838612 2 P 0 ;0,1=28,2=0.000000
L 5.22806654 2.29838612 5.2285998 2.29547008 2 P 0 ;0,1=28,2=0.000000
L 5.2285998 2.29547008 5.22993327 2.29255325 2 P 0 ;0,1=28,2=0.000000
L 5.22993327 2.29255325 5.23153346 2.29088612 2 P 0 ;0,1=28,2=0.000000
L 5.23153346 2.29088612 5.2333997 2.29046959 2 P 0 ;0,1=28,2=0.000000
L 5.2333997 2.29046959 5.23553307 2.29130276 2 P 0 ;0,1=28,2=0.000000
L 5.23553307 2.29130276 5.23713327 2.29338642 2 P 0 ;0,1=28,2=0.000000
L 5.23713327 2.29338642 5.23873337 2.29713632 2 P 0 ;0,1=28,2=0.000000
L 5.20976969 2.32171998 5.20976969 2.34671998 2 P 0 ;0,1=26,2=0.000000
L 5.20976969 2.34671998 5.20656988 2.34172028 2 P 0 ;0,1=26,2=0.000000
L 5.20656988 2.32171998 5.21296949 2.32171998 2 P 0 ;0,1=26,2=0.000000
L 5.23376969 2.34671998 5.23163632 2.34588681 2 P 0 ;0,1=26,2=0.000000
L 5.23163632 2.34588681 5.23003661 2.34380315 2 P 0 ;0,1=26,2=0.000000
L 5.23003661 2.34380315 5.22896978 2.34130364 2 P 0 ;0,1=26,2=0.000000
L 5.22896978 2.34130364 5.22816988 2.33796949 2 P 0 ;0,1=26,2=0.000000
L 5.22816988 2.33796949 5.22790325 2.33421959 2 P 0 ;0,1=26,2=0.000000
L 5.22790325 2.33421959 5.22816988 2.33046959 2 P 0 ;0,1=26,2=0.000000
L 5.22816988 2.33046959 5.22896978 2.32713622 2 P 0 ;0,1=26,2=0.000000
L 5.22896978 2.32713622 5.23003661 2.32463602 2 P 0 ;0,1=26,2=0.000000
L 5.23003661 2.32463602 5.23163632 2.32255305 2 P 0 ;0,1=26,2=0.000000
L 5.23163632 2.32255305 5.23376969 2.32171998 2 P 0 ;0,1=26,2=0.000000
L 5.23376969 2.32171998 5.23590305 2.32255305 2 P 0 ;0,1=26,2=0.000000
L 5.23590305 2.32255305 5.23750325 2.32463602 2 P 0 ;0,1=26,2=0.000000
L 5.23750325 2.32463602 5.23857008 2.32713622 2 P 0 ;0,1=26,2=0.000000
L 5.23857008 2.32713622 5.23936998 2.33046959 2 P 0 ;0,1=26,2=0.000000
L 5.23936998 2.33046959 5.23963661 2.33421959 2 P 0 ;0,1=26,2=0.000000
L 5.23963661 2.33421959 5.23936998 2.33796949 2 P 0 ;0,1=26,2=0.000000
L 5.23936998 2.33796949 5.23857008 2.34130364 2 P 0 ;0,1=26,2=0.000000
L 5.23857008 2.34130364 5.23750325 2.34380315 2 P 0 ;0,1=26,2=0.000000
L 5.23750325 2.34380315 5.23590305 2.34588681 2 P 0 ;0,1=26,2=0.000000
L 5.23590305 2.34588681 5.23376969 2.34671998 2 P 0 ;0,1=26,2=0.000000
L 5.2333997 2.37171998 5.2333997 2.39671998 2 P 0 ;0,1=277,2=0.000000
L 5.2333997 2.39671998 5.2301999 2.39172028 2 P 0 ;0,1=277,2=0.000000
L 5.2301999 2.37171998 5.23659951 2.37171998 2 P 0 ;0,1=277,2=0.000000
L 5.2573997 2.37171998 5.2573997 2.39671998 2 P 0 ;0,1=277,2=0.000000
L 5.2573997 2.39671998 5.2541999 2.39172028 2 P 0 ;0,1=277,2=0.000000
L 5.2541999 2.37171998 5.26059951 2.37171998 2 P 0 ;0,1=277,2=0.000000
L 5.20976969 2.42171998 5.20976969 2.44671998 2 P 0 ;0,1=278,2=0.000000
L 5.20976969 2.44671998 5.20656988 2.44172028 2 P 0 ;0,1=278,2=0.000000
L 5.20656988 2.42171998 5.21296949 2.42171998 2 P 0 ;0,1=278,2=0.000000
L 5.22870315 2.44255335 5.23030325 2.44505285 2 P 0 ;0,1=278,2=0.000000
L 5.23030325 2.44505285 5.23216998 2.44630335 2 P 0 ;0,1=278,2=0.000000
L 5.23216998 2.44630335 5.23430335 2.44671998 2 P 0 ;0,1=278,2=0.000000
L 5.23430335 2.44671998 5.23696998 2.44588681 2 P 0 ;0,1=278,2=0.000000
L 5.23696998 2.44588681 5.23883671 2.44380315 2 P 0 ;0,1=278,2=0.000000
L 5.23883671 2.44380315 5.23936998 2.44130364 2 P 0 ;0,1=278,2=0.000000
L 5.23936998 2.44130364 5.23910335 2.43880266 2 P 0 ;0,1=278,2=0.000000
L 5.23910335 2.43880266 5.23803642 2.43671978 2 P 0 ;0,1=278,2=0.000000
L 5.23803642 2.43671978 5.23270325 2.43255325 2 P 0 ;0,1=278,2=0.000000
L 5.23270325 2.43255325 5.23030325 2.42963642 2 P 0 ;0,1=278,2=0.000000
L 5.23030325 2.42963642 5.22870315 2.42546909 2 P 0 ;0,1=278,2=0.000000
L 5.22870315 2.42546909 5.22816988 2.42171998 2 P 0 ;0,1=278,2=0.000000
L 5.22816988 2.42171998 5.23936998 2.42171998 2 P 0 ;0,1=278,2=0.000000
L 5.2333997 2.47171998 5.2333997 2.49671998 2 P 0 ;0,1=279,2=0.000000
L 5.2333997 2.49671998 5.2301999 2.49172028 2 P 0 ;0,1=279,2=0.000000
L 5.2301999 2.47171998 5.23659951 2.47171998 2 P 0 ;0,1=279,2=0.000000
L 5.25153327 2.47671959 5.25313297 2.47380285 2 P 0 ;0,1=279,2=0.000000
L 5.25313297 2.47380285 5.25526634 2.47213652 2 P 0 ;0,1=279,2=0.000000
L 5.25526634 2.47213652 5.25766683 2.47171998 2 P 0 ;0,1=279,2=0.000000
L 5.25766683 2.47171998 5.2598002 2.47213652 2 P 0 ;0,1=279,2=0.000000
L 5.2598002 2.47213652 5.26193356 2.47421939 2 P 0 ;0,1=279,2=0.000000
L 5.26193356 2.47421939 5.26326663 2.47671959 2 P 0 ;0,1=279,2=0.000000
L 5.26326663 2.47671959 5.26353317 2.47921988 2 P 0 ;0,1=279,2=0.000000
L 5.26353317 2.47921988 5.263 2.48213593 2 P 0 ;0,1=279,2=0.000000
L 5.263 2.48213593 5.26113327 2.48421959 2 P 0 ;0,1=279,2=0.000000
L 5.26113327 2.48421959 5.25926644 2.48505344 2 P 0 ;0,1=279,2=0.000000
L 5.25926644 2.48505344 5.25686654 2.48505344 2 P 0 ;0,1=279,2=0.000000
L 5.25926644 2.48505344 5.26086663 2.48630325 2 P 0 ;0,1=279,2=0.000000
L 5.26086663 2.48630325 5.2622001 2.48838612 2 P 0 ;0,1=279,2=0.000000
L 5.2622001 2.48838612 5.26273337 2.49088632 2 P 0 ;0,1=279,2=0.000000
L 5.26273337 2.49088632 5.2622001 2.49338652 2 P 0 ;0,1=279,2=0.000000
L 5.2622001 2.49338652 5.26086663 2.49546939 2 P 0 ;0,1=279,2=0.000000
L 5.26086663 2.49546939 5.25846663 2.49671998 2 P 0 ;0,1=279,2=0.000000
L 5.25846663 2.49671998 5.25606663 2.49630335 2 P 0 ;0,1=279,2=0.000000
L 5.25606663 2.49630335 5.25366663 2.49463632 2 P 0 ;0,1=279,2=0.000000
L 5.20976969 2.52171998 5.20976969 2.54671998 2 P 0 ;0,1=63,2=0.000000
L 5.20976969 2.54671998 5.20656988 2.54172028 2 P 0 ;0,1=63,2=0.000000
L 5.20656988 2.52171998 5.21296949 2.52171998 2 P 0 ;0,1=63,2=0.000000
L 5.23696998 2.52171998 5.23696998 2.54671998 2 P 0 ;0,1=63,2=0.000000
L 5.23696998 2.54671998 5.22710295 2.52880325 2 P 0 ;0,1=63,2=0.000000
L 5.22710295 2.52880325 5.24043691 2.52880325 2 P 0 ;0,1=63,2=0.000000
L 5.2333997 2.57171998 5.2333997 2.59671998 2 P 0 ;0,1=280,2=0.000000
L 5.2333997 2.59671998 5.2301999 2.59172028 2 P 0 ;0,1=280,2=0.000000
L 5.2301999 2.57171998 5.23659951 2.57171998 2 P 0 ;0,1=280,2=0.000000
L 5.25153327 2.57546909 5.25313297 2.57338622 2 P 0 ;0,1=280,2=0.000000
L 5.25313297 2.57338622 5.2549997 2.57213652 2 P 0 ;0,1=280,2=0.000000
L 5.2549997 2.57213652 5.2573997 2.57171998 2 P 0 ;0,1=280,2=0.000000
L 5.2573997 2.57171998 5.2598002 2.57255305 2 P 0 ;0,1=280,2=0.000000
L 5.2598002 2.57255305 5.26166644 2.57421939 2 P 0 ;0,1=280,2=0.000000
L 5.26166644 2.57421939 5.263 2.57713622 2 P 0 ;0,1=280,2=0.000000
L 5.263 2.57713622 5.26326663 2.58046959 2 P 0 ;0,1=280,2=0.000000
L 5.26326663 2.58046959 5.26273337 2.58380295 2 P 0 ;0,1=280,2=0.000000
L 5.26273337 2.58380295 5.2613998 2.58588661 2 P 0 ;0,1=280,2=0.000000
L 5.2613998 2.58588661 5.25953307 2.58755295 2 P 0 ;0,1=280,2=0.000000
L 5.25953307 2.58755295 5.25766683 2.58796949 2 P 0 ;0,1=280,2=0.000000
L 5.25766683 2.58796949 5.2558 2.58755295 2 P 0 ;0,1=280,2=0.000000
L 5.2558 2.58755295 5.2534001 2.58588661 2 P 0 ;0,1=280,2=0.000000
L 5.2534001 2.58588661 5.2541999 2.59671998 2 P 0 ;0,1=280,2=0.000000
L 5.2541999 2.59671998 5.2613998 2.59671998 2 P 0 ;0,1=280,2=0.000000
L 5.20976969 2.62171998 5.20976969 2.64671998 2 P 0 ;0,1=281,2=0.000000
L 5.20976969 2.64671998 5.20656988 2.64172028 2 P 0 ;0,1=281,2=0.000000
L 5.20656988 2.62171998 5.21296949 2.62171998 2 P 0 ;0,1=281,2=0.000000
L 5.22870315 2.63213593 5.23056988 2.63505344 2 P 0 ;0,1=281,2=0.000000
L 5.23056988 2.63505344 5.23216998 2.63671978 2 P 0 ;0,1=281,2=0.000000
L 5.23216998 2.63671978 5.23430335 2.63755295 2 P 0 ;0,1=281,2=0.000000
L 5.23430335 2.63755295 5.23617018 2.63671978 2 P 0 ;0,1=281,2=0.000000
L 5.23617018 2.63671978 5.23750325 2.63505344 2 P 0 ;0,1=281,2=0.000000
L 5.23750325 2.63505344 5.23857008 2.63255325 2 P 0 ;0,1=281,2=0.000000
L 5.23857008 2.63255325 5.23883671 2.62963642 2 P 0 ;0,1=281,2=0.000000
L 5.23883671 2.62963642 5.23857008 2.62713622 2 P 0 ;0,1=281,2=0.000000
L 5.23857008 2.62713622 5.23750325 2.62463602 2 P 0 ;0,1=281,2=0.000000
L 5.23750325 2.62463602 5.23590305 2.62255305 2 P 0 ;0,1=281,2=0.000000
L 5.23590305 2.62255305 5.23403681 2.62171998 2 P 0 ;0,1=281,2=0.000000
L 5.23403681 2.62171998 5.23190344 2.62255305 2 P 0 ;0,1=281,2=0.000000
L 5.23190344 2.62255305 5.23003661 2.62505256 2 P 0 ;0,1=281,2=0.000000
L 5.23003661 2.62505256 5.22896978 2.62880325 2 P 0 ;0,1=281,2=0.000000
L 5.22896978 2.62880325 5.22870315 2.63296978 2 P 0 ;0,1=281,2=0.000000
L 5.22870315 2.63296978 5.22923632 2.63838612 2 P 0 ;0,1=281,2=0.000000
L 5.22923632 2.63838612 5.23003661 2.64130364 2 P 0 ;0,1=281,2=0.000000
L 5.23003661 2.64130364 5.23136969 2.64421969 2 P 0 ;0,1=281,2=0.000000
L 5.23136969 2.64421969 5.23323652 2.64630335 2 P 0 ;0,1=281,2=0.000000
L 5.23323652 2.64630335 5.23510325 2.64671998 2 P 0 ;0,1=281,2=0.000000
L 5.23510325 2.64671998 5.23696998 2.64588681 2 P 0 ;0,1=281,2=0.000000
L 5.23696998 2.64588681 5.23830354 2.64380315 2 P 0 ;0,1=281,2=0.000000
L 5.2333997 2.67171998 5.2333997 2.69671998 2 P 0 ;0,1=282,2=0.000000
L 5.2333997 2.69671998 5.2301999 2.69172028 2 P 0 ;0,1=282,2=0.000000
L 5.2301999 2.67171998 5.23659951 2.67171998 2 P 0 ;0,1=282,2=0.000000
L 5.25686654 2.67171998 5.2573997 2.67713622 2 P 0 ;0,1=282,2=0.000000
L 5.2573997 2.67713622 5.2582 2.68171929 2 P 0 ;0,1=282,2=0.000000
L 5.2582 2.68171929 5.25926644 2.68588661 2 P 0 ;0,1=282,2=0.000000
L 5.25926644 2.68588661 5.2606 2.69046978 2 P 0 ;0,1=282,2=0.000000
L 5.2606 2.69046978 5.26273337 2.69671998 2 P 0 ;0,1=282,2=0.000000
L 5.26273337 2.69671998 5.25206654 2.69671998 2 P 0 ;0,1=282,2=0.000000
L 5.20976969 2.72171998 5.20976969 2.74671998 2 P 0 ;0,1=27,2=0.000000
L 5.20976969 2.74671998 5.20656988 2.74172028 2 P 0 ;0,1=27,2=0.000000
L 5.20656988 2.72171998 5.21296949 2.72171998 2 P 0 ;0,1=27,2=0.000000
L 5.23376969 2.72171998 5.23563642 2.72213652 2 P 0 ;0,1=27,2=0.000000
L 5.23563642 2.72213652 5.23776978 2.72338622 2 P 0 ;0,1=27,2=0.000000
L 5.23776978 2.72338622 5.23910335 2.72546909 2 P 0 ;0,1=27,2=0.000000
L 5.23910335 2.72546909 5.23963661 2.72838671 2 P 0 ;0,1=27,2=0.000000
L 5.23963661 2.72838671 5.23910335 2.73130276 2 P 0 ;0,1=27,2=0.000000
L 5.23910335 2.73130276 5.23750325 2.73380295 2 P 0 ;0,1=27,2=0.000000
L 5.23750325 2.73380295 5.23510325 2.73505344 2 P 0 ;0,1=27,2=0.000000
L 5.23510325 2.73505344 5.23243661 2.73505344 2 P 0 ;0,1=27,2=0.000000
L 5.23243661 2.73505344 5.23083652 2.73588661 2 P 0 ;0,1=27,2=0.000000
L 5.23083652 2.73588661 5.22950295 2.73796949 2 P 0 ;0,1=27,2=0.000000
L 5.22950295 2.73796949 5.22896978 2.74088632 2 P 0 ;0,1=27,2=0.000000
L 5.22896978 2.74088632 5.22977008 2.74380315 2 P 0 ;0,1=27,2=0.000000
L 5.22977008 2.74380315 5.23163632 2.74588681 2 P 0 ;0,1=27,2=0.000000
L 5.23163632 2.74588681 5.23376969 2.74671998 2 P 0 ;0,1=27,2=0.000000
L 5.23376969 2.74671998 5.23590305 2.74588681 2 P 0 ;0,1=27,2=0.000000
L 5.23590305 2.74588681 5.23776978 2.74380315 2 P 0 ;0,1=27,2=0.000000
L 5.23776978 2.74380315 5.23857008 2.74088632 2 P 0 ;0,1=27,2=0.000000
L 5.23857008 2.74088632 5.23803642 2.73796949 2 P 0 ;0,1=27,2=0.000000
L 5.23803642 2.73796949 5.23670335 2.73588661 2 P 0 ;0,1=27,2=0.000000
L 5.23670335 2.73588661 5.23510325 2.73505344 2 P 0 ;0,1=27,2=0.000000
L 5.23510325 2.73505344 5.23243661 2.73505344 2 P 0 ;0,1=27,2=0.000000
L 5.23243661 2.73505344 5.23003661 2.73380295 2 P 0 ;0,1=27,2=0.000000
L 5.23003661 2.73380295 5.22843652 2.73130276 2 P 0 ;0,1=27,2=0.000000
L 5.22843652 2.73130276 5.22790325 2.72838671 2 P 0 ;0,1=27,2=0.000000
L 5.22790325 2.72838671 5.22843652 2.72546909 2 P 0 ;0,1=27,2=0.000000
L 5.22843652 2.72546909 5.22977008 2.72338622 2 P 0 ;0,1=27,2=0.000000
L 5.22977008 2.72338622 5.23190344 2.72213652 2 P 0 ;0,1=27,2=0.000000
L 5.23190344 2.72213652 5.23376969 2.72171998 2 P 0 ;0,1=27,2=0.000000
L 5.2333997 2.77171998 5.2333997 2.79671998 2 P 0 ;0,1=283,2=0.000000
L 5.2333997 2.79671998 5.2301999 2.79172028 2 P 0 ;0,1=283,2=0.000000
L 5.2301999 2.77171998 5.23659951 2.77171998 2 P 0 ;0,1=283,2=0.000000
L 5.25286634 2.77463602 5.25473317 2.77255305 2 P 0 ;0,1=283,2=0.000000
L 5.25473317 2.77255305 5.25686654 2.77171998 2 P 0 ;0,1=283,2=0.000000
L 5.25686654 2.77171998 5.2589999 2.77255305 2 P 0 ;0,1=283,2=0.000000
L 5.2589999 2.77255305 5.26086663 2.77505256 2 P 0 ;0,1=283,2=0.000000
L 5.26086663 2.77505256 5.2622001 2.77880325 2 P 0 ;0,1=283,2=0.000000
L 5.2622001 2.77880325 5.26273337 2.78255325 2 P 0 ;0,1=283,2=0.000000
L 5.26273337 2.78255325 5.26273337 2.78713632 2 P 0 ;0,1=283,2=0.000000
L 5.26273337 2.78713632 5.2622001 2.79088632 2 P 0 ;0,1=283,2=0.000000
L 5.2622001 2.79088632 5.26086663 2.79421969 2 P 0 ;0,1=283,2=0.000000
L 5.26086663 2.79421969 5.25926644 2.79588681 2 P 0 ;0,1=283,2=0.000000
L 5.25926644 2.79588681 5.2573997 2.79671998 2 P 0 ;0,1=283,2=0.000000
L 5.2573997 2.79671998 5.25526634 2.79588681 2 P 0 ;0,1=283,2=0.000000
L 5.25526634 2.79588681 5.25366663 2.79421969 2 P 0 ;0,1=283,2=0.000000
L 5.25366663 2.79421969 5.2525998 2.79172028 2 P 0 ;0,1=283,2=0.000000
L 5.2525998 2.79172028 5.25206654 2.78838612 2 P 0 ;0,1=283,2=0.000000
L 5.25206654 2.78838612 5.2525998 2.78547008 2 P 0 ;0,1=283,2=0.000000
L 5.2525998 2.78547008 5.25393327 2.78255325 2 P 0 ;0,1=283,2=0.000000
L 5.25393327 2.78255325 5.25553346 2.78088612 2 P 0 ;0,1=283,2=0.000000
L 5.25553346 2.78088612 5.2573997 2.78046959 2 P 0 ;0,1=283,2=0.000000
L 5.2573997 2.78046959 5.25953307 2.78130276 2 P 0 ;0,1=283,2=0.000000
L 5.25953307 2.78130276 5.26113327 2.78338642 2 P 0 ;0,1=283,2=0.000000
L 5.26113327 2.78338642 5.26273337 2.78713632 2 P 0 ;0,1=283,2=0.000000
L 5.20470315 2.84255335 5.20630325 2.84505285 2 P 0 ;0,1=284,2=0.000000
L 5.20630325 2.84505285 5.20816998 2.84630335 2 P 0 ;0,1=284,2=0.000000
L 5.20816998 2.84630335 5.21030335 2.84671998 2 P 0 ;0,1=284,2=0.000000
L 5.21030335 2.84671998 5.21296998 2.84588681 2 P 0 ;0,1=284,2=0.000000
L 5.21296998 2.84588681 5.21483671 2.84380315 2 P 0 ;0,1=284,2=0.000000
L 5.21483671 2.84380315 5.21536998 2.84130364 2 P 0 ;0,1=284,2=0.000000
L 5.21536998 2.84130364 5.21510335 2.83880266 2 P 0 ;0,1=284,2=0.000000
L 5.21510335 2.83880266 5.21403642 2.83671978 2 P 0 ;0,1=284,2=0.000000
L 5.21403642 2.83671978 5.20870325 2.83255325 2 P 0 ;0,1=284,2=0.000000
L 5.20870325 2.83255325 5.20630325 2.82963642 2 P 0 ;0,1=284,2=0.000000
L 5.20630325 2.82963642 5.20470315 2.82546909 2 P 0 ;0,1=284,2=0.000000
L 5.20470315 2.82546909 5.20416988 2.82171998 2 P 0 ;0,1=284,2=0.000000
L 5.20416988 2.82171998 5.21536998 2.82171998 2 P 0 ;0,1=284,2=0.000000
L 5.23376969 2.84671998 5.23163632 2.84588681 2 P 0 ;0,1=284,2=0.000000
L 5.23163632 2.84588681 5.23003661 2.84380315 2 P 0 ;0,1=284,2=0.000000
L 5.23003661 2.84380315 5.22896978 2.84130364 2 P 0 ;0,1=284,2=0.000000
L 5.22896978 2.84130364 5.22816988 2.83796949 2 P 0 ;0,1=284,2=0.000000
L 5.22816988 2.83796949 5.22790325 2.83421959 2 P 0 ;0,1=284,2=0.000000
L 5.22790325 2.83421959 5.22816988 2.83046959 2 P 0 ;0,1=284,2=0.000000
L 5.22816988 2.83046959 5.22896978 2.82713622 2 P 0 ;0,1=284,2=0.000000
L 5.22896978 2.82713622 5.23003661 2.82463602 2 P 0 ;0,1=284,2=0.000000
L 5.23003661 2.82463602 5.23163632 2.82255305 2 P 0 ;0,1=284,2=0.000000
L 5.23163632 2.82255305 5.23376969 2.82171998 2 P 0 ;0,1=284,2=0.000000
L 5.23376969 2.82171998 5.23590305 2.82255305 2 P 0 ;0,1=284,2=0.000000
L 5.23590305 2.82255305 5.23750325 2.82463602 2 P 0 ;0,1=284,2=0.000000
L 5.23750325 2.82463602 5.23857008 2.82713622 2 P 0 ;0,1=284,2=0.000000
L 5.23857008 2.82713622 5.23936998 2.83046959 2 P 0 ;0,1=284,2=0.000000
L 5.23936998 2.83046959 5.23963661 2.83421959 2 P 0 ;0,1=284,2=0.000000
L 5.23963661 2.83421959 5.23936998 2.83796949 2 P 0 ;0,1=284,2=0.000000
L 5.23936998 2.83796949 5.23857008 2.84130364 2 P 0 ;0,1=284,2=0.000000
L 5.23857008 2.84130364 5.23750325 2.84380315 2 P 0 ;0,1=284,2=0.000000
L 5.23750325 2.84380315 5.23590305 2.84588681 2 P 0 ;0,1=284,2=0.000000
L 5.23590305 2.84588681 5.23376969 2.84671998 2 P 0 ;0,1=284,2=0.000000
L 4.62053996 1.71381299 4.59553996 1.72047972 2 P 0 ;0,1=48,2=270.000000
L 4.59553996 1.72047972 4.62053996 1.72714695 2 P 0 ;0,1=48,2=270.000000
L 4.61179035 1.72474646 4.61179035 1.71621299 2 P 0 ;0,1=48,2=270.000000
L 4.6572065 1.72261309 4.65595669 1.72368002 2 P 0 ;0,1=285,2=270.000000
L 4.65595669 1.72368002 4.65387382 1.72447982 2 P 0 ;0,1=285,2=270.000000
L 4.65387382 1.72447982 4.6509563 1.72501358 2 P 0 ;0,1=285,2=270.000000
L 4.6509563 1.72501358 4.64845679 1.72447982 2 P 0 ;0,1=285,2=270.000000
L 4.64845679 1.72447982 4.64679055 1.72341339 2 P 0 ;0,1=285,2=270.000000
L 4.64679055 1.72341339 4.64553996 1.72154665 2 P 0 ;0,1=285,2=270.000000
L 4.64553996 1.72154665 4.64553996 1.71434675 2 P 0 ;0,1=285,2=270.000000
L 4.64553996 1.71434675 4.67053996 1.71434675 2 P 0 ;0,1=285,2=270.000000
L 4.67053996 1.71434675 4.67053996 1.72314675 2 P 0 ;0,1=285,2=270.000000
L 4.67053996 1.72314675 4.66887372 1.72501358 2 P 0 ;0,1=285,2=270.000000
L 4.66887372 1.72501358 4.66637343 1.72608002 2 P 0 ;0,1=285,2=270.000000
L 4.66637343 1.72608002 4.66345669 1.72661319 2 P 0 ;0,1=285,2=270.000000
L 4.66345669 1.72661319 4.66054065 1.72608002 2 P 0 ;0,1=285,2=270.000000
L 4.66054065 1.72608002 4.65804035 1.72447982 2 P 0 ;0,1=285,2=270.000000
L 4.65804035 1.72447982 4.6572065 1.72261309 2 P 0 ;0,1=285,2=270.000000
L 4.6572065 1.72261309 4.6572065 1.71434675 2 P 0 ;0,1=285,2=270.000000
L 4.69762362 1.72634665 4.69637313 1.72474646 2 P 0 ;0,1=49,2=270.000000
L 4.69637313 1.72474646 4.69553996 1.72288022 2 P 0 ;0,1=49,2=270.000000
L 4.69553996 1.72288022 4.69553996 1.72074685 2 P 0 ;0,1=49,2=270.000000
L 4.69553996 1.72074685 4.69679055 1.71834636 2 P 0 ;0,1=49,2=270.000000
L 4.69679055 1.71834636 4.69887343 1.71648012 2 P 0 ;0,1=49,2=270.000000
L 4.69887343 1.71648012 4.70137362 1.71514656 2 P 0 ;0,1=49,2=270.000000
L 4.70137362 1.71514656 4.70554016 1.71407963 2 P 0 ;0,1=49,2=270.000000
L 4.70554016 1.71407963 4.70929016 1.71381299 2 P 0 ;0,1=49,2=270.000000
L 4.70929016 1.71381299 4.71304006 1.71434675 2 P 0 ;0,1=49,2=270.000000
L 4.71304006 1.71434675 4.71554035 1.71514656 2 P 0 ;0,1=49,2=270.000000
L 4.71554035 1.71514656 4.71804055 1.71674665 2 P 0 ;0,1=49,2=270.000000
L 4.71804055 1.71674665 4.71970689 1.71861348 2 P 0 ;0,1=49,2=270.000000
L 4.71970689 1.71861348 4.72053996 1.72047972 2 P 0 ;0,1=49,2=270.000000
L 4.72053996 1.72047972 4.72053996 1.72234646 2 P 0 ;0,1=49,2=270.000000
L 4.72053996 1.72234646 4.71970689 1.72421329 2 P 0 ;0,1=49,2=270.000000
L 4.71970689 1.72421329 4.71845709 1.72581339 2 P 0 ;0,1=49,2=270.000000
L 4.71845709 1.72581339 4.71679085 1.72714695 2 P 0 ;0,1=49,2=270.000000
L 4.77053996 1.72461329 4.74553996 1.72461329 2 P 0 ;0,1=255,2=270.000000
L 4.74553996 1.72461329 4.74553996 1.72994656 2 P 0 ;0,1=255,2=270.000000
L 4.74553996 1.72994656 4.74679055 1.73207992 2 P 0 ;0,1=255,2=270.000000
L 4.74679055 1.73207992 4.74845679 1.73368002 2 P 0 ;0,1=255,2=270.000000
L 4.74845679 1.73368002 4.7509563 1.73501358 2 P 0 ;0,1=255,2=270.000000
L 4.7509563 1.73501358 4.75387382 1.73608002 2 P 0 ;0,1=255,2=270.000000
L 4.75387382 1.73608002 4.75804035 1.73634665 2 P 0 ;0,1=255,2=270.000000
L 4.75804035 1.73634665 4.76220689 1.73608002 2 P 0 ;0,1=255,2=270.000000
L 4.76220689 1.73608002 4.76512372 1.73501358 2 P 0 ;0,1=255,2=270.000000
L 4.76512372 1.73501358 4.76762392 1.73368002 2 P 0 ;0,1=255,2=270.000000
L 4.76762392 1.73368002 4.76929026 1.73207992 2 P 0 ;0,1=255,2=270.000000
L 4.76929026 1.73207992 4.77053996 1.72994656 2 P 0 ;0,1=255,2=270.000000
L 4.77053996 1.72994656 4.77053996 1.72461329 2 P 0 ;0,1=255,2=270.000000
L 4.82053996 1.73581339 4.82053996 1.72514656 2 P 0 ;0,1=286,2=270.000000
L 4.82053996 1.72514656 4.79553996 1.72514656 2 P 0 ;0,1=286,2=270.000000
L 4.79553996 1.72514656 4.79553996 1.73581339 2 P 0 ;0,1=286,2=270.000000
L 4.80762303 1.73154665 4.80762303 1.72514656 2 P 0 ;0,1=286,2=270.000000
L 4.87053996 1.72541319 4.84553996 1.72541319 2 P 0 ;0,1=287,2=270.000000
L 4.84553996 1.72541319 4.84553996 1.73554675 2 P 0 ;0,1=287,2=270.000000
L 4.85762303 1.73181329 4.85762303 1.72541319 2 P 0 ;0,1=287,2=270.000000
L 4.90804035 1.72207992 4.90804035 1.72741348 2 P 0 ;0,1=256,2=270.000000
L 4.90804035 1.72741348 4.91554035 1.72741348 2 P 0 ;0,1=256,2=270.000000
L 4.91554035 1.72741348 4.91804055 1.72581339 2 P 0 ;0,1=256,2=270.000000
L 4.91804055 1.72581339 4.91970689 1.72394665 2 P 0 ;0,1=256,2=270.000000
L 4.91970689 1.72394665 4.92053996 1.72128002 2 P 0 ;0,1=256,2=270.000000
L 4.92053996 1.72128002 4.91970689 1.71861348 2 P 0 ;0,1=256,2=270.000000
L 4.91970689 1.71861348 4.91804055 1.71674665 2 P 0 ;0,1=256,2=270.000000
L 4.91804055 1.71674665 4.91554035 1.71514656 2 P 0 ;0,1=256,2=270.000000
L 4.91554035 1.71514656 4.91262352 1.71407963 2 P 0 ;0,1=256,2=270.000000
L 4.91262352 1.71407963 4.90929016 1.71354646 2 P 0 ;0,1=256,2=270.000000
L 4.90929016 1.71354646 4.90637333 1.71354646 2 P 0 ;0,1=256,2=270.000000
L 4.90637333 1.71354646 4.90387382 1.71407963 2 P 0 ;0,1=256,2=270.000000
L 4.90387382 1.71407963 4.9009563 1.71514656 2 P 0 ;0,1=256,2=270.000000
L 4.9009563 1.71514656 4.89845679 1.71674665 2 P 0 ;0,1=256,2=270.000000
L 4.89845679 1.71674665 4.89679055 1.71834636 2 P 0 ;0,1=256,2=270.000000
L 4.89679055 1.71834636 4.89553996 1.72047972 2 P 0 ;0,1=256,2=270.000000
L 4.89553996 1.72047972 4.89553996 1.72234646 2 P 0 ;0,1=256,2=270.000000
L 4.89553996 1.72234646 4.89637313 1.72447982 2 P 0 ;0,1=256,2=270.000000
L 4.89637313 1.72447982 4.89804026 1.72608002 2 P 0 ;0,1=256,2=270.000000
L 4.97053996 1.71487992 4.94553996 1.71487992 2 P 0 ;0,1=288,2=270.000000
L 4.94553996 1.72608002 4.97053996 1.72608002 2 P 0 ;0,1=288,2=270.000000
L 4.95804035 1.72608002 4.95804035 1.71487992 2 P 0 ;0,1=288,2=270.000000
L 5.01554035 1.71514656 5.01804055 1.71648012 2 P 0 ;0,1=289,2=270.000000
L 5.01804055 1.71648012 5.01970689 1.71807972 2 P 0 ;0,1=289,2=270.000000
L 5.01970689 1.71807972 5.02053996 1.71994656 2 P 0 ;0,1=289,2=270.000000
L 5.02053996 1.71994656 5.01970689 1.72207992 2 P 0 ;0,1=289,2=270.000000
L 5.01970689 1.72207992 5.01804055 1.72368002 2 P 0 ;0,1=289,2=270.000000
L 5.01804055 1.72368002 5.01554035 1.72528012 2 P 0 ;0,1=289,2=270.000000
L 5.01554035 1.72528012 5.01220689 1.72581339 2 P 0 ;0,1=289,2=270.000000
L 5.01220689 1.72581339 4.99553996 1.72581339 2 P 0 ;0,1=289,2=270.000000
L 5.07053996 1.71461329 5.04553996 1.71461329 2 P 0 ;0,1=290,2=270.000000
L 5.04553996 1.72474646 5.06095719 1.71461329 2 P 0 ;0,1=290,2=270.000000
L 5.07053996 1.72634665 5.05387382 1.71914665 2 P 0 ;0,1=290,2=270.000000
L 5.22833317 2.89255335 5.22993327 2.89505285 2 P 0 ;0,1=270,2=0.000000
L 5.22993327 2.89505285 5.2318 2.89630335 2 P 0 ;0,1=270,2=0.000000
L 5.2318 2.89630335 5.23393337 2.89671998 2 P 0 ;0,1=270,2=0.000000
L 5.23393337 2.89671998 5.2366 2.89588681 2 P 0 ;0,1=270,2=0.000000
L 5.2366 2.89588681 5.23846673 2.89380315 2 P 0 ;0,1=270,2=0.000000
L 5.23846673 2.89380315 5.239 2.89130364 2 P 0 ;0,1=270,2=0.000000
L 5.239 2.89130364 5.23873337 2.88880266 2 P 0 ;0,1=270,2=0.000000
L 5.23873337 2.88880266 5.23766644 2.88671978 2 P 0 ;0,1=270,2=0.000000
L 5.23766644 2.88671978 5.23233327 2.88255325 2 P 0 ;0,1=270,2=0.000000
L 5.23233327 2.88255325 5.22993327 2.87963642 2 P 0 ;0,1=270,2=0.000000
L 5.22993327 2.87963642 5.22833317 2.87546909 2 P 0 ;0,1=270,2=0.000000
L 5.22833317 2.87546909 5.2277999 2.87171998 2 P 0 ;0,1=270,2=0.000000
L 5.2277999 2.87171998 5.239 2.87171998 2 P 0 ;0,1=270,2=0.000000
L 5.2573997 2.87171998 5.2573997 2.89671998 2 P 0 ;0,1=270,2=0.000000
L 5.2573997 2.89671998 5.2541999 2.89172028 2 P 0 ;0,1=270,2=0.000000
L 5.2541999 2.87171998 5.26059951 2.87171998 2 P 0 ;0,1=270,2=0.000000
L 5.20470315 2.94255335 5.20630325 2.94505285 2 P 0 ;0,1=271,2=0.000000
L 5.20630325 2.94505285 5.20816998 2.94630335 2 P 0 ;0,1=271,2=0.000000
L 5.20816998 2.94630335 5.21030335 2.94671998 2 P 0 ;0,1=271,2=0.000000
L 5.21030335 2.94671998 5.21296998 2.94588681 2 P 0 ;0,1=271,2=0.000000
L 5.21296998 2.94588681 5.21483671 2.94380315 2 P 0 ;0,1=271,2=0.000000
L 5.21483671 2.94380315 5.21536998 2.94130364 2 P 0 ;0,1=271,2=0.000000
L 5.21536998 2.94130364 5.21510335 2.93880266 2 P 0 ;0,1=271,2=0.000000
L 5.21510335 2.93880266 5.21403642 2.93671978 2 P 0 ;0,1=271,2=0.000000
L 5.21403642 2.93671978 5.20870325 2.93255325 2 P 0 ;0,1=271,2=0.000000
L 5.20870325 2.93255325 5.20630325 2.92963642 2 P 0 ;0,1=271,2=0.000000
L 5.20630325 2.92963642 5.20470315 2.92546909 2 P 0 ;0,1=271,2=0.000000
L 5.20470315 2.92546909 5.20416988 2.92171998 2 P 0 ;0,1=271,2=0.000000
L 5.20416988 2.92171998 5.21536998 2.92171998 2 P 0 ;0,1=271,2=0.000000
L 5.22870315 2.94255335 5.23030325 2.94505285 2 P 0 ;0,1=271,2=0.000000
L 5.23030325 2.94505285 5.23216998 2.94630335 2 P 0 ;0,1=271,2=0.000000
L 5.23216998 2.94630335 5.23430335 2.94671998 2 P 0 ;0,1=271,2=0.000000
L 5.23430335 2.94671998 5.23696998 2.94588681 2 P 0 ;0,1=271,2=0.000000
L 5.23696998 2.94588681 5.23883671 2.94380315 2 P 0 ;0,1=271,2=0.000000
L 5.23883671 2.94380315 5.23936998 2.94130364 2 P 0 ;0,1=271,2=0.000000
L 5.23936998 2.94130364 5.23910335 2.93880266 2 P 0 ;0,1=271,2=0.000000
L 5.23910335 2.93880266 5.23803642 2.93671978 2 P 0 ;0,1=271,2=0.000000
L 5.23803642 2.93671978 5.23270325 2.93255325 2 P 0 ;0,1=271,2=0.000000
L 5.23270325 2.93255325 5.23030325 2.92963642 2 P 0 ;0,1=271,2=0.000000
L 5.23030325 2.92963642 5.22870315 2.92546909 2 P 0 ;0,1=271,2=0.000000
L 5.22870315 2.92546909 5.22816988 2.92171998 2 P 0 ;0,1=271,2=0.000000
L 5.22816988 2.92171998 5.23936998 2.92171998 2 P 0 ;0,1=271,2=0.000000
L 5.22833317 2.99255335 5.22993327 2.99505285 2 P 0 ;0,1=64,2=0.000000
L 5.22993327 2.99505285 5.2318 2.99630335 2 P 0 ;0,1=64,2=0.000000
L 5.2318 2.99630335 5.23393337 2.99671998 2 P 0 ;0,1=64,2=0.000000
L 5.23393337 2.99671998 5.2366 2.99588681 2 P 0 ;0,1=64,2=0.000000
L 5.2366 2.99588681 5.23846673 2.99380315 2 P 0 ;0,1=64,2=0.000000
L 5.23846673 2.99380315 5.239 2.99130364 2 P 0 ;0,1=64,2=0.000000
L 5.239 2.99130364 5.23873337 2.98880266 2 P 0 ;0,1=64,2=0.000000
L 5.23873337 2.98880266 5.23766644 2.98671978 2 P 0 ;0,1=64,2=0.000000
L 5.23766644 2.98671978 5.23233327 2.98255325 2 P 0 ;0,1=64,2=0.000000
L 5.23233327 2.98255325 5.22993327 2.97963642 2 P 0 ;0,1=64,2=0.000000
L 5.22993327 2.97963642 5.22833317 2.97546909 2 P 0 ;0,1=64,2=0.000000
L 5.22833317 2.97546909 5.2277999 2.97171998 2 P 0 ;0,1=64,2=0.000000
L 5.2277999 2.97171998 5.239 2.97171998 2 P 0 ;0,1=64,2=0.000000
L 5.25153327 2.97671959 5.25313297 2.97380285 2 P 0 ;0,1=64,2=0.000000
L 5.25313297 2.97380285 5.25526634 2.97213652 2 P 0 ;0,1=64,2=0.000000
L 5.25526634 2.97213652 5.25766683 2.97171998 2 P 0 ;0,1=64,2=0.000000
L 5.25766683 2.97171998 5.2598002 2.97213652 2 P 0 ;0,1=64,2=0.000000
L 5.2598002 2.97213652 5.26193356 2.97421939 2 P 0 ;0,1=64,2=0.000000
L 5.26193356 2.97421939 5.26326663 2.97671959 2 P 0 ;0,1=64,2=0.000000
L 5.26326663 2.97671959 5.26353317 2.97921988 2 P 0 ;0,1=64,2=0.000000
L 5.26353317 2.97921988 5.263 2.98213593 2 P 0 ;0,1=64,2=0.000000
L 5.263 2.98213593 5.26113327 2.98421959 2 P 0 ;0,1=64,2=0.000000
L 5.26113327 2.98421959 5.25926644 2.98505344 2 P 0 ;0,1=64,2=0.000000
L 5.25926644 2.98505344 5.25686654 2.98505344 2 P 0 ;0,1=64,2=0.000000
L 5.25926644 2.98505344 5.26086663 2.98630325 2 P 0 ;0,1=64,2=0.000000
L 5.26086663 2.98630325 5.2622001 2.98838612 2 P 0 ;0,1=64,2=0.000000
L 5.2622001 2.98838612 5.26273337 2.99088632 2 P 0 ;0,1=64,2=0.000000
L 5.26273337 2.99088632 5.2622001 2.99338652 2 P 0 ;0,1=64,2=0.000000
L 5.2622001 2.99338652 5.26086663 2.99546939 2 P 0 ;0,1=64,2=0.000000
L 5.26086663 2.99546939 5.25846663 2.99671998 2 P 0 ;0,1=64,2=0.000000
L 5.25846663 2.99671998 5.25606663 2.99630335 2 P 0 ;0,1=64,2=0.000000
L 5.25606663 2.99630335 5.25366663 2.99463632 2 P 0 ;0,1=64,2=0.000000
L 5.20470315 3.04255335 5.20630325 3.04505285 2 P 0 ;0,1=65,2=0.000000
L 5.20630325 3.04505285 5.20816998 3.04630335 2 P 0 ;0,1=65,2=0.000000
L 5.20816998 3.04630335 5.21030335 3.04671998 2 P 0 ;0,1=65,2=0.000000
L 5.21030335 3.04671998 5.21296998 3.04588681 2 P 0 ;0,1=65,2=0.000000
L 5.21296998 3.04588681 5.21483671 3.04380315 2 P 0 ;0,1=65,2=0.000000
L 5.21483671 3.04380315 5.21536998 3.04130364 2 P 0 ;0,1=65,2=0.000000
L 5.21536998 3.04130364 5.21510335 3.03880266 2 P 0 ;0,1=65,2=0.000000
L 5.21510335 3.03880266 5.21403642 3.03671978 2 P 0 ;0,1=65,2=0.000000
L 5.21403642 3.03671978 5.20870325 3.03255325 2 P 0 ;0,1=65,2=0.000000
L 5.20870325 3.03255325 5.20630325 3.02963642 2 P 0 ;0,1=65,2=0.000000
L 5.20630325 3.02963642 5.20470315 3.02546909 2 P 0 ;0,1=65,2=0.000000
L 5.20470315 3.02546909 5.20416988 3.02171998 2 P 0 ;0,1=65,2=0.000000
L 5.20416988 3.02171998 5.21536998 3.02171998 2 P 0 ;0,1=65,2=0.000000
L 5.23696998 3.02171998 5.23696998 3.04671998 2 P 0 ;0,1=65,2=0.000000
L 5.23696998 3.04671998 5.22710295 3.02880325 2 P 0 ;0,1=65,2=0.000000
L 5.22710295 3.02880325 5.24043691 3.02880325 2 P 0 ;0,1=65,2=0.000000
L 5.22833317 3.09255335 5.22993327 3.09505285 2 P 0 ;0,1=291,2=0.000000
L 5.22993327 3.09505285 5.2318 3.09630335 2 P 0 ;0,1=291,2=0.000000
L 5.2318 3.09630335 5.23393337 3.09671998 2 P 0 ;0,1=291,2=0.000000
L 5.23393337 3.09671998 5.2366 3.09588681 2 P 0 ;0,1=291,2=0.000000
L 5.2366 3.09588681 5.23846673 3.09380315 2 P 0 ;0,1=291,2=0.000000
L 5.23846673 3.09380315 5.239 3.09130364 2 P 0 ;0,1=291,2=0.000000
L 5.239 3.09130364 5.23873337 3.08880266 2 P 0 ;0,1=291,2=0.000000
L 5.23873337 3.08880266 5.23766644 3.08671978 2 P 0 ;0,1=291,2=0.000000
L 5.23766644 3.08671978 5.23233327 3.08255325 2 P 0 ;0,1=291,2=0.000000
L 5.23233327 3.08255325 5.22993327 3.07963642 2 P 0 ;0,1=291,2=0.000000
L 5.22993327 3.07963642 5.22833317 3.07546909 2 P 0 ;0,1=291,2=0.000000
L 5.22833317 3.07546909 5.2277999 3.07171998 2 P 0 ;0,1=291,2=0.000000
L 5.2277999 3.07171998 5.239 3.07171998 2 P 0 ;0,1=291,2=0.000000
L 5.25153327 3.07546909 5.25313297 3.07338622 2 P 0 ;0,1=291,2=0.000000
L 5.25313297 3.07338622 5.2549997 3.07213652 2 P 0 ;0,1=291,2=0.000000
L 5.2549997 3.07213652 5.2573997 3.07171998 2 P 0 ;0,1=291,2=0.000000
L 5.2573997 3.07171998 5.2598002 3.07255305 2 P 0 ;0,1=291,2=0.000000
L 5.2598002 3.07255305 5.26166644 3.07421939 2 P 0 ;0,1=291,2=0.000000
L 5.26166644 3.07421939 5.263 3.07713622 2 P 0 ;0,1=291,2=0.000000
L 5.263 3.07713622 5.26326663 3.08046959 2 P 0 ;0,1=291,2=0.000000
L 5.26326663 3.08046959 5.26273337 3.08380295 2 P 0 ;0,1=291,2=0.000000
L 5.26273337 3.08380295 5.2613998 3.08588661 2 P 0 ;0,1=291,2=0.000000
L 5.2613998 3.08588661 5.25953307 3.08755295 2 P 0 ;0,1=291,2=0.000000
L 5.25953307 3.08755295 5.25766683 3.08796949 2 P 0 ;0,1=291,2=0.000000
L 5.25766683 3.08796949 5.2558 3.08755295 2 P 0 ;0,1=291,2=0.000000
L 5.2558 3.08755295 5.2534001 3.08588661 2 P 0 ;0,1=291,2=0.000000
L 5.2534001 3.08588661 5.2541999 3.09671998 2 P 0 ;0,1=291,2=0.000000
L 5.2541999 3.09671998 5.2613998 3.09671998 2 P 0 ;0,1=291,2=0.000000
L 5.20470315 3.14255335 5.20630325 3.14505285 2 P 0 ;0,1=292,2=0.000000
L 5.20630325 3.14505285 5.20816998 3.14630335 2 P 0 ;0,1=292,2=0.000000
L 5.20816998 3.14630335 5.21030335 3.14671998 2 P 0 ;0,1=292,2=0.000000
L 5.21030335 3.14671998 5.21296998 3.14588681 2 P 0 ;0,1=292,2=0.000000
L 5.21296998 3.14588681 5.21483671 3.14380315 2 P 0 ;0,1=292,2=0.000000
L 5.21483671 3.14380315 5.21536998 3.14130364 2 P 0 ;0,1=292,2=0.000000
L 5.21536998 3.14130364 5.21510335 3.13880266 2 P 0 ;0,1=292,2=0.000000
L 5.21510335 3.13880266 5.21403642 3.13671978 2 P 0 ;0,1=292,2=0.000000
L 5.21403642 3.13671978 5.20870325 3.13255325 2 P 0 ;0,1=292,2=0.000000
L 5.20870325 3.13255325 5.20630325 3.12963642 2 P 0 ;0,1=292,2=0.000000
L 5.20630325 3.12963642 5.20470315 3.12546909 2 P 0 ;0,1=292,2=0.000000
L 5.20470315 3.12546909 5.20416988 3.12171998 2 P 0 ;0,1=292,2=0.000000
L 5.20416988 3.12171998 5.21536998 3.12171998 2 P 0 ;0,1=292,2=0.000000
L 5.22870315 3.13213593 5.23056988 3.13505344 2 P 0 ;0,1=292,2=0.000000
L 5.23056988 3.13505344 5.23216998 3.13671978 2 P 0 ;0,1=292,2=0.000000
L 5.23216998 3.13671978 5.23430335 3.13755295 2 P 0 ;0,1=292,2=0.000000
L 5.23430335 3.13755295 5.23617018 3.13671978 2 P 0 ;0,1=292,2=0.000000
L 5.23617018 3.13671978 5.23750325 3.13505344 2 P 0 ;0,1=292,2=0.000000
L 5.23750325 3.13505344 5.23857008 3.13255325 2 P 0 ;0,1=292,2=0.000000
L 5.23857008 3.13255325 5.23883671 3.12963642 2 P 0 ;0,1=292,2=0.000000
L 5.23883671 3.12963642 5.23857008 3.12713622 2 P 0 ;0,1=292,2=0.000000
L 5.23857008 3.12713622 5.23750325 3.12463602 2 P 0 ;0,1=292,2=0.000000
L 5.23750325 3.12463602 5.23590305 3.12255305 2 P 0 ;0,1=292,2=0.000000
L 5.23590305 3.12255305 5.23403681 3.12171998 2 P 0 ;0,1=292,2=0.000000
L 5.23403681 3.12171998 5.23190344 3.12255305 2 P 0 ;0,1=292,2=0.000000
L 5.23190344 3.12255305 5.23003661 3.12505256 2 P 0 ;0,1=292,2=0.000000
L 5.23003661 3.12505256 5.22896978 3.12880325 2 P 0 ;0,1=292,2=0.000000
L 5.22896978 3.12880325 5.22870315 3.13296978 2 P 0 ;0,1=292,2=0.000000
L 5.22870315 3.13296978 5.22923632 3.13838612 2 P 0 ;0,1=292,2=0.000000
L 5.22923632 3.13838612 5.23003661 3.14130364 2 P 0 ;0,1=292,2=0.000000
L 5.23003661 3.14130364 5.23136969 3.14421969 2 P 0 ;0,1=292,2=0.000000
L 5.23136969 3.14421969 5.23323652 3.14630335 2 P 0 ;0,1=292,2=0.000000
L 5.23323652 3.14630335 5.23510325 3.14671998 2 P 0 ;0,1=292,2=0.000000
L 5.23510325 3.14671998 5.23696998 3.14588681 2 P 0 ;0,1=292,2=0.000000
L 5.23696998 3.14588681 5.23830354 3.14380315 2 P 0 ;0,1=292,2=0.000000
L 5.22833317 3.19255335 5.22993327 3.19505285 2 P 0 ;0,1=293,2=0.000000
L 5.22993327 3.19505285 5.2318 3.19630335 2 P 0 ;0,1=293,2=0.000000
L 5.2318 3.19630335 5.23393337 3.19671998 2 P 0 ;0,1=293,2=0.000000
L 5.23393337 3.19671998 5.2366 3.19588681 2 P 0 ;0,1=293,2=0.000000
L 5.2366 3.19588681 5.23846673 3.19380315 2 P 0 ;0,1=293,2=0.000000
L 5.23846673 3.19380315 5.239 3.19130364 2 P 0 ;0,1=293,2=0.000000
L 5.239 3.19130364 5.23873337 3.18880266 2 P 0 ;0,1=293,2=0.000000
L 5.23873337 3.18880266 5.23766644 3.18671978 2 P 0 ;0,1=293,2=0.000000
L 5.23766644 3.18671978 5.23233327 3.18255325 2 P 0 ;0,1=293,2=0.000000
L 5.23233327 3.18255325 5.22993327 3.17963642 2 P 0 ;0,1=293,2=0.000000
L 5.22993327 3.17963642 5.22833317 3.17546909 2 P 0 ;0,1=293,2=0.000000
L 5.22833317 3.17546909 5.2277999 3.17171998 2 P 0 ;0,1=293,2=0.000000
L 5.2277999 3.17171998 5.239 3.17171998 2 P 0 ;0,1=293,2=0.000000
L 5.25686654 3.17171998 5.2573997 3.17713622 2 P 0 ;0,1=293,2=0.000000
L 5.2573997 3.17713622 5.2582 3.18171929 2 P 0 ;0,1=293,2=0.000000
L 5.2582 3.18171929 5.25926644 3.18588661 2 P 0 ;0,1=293,2=0.000000
L 5.25926644 3.18588661 5.2606 3.19046978 2 P 0 ;0,1=293,2=0.000000
L 5.2606 3.19046978 5.26273337 3.19671998 2 P 0 ;0,1=293,2=0.000000
L 5.26273337 3.19671998 5.25206654 3.19671998 2 P 0 ;0,1=293,2=0.000000
L 5.20470315 3.24255335 5.20630325 3.24505285 2 P 0 ;0,1=66,2=0.000000
L 5.20630325 3.24505285 5.20816998 3.24630335 2 P 0 ;0,1=66,2=0.000000
L 5.20816998 3.24630335 5.21030335 3.24671998 2 P 0 ;0,1=66,2=0.000000
L 5.21030335 3.24671998 5.21296998 3.24588681 2 P 0 ;0,1=66,2=0.000000
L 5.21296998 3.24588681 5.21483671 3.24380315 2 P 0 ;0,1=66,2=0.000000
L 5.21483671 3.24380315 5.21536998 3.24130364 2 P 0 ;0,1=66,2=0.000000
L 5.21536998 3.24130364 5.21510335 3.23880266 2 P 0 ;0,1=66,2=0.000000
L 5.21510335 3.23880266 5.21403642 3.23671978 2 P 0 ;0,1=66,2=0.000000
L 5.21403642 3.23671978 5.20870325 3.23255325 2 P 0 ;0,1=66,2=0.000000
L 5.20870325 3.23255325 5.20630325 3.22963642 2 P 0 ;0,1=66,2=0.000000
L 5.20630325 3.22963642 5.20470315 3.22546909 2 P 0 ;0,1=66,2=0.000000
L 5.20470315 3.22546909 5.20416988 3.22171998 2 P 0 ;0,1=66,2=0.000000
L 5.20416988 3.22171998 5.21536998 3.22171998 2 P 0 ;0,1=66,2=0.000000
L 5.23376969 3.22171998 5.23563642 3.22213652 2 P 0 ;0,1=66,2=0.000000
L 5.23563642 3.22213652 5.23776978 3.22338622 2 P 0 ;0,1=66,2=0.000000
L 5.23776978 3.22338622 5.23910335 3.22546909 2 P 0 ;0,1=66,2=0.000000
L 5.23910335 3.22546909 5.23963661 3.22838671 2 P 0 ;0,1=66,2=0.000000
L 5.23963661 3.22838671 5.23910335 3.23130276 2 P 0 ;0,1=66,2=0.000000
L 5.23910335 3.23130276 5.23750325 3.23380295 2 P 0 ;0,1=66,2=0.000000
L 5.23750325 3.23380295 5.23510325 3.23505344 2 P 0 ;0,1=66,2=0.000000
L 5.23510325 3.23505344 5.23243661 3.23505344 2 P 0 ;0,1=66,2=0.000000
L 5.23243661 3.23505344 5.23083652 3.23588661 2 P 0 ;0,1=66,2=0.000000
L 5.23083652 3.23588661 5.22950295 3.23796949 2 P 0 ;0,1=66,2=0.000000
L 5.22950295 3.23796949 5.22896978 3.24088632 2 P 0 ;0,1=66,2=0.000000
L 5.22896978 3.24088632 5.22977008 3.24380315 2 P 0 ;0,1=66,2=0.000000
L 5.22977008 3.24380315 5.23163632 3.24588681 2 P 0 ;0,1=66,2=0.000000
L 5.23163632 3.24588681 5.23376969 3.24671998 2 P 0 ;0,1=66,2=0.000000
L 5.23376969 3.24671998 5.23590305 3.24588681 2 P 0 ;0,1=66,2=0.000000
L 5.23590305 3.24588681 5.23776978 3.24380315 2 P 0 ;0,1=66,2=0.000000
L 5.23776978 3.24380315 5.23857008 3.24088632 2 P 0 ;0,1=66,2=0.000000
L 5.23857008 3.24088632 5.23803642 3.23796949 2 P 0 ;0,1=66,2=0.000000
L 5.23803642 3.23796949 5.23670335 3.23588661 2 P 0 ;0,1=66,2=0.000000
L 5.23670335 3.23588661 5.23510325 3.23505344 2 P 0 ;0,1=66,2=0.000000
L 5.23510325 3.23505344 5.23243661 3.23505344 2 P 0 ;0,1=66,2=0.000000
L 5.23243661 3.23505344 5.23003661 3.23380295 2 P 0 ;0,1=66,2=0.000000
L 5.23003661 3.23380295 5.22843652 3.23130276 2 P 0 ;0,1=66,2=0.000000
L 5.22843652 3.23130276 5.22790325 3.22838671 2 P 0 ;0,1=66,2=0.000000
L 5.22790325 3.22838671 5.22843652 3.22546909 2 P 0 ;0,1=66,2=0.000000
L 5.22843652 3.22546909 5.22977008 3.22338622 2 P 0 ;0,1=66,2=0.000000
L 5.22977008 3.22338622 5.23190344 3.22213652 2 P 0 ;0,1=66,2=0.000000
L 5.23190344 3.22213652 5.23376969 3.22171998 2 P 0 ;0,1=66,2=0.000000
L 5.22833317 3.29255335 5.22993327 3.29505285 2 P 0 ;0,1=294,2=0.000000
L 5.22993327 3.29505285 5.2318 3.29630335 2 P 0 ;0,1=294,2=0.000000
L 5.2318 3.29630335 5.23393337 3.29671998 2 P 0 ;0,1=294,2=0.000000
L 5.23393337 3.29671998 5.2366 3.29588681 2 P 0 ;0,1=294,2=0.000000
L 5.2366 3.29588681 5.23846673 3.29380315 2 P 0 ;0,1=294,2=0.000000
L 5.23846673 3.29380315 5.239 3.29130364 2 P 0 ;0,1=294,2=0.000000
L 5.239 3.29130364 5.23873337 3.28880266 2 P 0 ;0,1=294,2=0.000000
L 5.23873337 3.28880266 5.23766644 3.28671978 2 P 0 ;0,1=294,2=0.000000
L 5.23766644 3.28671978 5.23233327 3.28255325 2 P 0 ;0,1=294,2=0.000000
L 5.23233327 3.28255325 5.22993327 3.27963642 2 P 0 ;0,1=294,2=0.000000
L 5.22993327 3.27963642 5.22833317 3.27546909 2 P 0 ;0,1=294,2=0.000000
L 5.22833317 3.27546909 5.2277999 3.27171998 2 P 0 ;0,1=294,2=0.000000
L 5.2277999 3.27171998 5.239 3.27171998 2 P 0 ;0,1=294,2=0.000000
L 5.25286634 3.27463602 5.25473317 3.27255305 2 P 0 ;0,1=294,2=0.000000
L 5.25473317 3.27255305 5.25686654 3.27171998 2 P 0 ;0,1=294,2=0.000000
L 5.25686654 3.27171998 5.2589999 3.27255305 2 P 0 ;0,1=294,2=0.000000
L 5.2589999 3.27255305 5.26086663 3.27505256 2 P 0 ;0,1=294,2=0.000000
L 5.26086663 3.27505256 5.2622001 3.27880325 2 P 0 ;0,1=294,2=0.000000
L 5.2622001 3.27880325 5.26273337 3.28255325 2 P 0 ;0,1=294,2=0.000000
L 5.26273337 3.28255325 5.26273337 3.28713632 2 P 0 ;0,1=294,2=0.000000
L 5.26273337 3.28713632 5.2622001 3.29088632 2 P 0 ;0,1=294,2=0.000000
L 5.2622001 3.29088632 5.26086663 3.29421969 2 P 0 ;0,1=294,2=0.000000
L 5.26086663 3.29421969 5.25926644 3.29588681 2 P 0 ;0,1=294,2=0.000000
L 5.25926644 3.29588681 5.2573997 3.29671998 2 P 0 ;0,1=294,2=0.000000
L 5.2573997 3.29671998 5.25526634 3.29588681 2 P 0 ;0,1=294,2=0.000000
L 5.25526634 3.29588681 5.25366663 3.29421969 2 P 0 ;0,1=294,2=0.000000
L 5.25366663 3.29421969 5.2525998 3.29172028 2 P 0 ;0,1=294,2=0.000000
L 5.2525998 3.29172028 5.25206654 3.28838612 2 P 0 ;0,1=294,2=0.000000
L 5.25206654 3.28838612 5.2525998 3.28547008 2 P 0 ;0,1=294,2=0.000000
L 5.2525998 3.28547008 5.25393327 3.28255325 2 P 0 ;0,1=294,2=0.000000
L 5.25393327 3.28255325 5.25553346 3.28088612 2 P 0 ;0,1=294,2=0.000000
L 5.25553346 3.28088612 5.2573997 3.28046959 2 P 0 ;0,1=294,2=0.000000
L 5.2573997 3.28046959 5.25953307 3.28130276 2 P 0 ;0,1=294,2=0.000000
L 5.25953307 3.28130276 5.26113327 3.28338642 2 P 0 ;0,1=294,2=0.000000
L 5.26113327 3.28338642 5.26273337 3.28713632 2 P 0 ;0,1=294,2=0.000000
L 5.20390325 3.32671959 5.20550295 3.32380285 2 P 0 ;0,1=295,2=0.000000
L 5.20550295 3.32380285 5.20763632 3.32213652 2 P 0 ;0,1=295,2=0.000000
L 5.20763632 3.32213652 5.21003681 3.32171998 2 P 0 ;0,1=295,2=0.000000
L 5.21003681 3.32171998 5.21217018 3.32213652 2 P 0 ;0,1=295,2=0.000000
L 5.21217018 3.32213652 5.21430354 3.32421939 2 P 0 ;0,1=295,2=0.000000
L 5.21430354 3.32421939 5.21563661 3.32671959 2 P 0 ;0,1=295,2=0.000000
L 5.21563661 3.32671959 5.21590315 3.32921988 2 P 0 ;0,1=295,2=0.000000
L 5.21590315 3.32921988 5.21536998 3.33213593 2 P 0 ;0,1=295,2=0.000000
L 5.21536998 3.33213593 5.21350325 3.33421959 2 P 0 ;0,1=295,2=0.000000
L 5.21350325 3.33421959 5.21163642 3.33505344 2 P 0 ;0,1=295,2=0.000000
L 5.21163642 3.33505344 5.20923652 3.33505344 2 P 0 ;0,1=295,2=0.000000
L 5.21163642 3.33505344 5.21323661 3.33630325 2 P 0 ;0,1=295,2=0.000000
L 5.21323661 3.33630325 5.21457008 3.33838612 2 P 0 ;0,1=295,2=0.000000
L 5.21457008 3.33838612 5.21510335 3.34088632 2 P 0 ;0,1=295,2=0.000000
L 5.21510335 3.34088632 5.21457008 3.34338652 2 P 0 ;0,1=295,2=0.000000
L 5.21457008 3.34338652 5.21323661 3.34546939 2 P 0 ;0,1=295,2=0.000000
L 5.21323661 3.34546939 5.21083661 3.34671998 2 P 0 ;0,1=295,2=0.000000
L 5.21083661 3.34671998 5.20843661 3.34630335 2 P 0 ;0,1=295,2=0.000000
L 5.20843661 3.34630335 5.20603661 3.34463632 2 P 0 ;0,1=295,2=0.000000
L 5.23376969 3.34671998 5.23163632 3.34588681 2 P 0 ;0,1=295,2=0.000000
L 5.23163632 3.34588681 5.23003661 3.34380315 2 P 0 ;0,1=295,2=0.000000
L 5.23003661 3.34380315 5.22896978 3.34130364 2 P 0 ;0,1=295,2=0.000000
L 5.22896978 3.34130364 5.22816988 3.33796949 2 P 0 ;0,1=295,2=0.000000
L 5.22816988 3.33796949 5.22790325 3.33421959 2 P 0 ;0,1=295,2=0.000000
L 5.22790325 3.33421959 5.22816988 3.33046959 2 P 0 ;0,1=295,2=0.000000
L 5.22816988 3.33046959 5.22896978 3.32713622 2 P 0 ;0,1=295,2=0.000000
L 5.22896978 3.32713622 5.23003661 3.32463602 2 P 0 ;0,1=295,2=0.000000
L 5.23003661 3.32463602 5.23163632 3.32255305 2 P 0 ;0,1=295,2=0.000000
L 5.23163632 3.32255305 5.23376969 3.32171998 2 P 0 ;0,1=295,2=0.000000
L 5.23376969 3.32171998 5.23590305 3.32255305 2 P 0 ;0,1=295,2=0.000000
L 5.23590305 3.32255305 5.23750325 3.32463602 2 P 0 ;0,1=295,2=0.000000
L 5.23750325 3.32463602 5.23857008 3.32713622 2 P 0 ;0,1=295,2=0.000000
L 5.23857008 3.32713622 5.23936998 3.33046959 2 P 0 ;0,1=295,2=0.000000
L 5.23936998 3.33046959 5.23963661 3.33421959 2 P 0 ;0,1=295,2=0.000000
L 5.23963661 3.33421959 5.23936998 3.33796949 2 P 0 ;0,1=295,2=0.000000
L 5.23936998 3.33796949 5.23857008 3.34130364 2 P 0 ;0,1=295,2=0.000000
L 5.23857008 3.34130364 5.23750325 3.34380315 2 P 0 ;0,1=295,2=0.000000
L 5.23750325 3.34380315 5.23590305 3.34588681 2 P 0 ;0,1=295,2=0.000000
L 5.23590305 3.34588681 5.23376969 3.34671998 2 P 0 ;0,1=295,2=0.000000
L 5.22753327 3.37671959 5.22913297 3.37380285 2 P 0 ;0,1=296,2=0.000000
L 5.22913297 3.37380285 5.23126634 3.37213652 2 P 0 ;0,1=296,2=0.000000
L 5.23126634 3.37213652 5.23366683 3.37171998 2 P 0 ;0,1=296,2=0.000000
L 5.23366683 3.37171998 5.2358002 3.37213652 2 P 0 ;0,1=296,2=0.000000
L 5.2358002 3.37213652 5.23793356 3.37421939 2 P 0 ;0,1=296,2=0.000000
L 5.23793356 3.37421939 5.23926663 3.37671959 2 P 0 ;0,1=296,2=0.000000
L 5.23926663 3.37671959 5.23953317 3.37921988 2 P 0 ;0,1=296,2=0.000000
L 5.23953317 3.37921988 5.239 3.38213593 2 P 0 ;0,1=296,2=0.000000
L 5.239 3.38213593 5.23713327 3.38421959 2 P 0 ;0,1=296,2=0.000000
L 5.23713327 3.38421959 5.23526644 3.38505344 2 P 0 ;0,1=296,2=0.000000
L 5.23526644 3.38505344 5.23286654 3.38505344 2 P 0 ;0,1=296,2=0.000000
L 5.23526644 3.38505344 5.23686663 3.38630325 2 P 0 ;0,1=296,2=0.000000
L 5.23686663 3.38630325 5.2382001 3.38838612 2 P 0 ;0,1=296,2=0.000000
L 5.2382001 3.38838612 5.23873337 3.39088632 2 P 0 ;0,1=296,2=0.000000
L 5.23873337 3.39088632 5.2382001 3.39338652 2 P 0 ;0,1=296,2=0.000000
L 5.2382001 3.39338652 5.23686663 3.39546939 2 P 0 ;0,1=296,2=0.000000
L 5.23686663 3.39546939 5.23446663 3.39671998 2 P 0 ;0,1=296,2=0.000000
L 5.23446663 3.39671998 5.23206663 3.39630335 2 P 0 ;0,1=296,2=0.000000
L 5.23206663 3.39630335 5.22966663 3.39463632 2 P 0 ;0,1=296,2=0.000000
L 5.2573997 3.37171998 5.2573997 3.39671998 2 P 0 ;0,1=296,2=0.000000
L 5.2573997 3.39671998 5.2541999 3.39172028 2 P 0 ;0,1=296,2=0.000000
L 5.2541999 3.37171998 5.26059951 3.37171998 2 P 0 ;0,1=296,2=0.000000
L 5.20390325 3.42671959 5.20550295 3.42380285 2 P 0 ;0,1=297,2=0.000000
L 5.20550295 3.42380285 5.20763632 3.42213652 2 P 0 ;0,1=297,2=0.000000
L 5.20763632 3.42213652 5.21003681 3.42171998 2 P 0 ;0,1=297,2=0.000000
L 5.21003681 3.42171998 5.21217018 3.42213652 2 P 0 ;0,1=297,2=0.000000
L 5.21217018 3.42213652 5.21430354 3.42421939 2 P 0 ;0,1=297,2=0.000000
L 5.21430354 3.42421939 5.21563661 3.42671959 2 P 0 ;0,1=297,2=0.000000
L 5.21563661 3.42671959 5.21590315 3.42921988 2 P 0 ;0,1=297,2=0.000000
L 5.21590315 3.42921988 5.21536998 3.43213593 2 P 0 ;0,1=297,2=0.000000
L 5.21536998 3.43213593 5.21350325 3.43421959 2 P 0 ;0,1=297,2=0.000000
L 5.21350325 3.43421959 5.21163642 3.43505344 2 P 0 ;0,1=297,2=0.000000
L 5.21163642 3.43505344 5.20923652 3.43505344 2 P 0 ;0,1=297,2=0.000000
L 5.21163642 3.43505344 5.21323661 3.43630325 2 P 0 ;0,1=297,2=0.000000
L 5.21323661 3.43630325 5.21457008 3.43838612 2 P 0 ;0,1=297,2=0.000000
L 5.21457008 3.43838612 5.21510335 3.44088632 2 P 0 ;0,1=297,2=0.000000
L 5.21510335 3.44088632 5.21457008 3.44338652 2 P 0 ;0,1=297,2=0.000000
L 5.21457008 3.44338652 5.21323661 3.44546939 2 P 0 ;0,1=297,2=0.000000
L 5.21323661 3.44546939 5.21083661 3.44671998 2 P 0 ;0,1=297,2=0.000000
L 5.21083661 3.44671998 5.20843661 3.44630335 2 P 0 ;0,1=297,2=0.000000
L 5.20843661 3.44630335 5.20603661 3.44463632 2 P 0 ;0,1=297,2=0.000000
L 5.22870315 3.44255335 5.23030325 3.44505285 2 P 0 ;0,1=297,2=0.000000
L 5.23030325 3.44505285 5.23216998 3.44630335 2 P 0 ;0,1=297,2=0.000000
L 5.23216998 3.44630335 5.23430335 3.44671998 2 P 0 ;0,1=297,2=0.000000
L 5.23430335 3.44671998 5.23696998 3.44588681 2 P 0 ;0,1=297,2=0.000000
L 5.23696998 3.44588681 5.23883671 3.44380315 2 P 0 ;0,1=297,2=0.000000
L 5.23883671 3.44380315 5.23936998 3.44130364 2 P 0 ;0,1=297,2=0.000000
L 5.23936998 3.44130364 5.23910335 3.43880266 2 P 0 ;0,1=297,2=0.000000
L 5.23910335 3.43880266 5.23803642 3.43671978 2 P 0 ;0,1=297,2=0.000000
L 5.23803642 3.43671978 5.23270325 3.43255325 2 P 0 ;0,1=297,2=0.000000
L 5.23270325 3.43255325 5.23030325 3.42963642 2 P 0 ;0,1=297,2=0.000000
L 5.23030325 3.42963642 5.22870315 3.42546909 2 P 0 ;0,1=297,2=0.000000
L 5.22870315 3.42546909 5.22816988 3.42171998 2 P 0 ;0,1=297,2=0.000000
L 5.22816988 3.42171998 5.23936998 3.42171998 2 P 0 ;0,1=297,2=0.000000
L 5.22753327 3.47671959 5.22913297 3.47380285 2 P 0 ;0,1=298,2=0.000000
L 5.22913297 3.47380285 5.23126634 3.47213652 2 P 0 ;0,1=298,2=0.000000
L 5.23126634 3.47213652 5.23366683 3.47171998 2 P 0 ;0,1=298,2=0.000000
L 5.23366683 3.47171998 5.2358002 3.47213652 2 P 0 ;0,1=298,2=0.000000
L 5.2358002 3.47213652 5.23793356 3.47421939 2 P 0 ;0,1=298,2=0.000000
L 5.23793356 3.47421939 5.23926663 3.47671959 2 P 0 ;0,1=298,2=0.000000
L 5.23926663 3.47671959 5.23953317 3.47921988 2 P 0 ;0,1=298,2=0.000000
L 5.23953317 3.47921988 5.239 3.48213593 2 P 0 ;0,1=298,2=0.000000
L 5.239 3.48213593 5.23713327 3.48421959 2 P 0 ;0,1=298,2=0.000000
L 5.23713327 3.48421959 5.23526644 3.48505344 2 P 0 ;0,1=298,2=0.000000
L 5.23526644 3.48505344 5.23286654 3.48505344 2 P 0 ;0,1=298,2=0.000000
L 5.23526644 3.48505344 5.23686663 3.48630325 2 P 0 ;0,1=298,2=0.000000
L 5.23686663 3.48630325 5.2382001 3.48838612 2 P 0 ;0,1=298,2=0.000000
L 5.2382001 3.48838612 5.23873337 3.49088632 2 P 0 ;0,1=298,2=0.000000
L 5.23873337 3.49088632 5.2382001 3.49338652 2 P 0 ;0,1=298,2=0.000000
L 5.2382001 3.49338652 5.23686663 3.49546939 2 P 0 ;0,1=298,2=0.000000
L 5.23686663 3.49546939 5.23446663 3.49671998 2 P 0 ;0,1=298,2=0.000000
L 5.23446663 3.49671998 5.23206663 3.49630335 2 P 0 ;0,1=298,2=0.000000
L 5.23206663 3.49630335 5.22966663 3.49463632 2 P 0 ;0,1=298,2=0.000000
L 5.25153327 3.47671959 5.25313297 3.47380285 2 P 0 ;0,1=298,2=0.000000
L 5.25313297 3.47380285 5.25526634 3.47213652 2 P 0 ;0,1=298,2=0.000000
L 5.25526634 3.47213652 5.25766683 3.47171998 2 P 0 ;0,1=298,2=0.000000
L 5.25766683 3.47171998 5.2598002 3.47213652 2 P 0 ;0,1=298,2=0.000000
L 5.2598002 3.47213652 5.26193356 3.47421939 2 P 0 ;0,1=298,2=0.000000
L 5.26193356 3.47421939 5.26326663 3.47671959 2 P 0 ;0,1=298,2=0.000000
L 5.26326663 3.47671959 5.26353317 3.47921988 2 P 0 ;0,1=298,2=0.000000
L 5.26353317 3.47921988 5.263 3.48213593 2 P 0 ;0,1=298,2=0.000000
L 5.263 3.48213593 5.26113327 3.48421959 2 P 0 ;0,1=298,2=0.000000
L 5.26113327 3.48421959 5.25926644 3.48505344 2 P 0 ;0,1=298,2=0.000000
L 5.25926644 3.48505344 5.25686654 3.48505344 2 P 0 ;0,1=298,2=0.000000
L 5.25926644 3.48505344 5.26086663 3.48630325 2 P 0 ;0,1=298,2=0.000000
L 5.26086663 3.48630325 5.2622001 3.48838612 2 P 0 ;0,1=298,2=0.000000
L 5.2622001 3.48838612 5.26273337 3.49088632 2 P 0 ;0,1=298,2=0.000000
L 5.26273337 3.49088632 5.2622001 3.49338652 2 P 0 ;0,1=298,2=0.000000
L 5.2622001 3.49338652 5.26086663 3.49546939 2 P 0 ;0,1=298,2=0.000000
L 5.26086663 3.49546939 5.25846663 3.49671998 2 P 0 ;0,1=298,2=0.000000
L 5.25846663 3.49671998 5.25606663 3.49630335 2 P 0 ;0,1=298,2=0.000000
L 5.25606663 3.49630335 5.25366663 3.49463632 2 P 0 ;0,1=298,2=0.000000
L 5.20390325 3.52671959 5.20550295 3.52380285 2 P 0 ;0,1=299,2=0.000000
L 5.20550295 3.52380285 5.20763632 3.52213652 2 P 0 ;0,1=299,2=0.000000
L 5.20763632 3.52213652 5.21003681 3.52171998 2 P 0 ;0,1=299,2=0.000000
L 5.21003681 3.52171998 5.21217018 3.52213652 2 P 0 ;0,1=299,2=0.000000
L 5.21217018 3.52213652 5.21430354 3.52421939 2 P 0 ;0,1=299,2=0.000000
L 5.21430354 3.52421939 5.21563661 3.52671959 2 P 0 ;0,1=299,2=0.000000
L 5.21563661 3.52671959 5.21590315 3.52921988 2 P 0 ;0,1=299,2=0.000000
L 5.21590315 3.52921988 5.21536998 3.53213593 2 P 0 ;0,1=299,2=0.000000
L 5.21536998 3.53213593 5.21350325 3.53421959 2 P 0 ;0,1=299,2=0.000000
L 5.21350325 3.53421959 5.21163642 3.53505344 2 P 0 ;0,1=299,2=0.000000
L 5.21163642 3.53505344 5.20923652 3.53505344 2 P 0 ;0,1=299,2=0.000000
L 5.21163642 3.53505344 5.21323661 3.53630325 2 P 0 ;0,1=299,2=0.000000
L 5.21323661 3.53630325 5.21457008 3.53838612 2 P 0 ;0,1=299,2=0.000000
L 5.21457008 3.53838612 5.21510335 3.54088632 2 P 0 ;0,1=299,2=0.000000
L 5.21510335 3.54088632 5.21457008 3.54338652 2 P 0 ;0,1=299,2=0.000000
L 5.21457008 3.54338652 5.21323661 3.54546939 2 P 0 ;0,1=299,2=0.000000
L 5.21323661 3.54546939 5.21083661 3.54671998 2 P 0 ;0,1=299,2=0.000000
L 5.21083661 3.54671998 5.20843661 3.54630335 2 P 0 ;0,1=299,2=0.000000
L 5.20843661 3.54630335 5.20603661 3.54463632 2 P 0 ;0,1=299,2=0.000000
L 5.23696998 3.52171998 5.23696998 3.54671998 2 P 0 ;0,1=299,2=0.000000
L 5.23696998 3.54671998 5.22710295 3.52880325 2 P 0 ;0,1=299,2=0.000000
L 5.22710295 3.52880325 5.24043691 3.52880325 2 P 0 ;0,1=299,2=0.000000
L 5.22753327 3.57671959 5.22913297 3.57380285 2 P 0 ;0,1=300,2=0.000000
L 5.22913297 3.57380285 5.23126634 3.57213652 2 P 0 ;0,1=300,2=0.000000
L 5.23126634 3.57213652 5.23366683 3.57171998 2 P 0 ;0,1=300,2=0.000000
L 5.23366683 3.57171998 5.2358002 3.57213652 2 P 0 ;0,1=300,2=0.000000
L 5.2358002 3.57213652 5.23793356 3.57421939 2 P 0 ;0,1=300,2=0.000000
L 5.23793356 3.57421939 5.23926663 3.57671959 2 P 0 ;0,1=300,2=0.000000
L 5.23926663 3.57671959 5.23953317 3.57921988 2 P 0 ;0,1=300,2=0.000000
L 5.23953317 3.57921988 5.239 3.58213593 2 P 0 ;0,1=300,2=0.000000
L 5.239 3.58213593 5.23713327 3.58421959 2 P 0 ;0,1=300,2=0.000000
L 5.23713327 3.58421959 5.23526644 3.58505344 2 P 0 ;0,1=300,2=0.000000
L 5.23526644 3.58505344 5.23286654 3.58505344 2 P 0 ;0,1=300,2=0.000000
L 5.23526644 3.58505344 5.23686663 3.58630325 2 P 0 ;0,1=300,2=0.000000
L 5.23686663 3.58630325 5.2382001 3.58838612 2 P 0 ;0,1=300,2=0.000000
L 5.2382001 3.58838612 5.23873337 3.59088632 2 P 0 ;0,1=300,2=0.000000
L 5.23873337 3.59088632 5.2382001 3.59338652 2 P 0 ;0,1=300,2=0.000000
L 5.2382001 3.59338652 5.23686663 3.59546939 2 P 0 ;0,1=300,2=0.000000
L 5.23686663 3.59546939 5.23446663 3.59671998 2 P 0 ;0,1=300,2=0.000000
L 5.23446663 3.59671998 5.23206663 3.59630335 2 P 0 ;0,1=300,2=0.000000
L 5.23206663 3.59630335 5.22966663 3.59463632 2 P 0 ;0,1=300,2=0.000000
L 5.25153327 3.57546909 5.25313297 3.57338622 2 P 0 ;0,1=300,2=0.000000
L 5.25313297 3.57338622 5.2549997 3.57213652 2 P 0 ;0,1=300,2=0.000000
L 5.2549997 3.57213652 5.2573997 3.57171998 2 P 0 ;0,1=300,2=0.000000
L 5.2573997 3.57171998 5.2598002 3.57255305 2 P 0 ;0,1=300,2=0.000000
L 5.2598002 3.57255305 5.26166644 3.57421939 2 P 0 ;0,1=300,2=0.000000
L 5.26166644 3.57421939 5.263 3.57713622 2 P 0 ;0,1=300,2=0.000000
L 5.263 3.57713622 5.26326663 3.58046959 2 P 0 ;0,1=300,2=0.000000
L 5.26326663 3.58046959 5.26273337 3.58380295 2 P 0 ;0,1=300,2=0.000000
L 5.26273337 3.58380295 5.2613998 3.58588661 2 P 0 ;0,1=300,2=0.000000
L 5.2613998 3.58588661 5.25953307 3.58755295 2 P 0 ;0,1=300,2=0.000000
L 5.25953307 3.58755295 5.25766683 3.58796949 2 P 0 ;0,1=300,2=0.000000
L 5.25766683 3.58796949 5.2558 3.58755295 2 P 0 ;0,1=300,2=0.000000
L 5.2558 3.58755295 5.2534001 3.58588661 2 P 0 ;0,1=300,2=0.000000
L 5.2534001 3.58588661 5.2541999 3.59671998 2 P 0 ;0,1=300,2=0.000000
L 5.2541999 3.59671998 5.2613998 3.59671998 2 P 0 ;0,1=300,2=0.000000
L 5.20390325 3.62671959 5.20550295 3.62380285 2 P 0 ;0,1=301,2=0.000000
L 5.20550295 3.62380285 5.20763632 3.62213652 2 P 0 ;0,1=301,2=0.000000
L 5.20763632 3.62213652 5.21003681 3.62171998 2 P 0 ;0,1=301,2=0.000000
L 5.21003681 3.62171998 5.21217018 3.62213652 2 P 0 ;0,1=301,2=0.000000
L 5.21217018 3.62213652 5.21430354 3.62421939 2 P 0 ;0,1=301,2=0.000000
L 5.21430354 3.62421939 5.21563661 3.62671959 2 P 0 ;0,1=301,2=0.000000
L 5.21563661 3.62671959 5.21590315 3.62921988 2 P 0 ;0,1=301,2=0.000000
L 5.21590315 3.62921988 5.21536998 3.63213593 2 P 0 ;0,1=301,2=0.000000
L 5.21536998 3.63213593 5.21350325 3.63421959 2 P 0 ;0,1=301,2=0.000000
L 5.21350325 3.63421959 5.21163642 3.63505344 2 P 0 ;0,1=301,2=0.000000
L 5.21163642 3.63505344 5.20923652 3.63505344 2 P 0 ;0,1=301,2=0.000000
L 5.21163642 3.63505344 5.21323661 3.63630325 2 P 0 ;0,1=301,2=0.000000
L 5.21323661 3.63630325 5.21457008 3.63838612 2 P 0 ;0,1=301,2=0.000000
L 5.21457008 3.63838612 5.21510335 3.64088632 2 P 0 ;0,1=301,2=0.000000
L 5.21510335 3.64088632 5.21457008 3.64338652 2 P 0 ;0,1=301,2=0.000000
L 5.21457008 3.64338652 5.21323661 3.64546939 2 P 0 ;0,1=301,2=0.000000
L 5.21323661 3.64546939 5.21083661 3.64671998 2 P 0 ;0,1=301,2=0.000000
L 5.21083661 3.64671998 5.20843661 3.64630335 2 P 0 ;0,1=301,2=0.000000
L 5.20843661 3.64630335 5.20603661 3.64463632 2 P 0 ;0,1=301,2=0.000000
L 5.22870315 3.63213593 5.23056988 3.63505344 2 P 0 ;0,1=301,2=0.000000
L 5.23056988 3.63505344 5.23216998 3.63671978 2 P 0 ;0,1=301,2=0.000000
L 5.23216998 3.63671978 5.23430335 3.63755295 2 P 0 ;0,1=301,2=0.000000
L 5.23430335 3.63755295 5.23617018 3.63671978 2 P 0 ;0,1=301,2=0.000000
L 5.23617018 3.63671978 5.23750325 3.63505344 2 P 0 ;0,1=301,2=0.000000
L 5.23750325 3.63505344 5.23857008 3.63255325 2 P 0 ;0,1=301,2=0.000000
L 5.23857008 3.63255325 5.23883671 3.62963642 2 P 0 ;0,1=301,2=0.000000
L 5.23883671 3.62963642 5.23857008 3.62713622 2 P 0 ;0,1=301,2=0.000000
L 5.23857008 3.62713622 5.23750325 3.62463602 2 P 0 ;0,1=301,2=0.000000
L 5.23750325 3.62463602 5.23590305 3.62255305 2 P 0 ;0,1=301,2=0.000000
L 5.23590305 3.62255305 5.23403681 3.62171998 2 P 0 ;0,1=301,2=0.000000
L 5.23403681 3.62171998 5.23190344 3.62255305 2 P 0 ;0,1=301,2=0.000000
L 5.23190344 3.62255305 5.23003661 3.62505256 2 P 0 ;0,1=301,2=0.000000
L 5.23003661 3.62505256 5.22896978 3.62880325 2 P 0 ;0,1=301,2=0.000000
L 5.22896978 3.62880325 5.22870315 3.63296978 2 P 0 ;0,1=301,2=0.000000
L 5.22870315 3.63296978 5.22923632 3.63838612 2 P 0 ;0,1=301,2=0.000000
L 5.22923632 3.63838612 5.23003661 3.64130364 2 P 0 ;0,1=301,2=0.000000
L 5.23003661 3.64130364 5.23136969 3.64421969 2 P 0 ;0,1=301,2=0.000000
L 5.23136969 3.64421969 5.23323652 3.64630335 2 P 0 ;0,1=301,2=0.000000
L 5.23323652 3.64630335 5.23510325 3.64671998 2 P 0 ;0,1=301,2=0.000000
L 5.23510325 3.64671998 5.23696998 3.64588681 2 P 0 ;0,1=301,2=0.000000
L 5.23696998 3.64588681 5.23830354 3.64380315 2 P 0 ;0,1=301,2=0.000000
L 5.22753327 3.67671959 5.22913297 3.67380285 2 P 0 ;0,1=302,2=0.000000
L 5.22913297 3.67380285 5.23126634 3.67213652 2 P 0 ;0,1=302,2=0.000000
L 5.23126634 3.67213652 5.23366683 3.67171998 2 P 0 ;0,1=302,2=0.000000
L 5.23366683 3.67171998 5.2358002 3.67213652 2 P 0 ;0,1=302,2=0.000000
L 5.2358002 3.67213652 5.23793356 3.67421939 2 P 0 ;0,1=302,2=0.000000
L 5.23793356 3.67421939 5.23926663 3.67671959 2 P 0 ;0,1=302,2=0.000000
L 5.23926663 3.67671959 5.23953317 3.67921988 2 P 0 ;0,1=302,2=0.000000
L 5.23953317 3.67921988 5.239 3.68213593 2 P 0 ;0,1=302,2=0.000000
L 5.239 3.68213593 5.23713327 3.68421959 2 P 0 ;0,1=302,2=0.000000
L 5.23713327 3.68421959 5.23526644 3.68505344 2 P 0 ;0,1=302,2=0.000000
L 5.23526644 3.68505344 5.23286654 3.68505344 2 P 0 ;0,1=302,2=0.000000
L 5.23526644 3.68505344 5.23686663 3.68630325 2 P 0 ;0,1=302,2=0.000000
L 5.23686663 3.68630325 5.2382001 3.68838612 2 P 0 ;0,1=302,2=0.000000
L 5.2382001 3.68838612 5.23873337 3.69088632 2 P 0 ;0,1=302,2=0.000000
L 5.23873337 3.69088632 5.2382001 3.69338652 2 P 0 ;0,1=302,2=0.000000
L 5.2382001 3.69338652 5.23686663 3.69546939 2 P 0 ;0,1=302,2=0.000000
L 5.23686663 3.69546939 5.23446663 3.69671998 2 P 0 ;0,1=302,2=0.000000
L 5.23446663 3.69671998 5.23206663 3.69630335 2 P 0 ;0,1=302,2=0.000000
L 5.23206663 3.69630335 5.22966663 3.69463632 2 P 0 ;0,1=302,2=0.000000
L 5.25686654 3.67171998 5.2573997 3.67713622 2 P 0 ;0,1=302,2=0.000000
L 5.2573997 3.67713622 5.2582 3.68171929 2 P 0 ;0,1=302,2=0.000000
L 5.2582 3.68171929 5.25926644 3.68588661 2 P 0 ;0,1=302,2=0.000000
L 5.25926644 3.68588661 5.2606 3.69046978 2 P 0 ;0,1=302,2=0.000000
L 5.2606 3.69046978 5.26273337 3.69671998 2 P 0 ;0,1=302,2=0.000000
L 5.26273337 3.69671998 5.25206654 3.69671998 2 P 0 ;0,1=302,2=0.000000
L 5.20390325 3.72671959 5.20550295 3.72380285 2 P 0 ;0,1=303,2=0.000000
L 5.20550295 3.72380285 5.20763632 3.72213652 2 P 0 ;0,1=303,2=0.000000
L 5.20763632 3.72213652 5.21003681 3.72171998 2 P 0 ;0,1=303,2=0.000000
L 5.21003681 3.72171998 5.21217018 3.72213652 2 P 0 ;0,1=303,2=0.000000
L 5.21217018 3.72213652 5.21430354 3.72421939 2 P 0 ;0,1=303,2=0.000000
L 5.21430354 3.72421939 5.21563661 3.72671959 2 P 0 ;0,1=303,2=0.000000
L 5.21563661 3.72671959 5.21590315 3.72921988 2 P 0 ;0,1=303,2=0.000000
L 5.21590315 3.72921988 5.21536998 3.73213593 2 P 0 ;0,1=303,2=0.000000
L 5.21536998 3.73213593 5.21350325 3.73421959 2 P 0 ;0,1=303,2=0.000000
L 5.21350325 3.73421959 5.21163642 3.73505344 2 P 0 ;0,1=303,2=0.000000
L 5.21163642 3.73505344 5.20923652 3.73505344 2 P 0 ;0,1=303,2=0.000000
L 5.21163642 3.73505344 5.21323661 3.73630325 2 P 0 ;0,1=303,2=0.000000
L 5.21323661 3.73630325 5.21457008 3.73838612 2 P 0 ;0,1=303,2=0.000000
L 5.21457008 3.73838612 5.21510335 3.74088632 2 P 0 ;0,1=303,2=0.000000
L 5.21510335 3.74088632 5.21457008 3.74338652 2 P 0 ;0,1=303,2=0.000000
L 5.21457008 3.74338652 5.21323661 3.74546939 2 P 0 ;0,1=303,2=0.000000
L 5.21323661 3.74546939 5.21083661 3.74671998 2 P 0 ;0,1=303,2=0.000000
L 5.21083661 3.74671998 5.20843661 3.74630335 2 P 0 ;0,1=303,2=0.000000
L 5.20843661 3.74630335 5.20603661 3.74463632 2 P 0 ;0,1=303,2=0.000000
L 5.23376969 3.72171998 5.23563642 3.72213652 2 P 0 ;0,1=303,2=0.000000
L 5.23563642 3.72213652 5.23776978 3.72338622 2 P 0 ;0,1=303,2=0.000000
L 5.23776978 3.72338622 5.23910335 3.72546909 2 P 0 ;0,1=303,2=0.000000
L 5.23910335 3.72546909 5.23963661 3.72838671 2 P 0 ;0,1=303,2=0.000000
L 5.23963661 3.72838671 5.23910335 3.73130276 2 P 0 ;0,1=303,2=0.000000
L 5.23910335 3.73130276 5.23750325 3.73380295 2 P 0 ;0,1=303,2=0.000000
L 5.23750325 3.73380295 5.23510325 3.73505344 2 P 0 ;0,1=303,2=0.000000
L 5.23510325 3.73505344 5.23243661 3.73505344 2 P 0 ;0,1=303,2=0.000000
L 5.23243661 3.73505344 5.23083652 3.73588661 2 P 0 ;0,1=303,2=0.000000
L 5.23083652 3.73588661 5.22950295 3.73796949 2 P 0 ;0,1=303,2=0.000000
L 5.22950295 3.73796949 5.22896978 3.74088632 2 P 0 ;0,1=303,2=0.000000
L 5.22896978 3.74088632 5.22977008 3.74380315 2 P 0 ;0,1=303,2=0.000000
L 5.22977008 3.74380315 5.23163632 3.74588681 2 P 0 ;0,1=303,2=0.000000
L 5.23163632 3.74588681 5.23376969 3.74671998 2 P 0 ;0,1=303,2=0.000000
L 5.23376969 3.74671998 5.23590305 3.74588681 2 P 0 ;0,1=303,2=0.000000
L 5.23590305 3.74588681 5.23776978 3.74380315 2 P 0 ;0,1=303,2=0.000000
L 5.23776978 3.74380315 5.23857008 3.74088632 2 P 0 ;0,1=303,2=0.000000
L 5.23857008 3.74088632 5.23803642 3.73796949 2 P 0 ;0,1=303,2=0.000000
L 5.23803642 3.73796949 5.23670335 3.73588661 2 P 0 ;0,1=303,2=0.000000
L 5.23670335 3.73588661 5.23510325 3.73505344 2 P 0 ;0,1=303,2=0.000000
L 5.23510325 3.73505344 5.23243661 3.73505344 2 P 0 ;0,1=303,2=0.000000
L 5.23243661 3.73505344 5.23003661 3.73380295 2 P 0 ;0,1=303,2=0.000000
L 5.23003661 3.73380295 5.22843652 3.73130276 2 P 0 ;0,1=303,2=0.000000
L 5.22843652 3.73130276 5.22790325 3.72838671 2 P 0 ;0,1=303,2=0.000000
L 5.22790325 3.72838671 5.22843652 3.72546909 2 P 0 ;0,1=303,2=0.000000
L 5.22843652 3.72546909 5.22977008 3.72338622 2 P 0 ;0,1=303,2=0.000000
L 5.22977008 3.72338622 5.23190344 3.72213652 2 P 0 ;0,1=303,2=0.000000
L 5.23190344 3.72213652 5.23376969 3.72171998 2 P 0 ;0,1=303,2=0.000000
L 5.22753327 3.77671959 5.22913297 3.77380285 2 P 0 ;0,1=304,2=0.000000
L 5.22913297 3.77380285 5.23126634 3.77213652 2 P 0 ;0,1=304,2=0.000000
L 5.23126634 3.77213652 5.23366683 3.77171998 2 P 0 ;0,1=304,2=0.000000
L 5.23366683 3.77171998 5.2358002 3.77213652 2 P 0 ;0,1=304,2=0.000000
L 5.2358002 3.77213652 5.23793356 3.77421939 2 P 0 ;0,1=304,2=0.000000
L 5.23793356 3.77421939 5.23926663 3.77671959 2 P 0 ;0,1=304,2=0.000000
L 5.23926663 3.77671959 5.23953317 3.77921988 2 P 0 ;0,1=304,2=0.000000
L 5.23953317 3.77921988 5.239 3.78213593 2 P 0 ;0,1=304,2=0.000000
L 5.239 3.78213593 5.23713327 3.78421959 2 P 0 ;0,1=304,2=0.000000
L 5.23713327 3.78421959 5.23526644 3.78505344 2 P 0 ;0,1=304,2=0.000000
L 5.23526644 3.78505344 5.23286654 3.78505344 2 P 0 ;0,1=304,2=0.000000
L 5.23526644 3.78505344 5.23686663 3.78630325 2 P 0 ;0,1=304,2=0.000000
L 5.23686663 3.78630325 5.2382001 3.78838612 2 P 0 ;0,1=304,2=0.000000
L 5.2382001 3.78838612 5.23873337 3.79088632 2 P 0 ;0,1=304,2=0.000000
L 5.23873337 3.79088632 5.2382001 3.79338652 2 P 0 ;0,1=304,2=0.000000
L 5.2382001 3.79338652 5.23686663 3.79546939 2 P 0 ;0,1=304,2=0.000000
L 5.23686663 3.79546939 5.23446663 3.79671998 2 P 0 ;0,1=304,2=0.000000
L 5.23446663 3.79671998 5.23206663 3.79630335 2 P 0 ;0,1=304,2=0.000000
L 5.23206663 3.79630335 5.22966663 3.79463632 2 P 0 ;0,1=304,2=0.000000
L 5.25286634 3.77463602 5.25473317 3.77255305 2 P 0 ;0,1=304,2=0.000000
L 5.25473317 3.77255305 5.25686654 3.77171998 2 P 0 ;0,1=304,2=0.000000
L 5.25686654 3.77171998 5.2589999 3.77255305 2 P 0 ;0,1=304,2=0.000000
L 5.2589999 3.77255305 5.26086663 3.77505256 2 P 0 ;0,1=304,2=0.000000
L 5.26086663 3.77505256 5.2622001 3.77880325 2 P 0 ;0,1=304,2=0.000000
L 5.2622001 3.77880325 5.26273337 3.78255325 2 P 0 ;0,1=304,2=0.000000
L 5.26273337 3.78255325 5.26273337 3.78713632 2 P 0 ;0,1=304,2=0.000000
L 5.26273337 3.78713632 5.2622001 3.79088632 2 P 0 ;0,1=304,2=0.000000
L 5.2622001 3.79088632 5.26086663 3.79421969 2 P 0 ;0,1=304,2=0.000000
L 5.26086663 3.79421969 5.25926644 3.79588681 2 P 0 ;0,1=304,2=0.000000
L 5.25926644 3.79588681 5.2573997 3.79671998 2 P 0 ;0,1=304,2=0.000000
L 5.2573997 3.79671998 5.25526634 3.79588681 2 P 0 ;0,1=304,2=0.000000
L 5.25526634 3.79588681 5.25366663 3.79421969 2 P 0 ;0,1=304,2=0.000000
L 5.25366663 3.79421969 5.2525998 3.79172028 2 P 0 ;0,1=304,2=0.000000
L 5.2525998 3.79172028 5.25206654 3.78838612 2 P 0 ;0,1=304,2=0.000000
L 5.25206654 3.78838612 5.2525998 3.78547008 2 P 0 ;0,1=304,2=0.000000
L 5.2525998 3.78547008 5.25393327 3.78255325 2 P 0 ;0,1=304,2=0.000000
L 5.25393327 3.78255325 5.25553346 3.78088612 2 P 0 ;0,1=304,2=0.000000
L 5.25553346 3.78088612 5.2573997 3.78046959 2 P 0 ;0,1=304,2=0.000000
L 5.2573997 3.78046959 5.25953307 3.78130276 2 P 0 ;0,1=304,2=0.000000
L 5.25953307 3.78130276 5.26113327 3.78338642 2 P 0 ;0,1=304,2=0.000000
L 5.26113327 3.78338642 5.26273337 3.78713632 2 P 0 ;0,1=304,2=0.000000
L 5.21296998 3.82171998 5.21296998 3.84671998 2 P 0 ;0,1=305,2=0.000000
L 5.21296998 3.84671998 5.20310295 3.82880325 2 P 0 ;0,1=305,2=0.000000
L 5.20310295 3.82880325 5.21643691 3.82880325 2 P 0 ;0,1=305,2=0.000000
L 5.23376969 3.84671998 5.23163632 3.84588681 2 P 0 ;0,1=305,2=0.000000
L 5.23163632 3.84588681 5.23003661 3.84380315 2 P 0 ;0,1=305,2=0.000000
L 5.23003661 3.84380315 5.22896978 3.84130364 2 P 0 ;0,1=305,2=0.000000
L 5.22896978 3.84130364 5.22816988 3.83796949 2 P 0 ;0,1=305,2=0.000000
L 5.22816988 3.83796949 5.22790325 3.83421959 2 P 0 ;0,1=305,2=0.000000
L 5.22790325 3.83421959 5.22816988 3.83046959 2 P 0 ;0,1=305,2=0.000000
L 5.22816988 3.83046959 5.22896978 3.82713622 2 P 0 ;0,1=305,2=0.000000
L 5.22896978 3.82713622 5.23003661 3.82463602 2 P 0 ;0,1=305,2=0.000000
L 5.23003661 3.82463602 5.23163632 3.82255305 2 P 0 ;0,1=305,2=0.000000
L 5.23163632 3.82255305 5.23376969 3.82171998 2 P 0 ;0,1=305,2=0.000000
L 5.23376969 3.82171998 5.23590305 3.82255305 2 P 0 ;0,1=305,2=0.000000
L 5.23590305 3.82255305 5.23750325 3.82463602 2 P 0 ;0,1=305,2=0.000000
L 5.23750325 3.82463602 5.23857008 3.82713622 2 P 0 ;0,1=305,2=0.000000
L 5.23857008 3.82713622 5.23936998 3.83046959 2 P 0 ;0,1=305,2=0.000000
L 5.23936998 3.83046959 5.23963661 3.83421959 2 P 0 ;0,1=305,2=0.000000
L 5.23963661 3.83421959 5.23936998 3.83796949 2 P 0 ;0,1=305,2=0.000000
L 5.23936998 3.83796949 5.23857008 3.84130364 2 P 0 ;0,1=305,2=0.000000
L 5.23857008 3.84130364 5.23750325 3.84380315 2 P 0 ;0,1=305,2=0.000000
L 5.23750325 3.84380315 5.23590305 3.84588681 2 P 0 ;0,1=305,2=0.000000
L 5.23590305 3.84588681 5.23376969 3.84671998 2 P 0 ;0,1=305,2=0.000000
L 10.68503996 1.7441 10.68503996 1.77953996 3 P 0 
L 10.68503996 1.77953996 10.58425 1.77953996 3 P 0 
A 10.58425 1.77953996 10.49133002 1.87246004 10.58383002 1.87203996 3 P 0 Y
L 10.49133002 1.87246004 10.49133002 3.85941004 3 P 0 
A 10.49133002 3.85941004 10.5847 3.95276004 10.5838502 3.86023996 3 P 0 Y
L 10.5847 3.95276004 10.72441004 3.95276004 3 P 0 
L 10.72441004 3.95276004 10.72441004 3.9882 3 P 0 
L 10.72441004 3.9882 10.94881004 3.9882 3 P 0 
L 10.94881004 3.9882 10.94881004 3.95276004 3 P 0 
L 10.94881004 3.95276004 11.08785 3.95276004 3 P 0 
A 11.08785 3.95276004 11.15455039 3.92590413 11.08935098 3.86023002 3 P 0 Y
A 11.15455039 3.92590413 11.18188996 3.8594 11.08935 3.86022884 3 P 0 Y
L 11.18188996 3.8594 11.18188996 1.87286004 3 P 0 
A 11.18188996 1.87286004 11.08856004 1.77953996 11.08937982 1.87205 3 P 0 Y
L 11.08856004 1.77953996 10.98818002 1.77953002 3 P 0 
L 10.98818002 1.77953002 10.98818002 1.7441 3 P 0 
L 10.98818002 1.7441 10.68503996 1.7441 3 P 0 
L 10.52851998 3.74115 10.51101998 3.7569 3 P 0 
L 10.51101998 3.7569 10.49531004 3.7569 3 P 0 
L 10.49531004 3.7569 10.51105 3.74115 3 P 0 
L 10.51105 3.74115 10.54648996 3.74115 3 P 0 
L 10.54648996 3.74115 10.54646004 3.5758 3 P 0 
L 10.54646004 3.5758 10.51101998 3.5758 3 P 0 
L 10.51101998 3.5758 10.49528002 3.56005 3 P 0 
L 10.49528002 3.56005 10.51101998 3.56005 3 P 0 
L 10.51101998 3.56005 10.51101998 2.96458002 3 P 0 
L 10.51101998 2.96458002 10.49528002 2.96458002 3 P 0 
L 10.49528002 2.96458002 10.51101998 2.94883996 3 P 0 
L 10.51101998 2.94883996 10.54646004 2.94883002 3 P 0 
L 10.54646004 2.94883002 10.54646004 2.78348002 3 P 0 
L 10.54646004 2.78348002 10.51101998 2.78348002 3 P 0 
L 10.51101998 2.78348002 10.49528002 2.76773002 3 P 0 
L 10.49528002 2.76773002 10.51101998 2.76773002 3 P 0 
L 10.51101998 2.76773002 10.51101998 2.17383002 3 P 0 
L 10.51101998 2.17383002 10.49528002 2.17383002 3 P 0 
L 10.49528002 2.17383002 10.51101998 2.15808002 3 P 0 
L 10.51101998 2.15808002 10.54646004 2.15808002 3 P 0 
L 10.54646004 2.15808002 10.54646004 1.99273002 3 P 0 
L 10.54646004 1.99273002 10.51101998 1.99273002 3 P 0 
L 10.51101998 1.99273002 10.49528002 1.97698002 3 P 0 
L 10.49528002 1.97698002 10.51101998 1.97698002 3 P 0 
L 10.51101998 1.97698002 10.52491998 1.99273002 3 P 0 
L 10.51101998 2.17383002 10.52676998 2.15808002 3 P 0 
L 10.52676998 2.15808002 10.52676998 2.78348002 3 P 0 
L 10.52676998 2.78348002 10.51101998 2.76773002 3 P 0 
L 10.51101998 2.78348002 10.51101998 2.94883002 2 P 0 
L 10.51101998 2.96458002 10.52676998 2.94883996 3 P 0 
L 10.52676998 2.94883996 10.52676998 3.5758 3 P 0 
L 10.52676998 3.5758 10.51101998 3.56005 3 P 0 
L 11.14683002 3.74115 11.1622 3.75688996 3 P 0 
L 11.1622 3.75688996 11.17793996 3.75688996 3 P 0 
L 11.17793996 3.75688996 11.1622 3.74115 3 P 0 
L 11.1622 3.74115 11.12676004 3.74115 3 P 0 
L 11.12676004 3.74115 11.12676004 3.5758 3 P 0 
L 11.12676004 3.5758 11.1622 3.5758 3 P 0 
L 11.1622 3.5758 11.17793996 3.56005 3 P 0 
L 11.17793996 3.56005 11.1622 3.56005 3 P 0 
L 11.1622 3.56005 11.1622 2.96456998 3 P 0 
L 11.1622 2.96456998 11.17793996 2.96456998 3 P 0 
L 11.17793996 2.96456998 11.1622 2.94883002 3 P 0 
L 11.1622 2.94883002 11.12676004 2.94883002 3 P 0 
L 11.12676004 2.94883002 11.12676004 2.78346998 3 P 0 
L 11.12676004 2.78346998 11.1622 2.78346998 3 P 0 
L 11.1622 2.78346998 11.17793996 2.76771998 3 P 0 
L 11.17793996 2.76771998 11.1622 2.76771998 3 P 0 
L 11.1622 2.76771998 11.1622 2.17383002 3 P 0 
L 11.1622 2.17383002 11.17793996 2.17383002 3 P 0 
L 11.17793996 2.17383002 11.1622 2.15808002 3 P 0 
L 11.1622 2.15808002 11.12676004 2.15808002 3 P 0 
L 11.12676004 2.15808002 11.12676004 1.99273002 3 P 0 
L 11.12676004 1.99273002 11.1622 1.99273002 3 P 0 
L 11.1622 1.99273002 11.17793996 1.97698002 3 P 0 
L 11.17793996 1.97698002 11.1622 1.97698002 3 P 0 
L 11.1622 1.97698002 11.14633996 1.99273002 3 P 0 
L 11.1622 3.56005 11.14645 3.5758 3 P 0 
L 11.14645 3.5758 11.14633996 2.94883002 3 P 0 
L 11.14633996 2.94883002 11.1622 2.96456998 3 P 0 
L 11.1622 2.94881998 11.1622 2.78346998 3 P 0 
L 11.1622 2.76771998 11.14645 2.78346998 3 P 0 
L 11.14645 2.78346998 11.14645 2.15808002 3 P 0 
L 11.14645 2.15808002 11.16218996 2.17383002 3 P 0 
L 11.1622 1.97698002 11.1622 1.87186004 3 P 0 
A 11.1622 1.87186004 11.08956004 1.79921998 11.08956004 1.87185994 3 P 0 Y
L 11.08956004 1.79921998 11.08936004 1.79921998 3 P 0 
L 11.08936004 1.79921998 10.96111998 1.79921998 3 P 0 
L 10.96111998 1.79921998 10.96111998 1.75788996 3 P 0 
L 10.96111998 1.75788996 10.71211004 1.75788996 3 P 0 
L 10.71211004 1.75788996 10.71211004 1.79921998 3 P 0 
L 10.71211004 1.79921998 10.58385 1.79921998 3 P 0 
L 10.58385 1.79921998 10.58366998 1.79921998 3 P 0 
A 10.58366998 1.79921998 10.51101998 1.87186004 10.58366004 1.87186004 3 P 0 Y
L 10.51101998 1.87186004 10.51101998 1.97708002 3 P 0 
A 11.14683002 3.86271004 11.12950719 3.90145246 11.09015 3.86061073 3 P 0 N
A 11.12950719 3.90145246 11.09015 3.91733002 11.09014921 3.86061004 3 P 0 N
L 11.09015 3.91733002 10.89616004 3.91733002 3 P 0 
L 10.89616004 3.91733002 10.89616004 3.95276004 3 P 0 
L 10.89616004 3.95276004 10.77706998 3.95276004 3 P 0 
L 10.77706998 3.95276004 10.77706998 3.91733002 3 P 0 
L 10.77706998 3.91733002 10.58386004 3.91733002 3 P 0 
A 10.58386004 3.91733002 10.52851998 3.86198996 10.58386004 3.86198996 3 P 0 N
L 10.52851998 3.86198996 10.52851998 3.74115 3 P 0 
L 10.75148002 3.93308002 10.76721998 3.91733002 3 P 0 
L 10.75393002 3.97245 10.77706998 3.95276004 3 P 0 
L 10.89616004 3.95276004 10.91928996 3.97245 3 P 0 
L 10.92175 3.93308002 10.906 3.91733002 3 P 0 
L 10.77706998 3.91733002 10.77706998 3.90158002 3 P 0 
L 10.77706998 3.90158002 10.89616004 3.90158002 3 P 0 
L 10.89616004 3.90158002 10.89616004 3.91733002 3 P 0 
L 10.71211004 1.79921998 10.72785 1.81496998 3 P 0 
A 10.52486998 1.87186004 10.58176004 1.81496998 10.58176004 1.87186004 3 P 0 N
L 10.58176004 1.81496998 10.58385 1.81496998 3 P 0 
L 10.58385 1.81496998 10.7377 1.81498002 3 P 0 
L 10.7377 1.81498002 10.73768996 1.83071998 3 P 0 
L 10.73768996 1.83071998 10.7377 1.77953996 3 P 0 
L 10.7377 1.77953996 10.93553002 1.77953996 3 P 0 
L 10.93553002 1.77953996 10.93553002 1.81498002 3 P 0 
L 10.93553002 1.81498002 11.08936004 1.81496998 3 P 0 
L 11.08936004 1.81496998 11.08946998 1.81496998 3 P 0 
A 11.08946998 1.81496998 11.14633996 1.87183996 11.08946998 1.87183996 3 P 0 N
L 10.93553002 1.81498002 10.93553002 1.83071998 3 P 0 
L 10.93553002 1.83071998 10.89615 1.83071998 3 P 0 
L 10.89615 1.83071998 10.77706004 1.83071998 3 P 0 
L 10.77706004 1.83071998 10.73768996 1.83071998 3 P 0 
L 10.96111998 1.79921998 10.94538002 1.81496998 3 P 0 
L 10.7377 1.77953996 10.71456004 1.75985 3 P 0 
L 10.95866004 1.75985 10.93553002 1.77953996 3 P 0 
L 10.52491998 1.87178002 10.52491998 1.99295 3 P 0 
L 11.14633996 2.06861004 11.14633996 2.06868996 2 P 8191 
L 11.1622 2.86528002 11.1622 2.94898002 3 P 0 
L 11.1622 1.99273002 11.1622 2.15808002 3 P 0 
L 11.14633996 1.87183996 11.14633996 1.99273002 3 P 0 
L 11.14683002 3.74115 11.14683002 3.86271004 3 P 0 
L 10.51101998 1.99273002 10.51101998 2.15808002 3 P 0 
L 10.51101998 2.76631004 10.51101998 2.74745 3 P 0 
L 10.51101998 2.9478 10.51101998 2.78461004 3 P 0 
L 10.51101998 3.55888996 10.51101998 2.96508996 3 P 0 
L 10.51101998 3.73971004 10.51101998 3.57635 3 P 0 
L 11.1622 3.75658996 11.1622 3.86043996 3 P 0 
A 11.1622 3.86043996 11.08955 3.93308002 11.08274085 3.85361998 3 P 0 N
L 11.08955 3.93308002 10.92175 3.93308002 3 P 0 
L 10.92175 3.93308002 10.92175 3.97441998 3 P 0 
L 10.92175 3.97441998 10.75148002 3.97441998 3 P 0 
L 10.75148002 3.97441998 10.75148002 3.93308002 3 P 0 
L 10.75148002 3.93308002 10.58366004 3.93308002 3 P 0 
A 10.58366004 3.93308002 10.51101998 3.86043996 10.58223002 3.86186998 3 P 0 N
L 10.51101998 3.86043996 10.51101998 3.75903002 3 P 0 
L 11.1622 3.57576004 11.1622 3.73935 3 P 0 
L 11.1622 2.96475 11.1622 3.55796004 3 P 0 
L 11.17383317 1.76639961 11.1757501 1.76319931 2 P 0 ;0,1=308,2=0.000000
L 11.1757501 1.76319931 11.17804961 1.76106644 2 P 0 ;0,1=308,2=0.000000
L 11.17804961 1.76106644 11.18073307 1.76 2 P 0 ;0,1=308,2=0.000000
L 11.18073307 1.76 11.1837998 1.76106644 2 P 0 ;0,1=308,2=0.000000
L 11.1837998 1.76106644 11.1861 1.76319931 2 P 0 ;0,1=308,2=0.000000
L 11.1861 1.76319931 11.1884002 1.76639961 2 P 0 ;0,1=308,2=0.000000
L 11.1884002 1.76639961 11.18916673 1.77066634 2 P 0 ;0,1=308,2=0.000000
L 11.18916673 1.77066634 11.18916673 1.792 2 P 0 ;0,1=308,2=0.000000
L 11.201 1.74933366 11.224 1.74933366 2 P 0 ;0,1=308,2=0.000000
L 11.23583317 1.76 11.23583317 1.792 2 P 0 ;0,1=308,2=0.000000
L 11.23583317 1.792 11.24503327 1.792 2 P 0 ;0,1=308,2=0.000000
L 11.24503327 1.792 11.2481 1.79039931 2 P 0 ;0,1=308,2=0.000000
L 11.2481 1.79039931 11.2504002 1.78666673 2 P 0 ;0,1=308,2=0.000000
L 11.2504002 1.78666673 11.25116673 1.7824 2 P 0 ;0,1=308,2=0.000000
L 11.25116673 1.7824 11.2504002 1.77813327 2 P 0 ;0,1=308,2=0.000000
L 11.2504002 1.77813327 11.24848327 1.77493307 2 P 0 ;0,1=308,2=0.000000
L 11.24848327 1.77493307 11.24503327 1.77333238 2 P 0 ;0,1=308,2=0.000000
L 11.24503327 1.77333238 11.23583317 1.77333238 2 P 0 ;0,1=308,2=0.000000
L 11.28216673 1.76 11.26683317 1.76 2 P 0 ;0,1=308,2=0.000000
L 11.26683317 1.76 11.26683317 1.792 2 P 0 ;0,1=308,2=0.000000
L 11.26683317 1.792 11.28216673 1.792 2 P 0 ;0,1=308,2=0.000000
L 11.27603327 1.77653366 11.26683317 1.77653366 2 P 0 ;0,1=308,2=0.000000
L 11.2974499 1.76 11.31355 1.792 2 P 0 ;0,1=308,2=0.000000
L 11.2974499 1.792 11.31355 1.76 2 P 0 ;0,1=308,2=0.000000
L 11.325 1.74933366 11.348 1.74933366 2 P 0 ;0,1=308,2=0.000000
L 11.3697998 1.77599951 11.37746693 1.77599951 2 P 0 ;0,1=308,2=0.000000
L 11.37746693 1.77599951 11.37746693 1.76639961 2 P 0 ;0,1=308,2=0.000000
L 11.37746693 1.76639961 11.37516673 1.76319931 2 P 0 ;0,1=308,2=0.000000
L 11.37516673 1.76319931 11.37248327 1.76106644 2 P 0 ;0,1=308,2=0.000000
L 11.37248327 1.76106644 11.3686501 1.76 2 P 0 ;0,1=308,2=0.000000
L 11.3686501 1.76 11.36481683 1.76106644 2 P 0 ;0,1=308,2=0.000000
L 11.36481683 1.76106644 11.36213337 1.76319931 2 P 0 ;0,1=308,2=0.000000
L 11.36213337 1.76319931 11.35983317 1.76639961 2 P 0 ;0,1=308,2=0.000000
L 11.35983317 1.76639961 11.35829951 1.77013307 2 P 0 ;0,1=308,2=0.000000
L 11.35829951 1.77013307 11.35753297 1.7743998 2 P 0 ;0,1=308,2=0.000000
L 11.35753297 1.7743998 11.35753297 1.77813327 2 P 0 ;0,1=308,2=0.000000
L 11.35753297 1.77813327 11.35829951 1.78133268 2 P 0 ;0,1=308,2=0.000000
L 11.35829951 1.78133268 11.35983317 1.78506713 2 P 0 ;0,1=308,2=0.000000
L 11.35983317 1.78506713 11.36213337 1.78826644 2 P 0 ;0,1=308,2=0.000000
L 11.36213337 1.78826644 11.36443287 1.79039931 2 P 0 ;0,1=308,2=0.000000
L 11.36443287 1.79039931 11.36749961 1.792 2 P 0 ;0,1=308,2=0.000000
L 11.36749961 1.792 11.37018307 1.792 2 P 0 ;0,1=308,2=0.000000
L 11.37018307 1.792 11.3732498 1.79093346 2 P 0 ;0,1=308,2=0.000000
L 11.3732498 1.79093346 11.37555 1.7887997 2 P 0 ;0,1=308,2=0.000000
L 11.39083317 1.76 11.39083317 1.792 2 P 0 ;0,1=308,2=0.000000
L 11.39083317 1.792 11.40003327 1.792 2 P 0 ;0,1=308,2=0.000000
L 11.40003327 1.792 11.4031 1.79039931 2 P 0 ;0,1=308,2=0.000000
L 11.4031 1.79039931 11.4054002 1.78666673 2 P 0 ;0,1=308,2=0.000000
L 11.4054002 1.78666673 11.40616673 1.7824 2 P 0 ;0,1=308,2=0.000000
L 11.40616673 1.7824 11.4054002 1.77813327 2 P 0 ;0,1=308,2=0.000000
L 11.4054002 1.77813327 11.40348327 1.77493307 2 P 0 ;0,1=308,2=0.000000
L 11.40348327 1.77493307 11.40003327 1.77333238 2 P 0 ;0,1=308,2=0.000000
L 11.40003327 1.77333238 11.39083317 1.77333238 2 P 0 ;0,1=308,2=0.000000
L 11.42106663 1.792 11.42106663 1.76906663 2 P 0 ;0,1=308,2=0.000000
L 11.42106663 1.76906663 11.4225997 1.76426575 2 P 0 ;0,1=308,2=0.000000
L 11.4225997 1.76426575 11.42566634 1.76106644 2 P 0 ;0,1=308,2=0.000000
L 11.42566634 1.76106644 11.42949961 1.76 2 P 0 ;0,1=308,2=0.000000
L 11.42949961 1.76 11.43333356 1.76106644 2 P 0 ;0,1=308,2=0.000000
L 11.43333356 1.76106644 11.4364002 1.76426575 2 P 0 ;0,1=308,2=0.000000
L 11.4364002 1.76426575 11.43793327 1.76906663 2 P 0 ;0,1=308,2=0.000000
L 11.43793327 1.76906663 11.43793327 1.792 2 P 0 ;0,1=308,2=0.000000
L 11.46049961 1.76 11.46049961 1.792 2 P 0 ;0,1=308,2=0.000000
L 11.46049961 1.792 11.4558999 1.7856003 2 P 0 ;0,1=308,2=0.000000
L 11.4558999 1.76 11.46509931 1.76 2 P 0 ;0,1=308,2=0.000000
L 11.23732972 1.87671998 11.23732972 1.90171998 2 P 0 ;0,1=52,2=0.000000
L 11.23732972 1.90171998 11.23412992 1.89672028 2 P 0 ;0,1=52,2=0.000000
L 11.23412992 1.87671998 11.24052953 1.87671998 2 P 0 ;0,1=52,2=0.000000
L 11.20863317 1.94755335 11.21023327 1.95005285 2 P 0 ;0,1=53,2=0.000000
L 11.21023327 1.95005285 11.2121 1.95130335 2 P 0 ;0,1=53,2=0.000000
L 11.2121 1.95130335 11.21423337 1.95171998 2 P 0 ;0,1=53,2=0.000000
L 11.21423337 1.95171998 11.2169 1.95088681 2 P 0 ;0,1=53,2=0.000000
L 11.2169 1.95088681 11.21876673 1.94880315 2 P 0 ;0,1=53,2=0.000000
L 11.21876673 1.94880315 11.2193 1.94630364 2 P 0 ;0,1=53,2=0.000000
L 11.2193 1.94630364 11.21903337 1.94380266 2 P 0 ;0,1=53,2=0.000000
L 11.21903337 1.94380266 11.21796644 1.94171978 2 P 0 ;0,1=53,2=0.000000
L 11.21796644 1.94171978 11.21263327 1.93755325 2 P 0 ;0,1=53,2=0.000000
L 11.21263327 1.93755325 11.21023327 1.93463642 2 P 0 ;0,1=53,2=0.000000
L 11.21023327 1.93463642 11.20863317 1.93046909 2 P 0 ;0,1=53,2=0.000000
L 11.20863317 1.93046909 11.2080999 1.92671998 2 P 0 ;0,1=53,2=0.000000
L 11.2080999 1.92671998 11.2193 1.92671998 2 P 0 ;0,1=53,2=0.000000
L 11.23146329 1.98171959 11.23306299 1.97880285 2 P 0 ;0,1=57,2=0.000000
L 11.23306299 1.97880285 11.23519636 1.97713652 2 P 0 ;0,1=57,2=0.000000
L 11.23519636 1.97713652 11.23759685 1.97671998 2 P 0 ;0,1=57,2=0.000000
L 11.23759685 1.97671998 11.23973022 1.97713652 2 P 0 ;0,1=57,2=0.000000
L 11.23973022 1.97713652 11.24186358 1.97921939 2 P 0 ;0,1=57,2=0.000000
L 11.24186358 1.97921939 11.24319665 1.98171959 2 P 0 ;0,1=57,2=0.000000
L 11.24319665 1.98171959 11.24346319 1.98421988 2 P 0 ;0,1=57,2=0.000000
L 11.24346319 1.98421988 11.24293002 1.98713593 2 P 0 ;0,1=57,2=0.000000
L 11.24293002 1.98713593 11.24106329 1.98921959 2 P 0 ;0,1=57,2=0.000000
L 11.24106329 1.98921959 11.23919646 1.99005344 2 P 0 ;0,1=57,2=0.000000
L 11.23919646 1.99005344 11.23679656 1.99005344 2 P 0 ;0,1=57,2=0.000000
L 11.23919646 1.99005344 11.24079665 1.99130325 2 P 0 ;0,1=57,2=0.000000
L 11.24079665 1.99130325 11.24213012 1.99338612 2 P 0 ;0,1=57,2=0.000000
L 11.24213012 1.99338612 11.24266339 1.99588632 2 P 0 ;0,1=57,2=0.000000
L 11.24266339 1.99588632 11.24213012 1.99838652 2 P 0 ;0,1=57,2=0.000000
L 11.24213012 1.99838652 11.24079665 2.00046939 2 P 0 ;0,1=57,2=0.000000
L 11.24079665 2.00046939 11.23839665 2.00171998 2 P 0 ;0,1=57,2=0.000000
L 11.23839665 2.00171998 11.23599665 2.00130335 2 P 0 ;0,1=57,2=0.000000
L 11.23599665 2.00130335 11.23359665 1.99963632 2 P 0 ;0,1=57,2=0.000000
L 11.2169 2.02671998 11.2169 2.05171998 2 P 0 ;0,1=58,2=0.000000
L 11.2169 2.05171998 11.20703297 2.03380325 2 P 0 ;0,1=58,2=0.000000
L 11.20703297 2.03380325 11.22036693 2.03380325 2 P 0 ;0,1=58,2=0.000000
L 11.23146329 2.08046909 11.23306299 2.07838622 2 P 0 ;0,1=273,2=0.000000
L 11.23306299 2.07838622 11.23492972 2.07713652 2 P 0 ;0,1=273,2=0.000000
L 11.23492972 2.07713652 11.23732972 2.07671998 2 P 0 ;0,1=273,2=0.000000
L 11.23732972 2.07671998 11.23973022 2.07755305 2 P 0 ;0,1=273,2=0.000000
L 11.23973022 2.07755305 11.24159646 2.07921939 2 P 0 ;0,1=273,2=0.000000
L 11.24159646 2.07921939 11.24293002 2.08213622 2 P 0 ;0,1=273,2=0.000000
L 11.24293002 2.08213622 11.24319665 2.08546959 2 P 0 ;0,1=273,2=0.000000
L 11.24319665 2.08546959 11.24266339 2.08880295 2 P 0 ;0,1=273,2=0.000000
L 11.24266339 2.08880295 11.24132982 2.09088661 2 P 0 ;0,1=273,2=0.000000
L 11.24132982 2.09088661 11.23946309 2.09255295 2 P 0 ;0,1=273,2=0.000000
L 11.23946309 2.09255295 11.23759685 2.09296949 2 P 0 ;0,1=273,2=0.000000
L 11.23759685 2.09296949 11.23573002 2.09255295 2 P 0 ;0,1=273,2=0.000000
L 11.23573002 2.09255295 11.23333012 2.09088661 2 P 0 ;0,1=273,2=0.000000
L 11.23333012 2.09088661 11.23412992 2.10171998 2 P 0 ;0,1=273,2=0.000000
L 11.23412992 2.10171998 11.24132982 2.10171998 2 P 0 ;0,1=273,2=0.000000
L 11.20863317 2.13713593 11.2104999 2.14005344 2 P 0 ;0,1=274,2=0.000000
L 11.2104999 2.14005344 11.2121 2.14171978 2 P 0 ;0,1=274,2=0.000000
L 11.2121 2.14171978 11.21423337 2.14255295 2 P 0 ;0,1=274,2=0.000000
L 11.21423337 2.14255295 11.2161002 2.14171978 2 P 0 ;0,1=274,2=0.000000
L 11.2161002 2.14171978 11.21743327 2.14005344 2 P 0 ;0,1=274,2=0.000000
L 11.21743327 2.14005344 11.2185001 2.13755325 2 P 0 ;0,1=274,2=0.000000
L 11.2185001 2.13755325 11.21876673 2.13463642 2 P 0 ;0,1=274,2=0.000000
L 11.21876673 2.13463642 11.2185001 2.13213622 2 P 0 ;0,1=274,2=0.000000
L 11.2185001 2.13213622 11.21743327 2.12963602 2 P 0 ;0,1=274,2=0.000000
L 11.21743327 2.12963602 11.21583307 2.12755305 2 P 0 ;0,1=274,2=0.000000
L 11.21583307 2.12755305 11.21396683 2.12671998 2 P 0 ;0,1=274,2=0.000000
L 11.21396683 2.12671998 11.21183346 2.12755305 2 P 0 ;0,1=274,2=0.000000
L 11.21183346 2.12755305 11.20996663 2.13005256 2 P 0 ;0,1=274,2=0.000000
L 11.20996663 2.13005256 11.2088998 2.13380325 2 P 0 ;0,1=274,2=0.000000
L 11.2088998 2.13380325 11.20863317 2.13796978 2 P 0 ;0,1=274,2=0.000000
L 11.20863317 2.13796978 11.20916634 2.14338612 2 P 0 ;0,1=274,2=0.000000
L 11.20916634 2.14338612 11.20996663 2.14630364 2 P 0 ;0,1=274,2=0.000000
L 11.20996663 2.14630364 11.2112997 2.14921969 2 P 0 ;0,1=274,2=0.000000
L 11.2112997 2.14921969 11.21316654 2.15130335 2 P 0 ;0,1=274,2=0.000000
L 11.21316654 2.15130335 11.21503327 2.15171998 2 P 0 ;0,1=274,2=0.000000
L 11.21503327 2.15171998 11.2169 2.15088681 2 P 0 ;0,1=274,2=0.000000
L 11.2169 2.15088681 11.21823356 2.14880315 2 P 0 ;0,1=274,2=0.000000
L 11.23679656 2.17671998 11.23732972 2.18213622 2 P 0 ;0,1=275,2=0.000000
L 11.23732972 2.18213622 11.23813002 2.18671929 2 P 0 ;0,1=275,2=0.000000
L 11.23813002 2.18671929 11.23919646 2.19088661 2 P 0 ;0,1=275,2=0.000000
L 11.23919646 2.19088661 11.24053002 2.19546978 2 P 0 ;0,1=275,2=0.000000
L 11.24053002 2.19546978 11.24266339 2.20171998 2 P 0 ;0,1=275,2=0.000000
L 11.24266339 2.20171998 11.23199656 2.20171998 2 P 0 ;0,1=275,2=0.000000
L 11.2136997 2.22671998 11.21556644 2.22713652 2 P 0 ;0,1=276,2=0.000000
L 11.21556644 2.22713652 11.2176998 2.22838622 2 P 0 ;0,1=276,2=0.000000
L 11.2176998 2.22838622 11.21903337 2.23046909 2 P 0 ;0,1=276,2=0.000000
L 11.21903337 2.23046909 11.21956663 2.23338671 2 P 0 ;0,1=276,2=0.000000
L 11.21956663 2.23338671 11.21903337 2.23630276 2 P 0 ;0,1=276,2=0.000000
L 11.21903337 2.23630276 11.21743327 2.23880295 2 P 0 ;0,1=276,2=0.000000
L 11.21743327 2.23880295 11.21503327 2.24005344 2 P 0 ;0,1=276,2=0.000000
L 11.21503327 2.24005344 11.21236663 2.24005344 2 P 0 ;0,1=276,2=0.000000
L 11.21236663 2.24005344 11.21076654 2.24088661 2 P 0 ;0,1=276,2=0.000000
L 11.21076654 2.24088661 11.20943297 2.24296949 2 P 0 ;0,1=276,2=0.000000
L 11.20943297 2.24296949 11.2088998 2.24588632 2 P 0 ;0,1=276,2=0.000000
L 11.2088998 2.24588632 11.2097001 2.24880315 2 P 0 ;0,1=276,2=0.000000
L 11.2097001 2.24880315 11.21156634 2.25088681 2 P 0 ;0,1=276,2=0.000000
L 11.21156634 2.25088681 11.2136997 2.25171998 2 P 0 ;0,1=276,2=0.000000
L 11.2136997 2.25171998 11.21583307 2.25088681 2 P 0 ;0,1=276,2=0.000000
L 11.21583307 2.25088681 11.2176998 2.24880315 2 P 0 ;0,1=276,2=0.000000
L 11.2176998 2.24880315 11.2185001 2.24588632 2 P 0 ;0,1=276,2=0.000000
L 11.2185001 2.24588632 11.21796644 2.24296949 2 P 0 ;0,1=276,2=0.000000
L 11.21796644 2.24296949 11.21663337 2.24088661 2 P 0 ;0,1=276,2=0.000000
L 11.21663337 2.24088661 11.21503327 2.24005344 2 P 0 ;0,1=276,2=0.000000
L 11.21503327 2.24005344 11.21236663 2.24005344 2 P 0 ;0,1=276,2=0.000000
L 11.21236663 2.24005344 11.20996663 2.23880295 2 P 0 ;0,1=276,2=0.000000
L 11.20996663 2.23880295 11.20836654 2.23630276 2 P 0 ;0,1=276,2=0.000000
L 11.20836654 2.23630276 11.20783327 2.23338671 2 P 0 ;0,1=276,2=0.000000
L 11.20783327 2.23338671 11.20836654 2.23046909 2 P 0 ;0,1=276,2=0.000000
L 11.20836654 2.23046909 11.2097001 2.22838622 2 P 0 ;0,1=276,2=0.000000
L 11.2097001 2.22838622 11.21183346 2.22713652 2 P 0 ;0,1=276,2=0.000000
L 11.21183346 2.22713652 11.2136997 2.22671998 2 P 0 ;0,1=276,2=0.000000
L 11.23279636 2.27963602 11.23466319 2.27755305 2 P 0 ;0,1=28,2=0.000000
L 11.23466319 2.27755305 11.23679656 2.27671998 2 P 0 ;0,1=28,2=0.000000
L 11.23679656 2.27671998 11.23892992 2.27755305 2 P 0 ;0,1=28,2=0.000000
L 11.23892992 2.27755305 11.24079665 2.28005256 2 P 0 ;0,1=28,2=0.000000
L 11.24079665 2.28005256 11.24213012 2.28380325 2 P 0 ;0,1=28,2=0.000000
L 11.24213012 2.28380325 11.24266339 2.28755325 2 P 0 ;0,1=28,2=0.000000
L 11.24266339 2.28755325 11.24266339 2.29213632 2 P 0 ;0,1=28,2=0.000000
L 11.24266339 2.29213632 11.24213012 2.29588632 2 P 0 ;0,1=28,2=0.000000
L 11.24213012 2.29588632 11.24079665 2.29921969 2 P 0 ;0,1=28,2=0.000000
L 11.24079665 2.29921969 11.23919646 2.30088681 2 P 0 ;0,1=28,2=0.000000
L 11.23919646 2.30088681 11.23732972 2.30171998 2 P 0 ;0,1=28,2=0.000000
L 11.23732972 2.30171998 11.23519636 2.30088681 2 P 0 ;0,1=28,2=0.000000
L 11.23519636 2.30088681 11.23359665 2.29921969 2 P 0 ;0,1=28,2=0.000000
L 11.23359665 2.29921969 11.23252982 2.29672028 2 P 0 ;0,1=28,2=0.000000
L 11.23252982 2.29672028 11.23199656 2.29338612 2 P 0 ;0,1=28,2=0.000000
L 11.23199656 2.29338612 11.23252982 2.29047008 2 P 0 ;0,1=28,2=0.000000
L 11.23252982 2.29047008 11.23386329 2.28755325 2 P 0 ;0,1=28,2=0.000000
L 11.23386329 2.28755325 11.23546348 2.28588612 2 P 0 ;0,1=28,2=0.000000
L 11.23546348 2.28588612 11.23732972 2.28546959 2 P 0 ;0,1=28,2=0.000000
L 11.23732972 2.28546959 11.23946309 2.28630276 2 P 0 ;0,1=28,2=0.000000
L 11.23946309 2.28630276 11.24106329 2.28838642 2 P 0 ;0,1=28,2=0.000000
L 11.24106329 2.28838642 11.24266339 2.29213632 2 P 0 ;0,1=28,2=0.000000
L 11.2136997 2.31671998 11.2136997 2.34171998 2 P 0 ;0,1=26,2=0.000000
L 11.2136997 2.34171998 11.2104999 2.33672028 2 P 0 ;0,1=26,2=0.000000
L 11.2104999 2.31671998 11.21689951 2.31671998 2 P 0 ;0,1=26,2=0.000000
L 11.2376997 2.34171998 11.23556634 2.34088681 2 P 0 ;0,1=26,2=0.000000
L 11.23556634 2.34088681 11.23396663 2.33880315 2 P 0 ;0,1=26,2=0.000000
L 11.23396663 2.33880315 11.2328998 2.33630364 2 P 0 ;0,1=26,2=0.000000
L 11.2328998 2.33630364 11.2320999 2.33296949 2 P 0 ;0,1=26,2=0.000000
L 11.2320999 2.33296949 11.23183327 2.32921959 2 P 0 ;0,1=26,2=0.000000
L 11.23183327 2.32921959 11.2320999 2.32546959 2 P 0 ;0,1=26,2=0.000000
L 11.2320999 2.32546959 11.2328998 2.32213622 2 P 0 ;0,1=26,2=0.000000
L 11.2328998 2.32213622 11.23396663 2.31963602 2 P 0 ;0,1=26,2=0.000000
L 11.23396663 2.31963602 11.23556634 2.31755305 2 P 0 ;0,1=26,2=0.000000
L 11.23556634 2.31755305 11.2376997 2.31671998 2 P 0 ;0,1=26,2=0.000000
L 11.2376997 2.31671998 11.23983307 2.31755305 2 P 0 ;0,1=26,2=0.000000
L 11.23983307 2.31755305 11.24143327 2.31963602 2 P 0 ;0,1=26,2=0.000000
L 11.24143327 2.31963602 11.2425001 2.32213622 2 P 0 ;0,1=26,2=0.000000
L 11.2425001 2.32213622 11.2433 2.32546959 2 P 0 ;0,1=26,2=0.000000
L 11.2433 2.32546959 11.24356663 2.32921959 2 P 0 ;0,1=26,2=0.000000
L 11.24356663 2.32921959 11.2433 2.33296949 2 P 0 ;0,1=26,2=0.000000
L 11.2433 2.33296949 11.2425001 2.33630364 2 P 0 ;0,1=26,2=0.000000
L 11.2425001 2.33630364 11.24143327 2.33880315 2 P 0 ;0,1=26,2=0.000000
L 11.24143327 2.33880315 11.23983307 2.34088681 2 P 0 ;0,1=26,2=0.000000
L 11.23983307 2.34088681 11.2376997 2.34171998 2 P 0 ;0,1=26,2=0.000000
L 11.23732972 2.36671998 11.23732972 2.39171998 2 P 0 ;0,1=277,2=0.000000
L 11.23732972 2.39171998 11.23412992 2.38672028 2 P 0 ;0,1=277,2=0.000000
L 11.23412992 2.36671998 11.24052953 2.36671998 2 P 0 ;0,1=277,2=0.000000
L 11.26132972 2.36671998 11.26132972 2.39171998 2 P 0 ;0,1=277,2=0.000000
L 11.26132972 2.39171998 11.25812992 2.38672028 2 P 0 ;0,1=277,2=0.000000
L 11.25812992 2.36671998 11.26452953 2.36671998 2 P 0 ;0,1=277,2=0.000000
L 11.2136997 2.41671998 11.2136997 2.44171998 2 P 0 ;0,1=278,2=0.000000
L 11.2136997 2.44171998 11.2104999 2.43672028 2 P 0 ;0,1=278,2=0.000000
L 11.2104999 2.41671998 11.21689951 2.41671998 2 P 0 ;0,1=278,2=0.000000
L 11.23263317 2.43755335 11.23423327 2.44005285 2 P 0 ;0,1=278,2=0.000000
L 11.23423327 2.44005285 11.2361 2.44130335 2 P 0 ;0,1=278,2=0.000000
L 11.2361 2.44130335 11.23823337 2.44171998 2 P 0 ;0,1=278,2=0.000000
L 11.23823337 2.44171998 11.2409 2.44088681 2 P 0 ;0,1=278,2=0.000000
L 11.2409 2.44088681 11.24276673 2.43880315 2 P 0 ;0,1=278,2=0.000000
L 11.24276673 2.43880315 11.2433 2.43630364 2 P 0 ;0,1=278,2=0.000000
L 11.2433 2.43630364 11.24303337 2.43380266 2 P 0 ;0,1=278,2=0.000000
L 11.24303337 2.43380266 11.24196644 2.43171978 2 P 0 ;0,1=278,2=0.000000
L 11.24196644 2.43171978 11.23663327 2.42755325 2 P 0 ;0,1=278,2=0.000000
L 11.23663327 2.42755325 11.23423327 2.42463642 2 P 0 ;0,1=278,2=0.000000
L 11.23423327 2.42463642 11.23263317 2.42046909 2 P 0 ;0,1=278,2=0.000000
L 11.23263317 2.42046909 11.2320999 2.41671998 2 P 0 ;0,1=278,2=0.000000
L 11.2320999 2.41671998 11.2433 2.41671998 2 P 0 ;0,1=278,2=0.000000
L 11.23732972 2.46671998 11.23732972 2.49171998 2 P 0 ;0,1=279,2=0.000000
L 11.23732972 2.49171998 11.23412992 2.48672028 2 P 0 ;0,1=279,2=0.000000
L 11.23412992 2.46671998 11.24052953 2.46671998 2 P 0 ;0,1=279,2=0.000000
L 11.25546329 2.47171959 11.25706299 2.46880285 2 P 0 ;0,1=279,2=0.000000
L 11.25706299 2.46880285 11.25919636 2.46713652 2 P 0 ;0,1=279,2=0.000000
L 11.25919636 2.46713652 11.26159685 2.46671998 2 P 0 ;0,1=279,2=0.000000
L 11.26159685 2.46671998 11.26373022 2.46713652 2 P 0 ;0,1=279,2=0.000000
L 11.26373022 2.46713652 11.26586358 2.46921939 2 P 0 ;0,1=279,2=0.000000
L 11.26586358 2.46921939 11.26719665 2.47171959 2 P 0 ;0,1=279,2=0.000000
L 11.26719665 2.47171959 11.26746319 2.47421988 2 P 0 ;0,1=279,2=0.000000
L 11.26746319 2.47421988 11.26693002 2.47713593 2 P 0 ;0,1=279,2=0.000000
L 11.26693002 2.47713593 11.26506329 2.47921959 2 P 0 ;0,1=279,2=0.000000
L 11.26506329 2.47921959 11.26319646 2.48005344 2 P 0 ;0,1=279,2=0.000000
L 11.26319646 2.48005344 11.26079656 2.48005344 2 P 0 ;0,1=279,2=0.000000
L 11.26319646 2.48005344 11.26479665 2.48130325 2 P 0 ;0,1=279,2=0.000000
L 11.26479665 2.48130325 11.26613012 2.48338612 2 P 0 ;0,1=279,2=0.000000
L 11.26613012 2.48338612 11.26666339 2.48588632 2 P 0 ;0,1=279,2=0.000000
L 11.26666339 2.48588632 11.26613012 2.48838652 2 P 0 ;0,1=279,2=0.000000
L 11.26613012 2.48838652 11.26479665 2.49046939 2 P 0 ;0,1=279,2=0.000000
L 11.26479665 2.49046939 11.26239665 2.49171998 2 P 0 ;0,1=279,2=0.000000
L 11.26239665 2.49171998 11.25999665 2.49130335 2 P 0 ;0,1=279,2=0.000000
L 11.25999665 2.49130335 11.25759665 2.48963632 2 P 0 ;0,1=279,2=0.000000
L 11.2136997 2.51671998 11.2136997 2.54171998 2 P 0 ;0,1=63,2=0.000000
L 11.2136997 2.54171998 11.2104999 2.53672028 2 P 0 ;0,1=63,2=0.000000
L 11.2104999 2.51671998 11.21689951 2.51671998 2 P 0 ;0,1=63,2=0.000000
L 11.2409 2.51671998 11.2409 2.54171998 2 P 0 ;0,1=63,2=0.000000
L 11.2409 2.54171998 11.23103297 2.52380325 2 P 0 ;0,1=63,2=0.000000
L 11.23103297 2.52380325 11.24436693 2.52380325 2 P 0 ;0,1=63,2=0.000000
L 11.23732972 2.56671998 11.23732972 2.59171998 2 P 0 ;0,1=280,2=0.000000
L 11.23732972 2.59171998 11.23412992 2.58672028 2 P 0 ;0,1=280,2=0.000000
L 11.23412992 2.56671998 11.24052953 2.56671998 2 P 0 ;0,1=280,2=0.000000
L 11.25546329 2.57046909 11.25706299 2.56838622 2 P 0 ;0,1=280,2=0.000000
L 11.25706299 2.56838622 11.25892972 2.56713652 2 P 0 ;0,1=280,2=0.000000
L 11.25892972 2.56713652 11.26132972 2.56671998 2 P 0 ;0,1=280,2=0.000000
L 11.26132972 2.56671998 11.26373022 2.56755305 2 P 0 ;0,1=280,2=0.000000
L 11.26373022 2.56755305 11.26559646 2.56921939 2 P 0 ;0,1=280,2=0.000000
L 11.26559646 2.56921939 11.26693002 2.57213622 2 P 0 ;0,1=280,2=0.000000
L 11.26693002 2.57213622 11.26719665 2.57546959 2 P 0 ;0,1=280,2=0.000000
L 11.26719665 2.57546959 11.26666339 2.57880295 2 P 0 ;0,1=280,2=0.000000
L 11.26666339 2.57880295 11.26532982 2.58088661 2 P 0 ;0,1=280,2=0.000000
L 11.26532982 2.58088661 11.26346309 2.58255295 2 P 0 ;0,1=280,2=0.000000
L 11.26346309 2.58255295 11.26159685 2.58296949 2 P 0 ;0,1=280,2=0.000000
L 11.26159685 2.58296949 11.25973002 2.58255295 2 P 0 ;0,1=280,2=0.000000
L 11.25973002 2.58255295 11.25733012 2.58088661 2 P 0 ;0,1=280,2=0.000000
L 11.25733012 2.58088661 11.25812992 2.59171998 2 P 0 ;0,1=280,2=0.000000
L 11.25812992 2.59171998 11.26532982 2.59171998 2 P 0 ;0,1=280,2=0.000000
L 11.2136997 2.61671998 11.2136997 2.64171998 2 P 0 ;0,1=281,2=0.000000
L 11.2136997 2.64171998 11.2104999 2.63672028 2 P 0 ;0,1=281,2=0.000000
L 11.2104999 2.61671998 11.21689951 2.61671998 2 P 0 ;0,1=281,2=0.000000
L 11.23263317 2.62713593 11.2344999 2.63005344 2 P 0 ;0,1=281,2=0.000000
L 11.2344999 2.63005344 11.2361 2.63171978 2 P 0 ;0,1=281,2=0.000000
L 11.2361 2.63171978 11.23823337 2.63255295 2 P 0 ;0,1=281,2=0.000000
L 11.23823337 2.63255295 11.2401002 2.63171978 2 P 0 ;0,1=281,2=0.000000
L 11.2401002 2.63171978 11.24143327 2.63005344 2 P 0 ;0,1=281,2=0.000000
L 11.24143327 2.63005344 11.2425001 2.62755325 2 P 0 ;0,1=281,2=0.000000
L 11.2425001 2.62755325 11.24276673 2.62463642 2 P 0 ;0,1=281,2=0.000000
L 11.24276673 2.62463642 11.2425001 2.62213622 2 P 0 ;0,1=281,2=0.000000
L 11.2425001 2.62213622 11.24143327 2.61963602 2 P 0 ;0,1=281,2=0.000000
L 11.24143327 2.61963602 11.23983307 2.61755305 2 P 0 ;0,1=281,2=0.000000
L 11.23983307 2.61755305 11.23796683 2.61671998 2 P 0 ;0,1=281,2=0.000000
L 11.23796683 2.61671998 11.23583346 2.61755305 2 P 0 ;0,1=281,2=0.000000
L 11.23583346 2.61755305 11.23396663 2.62005256 2 P 0 ;0,1=281,2=0.000000
L 11.23396663 2.62005256 11.2328998 2.62380325 2 P 0 ;0,1=281,2=0.000000
L 11.2328998 2.62380325 11.23263317 2.62796978 2 P 0 ;0,1=281,2=0.000000
L 11.23263317 2.62796978 11.23316634 2.63338612 2 P 0 ;0,1=281,2=0.000000
L 11.23316634 2.63338612 11.23396663 2.63630364 2 P 0 ;0,1=281,2=0.000000
L 11.23396663 2.63630364 11.2352997 2.63921969 2 P 0 ;0,1=281,2=0.000000
L 11.2352997 2.63921969 11.23716654 2.64130335 2 P 0 ;0,1=281,2=0.000000
L 11.23716654 2.64130335 11.23903327 2.64171998 2 P 0 ;0,1=281,2=0.000000
L 11.23903327 2.64171998 11.2409 2.64088681 2 P 0 ;0,1=281,2=0.000000
L 11.2409 2.64088681 11.24223356 2.63880315 2 P 0 ;0,1=281,2=0.000000
L 11.2129997 2.665 11.2129997 2.69 2 P 0 ;0,1=282,2=0.000000
L 11.2129997 2.69 11.2097999 2.6850003 2 P 0 ;0,1=282,2=0.000000
L 11.2097999 2.665 11.21619951 2.665 2 P 0 ;0,1=282,2=0.000000
L 11.23646654 2.665 11.2369997 2.67041624 2 P 0 ;0,1=282,2=0.000000
L 11.2369997 2.67041624 11.2378 2.67499931 2 P 0 ;0,1=282,2=0.000000
L 11.2378 2.67499931 11.23886644 2.67916663 2 P 0 ;0,1=282,2=0.000000
L 11.23886644 2.67916663 11.2402 2.6837498 2 P 0 ;0,1=282,2=0.000000
L 11.2402 2.6837498 11.24233337 2.69 2 P 0 ;0,1=282,2=0.000000
L 11.24233337 2.69 11.23166654 2.69 2 P 0 ;0,1=282,2=0.000000
L 11.2136997 2.71671998 11.2136997 2.74171998 2 P 0 ;0,1=27,2=0.000000
L 11.2136997 2.74171998 11.2104999 2.73672028 2 P 0 ;0,1=27,2=0.000000
L 11.2104999 2.71671998 11.21689951 2.71671998 2 P 0 ;0,1=27,2=0.000000
L 11.2376997 2.71671998 11.23956644 2.71713652 2 P 0 ;0,1=27,2=0.000000
L 11.23956644 2.71713652 11.2416998 2.71838622 2 P 0 ;0,1=27,2=0.000000
L 11.2416998 2.71838622 11.24303337 2.72046909 2 P 0 ;0,1=27,2=0.000000
L 11.24303337 2.72046909 11.24356663 2.72338671 2 P 0 ;0,1=27,2=0.000000
L 11.24356663 2.72338671 11.24303337 2.72630276 2 P 0 ;0,1=27,2=0.000000
L 11.24303337 2.72630276 11.24143327 2.72880295 2 P 0 ;0,1=27,2=0.000000
L 11.24143327 2.72880295 11.23903327 2.73005344 2 P 0 ;0,1=27,2=0.000000
L 11.23903327 2.73005344 11.23636663 2.73005344 2 P 0 ;0,1=27,2=0.000000
L 11.23636663 2.73005344 11.23476654 2.73088661 2 P 0 ;0,1=27,2=0.000000
L 11.23476654 2.73088661 11.23343297 2.73296949 2 P 0 ;0,1=27,2=0.000000
L 11.23343297 2.73296949 11.2328998 2.73588632 2 P 0 ;0,1=27,2=0.000000
L 11.2328998 2.73588632 11.2337001 2.73880315 2 P 0 ;0,1=27,2=0.000000
L 11.2337001 2.73880315 11.23556634 2.74088681 2 P 0 ;0,1=27,2=0.000000
L 11.23556634 2.74088681 11.2376997 2.74171998 2 P 0 ;0,1=27,2=0.000000
L 11.2376997 2.74171998 11.23983307 2.74088681 2 P 0 ;0,1=27,2=0.000000
L 11.23983307 2.74088681 11.2416998 2.73880315 2 P 0 ;0,1=27,2=0.000000
L 11.2416998 2.73880315 11.2425001 2.73588632 2 P 0 ;0,1=27,2=0.000000
L 11.2425001 2.73588632 11.24196644 2.73296949 2 P 0 ;0,1=27,2=0.000000
L 11.24196644 2.73296949 11.24063337 2.73088661 2 P 0 ;0,1=27,2=0.000000
L 11.24063337 2.73088661 11.23903327 2.73005344 2 P 0 ;0,1=27,2=0.000000
L 11.23903327 2.73005344 11.23636663 2.73005344 2 P 0 ;0,1=27,2=0.000000
L 11.23636663 2.73005344 11.23396663 2.72880295 2 P 0 ;0,1=27,2=0.000000
L 11.23396663 2.72880295 11.23236654 2.72630276 2 P 0 ;0,1=27,2=0.000000
L 11.23236654 2.72630276 11.23183327 2.72338671 2 P 0 ;0,1=27,2=0.000000
L 11.23183327 2.72338671 11.23236654 2.72046909 2 P 0 ;0,1=27,2=0.000000
L 11.23236654 2.72046909 11.2337001 2.71838622 2 P 0 ;0,1=27,2=0.000000
L 11.2337001 2.71838622 11.23583346 2.71713652 2 P 0 ;0,1=27,2=0.000000
L 11.23583346 2.71713652 11.2376997 2.71671998 2 P 0 ;0,1=27,2=0.000000
L 11.2129997 2.765 11.2129997 2.79 2 P 0 ;0,1=283,2=0.000000
L 11.2129997 2.79 11.2097999 2.7850003 2 P 0 ;0,1=283,2=0.000000
L 11.2097999 2.765 11.21619951 2.765 2 P 0 ;0,1=283,2=0.000000
L 11.23246634 2.76791604 11.23433317 2.76583307 2 P 0 ;0,1=283,2=0.000000
L 11.23433317 2.76583307 11.23646654 2.765 2 P 0 ;0,1=283,2=0.000000
L 11.23646654 2.765 11.2385999 2.76583307 2 P 0 ;0,1=283,2=0.000000
L 11.2385999 2.76583307 11.24046663 2.76833258 2 P 0 ;0,1=283,2=0.000000
L 11.24046663 2.76833258 11.2418001 2.77208327 2 P 0 ;0,1=283,2=0.000000
L 11.2418001 2.77208327 11.24233337 2.77583327 2 P 0 ;0,1=283,2=0.000000
L 11.24233337 2.77583327 11.24233337 2.78041634 2 P 0 ;0,1=283,2=0.000000
L 11.24233337 2.78041634 11.2418001 2.78416634 2 P 0 ;0,1=283,2=0.000000
L 11.2418001 2.78416634 11.24046663 2.7874997 2 P 0 ;0,1=283,2=0.000000
L 11.24046663 2.7874997 11.23886644 2.78916683 2 P 0 ;0,1=283,2=0.000000
L 11.23886644 2.78916683 11.2369997 2.79 2 P 0 ;0,1=283,2=0.000000
L 11.2369997 2.79 11.23486634 2.78916683 2 P 0 ;0,1=283,2=0.000000
L 11.23486634 2.78916683 11.23326663 2.7874997 2 P 0 ;0,1=283,2=0.000000
L 11.23326663 2.7874997 11.2321998 2.7850003 2 P 0 ;0,1=283,2=0.000000
L 11.2321998 2.7850003 11.23166654 2.78166614 2 P 0 ;0,1=283,2=0.000000
L 11.23166654 2.78166614 11.2321998 2.7787501 2 P 0 ;0,1=283,2=0.000000
L 11.2321998 2.7787501 11.23353327 2.77583327 2 P 0 ;0,1=283,2=0.000000
L 11.23353327 2.77583327 11.23513346 2.77416614 2 P 0 ;0,1=283,2=0.000000
L 11.23513346 2.77416614 11.2369997 2.77374961 2 P 0 ;0,1=283,2=0.000000
L 11.2369997 2.77374961 11.23913307 2.77458278 2 P 0 ;0,1=283,2=0.000000
L 11.23913307 2.77458278 11.24073327 2.77666644 2 P 0 ;0,1=283,2=0.000000
L 11.24073327 2.77666644 11.24233337 2.78041634 2 P 0 ;0,1=283,2=0.000000
L 11.20863317 2.83755335 11.21023327 2.84005285 2 P 0 ;0,1=284,2=0.000000
L 11.21023327 2.84005285 11.2121 2.84130335 2 P 0 ;0,1=284,2=0.000000
L 11.2121 2.84130335 11.21423337 2.84171998 2 P 0 ;0,1=284,2=0.000000
L 11.21423337 2.84171998 11.2169 2.84088681 2 P 0 ;0,1=284,2=0.000000
L 11.2169 2.84088681 11.21876673 2.83880315 2 P 0 ;0,1=284,2=0.000000
L 11.21876673 2.83880315 11.2193 2.83630364 2 P 0 ;0,1=284,2=0.000000
L 11.2193 2.83630364 11.21903337 2.83380266 2 P 0 ;0,1=284,2=0.000000
L 11.21903337 2.83380266 11.21796644 2.83171978 2 P 0 ;0,1=284,2=0.000000
L 11.21796644 2.83171978 11.21263327 2.82755325 2 P 0 ;0,1=284,2=0.000000
L 11.21263327 2.82755325 11.21023327 2.82463642 2 P 0 ;0,1=284,2=0.000000
L 11.21023327 2.82463642 11.20863317 2.82046909 2 P 0 ;0,1=284,2=0.000000
L 11.20863317 2.82046909 11.2080999 2.81671998 2 P 0 ;0,1=284,2=0.000000
L 11.2080999 2.81671998 11.2193 2.81671998 2 P 0 ;0,1=284,2=0.000000
L 11.2376997 2.84171998 11.23556634 2.84088681 2 P 0 ;0,1=284,2=0.000000
L 11.23556634 2.84088681 11.23396663 2.83880315 2 P 0 ;0,1=284,2=0.000000
L 11.23396663 2.83880315 11.2328998 2.83630364 2 P 0 ;0,1=284,2=0.000000
L 11.2328998 2.83630364 11.2320999 2.83296949 2 P 0 ;0,1=284,2=0.000000
L 11.2320999 2.83296949 11.23183327 2.82921959 2 P 0 ;0,1=284,2=0.000000
L 11.23183327 2.82921959 11.2320999 2.82546959 2 P 0 ;0,1=284,2=0.000000
L 11.2320999 2.82546959 11.2328998 2.82213622 2 P 0 ;0,1=284,2=0.000000
L 11.2328998 2.82213622 11.23396663 2.81963602 2 P 0 ;0,1=284,2=0.000000
L 11.23396663 2.81963602 11.23556634 2.81755305 2 P 0 ;0,1=284,2=0.000000
L 11.23556634 2.81755305 11.2376997 2.81671998 2 P 0 ;0,1=284,2=0.000000
L 11.2376997 2.81671998 11.23983307 2.81755305 2 P 0 ;0,1=284,2=0.000000
L 11.23983307 2.81755305 11.24143327 2.81963602 2 P 0 ;0,1=284,2=0.000000
L 11.24143327 2.81963602 11.2425001 2.82213622 2 P 0 ;0,1=284,2=0.000000
L 11.2425001 2.82213622 11.2433 2.82546959 2 P 0 ;0,1=284,2=0.000000
L 11.2433 2.82546959 11.24356663 2.82921959 2 P 0 ;0,1=284,2=0.000000
L 11.24356663 2.82921959 11.2433 2.83296949 2 P 0 ;0,1=284,2=0.000000
L 11.2433 2.83296949 11.2425001 2.83630364 2 P 0 ;0,1=284,2=0.000000
L 11.2425001 2.83630364 11.24143327 2.83880315 2 P 0 ;0,1=284,2=0.000000
L 11.24143327 2.83880315 11.23983307 2.84088681 2 P 0 ;0,1=284,2=0.000000
L 11.23983307 2.84088681 11.2376997 2.84171998 2 P 0 ;0,1=284,2=0.000000
L 10.62446998 1.71881299 10.59946998 1.72547972 2 P 0 ;0,1=48,2=270.000000
L 10.59946998 1.72547972 10.62446998 1.73214695 2 P 0 ;0,1=48,2=270.000000
L 10.61572037 1.72974646 10.61572037 1.72121299 2 P 0 ;0,1=48,2=270.000000
L 10.66113652 1.72761309 10.65988671 1.72868002 2 P 0 ;0,1=285,2=270.000000
L 10.65988671 1.72868002 10.65780384 1.72947982 2 P 0 ;0,1=285,2=270.000000
L 10.65780384 1.72947982 10.65488632 1.73001358 2 P 0 ;0,1=285,2=270.000000
L 10.65488632 1.73001358 10.65238681 1.72947982 2 P 0 ;0,1=285,2=270.000000
L 10.65238681 1.72947982 10.65072057 1.72841339 2 P 0 ;0,1=285,2=270.000000
L 10.65072057 1.72841339 10.64946998 1.72654665 2 P 0 ;0,1=285,2=270.000000
L 10.64946998 1.72654665 10.64946998 1.71934675 2 P 0 ;0,1=285,2=270.000000
L 10.64946998 1.71934675 10.67446998 1.71934675 2 P 0 ;0,1=285,2=270.000000
L 10.67446998 1.71934675 10.67446998 1.72814675 2 P 0 ;0,1=285,2=270.000000
L 10.67446998 1.72814675 10.67280374 1.73001358 2 P 0 ;0,1=285,2=270.000000
L 10.67280374 1.73001358 10.67030344 1.73108002 2 P 0 ;0,1=285,2=270.000000
L 10.67030344 1.73108002 10.66738671 1.73161319 2 P 0 ;0,1=285,2=270.000000
L 10.66738671 1.73161319 10.66447067 1.73108002 2 P 0 ;0,1=285,2=270.000000
L 10.66447067 1.73108002 10.66197037 1.72947982 2 P 0 ;0,1=285,2=270.000000
L 10.66197037 1.72947982 10.66113652 1.72761309 2 P 0 ;0,1=285,2=270.000000
L 10.66113652 1.72761309 10.66113652 1.71934675 2 P 0 ;0,1=285,2=270.000000
L 10.70155364 1.73134665 10.70030315 1.72974646 2 P 0 ;0,1=49,2=270.000000
L 10.70030315 1.72974646 10.69946998 1.72788022 2 P 0 ;0,1=49,2=270.000000
L 10.69946998 1.72788022 10.69946998 1.72574685 2 P 0 ;0,1=49,2=270.000000
L 10.69946998 1.72574685 10.70072057 1.72334636 2 P 0 ;0,1=49,2=270.000000
L 10.70072057 1.72334636 10.70280344 1.72148012 2 P 0 ;0,1=49,2=270.000000
L 10.70280344 1.72148012 10.70530364 1.72014656 2 P 0 ;0,1=49,2=270.000000
L 10.70530364 1.72014656 10.70947018 1.71907963 2 P 0 ;0,1=49,2=270.000000
L 10.70947018 1.71907963 10.71322018 1.71881299 2 P 0 ;0,1=49,2=270.000000
L 10.71322018 1.71881299 10.71697008 1.71934675 2 P 0 ;0,1=49,2=270.000000
L 10.71697008 1.71934675 10.71947037 1.72014656 2 P 0 ;0,1=49,2=270.000000
L 10.71947037 1.72014656 10.72197057 1.72174665 2 P 0 ;0,1=49,2=270.000000
L 10.72197057 1.72174665 10.72363691 1.72361348 2 P 0 ;0,1=49,2=270.000000
L 10.72363691 1.72361348 10.72446998 1.72547972 2 P 0 ;0,1=49,2=270.000000
L 10.72446998 1.72547972 10.72446998 1.72734646 2 P 0 ;0,1=49,2=270.000000
L 10.72446998 1.72734646 10.72363691 1.72921329 2 P 0 ;0,1=49,2=270.000000
L 10.72363691 1.72921329 10.72238711 1.73081339 2 P 0 ;0,1=49,2=270.000000
L 10.72238711 1.73081339 10.72072087 1.73214695 2 P 0 ;0,1=49,2=270.000000
L 10.77446998 1.72461329 10.74946998 1.72461329 2 P 0 ;0,1=255,2=270.000000
L 10.74946998 1.72461329 10.74946998 1.72994656 2 P 0 ;0,1=255,2=270.000000
L 10.74946998 1.72994656 10.75072057 1.73207992 2 P 0 ;0,1=255,2=270.000000
L 10.75072057 1.73207992 10.75238681 1.73368002 2 P 0 ;0,1=255,2=270.000000
L 10.75238681 1.73368002 10.75488632 1.73501358 2 P 0 ;0,1=255,2=270.000000
L 10.75488632 1.73501358 10.75780384 1.73608002 2 P 0 ;0,1=255,2=270.000000
L 10.75780384 1.73608002 10.76197037 1.73634665 2 P 0 ;0,1=255,2=270.000000
L 10.76197037 1.73634665 10.76613691 1.73608002 2 P 0 ;0,1=255,2=270.000000
L 10.76613691 1.73608002 10.76905374 1.73501358 2 P 0 ;0,1=255,2=270.000000
L 10.76905374 1.73501358 10.77155394 1.73368002 2 P 0 ;0,1=255,2=270.000000
L 10.77155394 1.73368002 10.77322028 1.73207992 2 P 0 ;0,1=255,2=270.000000
L 10.77322028 1.73207992 10.77446998 1.72994656 2 P 0 ;0,1=255,2=270.000000
L 10.77446998 1.72994656 10.77446998 1.72461329 2 P 0 ;0,1=255,2=270.000000
L 10.82446998 1.73581339 10.82446998 1.72514656 2 P 0 ;0,1=286,2=270.000000
L 10.82446998 1.72514656 10.79946998 1.72514656 2 P 0 ;0,1=286,2=270.000000
L 10.79946998 1.72514656 10.79946998 1.73581339 2 P 0 ;0,1=286,2=270.000000
L 10.81155305 1.73154665 10.81155305 1.72514656 2 P 0 ;0,1=286,2=270.000000
L 10.87446998 1.72541319 10.84946998 1.72541319 2 P 0 ;0,1=287,2=270.000000
L 10.84946998 1.72541319 10.84946998 1.73554675 2 P 0 ;0,1=287,2=270.000000
L 10.86155305 1.73181329 10.86155305 1.72541319 2 P 0 ;0,1=287,2=270.000000
L 10.91197037 1.72707992 10.91197037 1.73241348 2 P 0 ;0,1=256,2=270.000000
L 10.91197037 1.73241348 10.91947037 1.73241348 2 P 0 ;0,1=256,2=270.000000
L 10.91947037 1.73241348 10.92197057 1.73081339 2 P 0 ;0,1=256,2=270.000000
L 10.92197057 1.73081339 10.92363691 1.72894665 2 P 0 ;0,1=256,2=270.000000
L 10.92363691 1.72894665 10.92446998 1.72628002 2 P 0 ;0,1=256,2=270.000000
L 10.92446998 1.72628002 10.92363691 1.72361348 2 P 0 ;0,1=256,2=270.000000
L 10.92363691 1.72361348 10.92197057 1.72174665 2 P 0 ;0,1=256,2=270.000000
L 10.92197057 1.72174665 10.91947037 1.72014656 2 P 0 ;0,1=256,2=270.000000
L 10.91947037 1.72014656 10.91655354 1.71907963 2 P 0 ;0,1=256,2=270.000000
L 10.91655354 1.71907963 10.91322018 1.71854646 2 P 0 ;0,1=256,2=270.000000
L 10.91322018 1.71854646 10.91030335 1.71854646 2 P 0 ;0,1=256,2=270.000000
L 10.91030335 1.71854646 10.90780384 1.71907963 2 P 0 ;0,1=256,2=270.000000
L 10.90780384 1.71907963 10.90488632 1.72014656 2 P 0 ;0,1=256,2=270.000000
L 10.90488632 1.72014656 10.90238681 1.72174665 2 P 0 ;0,1=256,2=270.000000
L 10.90238681 1.72174665 10.90072057 1.72334636 2 P 0 ;0,1=256,2=270.000000
L 10.90072057 1.72334636 10.89946998 1.72547972 2 P 0 ;0,1=256,2=270.000000
L 10.89946998 1.72547972 10.89946998 1.72734646 2 P 0 ;0,1=256,2=270.000000
L 10.89946998 1.72734646 10.90030315 1.72947982 2 P 0 ;0,1=256,2=270.000000
L 10.90030315 1.72947982 10.90197028 1.73108002 2 P 0 ;0,1=256,2=270.000000
L 10.97446998 1.71987992 10.94946998 1.71987992 2 P 0 ;0,1=288,2=270.000000
L 10.94946998 1.73108002 10.97446998 1.73108002 2 P 0 ;0,1=288,2=270.000000
L 10.96197037 1.73108002 10.96197037 1.71987992 2 P 0 ;0,1=288,2=270.000000
L 11.01947037 1.72014656 11.02197057 1.72148012 2 P 0 ;0,1=289,2=270.000000
L 11.02197057 1.72148012 11.02363691 1.72307972 2 P 0 ;0,1=289,2=270.000000
L 11.02363691 1.72307972 11.02446998 1.72494656 2 P 0 ;0,1=289,2=270.000000
L 11.02446998 1.72494656 11.02363691 1.72707992 2 P 0 ;0,1=289,2=270.000000
L 11.02363691 1.72707992 11.02197057 1.72868002 2 P 0 ;0,1=289,2=270.000000
L 11.02197057 1.72868002 11.01947037 1.73028012 2 P 0 ;0,1=289,2=270.000000
L 11.01947037 1.73028012 11.01613691 1.73081339 2 P 0 ;0,1=289,2=270.000000
L 11.01613691 1.73081339 10.99946998 1.73081339 2 P 0 ;0,1=289,2=270.000000
L 11.07446998 1.71961329 11.04946998 1.71961329 2 P 0 ;0,1=290,2=270.000000
L 11.04946998 1.72974646 11.0648872 1.71961329 2 P 0 ;0,1=290,2=270.000000
L 11.07446998 1.73134665 11.05780384 1.72414665 2 P 0 ;0,1=290,2=270.000000
L 11.23226319 2.88755335 11.23386329 2.89005285 2 P 0 ;0,1=270,2=0.000000
L 11.23386329 2.89005285 11.23573002 2.89130335 2 P 0 ;0,1=270,2=0.000000
L 11.23573002 2.89130335 11.23786339 2.89171998 2 P 0 ;0,1=270,2=0.000000
L 11.23786339 2.89171998 11.24053002 2.89088681 2 P 0 ;0,1=270,2=0.000000
L 11.24053002 2.89088681 11.24239675 2.88880315 2 P 0 ;0,1=270,2=0.000000
L 11.24239675 2.88880315 11.24293002 2.88630364 2 P 0 ;0,1=270,2=0.000000
L 11.24293002 2.88630364 11.24266339 2.88380266 2 P 0 ;0,1=270,2=0.000000
L 11.24266339 2.88380266 11.24159646 2.88171978 2 P 0 ;0,1=270,2=0.000000
L 11.24159646 2.88171978 11.23626329 2.87755325 2 P 0 ;0,1=270,2=0.000000
L 11.23626329 2.87755325 11.23386329 2.87463642 2 P 0 ;0,1=270,2=0.000000
L 11.23386329 2.87463642 11.23226319 2.87046909 2 P 0 ;0,1=270,2=0.000000
L 11.23226319 2.87046909 11.23172992 2.86671998 2 P 0 ;0,1=270,2=0.000000
L 11.23172992 2.86671998 11.24293002 2.86671998 2 P 0 ;0,1=270,2=0.000000
L 11.26132972 2.86671998 11.26132972 2.89171998 2 P 0 ;0,1=270,2=0.000000
L 11.26132972 2.89171998 11.25812992 2.88672028 2 P 0 ;0,1=270,2=0.000000
L 11.25812992 2.86671998 11.26452953 2.86671998 2 P 0 ;0,1=270,2=0.000000
L 11.20863317 2.93755335 11.21023327 2.94005285 2 P 0 ;0,1=271,2=0.000000
L 11.21023327 2.94005285 11.2121 2.94130335 2 P 0 ;0,1=271,2=0.000000
L 11.2121 2.94130335 11.21423337 2.94171998 2 P 0 ;0,1=271,2=0.000000
L 11.21423337 2.94171998 11.2169 2.94088681 2 P 0 ;0,1=271,2=0.000000
L 11.2169 2.94088681 11.21876673 2.93880315 2 P 0 ;0,1=271,2=0.000000
L 11.21876673 2.93880315 11.2193 2.93630364 2 P 0 ;0,1=271,2=0.000000
L 11.2193 2.93630364 11.21903337 2.93380266 2 P 0 ;0,1=271,2=0.000000
L 11.21903337 2.93380266 11.21796644 2.93171978 2 P 0 ;0,1=271,2=0.000000
L 11.21796644 2.93171978 11.21263327 2.92755325 2 P 0 ;0,1=271,2=0.000000
L 11.21263327 2.92755325 11.21023327 2.92463642 2 P 0 ;0,1=271,2=0.000000
L 11.21023327 2.92463642 11.20863317 2.92046909 2 P 0 ;0,1=271,2=0.000000
L 11.20863317 2.92046909 11.2080999 2.91671998 2 P 0 ;0,1=271,2=0.000000
L 11.2080999 2.91671998 11.2193 2.91671998 2 P 0 ;0,1=271,2=0.000000
L 11.23263317 2.93755335 11.23423327 2.94005285 2 P 0 ;0,1=271,2=0.000000
L 11.23423327 2.94005285 11.2361 2.94130335 2 P 0 ;0,1=271,2=0.000000
L 11.2361 2.94130335 11.23823337 2.94171998 2 P 0 ;0,1=271,2=0.000000
L 11.23823337 2.94171998 11.2409 2.94088681 2 P 0 ;0,1=271,2=0.000000
L 11.2409 2.94088681 11.24276673 2.93880315 2 P 0 ;0,1=271,2=0.000000
L 11.24276673 2.93880315 11.2433 2.93630364 2 P 0 ;0,1=271,2=0.000000
L 11.2433 2.93630364 11.24303337 2.93380266 2 P 0 ;0,1=271,2=0.000000
L 11.24303337 2.93380266 11.24196644 2.93171978 2 P 0 ;0,1=271,2=0.000000
L 11.24196644 2.93171978 11.23663327 2.92755325 2 P 0 ;0,1=271,2=0.000000
L 11.23663327 2.92755325 11.23423327 2.92463642 2 P 0 ;0,1=271,2=0.000000
L 11.23423327 2.92463642 11.23263317 2.92046909 2 P 0 ;0,1=271,2=0.000000
L 11.23263317 2.92046909 11.2320999 2.91671998 2 P 0 ;0,1=271,2=0.000000
L 11.2320999 2.91671998 11.2433 2.91671998 2 P 0 ;0,1=271,2=0.000000
L 11.23226319 2.98755335 11.23386329 2.99005285 2 P 0 ;0,1=64,2=0.000000
L 11.23386329 2.99005285 11.23573002 2.99130335 2 P 0 ;0,1=64,2=0.000000
L 11.23573002 2.99130335 11.23786339 2.99171998 2 P 0 ;0,1=64,2=0.000000
L 11.23786339 2.99171998 11.24053002 2.99088681 2 P 0 ;0,1=64,2=0.000000
L 11.24053002 2.99088681 11.24239675 2.98880315 2 P 0 ;0,1=64,2=0.000000
L 11.24239675 2.98880315 11.24293002 2.98630364 2 P 0 ;0,1=64,2=0.000000
L 11.24293002 2.98630364 11.24266339 2.98380266 2 P 0 ;0,1=64,2=0.000000
L 11.24266339 2.98380266 11.24159646 2.98171978 2 P 0 ;0,1=64,2=0.000000
L 11.24159646 2.98171978 11.23626329 2.97755325 2 P 0 ;0,1=64,2=0.000000
L 11.23626329 2.97755325 11.23386329 2.97463642 2 P 0 ;0,1=64,2=0.000000
L 11.23386329 2.97463642 11.23226319 2.97046909 2 P 0 ;0,1=64,2=0.000000
L 11.23226319 2.97046909 11.23172992 2.96671998 2 P 0 ;0,1=64,2=0.000000
L 11.23172992 2.96671998 11.24293002 2.96671998 2 P 0 ;0,1=64,2=0.000000
L 11.25546329 2.97171959 11.25706299 2.96880285 2 P 0 ;0,1=64,2=0.000000
L 11.25706299 2.96880285 11.25919636 2.96713652 2 P 0 ;0,1=64,2=0.000000
L 11.25919636 2.96713652 11.26159685 2.96671998 2 P 0 ;0,1=64,2=0.000000
L 11.26159685 2.96671998 11.26373022 2.96713652 2 P 0 ;0,1=64,2=0.000000
L 11.26373022 2.96713652 11.26586358 2.96921939 2 P 0 ;0,1=64,2=0.000000
L 11.26586358 2.96921939 11.26719665 2.97171959 2 P 0 ;0,1=64,2=0.000000
L 11.26719665 2.97171959 11.26746319 2.97421988 2 P 0 ;0,1=64,2=0.000000
L 11.26746319 2.97421988 11.26693002 2.97713593 2 P 0 ;0,1=64,2=0.000000
L 11.26693002 2.97713593 11.26506329 2.97921959 2 P 0 ;0,1=64,2=0.000000
L 11.26506329 2.97921959 11.26319646 2.98005344 2 P 0 ;0,1=64,2=0.000000
L 11.26319646 2.98005344 11.26079656 2.98005344 2 P 0 ;0,1=64,2=0.000000
L 11.26319646 2.98005344 11.26479665 2.98130325 2 P 0 ;0,1=64,2=0.000000
L 11.26479665 2.98130325 11.26613012 2.98338612 2 P 0 ;0,1=64,2=0.000000
L 11.26613012 2.98338612 11.26666339 2.98588632 2 P 0 ;0,1=64,2=0.000000
L 11.26666339 2.98588632 11.26613012 2.98838652 2 P 0 ;0,1=64,2=0.000000
L 11.26613012 2.98838652 11.26479665 2.99046939 2 P 0 ;0,1=64,2=0.000000
L 11.26479665 2.99046939 11.26239665 2.99171998 2 P 0 ;0,1=64,2=0.000000
L 11.26239665 2.99171998 11.25999665 2.99130335 2 P 0 ;0,1=64,2=0.000000
L 11.25999665 2.99130335 11.25759665 2.98963632 2 P 0 ;0,1=64,2=0.000000
L 11.20863317 3.03755335 11.21023327 3.04005285 2 P 0 ;0,1=65,2=0.000000
L 11.21023327 3.04005285 11.2121 3.04130335 2 P 0 ;0,1=65,2=0.000000
L 11.2121 3.04130335 11.21423337 3.04171998 2 P 0 ;0,1=65,2=0.000000
L 11.21423337 3.04171998 11.2169 3.04088681 2 P 0 ;0,1=65,2=0.000000
L 11.2169 3.04088681 11.21876673 3.03880315 2 P 0 ;0,1=65,2=0.000000
L 11.21876673 3.03880315 11.2193 3.03630364 2 P 0 ;0,1=65,2=0.000000
L 11.2193 3.03630364 11.21903337 3.03380266 2 P 0 ;0,1=65,2=0.000000
L 11.21903337 3.03380266 11.21796644 3.03171978 2 P 0 ;0,1=65,2=0.000000
L 11.21796644 3.03171978 11.21263327 3.02755325 2 P 0 ;0,1=65,2=0.000000
L 11.21263327 3.02755325 11.21023327 3.02463642 2 P 0 ;0,1=65,2=0.000000
L 11.21023327 3.02463642 11.20863317 3.02046909 2 P 0 ;0,1=65,2=0.000000
L 11.20863317 3.02046909 11.2080999 3.01671998 2 P 0 ;0,1=65,2=0.000000
L 11.2080999 3.01671998 11.2193 3.01671998 2 P 0 ;0,1=65,2=0.000000
L 11.2409 3.01671998 11.2409 3.04171998 2 P 0 ;0,1=65,2=0.000000
L 11.2409 3.04171998 11.23103297 3.02380325 2 P 0 ;0,1=65,2=0.000000
L 11.23103297 3.02380325 11.24436693 3.02380325 2 P 0 ;0,1=65,2=0.000000
L 11.23226319 3.08755335 11.23386329 3.09005285 2 P 0 ;0,1=291,2=0.000000
L 11.23386329 3.09005285 11.23573002 3.09130335 2 P 0 ;0,1=291,2=0.000000
L 11.23573002 3.09130335 11.23786339 3.09171998 2 P 0 ;0,1=291,2=0.000000
L 11.23786339 3.09171998 11.24053002 3.09088681 2 P 0 ;0,1=291,2=0.000000
L 11.24053002 3.09088681 11.24239675 3.08880315 2 P 0 ;0,1=291,2=0.000000
L 11.24239675 3.08880315 11.24293002 3.08630364 2 P 0 ;0,1=291,2=0.000000
L 11.24293002 3.08630364 11.24266339 3.08380266 2 P 0 ;0,1=291,2=0.000000
L 11.24266339 3.08380266 11.24159646 3.08171978 2 P 0 ;0,1=291,2=0.000000
L 11.24159646 3.08171978 11.23626329 3.07755325 2 P 0 ;0,1=291,2=0.000000
L 11.23626329 3.07755325 11.23386329 3.07463642 2 P 0 ;0,1=291,2=0.000000
L 11.23386329 3.07463642 11.23226319 3.07046909 2 P 0 ;0,1=291,2=0.000000
L 11.23226319 3.07046909 11.23172992 3.06671998 2 P 0 ;0,1=291,2=0.000000
L 11.23172992 3.06671998 11.24293002 3.06671998 2 P 0 ;0,1=291,2=0.000000
L 11.25546329 3.07046909 11.25706299 3.06838622 2 P 0 ;0,1=291,2=0.000000
L 11.25706299 3.06838622 11.25892972 3.06713652 2 P 0 ;0,1=291,2=0.000000
L 11.25892972 3.06713652 11.26132972 3.06671998 2 P 0 ;0,1=291,2=0.000000
L 11.26132972 3.06671998 11.26373022 3.06755305 2 P 0 ;0,1=291,2=0.000000
L 11.26373022 3.06755305 11.26559646 3.06921939 2 P 0 ;0,1=291,2=0.000000
L 11.26559646 3.06921939 11.26693002 3.07213622 2 P 0 ;0,1=291,2=0.000000
L 11.26693002 3.07213622 11.26719665 3.07546959 2 P 0 ;0,1=291,2=0.000000
L 11.26719665 3.07546959 11.26666339 3.07880295 2 P 0 ;0,1=291,2=0.000000
L 11.26666339 3.07880295 11.26532982 3.08088661 2 P 0 ;0,1=291,2=0.000000
L 11.26532982 3.08088661 11.26346309 3.08255295 2 P 0 ;0,1=291,2=0.000000
L 11.26346309 3.08255295 11.26159685 3.08296949 2 P 0 ;0,1=291,2=0.000000
L 11.26159685 3.08296949 11.25973002 3.08255295 2 P 0 ;0,1=291,2=0.000000
L 11.25973002 3.08255295 11.25733012 3.08088661 2 P 0 ;0,1=291,2=0.000000
L 11.25733012 3.08088661 11.25812992 3.09171998 2 P 0 ;0,1=291,2=0.000000
L 11.25812992 3.09171998 11.26532982 3.09171998 2 P 0 ;0,1=291,2=0.000000
L 11.20863317 3.13755335 11.21023327 3.14005285 2 P 0 ;0,1=292,2=0.000000
L 11.21023327 3.14005285 11.2121 3.14130335 2 P 0 ;0,1=292,2=0.000000
L 11.2121 3.14130335 11.21423337 3.14171998 2 P 0 ;0,1=292,2=0.000000
L 11.21423337 3.14171998 11.2169 3.14088681 2 P 0 ;0,1=292,2=0.000000
L 11.2169 3.14088681 11.21876673 3.13880315 2 P 0 ;0,1=292,2=0.000000
L 11.21876673 3.13880315 11.2193 3.13630364 2 P 0 ;0,1=292,2=0.000000
L 11.2193 3.13630364 11.21903337 3.13380266 2 P 0 ;0,1=292,2=0.000000
L 11.21903337 3.13380266 11.21796644 3.13171978 2 P 0 ;0,1=292,2=0.000000
L 11.21796644 3.13171978 11.21263327 3.12755325 2 P 0 ;0,1=292,2=0.000000
L 11.21263327 3.12755325 11.21023327 3.12463642 2 P 0 ;0,1=292,2=0.000000
L 11.21023327 3.12463642 11.20863317 3.12046909 2 P 0 ;0,1=292,2=0.000000
L 11.20863317 3.12046909 11.2080999 3.11671998 2 P 0 ;0,1=292,2=0.000000
L 11.2080999 3.11671998 11.2193 3.11671998 2 P 0 ;0,1=292,2=0.000000
L 11.23263317 3.12713593 11.2344999 3.13005344 2 P 0 ;0,1=292,2=0.000000
L 11.2344999 3.13005344 11.2361 3.13171978 2 P 0 ;0,1=292,2=0.000000
L 11.2361 3.13171978 11.23823337 3.13255295 2 P 0 ;0,1=292,2=0.000000
L 11.23823337 3.13255295 11.2401002 3.13171978 2 P 0 ;0,1=292,2=0.000000
L 11.2401002 3.13171978 11.24143327 3.13005344 2 P 0 ;0,1=292,2=0.000000
L 11.24143327 3.13005344 11.2425001 3.12755325 2 P 0 ;0,1=292,2=0.000000
L 11.2425001 3.12755325 11.24276673 3.12463642 2 P 0 ;0,1=292,2=0.000000
L 11.24276673 3.12463642 11.2425001 3.12213622 2 P 0 ;0,1=292,2=0.000000
L 11.2425001 3.12213622 11.24143327 3.11963602 2 P 0 ;0,1=292,2=0.000000
L 11.24143327 3.11963602 11.23983307 3.11755305 2 P 0 ;0,1=292,2=0.000000
L 11.23983307 3.11755305 11.23796683 3.11671998 2 P 0 ;0,1=292,2=0.000000
L 11.23796683 3.11671998 11.23583346 3.11755305 2 P 0 ;0,1=292,2=0.000000
L 11.23583346 3.11755305 11.23396663 3.12005256 2 P 0 ;0,1=292,2=0.000000
L 11.23396663 3.12005256 11.2328998 3.12380325 2 P 0 ;0,1=292,2=0.000000
L 11.2328998 3.12380325 11.23263317 3.12796978 2 P 0 ;0,1=292,2=0.000000
L 11.23263317 3.12796978 11.23316634 3.13338612 2 P 0 ;0,1=292,2=0.000000
L 11.23316634 3.13338612 11.23396663 3.13630364 2 P 0 ;0,1=292,2=0.000000
L 11.23396663 3.13630364 11.2352997 3.13921969 2 P 0 ;0,1=292,2=0.000000
L 11.2352997 3.13921969 11.23716654 3.14130335 2 P 0 ;0,1=292,2=0.000000
L 11.23716654 3.14130335 11.23903327 3.14171998 2 P 0 ;0,1=292,2=0.000000
L 11.23903327 3.14171998 11.2409 3.14088681 2 P 0 ;0,1=292,2=0.000000
L 11.2409 3.14088681 11.24223356 3.13880315 2 P 0 ;0,1=292,2=0.000000
L 11.23226319 3.18755335 11.23386329 3.19005285 2 P 0 ;0,1=293,2=0.000000
L 11.23386329 3.19005285 11.23573002 3.19130335 2 P 0 ;0,1=293,2=0.000000
L 11.23573002 3.19130335 11.23786339 3.19171998 2 P 0 ;0,1=293,2=0.000000
L 11.23786339 3.19171998 11.24053002 3.19088681 2 P 0 ;0,1=293,2=0.000000
L 11.24053002 3.19088681 11.24239675 3.18880315 2 P 0 ;0,1=293,2=0.000000
L 11.24239675 3.18880315 11.24293002 3.18630364 2 P 0 ;0,1=293,2=0.000000
L 11.24293002 3.18630364 11.24266339 3.18380266 2 P 0 ;0,1=293,2=0.000000
L 11.24266339 3.18380266 11.24159646 3.18171978 2 P 0 ;0,1=293,2=0.000000
L 11.24159646 3.18171978 11.23626329 3.17755325 2 P 0 ;0,1=293,2=0.000000
L 11.23626329 3.17755325 11.23386329 3.17463642 2 P 0 ;0,1=293,2=0.000000
L 11.23386329 3.17463642 11.23226319 3.17046909 2 P 0 ;0,1=293,2=0.000000
L 11.23226319 3.17046909 11.23172992 3.16671998 2 P 0 ;0,1=293,2=0.000000
L 11.23172992 3.16671998 11.24293002 3.16671998 2 P 0 ;0,1=293,2=0.000000
L 11.26079656 3.16671998 11.26132972 3.17213622 2 P 0 ;0,1=293,2=0.000000
L 11.26132972 3.17213622 11.26213002 3.17671929 2 P 0 ;0,1=293,2=0.000000
L 11.26213002 3.17671929 11.26319646 3.18088661 2 P 0 ;0,1=293,2=0.000000
L 11.26319646 3.18088661 11.26453002 3.18546978 2 P 0 ;0,1=293,2=0.000000
L 11.26453002 3.18546978 11.26666339 3.19171998 2 P 0 ;0,1=293,2=0.000000
L 11.26666339 3.19171998 11.25599656 3.19171998 2 P 0 ;0,1=293,2=0.000000
L 11.20863317 3.23755335 11.21023327 3.24005285 2 P 0 ;0,1=66,2=0.000000
L 11.21023327 3.24005285 11.2121 3.24130335 2 P 0 ;0,1=66,2=0.000000
L 11.2121 3.24130335 11.21423337 3.24171998 2 P 0 ;0,1=66,2=0.000000
L 11.21423337 3.24171998 11.2169 3.24088681 2 P 0 ;0,1=66,2=0.000000
L 11.2169 3.24088681 11.21876673 3.23880315 2 P 0 ;0,1=66,2=0.000000
L 11.21876673 3.23880315 11.2193 3.23630364 2 P 0 ;0,1=66,2=0.000000
L 11.2193 3.23630364 11.21903337 3.23380266 2 P 0 ;0,1=66,2=0.000000
L 11.21903337 3.23380266 11.21796644 3.23171978 2 P 0 ;0,1=66,2=0.000000
L 11.21796644 3.23171978 11.21263327 3.22755325 2 P 0 ;0,1=66,2=0.000000
L 11.21263327 3.22755325 11.21023327 3.22463642 2 P 0 ;0,1=66,2=0.000000
L 11.21023327 3.22463642 11.20863317 3.22046909 2 P 0 ;0,1=66,2=0.000000
L 11.20863317 3.22046909 11.2080999 3.21671998 2 P 0 ;0,1=66,2=0.000000
L 11.2080999 3.21671998 11.2193 3.21671998 2 P 0 ;0,1=66,2=0.000000
L 11.2376997 3.21671998 11.23956644 3.21713652 2 P 0 ;0,1=66,2=0.000000
L 11.23956644 3.21713652 11.2416998 3.21838622 2 P 0 ;0,1=66,2=0.000000
L 11.2416998 3.21838622 11.24303337 3.22046909 2 P 0 ;0,1=66,2=0.000000
L 11.24303337 3.22046909 11.24356663 3.22338671 2 P 0 ;0,1=66,2=0.000000
L 11.24356663 3.22338671 11.24303337 3.22630276 2 P 0 ;0,1=66,2=0.000000
L 11.24303337 3.22630276 11.24143327 3.22880295 2 P 0 ;0,1=66,2=0.000000
L 11.24143327 3.22880295 11.23903327 3.23005344 2 P 0 ;0,1=66,2=0.000000
L 11.23903327 3.23005344 11.23636663 3.23005344 2 P 0 ;0,1=66,2=0.000000
L 11.23636663 3.23005344 11.23476654 3.23088661 2 P 0 ;0,1=66,2=0.000000
L 11.23476654 3.23088661 11.23343297 3.23296949 2 P 0 ;0,1=66,2=0.000000
L 11.23343297 3.23296949 11.2328998 3.23588632 2 P 0 ;0,1=66,2=0.000000
L 11.2328998 3.23588632 11.2337001 3.23880315 2 P 0 ;0,1=66,2=0.000000
L 11.2337001 3.23880315 11.23556634 3.24088681 2 P 0 ;0,1=66,2=0.000000
L 11.23556634 3.24088681 11.2376997 3.24171998 2 P 0 ;0,1=66,2=0.000000
L 11.2376997 3.24171998 11.23983307 3.24088681 2 P 0 ;0,1=66,2=0.000000
L 11.23983307 3.24088681 11.2416998 3.23880315 2 P 0 ;0,1=66,2=0.000000
L 11.2416998 3.23880315 11.2425001 3.23588632 2 P 0 ;0,1=66,2=0.000000
L 11.2425001 3.23588632 11.24196644 3.23296949 2 P 0 ;0,1=66,2=0.000000
L 11.24196644 3.23296949 11.24063337 3.23088661 2 P 0 ;0,1=66,2=0.000000
L 11.24063337 3.23088661 11.23903327 3.23005344 2 P 0 ;0,1=66,2=0.000000
L 11.23903327 3.23005344 11.23636663 3.23005344 2 P 0 ;0,1=66,2=0.000000
L 11.23636663 3.23005344 11.23396663 3.22880295 2 P 0 ;0,1=66,2=0.000000
L 11.23396663 3.22880295 11.23236654 3.22630276 2 P 0 ;0,1=66,2=0.000000
L 11.23236654 3.22630276 11.23183327 3.22338671 2 P 0 ;0,1=66,2=0.000000
L 11.23183327 3.22338671 11.23236654 3.22046909 2 P 0 ;0,1=66,2=0.000000
L 11.23236654 3.22046909 11.2337001 3.21838622 2 P 0 ;0,1=66,2=0.000000
L 11.2337001 3.21838622 11.23583346 3.21713652 2 P 0 ;0,1=66,2=0.000000
L 11.23583346 3.21713652 11.2376997 3.21671998 2 P 0 ;0,1=66,2=0.000000
L 11.23293317 3.28083337 11.23453327 3.28333287 2 P 0 ;0,1=294,2=0.000000
L 11.23453327 3.28333287 11.2364 3.28458337 2 P 0 ;0,1=294,2=0.000000
L 11.2364 3.28458337 11.23853337 3.285 2 P 0 ;0,1=294,2=0.000000
L 11.23853337 3.285 11.2412 3.28416683 2 P 0 ;0,1=294,2=0.000000
L 11.2412 3.28416683 11.24306673 3.28208317 2 P 0 ;0,1=294,2=0.000000
L 11.24306673 3.28208317 11.2436 3.27958366 2 P 0 ;0,1=294,2=0.000000
L 11.2436 3.27958366 11.24333337 3.27708268 2 P 0 ;0,1=294,2=0.000000
L 11.24333337 3.27708268 11.24226644 3.2749998 2 P 0 ;0,1=294,2=0.000000
L 11.24226644 3.2749998 11.23693327 3.27083327 2 P 0 ;0,1=294,2=0.000000
L 11.23693327 3.27083327 11.23453327 3.26791644 2 P 0 ;0,1=294,2=0.000000
L 11.23453327 3.26791644 11.23293317 3.26374911 2 P 0 ;0,1=294,2=0.000000
L 11.23293317 3.26374911 11.2323999 3.26 2 P 0 ;0,1=294,2=0.000000
L 11.2323999 3.26 11.2436 3.26 2 P 0 ;0,1=294,2=0.000000
L 11.25746634 3.26291604 11.25933317 3.26083307 2 P 0 ;0,1=294,2=0.000000
L 11.25933317 3.26083307 11.26146654 3.26 2 P 0 ;0,1=294,2=0.000000
L 11.26146654 3.26 11.2635999 3.26083307 2 P 0 ;0,1=294,2=0.000000
L 11.2635999 3.26083307 11.26546663 3.26333258 2 P 0 ;0,1=294,2=0.000000
L 11.26546663 3.26333258 11.2668001 3.26708327 2 P 0 ;0,1=294,2=0.000000
L 11.2668001 3.26708327 11.26733337 3.27083327 2 P 0 ;0,1=294,2=0.000000
L 11.26733337 3.27083327 11.26733337 3.27541634 2 P 0 ;0,1=294,2=0.000000
L 11.26733337 3.27541634 11.2668001 3.27916634 2 P 0 ;0,1=294,2=0.000000
L 11.2668001 3.27916634 11.26546663 3.2824997 2 P 0 ;0,1=294,2=0.000000
L 11.26546663 3.2824997 11.26386644 3.28416683 2 P 0 ;0,1=294,2=0.000000
L 11.26386644 3.28416683 11.2619997 3.285 2 P 0 ;0,1=294,2=0.000000
L 11.2619997 3.285 11.25986634 3.28416683 2 P 0 ;0,1=294,2=0.000000
L 11.25986634 3.28416683 11.25826663 3.2824997 2 P 0 ;0,1=294,2=0.000000
L 11.25826663 3.2824997 11.2571998 3.2800003 2 P 0 ;0,1=294,2=0.000000
L 11.2571998 3.2800003 11.25666654 3.27666614 2 P 0 ;0,1=294,2=0.000000
L 11.25666654 3.27666614 11.2571998 3.2737501 2 P 0 ;0,1=294,2=0.000000
L 11.2571998 3.2737501 11.25853327 3.27083327 2 P 0 ;0,1=294,2=0.000000
L 11.25853327 3.27083327 11.26013346 3.26916614 2 P 0 ;0,1=294,2=0.000000
L 11.26013346 3.26916614 11.2619997 3.26874961 2 P 0 ;0,1=294,2=0.000000
L 11.2619997 3.26874961 11.26413307 3.26958278 2 P 0 ;0,1=294,2=0.000000
L 11.26413307 3.26958278 11.26573327 3.27166644 2 P 0 ;0,1=294,2=0.000000
L 11.26573327 3.27166644 11.26733337 3.27541634 2 P 0 ;0,1=294,2=0.000000
L 11.20783327 3.32171959 11.20943297 3.31880285 2 P 0 ;0,1=295,2=0.000000
L 11.20943297 3.31880285 11.21156634 3.31713652 2 P 0 ;0,1=295,2=0.000000
L 11.21156634 3.31713652 11.21396683 3.31671998 2 P 0 ;0,1=295,2=0.000000
L 11.21396683 3.31671998 11.2161002 3.31713652 2 P 0 ;0,1=295,2=0.000000
L 11.2161002 3.31713652 11.21823356 3.31921939 2 P 0 ;0,1=295,2=0.000000
L 11.21823356 3.31921939 11.21956663 3.32171959 2 P 0 ;0,1=295,2=0.000000
L 11.21956663 3.32171959 11.21983317 3.32421988 2 P 0 ;0,1=295,2=0.000000
L 11.21983317 3.32421988 11.2193 3.32713593 2 P 0 ;0,1=295,2=0.000000
L 11.2193 3.32713593 11.21743327 3.32921959 2 P 0 ;0,1=295,2=0.000000
L 11.21743327 3.32921959 11.21556644 3.33005344 2 P 0 ;0,1=295,2=0.000000
L 11.21556644 3.33005344 11.21316654 3.33005344 2 P 0 ;0,1=295,2=0.000000
L 11.21556644 3.33005344 11.21716663 3.33130325 2 P 0 ;0,1=295,2=0.000000
L 11.21716663 3.33130325 11.2185001 3.33338612 2 P 0 ;0,1=295,2=0.000000
L 11.2185001 3.33338612 11.21903337 3.33588632 2 P 0 ;0,1=295,2=0.000000
L 11.21903337 3.33588632 11.2185001 3.33838652 2 P 0 ;0,1=295,2=0.000000
L 11.2185001 3.33838652 11.21716663 3.34046939 2 P 0 ;0,1=295,2=0.000000
L 11.21716663 3.34046939 11.21476663 3.34171998 2 P 0 ;0,1=295,2=0.000000
L 11.21476663 3.34171998 11.21236663 3.34130335 2 P 0 ;0,1=295,2=0.000000
L 11.21236663 3.34130335 11.20996663 3.33963632 2 P 0 ;0,1=295,2=0.000000
L 11.2376997 3.34171998 11.23556634 3.34088681 2 P 0 ;0,1=295,2=0.000000
L 11.23556634 3.34088681 11.23396663 3.33880315 2 P 0 ;0,1=295,2=0.000000
L 11.23396663 3.33880315 11.2328998 3.33630364 2 P 0 ;0,1=295,2=0.000000
L 11.2328998 3.33630364 11.2320999 3.33296949 2 P 0 ;0,1=295,2=0.000000
L 11.2320999 3.33296949 11.23183327 3.32921959 2 P 0 ;0,1=295,2=0.000000
L 11.23183327 3.32921959 11.2320999 3.32546959 2 P 0 ;0,1=295,2=0.000000
L 11.2320999 3.32546959 11.2328998 3.32213622 2 P 0 ;0,1=295,2=0.000000
L 11.2328998 3.32213622 11.23396663 3.31963602 2 P 0 ;0,1=295,2=0.000000
L 11.23396663 3.31963602 11.23556634 3.31755305 2 P 0 ;0,1=295,2=0.000000
L 11.23556634 3.31755305 11.2376997 3.31671998 2 P 0 ;0,1=295,2=0.000000
L 11.2376997 3.31671998 11.23983307 3.31755305 2 P 0 ;0,1=295,2=0.000000
L 11.23983307 3.31755305 11.24143327 3.31963602 2 P 0 ;0,1=295,2=0.000000
L 11.24143327 3.31963602 11.2425001 3.32213622 2 P 0 ;0,1=295,2=0.000000
L 11.2425001 3.32213622 11.2433 3.32546959 2 P 0 ;0,1=295,2=0.000000
L 11.2433 3.32546959 11.24356663 3.32921959 2 P 0 ;0,1=295,2=0.000000
L 11.24356663 3.32921959 11.2433 3.33296949 2 P 0 ;0,1=295,2=0.000000
L 11.2433 3.33296949 11.2425001 3.33630364 2 P 0 ;0,1=295,2=0.000000
L 11.2425001 3.33630364 11.24143327 3.33880315 2 P 0 ;0,1=295,2=0.000000
L 11.24143327 3.33880315 11.23983307 3.34088681 2 P 0 ;0,1=295,2=0.000000
L 11.23983307 3.34088681 11.2376997 3.34171998 2 P 0 ;0,1=295,2=0.000000
L 11.23146329 3.37171959 11.23306299 3.36880285 2 P 0 ;0,1=296,2=0.000000
L 11.23306299 3.36880285 11.23519636 3.36713652 2 P 0 ;0,1=296,2=0.000000
L 11.23519636 3.36713652 11.23759685 3.36671998 2 P 0 ;0,1=296,2=0.000000
L 11.23759685 3.36671998 11.23973022 3.36713652 2 P 0 ;0,1=296,2=0.000000
L 11.23973022 3.36713652 11.24186358 3.36921939 2 P 0 ;0,1=296,2=0.000000
L 11.24186358 3.36921939 11.24319665 3.37171959 2 P 0 ;0,1=296,2=0.000000
L 11.24319665 3.37171959 11.24346319 3.37421988 2 P 0 ;0,1=296,2=0.000000
L 11.24346319 3.37421988 11.24293002 3.37713593 2 P 0 ;0,1=296,2=0.000000
L 11.24293002 3.37713593 11.24106329 3.37921959 2 P 0 ;0,1=296,2=0.000000
L 11.24106329 3.37921959 11.23919646 3.38005344 2 P 0 ;0,1=296,2=0.000000
L 11.23919646 3.38005344 11.23679656 3.38005344 2 P 0 ;0,1=296,2=0.000000
L 11.23919646 3.38005344 11.24079665 3.38130325 2 P 0 ;0,1=296,2=0.000000
L 11.24079665 3.38130325 11.24213012 3.38338612 2 P 0 ;0,1=296,2=0.000000
L 11.24213012 3.38338612 11.24266339 3.38588632 2 P 0 ;0,1=296,2=0.000000
L 11.24266339 3.38588632 11.24213012 3.38838652 2 P 0 ;0,1=296,2=0.000000
L 11.24213012 3.38838652 11.24079665 3.39046939 2 P 0 ;0,1=296,2=0.000000
L 11.24079665 3.39046939 11.23839665 3.39171998 2 P 0 ;0,1=296,2=0.000000
L 11.23839665 3.39171998 11.23599665 3.39130335 2 P 0 ;0,1=296,2=0.000000
L 11.23599665 3.39130335 11.23359665 3.38963632 2 P 0 ;0,1=296,2=0.000000
L 11.26132972 3.36671998 11.26132972 3.39171998 2 P 0 ;0,1=296,2=0.000000
L 11.26132972 3.39171998 11.25812992 3.38672028 2 P 0 ;0,1=296,2=0.000000
L 11.25812992 3.36671998 11.26452953 3.36671998 2 P 0 ;0,1=296,2=0.000000
L 11.20783327 3.42171959 11.20943297 3.41880285 2 P 0 ;0,1=297,2=0.000000
L 11.20943297 3.41880285 11.21156634 3.41713652 2 P 0 ;0,1=297,2=0.000000
L 11.21156634 3.41713652 11.21396683 3.41671998 2 P 0 ;0,1=297,2=0.000000
L 11.21396683 3.41671998 11.2161002 3.41713652 2 P 0 ;0,1=297,2=0.000000
L 11.2161002 3.41713652 11.21823356 3.41921939 2 P 0 ;0,1=297,2=0.000000
L 11.21823356 3.41921939 11.21956663 3.42171959 2 P 0 ;0,1=297,2=0.000000
L 11.21956663 3.42171959 11.21983317 3.42421988 2 P 0 ;0,1=297,2=0.000000
L 11.21983317 3.42421988 11.2193 3.42713593 2 P 0 ;0,1=297,2=0.000000
L 11.2193 3.42713593 11.21743327 3.42921959 2 P 0 ;0,1=297,2=0.000000
L 11.21743327 3.42921959 11.21556644 3.43005344 2 P 0 ;0,1=297,2=0.000000
L 11.21556644 3.43005344 11.21316654 3.43005344 2 P 0 ;0,1=297,2=0.000000
L 11.21556644 3.43005344 11.21716663 3.43130325 2 P 0 ;0,1=297,2=0.000000
L 11.21716663 3.43130325 11.2185001 3.43338612 2 P 0 ;0,1=297,2=0.000000
L 11.2185001 3.43338612 11.21903337 3.43588632 2 P 0 ;0,1=297,2=0.000000
L 11.21903337 3.43588632 11.2185001 3.43838652 2 P 0 ;0,1=297,2=0.000000
L 11.2185001 3.43838652 11.21716663 3.44046939 2 P 0 ;0,1=297,2=0.000000
L 11.21716663 3.44046939 11.21476663 3.44171998 2 P 0 ;0,1=297,2=0.000000
L 11.21476663 3.44171998 11.21236663 3.44130335 2 P 0 ;0,1=297,2=0.000000
L 11.21236663 3.44130335 11.20996663 3.43963632 2 P 0 ;0,1=297,2=0.000000
L 11.23263317 3.43755335 11.23423327 3.44005285 2 P 0 ;0,1=297,2=0.000000
L 11.23423327 3.44005285 11.2361 3.44130335 2 P 0 ;0,1=297,2=0.000000
L 11.2361 3.44130335 11.23823337 3.44171998 2 P 0 ;0,1=297,2=0.000000
L 11.23823337 3.44171998 11.2409 3.44088681 2 P 0 ;0,1=297,2=0.000000
L 11.2409 3.44088681 11.24276673 3.43880315 2 P 0 ;0,1=297,2=0.000000
L 11.24276673 3.43880315 11.2433 3.43630364 2 P 0 ;0,1=297,2=0.000000
L 11.2433 3.43630364 11.24303337 3.43380266 2 P 0 ;0,1=297,2=0.000000
L 11.24303337 3.43380266 11.24196644 3.43171978 2 P 0 ;0,1=297,2=0.000000
L 11.24196644 3.43171978 11.23663327 3.42755325 2 P 0 ;0,1=297,2=0.000000
L 11.23663327 3.42755325 11.23423327 3.42463642 2 P 0 ;0,1=297,2=0.000000
L 11.23423327 3.42463642 11.23263317 3.42046909 2 P 0 ;0,1=297,2=0.000000
L 11.23263317 3.42046909 11.2320999 3.41671998 2 P 0 ;0,1=297,2=0.000000
L 11.2320999 3.41671998 11.2433 3.41671998 2 P 0 ;0,1=297,2=0.000000
L 11.23146329 3.47171959 11.23306299 3.46880285 2 P 0 ;0,1=298,2=0.000000
L 11.23306299 3.46880285 11.23519636 3.46713652 2 P 0 ;0,1=298,2=0.000000
L 11.23519636 3.46713652 11.23759685 3.46671998 2 P 0 ;0,1=298,2=0.000000
L 11.23759685 3.46671998 11.23973022 3.46713652 2 P 0 ;0,1=298,2=0.000000
L 11.23973022 3.46713652 11.24186358 3.46921939 2 P 0 ;0,1=298,2=0.000000
L 11.24186358 3.46921939 11.24319665 3.47171959 2 P 0 ;0,1=298,2=0.000000
L 11.24319665 3.47171959 11.24346319 3.47421988 2 P 0 ;0,1=298,2=0.000000
L 11.24346319 3.47421988 11.24293002 3.47713593 2 P 0 ;0,1=298,2=0.000000
L 11.24293002 3.47713593 11.24106329 3.47921959 2 P 0 ;0,1=298,2=0.000000
L 11.24106329 3.47921959 11.23919646 3.48005344 2 P 0 ;0,1=298,2=0.000000
L 11.23919646 3.48005344 11.23679656 3.48005344 2 P 0 ;0,1=298,2=0.000000
L 11.23919646 3.48005344 11.24079665 3.48130325 2 P 0 ;0,1=298,2=0.000000
L 11.24079665 3.48130325 11.24213012 3.48338612 2 P 0 ;0,1=298,2=0.000000
L 11.24213012 3.48338612 11.24266339 3.48588632 2 P 0 ;0,1=298,2=0.000000
L 11.24266339 3.48588632 11.24213012 3.48838652 2 P 0 ;0,1=298,2=0.000000
L 11.24213012 3.48838652 11.24079665 3.49046939 2 P 0 ;0,1=298,2=0.000000
L 11.24079665 3.49046939 11.23839665 3.49171998 2 P 0 ;0,1=298,2=0.000000
L 11.23839665 3.49171998 11.23599665 3.49130335 2 P 0 ;0,1=298,2=0.000000
L 11.23599665 3.49130335 11.23359665 3.48963632 2 P 0 ;0,1=298,2=0.000000
L 11.25546329 3.47171959 11.25706299 3.46880285 2 P 0 ;0,1=298,2=0.000000
L 11.25706299 3.46880285 11.25919636 3.46713652 2 P 0 ;0,1=298,2=0.000000
L 11.25919636 3.46713652 11.26159685 3.46671998 2 P 0 ;0,1=298,2=0.000000
L 11.26159685 3.46671998 11.26373022 3.46713652 2 P 0 ;0,1=298,2=0.000000
L 11.26373022 3.46713652 11.26586358 3.46921939 2 P 0 ;0,1=298,2=0.000000
L 11.26586358 3.46921939 11.26719665 3.47171959 2 P 0 ;0,1=298,2=0.000000
L 11.26719665 3.47171959 11.26746319 3.47421988 2 P 0 ;0,1=298,2=0.000000
L 11.26746319 3.47421988 11.26693002 3.47713593 2 P 0 ;0,1=298,2=0.000000
L 11.26693002 3.47713593 11.26506329 3.47921959 2 P 0 ;0,1=298,2=0.000000
L 11.26506329 3.47921959 11.26319646 3.48005344 2 P 0 ;0,1=298,2=0.000000
L 11.26319646 3.48005344 11.26079656 3.48005344 2 P 0 ;0,1=298,2=0.000000
L 11.26319646 3.48005344 11.26479665 3.48130325 2 P 0 ;0,1=298,2=0.000000
L 11.26479665 3.48130325 11.26613012 3.48338612 2 P 0 ;0,1=298,2=0.000000
L 11.26613012 3.48338612 11.26666339 3.48588632 2 P 0 ;0,1=298,2=0.000000
L 11.26666339 3.48588632 11.26613012 3.48838652 2 P 0 ;0,1=298,2=0.000000
L 11.26613012 3.48838652 11.26479665 3.49046939 2 P 0 ;0,1=298,2=0.000000
L 11.26479665 3.49046939 11.26239665 3.49171998 2 P 0 ;0,1=298,2=0.000000
L 11.26239665 3.49171998 11.25999665 3.49130335 2 P 0 ;0,1=298,2=0.000000
L 11.25999665 3.49130335 11.25759665 3.48963632 2 P 0 ;0,1=298,2=0.000000
L 11.20783327 3.52171959 11.20943297 3.51880285 2 P 0 ;0,1=299,2=0.000000
L 11.20943297 3.51880285 11.21156634 3.51713652 2 P 0 ;0,1=299,2=0.000000
L 11.21156634 3.51713652 11.21396683 3.51671998 2 P 0 ;0,1=299,2=0.000000
L 11.21396683 3.51671998 11.2161002 3.51713652 2 P 0 ;0,1=299,2=0.000000
L 11.2161002 3.51713652 11.21823356 3.51921939 2 P 0 ;0,1=299,2=0.000000
L 11.21823356 3.51921939 11.21956663 3.52171959 2 P 0 ;0,1=299,2=0.000000
L 11.21956663 3.52171959 11.21983317 3.52421988 2 P 0 ;0,1=299,2=0.000000
L 11.21983317 3.52421988 11.2193 3.52713593 2 P 0 ;0,1=299,2=0.000000
L 11.2193 3.52713593 11.21743327 3.52921959 2 P 0 ;0,1=299,2=0.000000
L 11.21743327 3.52921959 11.21556644 3.53005344 2 P 0 ;0,1=299,2=0.000000
L 11.21556644 3.53005344 11.21316654 3.53005344 2 P 0 ;0,1=299,2=0.000000
L 11.21556644 3.53005344 11.21716663 3.53130325 2 P 0 ;0,1=299,2=0.000000
L 11.21716663 3.53130325 11.2185001 3.53338612 2 P 0 ;0,1=299,2=0.000000
L 11.2185001 3.53338612 11.21903337 3.53588632 2 P 0 ;0,1=299,2=0.000000
L 11.21903337 3.53588632 11.2185001 3.53838652 2 P 0 ;0,1=299,2=0.000000
L 11.2185001 3.53838652 11.21716663 3.54046939 2 P 0 ;0,1=299,2=0.000000
L 11.21716663 3.54046939 11.21476663 3.54171998 2 P 0 ;0,1=299,2=0.000000
L 11.21476663 3.54171998 11.21236663 3.54130335 2 P 0 ;0,1=299,2=0.000000
L 11.21236663 3.54130335 11.20996663 3.53963632 2 P 0 ;0,1=299,2=0.000000
L 11.2409 3.51671998 11.2409 3.54171998 2 P 0 ;0,1=299,2=0.000000
L 11.2409 3.54171998 11.23103297 3.52380325 2 P 0 ;0,1=299,2=0.000000
L 11.23103297 3.52380325 11.24436693 3.52380325 2 P 0 ;0,1=299,2=0.000000
L 11.23146329 3.57171959 11.23306299 3.56880285 2 P 0 ;0,1=300,2=0.000000
L 11.23306299 3.56880285 11.23519636 3.56713652 2 P 0 ;0,1=300,2=0.000000
L 11.23519636 3.56713652 11.23759685 3.56671998 2 P 0 ;0,1=300,2=0.000000
L 11.23759685 3.56671998 11.23973022 3.56713652 2 P 0 ;0,1=300,2=0.000000
L 11.23973022 3.56713652 11.24186358 3.56921939 2 P 0 ;0,1=300,2=0.000000
L 11.24186358 3.56921939 11.24319665 3.57171959 2 P 0 ;0,1=300,2=0.000000
L 11.24319665 3.57171959 11.24346319 3.57421988 2 P 0 ;0,1=300,2=0.000000
L 11.24346319 3.57421988 11.24293002 3.57713593 2 P 0 ;0,1=300,2=0.000000
L 11.24293002 3.57713593 11.24106329 3.57921959 2 P 0 ;0,1=300,2=0.000000
L 11.24106329 3.57921959 11.23919646 3.58005344 2 P 0 ;0,1=300,2=0.000000
L 11.23919646 3.58005344 11.23679656 3.58005344 2 P 0 ;0,1=300,2=0.000000
L 11.23919646 3.58005344 11.24079665 3.58130325 2 P 0 ;0,1=300,2=0.000000
L 11.24079665 3.58130325 11.24213012 3.58338612 2 P 0 ;0,1=300,2=0.000000
L 11.24213012 3.58338612 11.24266339 3.58588632 2 P 0 ;0,1=300,2=0.000000
L 11.24266339 3.58588632 11.24213012 3.58838652 2 P 0 ;0,1=300,2=0.000000
L 11.24213012 3.58838652 11.24079665 3.59046939 2 P 0 ;0,1=300,2=0.000000
L 11.24079665 3.59046939 11.23839665 3.59171998 2 P 0 ;0,1=300,2=0.000000
L 11.23839665 3.59171998 11.23599665 3.59130335 2 P 0 ;0,1=300,2=0.000000
L 11.23599665 3.59130335 11.23359665 3.58963632 2 P 0 ;0,1=300,2=0.000000
L 11.25546329 3.57046909 11.25706299 3.56838622 2 P 0 ;0,1=300,2=0.000000
L 11.25706299 3.56838622 11.25892972 3.56713652 2 P 0 ;0,1=300,2=0.000000
L 11.25892972 3.56713652 11.26132972 3.56671998 2 P 0 ;0,1=300,2=0.000000
L 11.26132972 3.56671998 11.26373022 3.56755305 2 P 0 ;0,1=300,2=0.000000
L 11.26373022 3.56755305 11.26559646 3.56921939 2 P 0 ;0,1=300,2=0.000000
L 11.26559646 3.56921939 11.26693002 3.57213622 2 P 0 ;0,1=300,2=0.000000
L 11.26693002 3.57213622 11.26719665 3.57546959 2 P 0 ;0,1=300,2=0.000000
L 11.26719665 3.57546959 11.26666339 3.57880295 2 P 0 ;0,1=300,2=0.000000
L 11.26666339 3.57880295 11.26532982 3.58088661 2 P 0 ;0,1=300,2=0.000000
L 11.26532982 3.58088661 11.26346309 3.58255295 2 P 0 ;0,1=300,2=0.000000
L 11.26346309 3.58255295 11.26159685 3.58296949 2 P 0 ;0,1=300,2=0.000000
L 11.26159685 3.58296949 11.25973002 3.58255295 2 P 0 ;0,1=300,2=0.000000
L 11.25973002 3.58255295 11.25733012 3.58088661 2 P 0 ;0,1=300,2=0.000000
L 11.25733012 3.58088661 11.25812992 3.59171998 2 P 0 ;0,1=300,2=0.000000
L 11.25812992 3.59171998 11.26532982 3.59171998 2 P 0 ;0,1=300,2=0.000000
L 11.20783327 3.62171959 11.20943297 3.61880285 2 P 0 ;0,1=301,2=0.000000
L 11.20943297 3.61880285 11.21156634 3.61713652 2 P 0 ;0,1=301,2=0.000000
L 11.21156634 3.61713652 11.21396683 3.61671998 2 P 0 ;0,1=301,2=0.000000
L 11.21396683 3.61671998 11.2161002 3.61713652 2 P 0 ;0,1=301,2=0.000000
L 11.2161002 3.61713652 11.21823356 3.61921939 2 P 0 ;0,1=301,2=0.000000
L 11.21823356 3.61921939 11.21956663 3.62171959 2 P 0 ;0,1=301,2=0.000000
L 11.21956663 3.62171959 11.21983317 3.62421988 2 P 0 ;0,1=301,2=0.000000
L 11.21983317 3.62421988 11.2193 3.62713593 2 P 0 ;0,1=301,2=0.000000
L 11.2193 3.62713593 11.21743327 3.62921959 2 P 0 ;0,1=301,2=0.000000
L 11.21743327 3.62921959 11.21556644 3.63005344 2 P 0 ;0,1=301,2=0.000000
L 11.21556644 3.63005344 11.21316654 3.63005344 2 P 0 ;0,1=301,2=0.000000
L 11.21556644 3.63005344 11.21716663 3.63130325 2 P 0 ;0,1=301,2=0.000000
L 11.21716663 3.63130325 11.2185001 3.63338612 2 P 0 ;0,1=301,2=0.000000
L 11.2185001 3.63338612 11.21903337 3.63588632 2 P 0 ;0,1=301,2=0.000000
L 11.21903337 3.63588632 11.2185001 3.63838652 2 P 0 ;0,1=301,2=0.000000
L 11.2185001 3.63838652 11.21716663 3.64046939 2 P 0 ;0,1=301,2=0.000000
L 11.21716663 3.64046939 11.21476663 3.64171998 2 P 0 ;0,1=301,2=0.000000
L 11.21476663 3.64171998 11.21236663 3.64130335 2 P 0 ;0,1=301,2=0.000000
L 11.21236663 3.64130335 11.20996663 3.63963632 2 P 0 ;0,1=301,2=0.000000
L 11.23263317 3.62713593 11.2344999 3.63005344 2 P 0 ;0,1=301,2=0.000000
L 11.2344999 3.63005344 11.2361 3.63171978 2 P 0 ;0,1=301,2=0.000000
L 11.2361 3.63171978 11.23823337 3.63255295 2 P 0 ;0,1=301,2=0.000000
L 11.23823337 3.63255295 11.2401002 3.63171978 2 P 0 ;0,1=301,2=0.000000
L 11.2401002 3.63171978 11.24143327 3.63005344 2 P 0 ;0,1=301,2=0.000000
L 11.24143327 3.63005344 11.2425001 3.62755325 2 P 0 ;0,1=301,2=0.000000
L 11.2425001 3.62755325 11.24276673 3.62463642 2 P 0 ;0,1=301,2=0.000000
L 11.24276673 3.62463642 11.2425001 3.62213622 2 P 0 ;0,1=301,2=0.000000
L 11.2425001 3.62213622 11.24143327 3.61963602 2 P 0 ;0,1=301,2=0.000000
L 11.24143327 3.61963602 11.23983307 3.61755305 2 P 0 ;0,1=301,2=0.000000
L 11.23983307 3.61755305 11.23796683 3.61671998 2 P 0 ;0,1=301,2=0.000000
L 11.23796683 3.61671998 11.23583346 3.61755305 2 P 0 ;0,1=301,2=0.000000
L 11.23583346 3.61755305 11.23396663 3.62005256 2 P 0 ;0,1=301,2=0.000000
L 11.23396663 3.62005256 11.2328998 3.62380325 2 P 0 ;0,1=301,2=0.000000
L 11.2328998 3.62380325 11.23263317 3.62796978 2 P 0 ;0,1=301,2=0.000000
L 11.23263317 3.62796978 11.23316634 3.63338612 2 P 0 ;0,1=301,2=0.000000
L 11.23316634 3.63338612 11.23396663 3.63630364 2 P 0 ;0,1=301,2=0.000000
L 11.23396663 3.63630364 11.2352997 3.63921969 2 P 0 ;0,1=301,2=0.000000
L 11.2352997 3.63921969 11.23716654 3.64130335 2 P 0 ;0,1=301,2=0.000000
L 11.23716654 3.64130335 11.23903327 3.64171998 2 P 0 ;0,1=301,2=0.000000
L 11.23903327 3.64171998 11.2409 3.64088681 2 P 0 ;0,1=301,2=0.000000
L 11.2409 3.64088681 11.24223356 3.63880315 2 P 0 ;0,1=301,2=0.000000
L 11.23146329 3.67171959 11.23306299 3.66880285 2 P 0 ;0,1=302,2=0.000000
L 11.23306299 3.66880285 11.23519636 3.66713652 2 P 0 ;0,1=302,2=0.000000
L 11.23519636 3.66713652 11.23759685 3.66671998 2 P 0 ;0,1=302,2=0.000000
L 11.23759685 3.66671998 11.23973022 3.66713652 2 P 0 ;0,1=302,2=0.000000
L 11.23973022 3.66713652 11.24186358 3.66921939 2 P 0 ;0,1=302,2=0.000000
L 11.24186358 3.66921939 11.24319665 3.67171959 2 P 0 ;0,1=302,2=0.000000
L 11.24319665 3.67171959 11.24346319 3.67421988 2 P 0 ;0,1=302,2=0.000000
L 11.24346319 3.67421988 11.24293002 3.67713593 2 P 0 ;0,1=302,2=0.000000
L 11.24293002 3.67713593 11.24106329 3.67921959 2 P 0 ;0,1=302,2=0.000000
L 11.24106329 3.67921959 11.23919646 3.68005344 2 P 0 ;0,1=302,2=0.000000
L 11.23919646 3.68005344 11.23679656 3.68005344 2 P 0 ;0,1=302,2=0.000000
L 11.23919646 3.68005344 11.24079665 3.68130325 2 P 0 ;0,1=302,2=0.000000
L 11.24079665 3.68130325 11.24213012 3.68338612 2 P 0 ;0,1=302,2=0.000000
L 11.24213012 3.68338612 11.24266339 3.68588632 2 P 0 ;0,1=302,2=0.000000
L 11.24266339 3.68588632 11.24213012 3.68838652 2 P 0 ;0,1=302,2=0.000000
L 11.24213012 3.68838652 11.24079665 3.69046939 2 P 0 ;0,1=302,2=0.000000
L 11.24079665 3.69046939 11.23839665 3.69171998 2 P 0 ;0,1=302,2=0.000000
L 11.23839665 3.69171998 11.23599665 3.69130335 2 P 0 ;0,1=302,2=0.000000
L 11.23599665 3.69130335 11.23359665 3.68963632 2 P 0 ;0,1=302,2=0.000000
L 11.26079656 3.66671998 11.26132972 3.67213622 2 P 0 ;0,1=302,2=0.000000
L 11.26132972 3.67213622 11.26213002 3.67671929 2 P 0 ;0,1=302,2=0.000000
L 11.26213002 3.67671929 11.26319646 3.68088661 2 P 0 ;0,1=302,2=0.000000
L 11.26319646 3.68088661 11.26453002 3.68546978 2 P 0 ;0,1=302,2=0.000000
L 11.26453002 3.68546978 11.26666339 3.69171998 2 P 0 ;0,1=302,2=0.000000
L 11.26666339 3.69171998 11.25599656 3.69171998 2 P 0 ;0,1=302,2=0.000000
L 11.20783327 3.72171959 11.20943297 3.71880285 2 P 0 ;0,1=303,2=0.000000
L 11.20943297 3.71880285 11.21156634 3.71713652 2 P 0 ;0,1=303,2=0.000000
L 11.21156634 3.71713652 11.21396683 3.71671998 2 P 0 ;0,1=303,2=0.000000
L 11.21396683 3.71671998 11.2161002 3.71713652 2 P 0 ;0,1=303,2=0.000000
L 11.2161002 3.71713652 11.21823356 3.71921939 2 P 0 ;0,1=303,2=0.000000
L 11.21823356 3.71921939 11.21956663 3.72171959 2 P 0 ;0,1=303,2=0.000000
L 11.21956663 3.72171959 11.21983317 3.72421988 2 P 0 ;0,1=303,2=0.000000
L 11.21983317 3.72421988 11.2193 3.72713593 2 P 0 ;0,1=303,2=0.000000
L 11.2193 3.72713593 11.21743327 3.72921959 2 P 0 ;0,1=303,2=0.000000
L 11.21743327 3.72921959 11.21556644 3.73005344 2 P 0 ;0,1=303,2=0.000000
L 11.21556644 3.73005344 11.21316654 3.73005344 2 P 0 ;0,1=303,2=0.000000
L 11.21556644 3.73005344 11.21716663 3.73130325 2 P 0 ;0,1=303,2=0.000000
L 11.21716663 3.73130325 11.2185001 3.73338612 2 P 0 ;0,1=303,2=0.000000
L 11.2185001 3.73338612 11.21903337 3.73588632 2 P 0 ;0,1=303,2=0.000000
L 11.21903337 3.73588632 11.2185001 3.73838652 2 P 0 ;0,1=303,2=0.000000
L 11.2185001 3.73838652 11.21716663 3.74046939 2 P 0 ;0,1=303,2=0.000000
L 11.21716663 3.74046939 11.21476663 3.74171998 2 P 0 ;0,1=303,2=0.000000
L 11.21476663 3.74171998 11.21236663 3.74130335 2 P 0 ;0,1=303,2=0.000000
L 11.21236663 3.74130335 11.20996663 3.73963632 2 P 0 ;0,1=303,2=0.000000
L 11.2376997 3.71671998 11.23956644 3.71713652 2 P 0 ;0,1=303,2=0.000000
L 11.23956644 3.71713652 11.2416998 3.71838622 2 P 0 ;0,1=303,2=0.000000
L 11.2416998 3.71838622 11.24303337 3.72046909 2 P 0 ;0,1=303,2=0.000000
L 11.24303337 3.72046909 11.24356663 3.72338671 2 P 0 ;0,1=303,2=0.000000
L 11.24356663 3.72338671 11.24303337 3.72630276 2 P 0 ;0,1=303,2=0.000000
L 11.24303337 3.72630276 11.24143327 3.72880295 2 P 0 ;0,1=303,2=0.000000
L 11.24143327 3.72880295 11.23903327 3.73005344 2 P 0 ;0,1=303,2=0.000000
L 11.23903327 3.73005344 11.23636663 3.73005344 2 P 0 ;0,1=303,2=0.000000
L 11.23636663 3.73005344 11.23476654 3.73088661 2 P 0 ;0,1=303,2=0.000000
L 11.23476654 3.73088661 11.23343297 3.73296949 2 P 0 ;0,1=303,2=0.000000
L 11.23343297 3.73296949 11.2328998 3.73588632 2 P 0 ;0,1=303,2=0.000000
L 11.2328998 3.73588632 11.2337001 3.73880315 2 P 0 ;0,1=303,2=0.000000
L 11.2337001 3.73880315 11.23556634 3.74088681 2 P 0 ;0,1=303,2=0.000000
L 11.23556634 3.74088681 11.2376997 3.74171998 2 P 0 ;0,1=303,2=0.000000
L 11.2376997 3.74171998 11.23983307 3.74088681 2 P 0 ;0,1=303,2=0.000000
L 11.23983307 3.74088681 11.2416998 3.73880315 2 P 0 ;0,1=303,2=0.000000
L 11.2416998 3.73880315 11.2425001 3.73588632 2 P 0 ;0,1=303,2=0.000000
L 11.2425001 3.73588632 11.24196644 3.73296949 2 P 0 ;0,1=303,2=0.000000
L 11.24196644 3.73296949 11.24063337 3.73088661 2 P 0 ;0,1=303,2=0.000000
L 11.24063337 3.73088661 11.23903327 3.73005344 2 P 0 ;0,1=303,2=0.000000
L 11.23903327 3.73005344 11.23636663 3.73005344 2 P 0 ;0,1=303,2=0.000000
L 11.23636663 3.73005344 11.23396663 3.72880295 2 P 0 ;0,1=303,2=0.000000
L 11.23396663 3.72880295 11.23236654 3.72630276 2 P 0 ;0,1=303,2=0.000000
L 11.23236654 3.72630276 11.23183327 3.72338671 2 P 0 ;0,1=303,2=0.000000
L 11.23183327 3.72338671 11.23236654 3.72046909 2 P 0 ;0,1=303,2=0.000000
L 11.23236654 3.72046909 11.2337001 3.71838622 2 P 0 ;0,1=303,2=0.000000
L 11.2337001 3.71838622 11.23583346 3.71713652 2 P 0 ;0,1=303,2=0.000000
L 11.23583346 3.71713652 11.2376997 3.71671998 2 P 0 ;0,1=303,2=0.000000
L 11.23146329 3.77171959 11.23306299 3.76880285 2 P 0 ;0,1=304,2=0.000000
L 11.23306299 3.76880285 11.23519636 3.76713652 2 P 0 ;0,1=304,2=0.000000
L 11.23519636 3.76713652 11.23759685 3.76671998 2 P 0 ;0,1=304,2=0.000000
L 11.23759685 3.76671998 11.23973022 3.76713652 2 P 0 ;0,1=304,2=0.000000
L 11.23973022 3.76713652 11.24186358 3.76921939 2 P 0 ;0,1=304,2=0.000000
L 11.24186358 3.76921939 11.24319665 3.77171959 2 P 0 ;0,1=304,2=0.000000
L 11.24319665 3.77171959 11.24346319 3.77421988 2 P 0 ;0,1=304,2=0.000000
L 11.24346319 3.77421988 11.24293002 3.77713593 2 P 0 ;0,1=304,2=0.000000
L 11.24293002 3.77713593 11.24106329 3.77921959 2 P 0 ;0,1=304,2=0.000000
L 11.24106329 3.77921959 11.23919646 3.78005344 2 P 0 ;0,1=304,2=0.000000
L 11.23919646 3.78005344 11.23679656 3.78005344 2 P 0 ;0,1=304,2=0.000000
L 11.23919646 3.78005344 11.24079665 3.78130325 2 P 0 ;0,1=304,2=0.000000
L 11.24079665 3.78130325 11.24213012 3.78338612 2 P 0 ;0,1=304,2=0.000000
L 11.24213012 3.78338612 11.24266339 3.78588632 2 P 0 ;0,1=304,2=0.000000
L 11.24266339 3.78588632 11.24213012 3.78838652 2 P 0 ;0,1=304,2=0.000000
L 11.24213012 3.78838652 11.24079665 3.79046939 2 P 0 ;0,1=304,2=0.000000
L 11.24079665 3.79046939 11.23839665 3.79171998 2 P 0 ;0,1=304,2=0.000000
L 11.23839665 3.79171998 11.23599665 3.79130335 2 P 0 ;0,1=304,2=0.000000
L 11.23599665 3.79130335 11.23359665 3.78963632 2 P 0 ;0,1=304,2=0.000000
L 11.25679636 3.76963602 11.25866319 3.76755305 2 P 0 ;0,1=304,2=0.000000
L 11.25866319 3.76755305 11.26079656 3.76671998 2 P 0 ;0,1=304,2=0.000000
L 11.26079656 3.76671998 11.26292992 3.76755305 2 P 0 ;0,1=304,2=0.000000
L 11.26292992 3.76755305 11.26479665 3.77005256 2 P 0 ;0,1=304,2=0.000000
L 11.26479665 3.77005256 11.26613012 3.77380325 2 P 0 ;0,1=304,2=0.000000
L 11.26613012 3.77380325 11.26666339 3.77755325 2 P 0 ;0,1=304,2=0.000000
L 11.26666339 3.77755325 11.26666339 3.78213632 2 P 0 ;0,1=304,2=0.000000
L 11.26666339 3.78213632 11.26613012 3.78588632 2 P 0 ;0,1=304,2=0.000000
L 11.26613012 3.78588632 11.26479665 3.78921969 2 P 0 ;0,1=304,2=0.000000
L 11.26479665 3.78921969 11.26319646 3.79088681 2 P 0 ;0,1=304,2=0.000000
L 11.26319646 3.79088681 11.26132972 3.79171998 2 P 0 ;0,1=304,2=0.000000
L 11.26132972 3.79171998 11.25919636 3.79088681 2 P 0 ;0,1=304,2=0.000000
L 11.25919636 3.79088681 11.25759665 3.78921969 2 P 0 ;0,1=304,2=0.000000
L 11.25759665 3.78921969 11.25652982 3.78672028 2 P 0 ;0,1=304,2=0.000000
L 11.25652982 3.78672028 11.25599656 3.78338612 2 P 0 ;0,1=304,2=0.000000
L 11.25599656 3.78338612 11.25652982 3.78047008 2 P 0 ;0,1=304,2=0.000000
L 11.25652982 3.78047008 11.25786329 3.77755325 2 P 0 ;0,1=304,2=0.000000
L 11.25786329 3.77755325 11.25946348 3.77588612 2 P 0 ;0,1=304,2=0.000000
L 11.25946348 3.77588612 11.26132972 3.77546959 2 P 0 ;0,1=304,2=0.000000
L 11.26132972 3.77546959 11.26346309 3.77630276 2 P 0 ;0,1=304,2=0.000000
L 11.26346309 3.77630276 11.26506329 3.77838642 2 P 0 ;0,1=304,2=0.000000
L 11.26506329 3.77838642 11.26666339 3.78213632 2 P 0 ;0,1=304,2=0.000000
L 11.2169 3.81671998 11.2169 3.84171998 2 P 0 ;0,1=305,2=0.000000
L 11.2169 3.84171998 11.20703297 3.82380325 2 P 0 ;0,1=305,2=0.000000
L 11.20703297 3.82380325 11.22036693 3.82380325 2 P 0 ;0,1=305,2=0.000000
L 11.2376997 3.84171998 11.23556634 3.84088681 2 P 0 ;0,1=305,2=0.000000
L 11.23556634 3.84088681 11.23396663 3.83880315 2 P 0 ;0,1=305,2=0.000000
L 11.23396663 3.83880315 11.2328998 3.83630364 2 P 0 ;0,1=305,2=0.000000
L 11.2328998 3.83630364 11.2320999 3.83296949 2 P 0 ;0,1=305,2=0.000000
L 11.2320999 3.83296949 11.23183327 3.82921959 2 P 0 ;0,1=305,2=0.000000
L 11.23183327 3.82921959 11.2320999 3.82546959 2 P 0 ;0,1=305,2=0.000000
L 11.2320999 3.82546959 11.2328998 3.82213622 2 P 0 ;0,1=305,2=0.000000
L 11.2328998 3.82213622 11.23396663 3.81963602 2 P 0 ;0,1=305,2=0.000000
L 11.23396663 3.81963602 11.23556634 3.81755305 2 P 0 ;0,1=305,2=0.000000
L 11.23556634 3.81755305 11.2376997 3.81671998 2 P 0 ;0,1=305,2=0.000000
L 11.2376997 3.81671998 11.23983307 3.81755305 2 P 0 ;0,1=305,2=0.000000
L 11.23983307 3.81755305 11.24143327 3.81963602 2 P 0 ;0,1=305,2=0.000000
L 11.24143327 3.81963602 11.2425001 3.82213622 2 P 0 ;0,1=305,2=0.000000
L 11.2425001 3.82213622 11.2433 3.82546959 2 P 0 ;0,1=305,2=0.000000
L 11.2433 3.82546959 11.24356663 3.82921959 2 P 0 ;0,1=305,2=0.000000
L 11.24356663 3.82921959 11.2433 3.83296949 2 P 0 ;0,1=305,2=0.000000
L 11.2433 3.83296949 11.2425001 3.83630364 2 P 0 ;0,1=305,2=0.000000
L 11.2425001 3.83630364 11.24143327 3.83880315 2 P 0 ;0,1=305,2=0.000000
L 11.24143327 3.83880315 11.23983307 3.84088681 2 P 0 ;0,1=305,2=0.000000
L 11.23983307 3.84088681 11.2376997 3.84171998 2 P 0 ;0,1=305,2=0.000000

### steps/drc/layers/legs/features
#
#Feature symbol names
#
$0 r2
$1 r5
$2 r6
$3 r7.87
$4 r15

#
#Feature attribute names
#
@0 .nomenclature
@1 .string_mirrored
@2 .string
@3 .string_angle

#
#Feature attribute text strings
#
&0 1
&1 10
&2 9
&3 18
&4 A82
&5 A2
&6 B11
&7 A1
&8 B82
&9 B2
&10 B1
&11 B12
&12 A11
&13 A12
&14 A10
&15 A13
&16 B13
&17 B10
&18 A81
&19 B81
&20 SHEET
&21 TITLE
&22 SCALE 1:1
&23 LAYER
&24 OF
&25 ART
&26 SILK SCREEN ( BOT )
&27 -
&28 Barreleye G2 SXM2-Riser
&29 DATE OCT/27/2017
&30 FD3
&31 FD1
&32 FD10
&33 FD12
&34 FD4
&35 FD5
&36 FD6
&37 R1562
&38 R1561
&39 R1560
&40 R1559
&41 R1611
&42 R1610
&43 R1628
&44 R1631
&45 R1629
&46 R1630
&47 R1595
&48 R1594
&49 R1600
&50 R1593
&51 R1592
&52 PSTR8
&53 PSTR1
&54 PSTR36
&55 PSTR14
&56 PSTR7
&57 PSTR5
&58 PSTR12
&59 PSTR11
&60 R1587
&61 R1574
&62 R1573
&63 R1572
&64 R1570
&65 R1568
&66 R1566
&67 R1571
&68 R1569
&69 R1567
&70 R1565
&71 R1564
&72 R1563
&73 R1556
&74 R1550
&75 R1551
&76 R1555
&77 R1557
&78 R1549
&79 R1552
&80 R1553
&81 R1558
&82 R1554
&83 R1545
&84 R1536
&85 R1535
&86 R1532
&87 R1533
&88 R1527
&89 R1526
&90 R1525
&91 R1513
&92 R1512
&93 R1511
&94 R1505
&95 R1504
&96 R1503
&97 R1502
&98 R1501
&99 R1494
&100 R1493
&101 R1472
&102 R1544
&103 R1517
&104 R1516
&105 R1515
&106 R1514
&107 R1461
&108 R1460
&109 R1154
&110 R1153
&111 R5
&112 R2
&113 R1522
&114 R1521
&115 R1490
&116 R1
&117 R1531
&118 PSTC25
&119 PSTC18
&120 PSTC32
&121 PSTC27
&122 PSTC24
&123 PSTC30
&124 PSTC31
&125 PSTC23
&126 PSTC16
&127 PSTC17
&128 PSTC19
&129 PSTC4
&130 PSTC9
&131 PSTC10
&132 PSTC7
&133 C2235
&134 C2234
&135 C2233
&136 C2232
&137 C2231
&138 C1993
&139 C1992
&140 C1991
&141 C1930
&142 C1929
&143 C423
&144 C422
&145 C430
&146 C5
&147 C6
&148 C427
&149 C428
&150 C429
&151 C433
&152 C434
&153 C439
&154 C440
&155 C421
&156 C424
&157 C4
&158 C3
&159 C425
&160 C426
&161 C431
&162 C432
&163 C435
&164 C436
&165 C438
&166 C437
&167 C2237
&168 C1
&169 C2
&170 C2198
&171 C2199
&172 C2200
&173 C2201
&174 C2202
&175 C2203
&176 C2204
&177 C2205
&178 C2206
&179 C2207
&180 C2208
&181 C2209
&182 C2210
&183 C2211
&184 C2212
&185 C2213
&186 C2214
&187 C2215
&188 C2216
&189 C2217
&190 C2218
&191 C2219
&192 C2220
&193 C2221
&194 C2222
&195 C2223
&196 C2224
&197 C2225
&198 C2226
&199 C2227
&200 C2228
&201 C2229
&202 C415
&203 C2230
&204 C416
&205 C2184
&206 C2181
&207 C2176
&208 C2175
&209 C418
&210 C420
&211 C419
&212 U166
&213 U167
&214 U168
&215 U172
&216 U75

#
#Layer features
#
L 1.88908002 -1.91246004 1.89293002 -1.91246004 0 P 0 
L 1.89126998 -1.91146004 1.89656998 -1.91146004 0 P 0 
L 1.89393996 -1.91046004 1.9155 -1.91046004 0 P 0 
L 1.91593996 -1.91246004 1.92048996 -1.91246004 0 P 0 
L 1.9126 -1.91146004 1.9184 -1.91146004 0 P 0 
L 1.89763002 -1.90946004 1.91016998 -1.90946004 0 P 0 
L 1.89053002 -1.96001004 1.8974 -1.96001004 0 P 0 
L 1.89053002 -1.95901004 1.8974 -1.95901004 0 P 0 
L 1.89053002 -1.95801004 1.8974 -1.95801004 0 P 0 
L 1.89053002 -1.95701004 1.8974 -1.95701004 0 P 0 
L 1.89053002 -1.95601004 1.8974 -1.95601004 0 P 0 
L 1.89053002 -1.95501004 1.8974 -1.95501004 0 P 0 
L 1.89053002 -1.95401004 1.8974 -1.95401004 0 P 0 
L 1.89053002 -1.95301004 1.89741004 -1.95301004 0 P 0 
L 1.89053002 -1.95201004 1.89741998 -1.95201004 0 P 0 
L 1.89053002 -1.95101004 1.89743996 -1.95101004 0 P 0 
L 1.89053002 -1.95001004 1.89745 -1.95001004 0 P 0 
L 1.89053002 -1.94901004 1.89746004 -1.94901004 0 P 0 
L 1.89053002 -1.94801004 1.89753002 -1.94801004 0 P 0 
L 1.89053002 -1.94701004 1.8977 -1.94701004 0 P 0 
L 1.89053002 -1.94601004 1.89798002 -1.94601004 0 P 0 
L 1.89053002 -1.94501004 1.89861004 -1.94501004 0 P 0 
L 1.89053002 -1.94401004 1.90005 -1.94401004 0 P 0 
L 1.89053002 -1.94301004 1.9113 -1.94301004 0 P 0 
L 1.89053002 -1.94201004 1.91168002 -1.94201004 0 P 0 
L 1.89053002 -1.94101004 1.91246998 -1.94101004 0 P 0 
L 1.89053002 -1.94001004 1.90093996 -1.94001004 0 P 0 
L 1.89053002 -1.93901004 1.89856004 -1.93901004 0 P 0 
L 1.89053002 -1.93801004 1.89786998 -1.93801004 0 P 0 
L 1.89053002 -1.93701004 1.89753996 -1.93701004 0 P 0 
L 1.89053002 -1.93601004 1.89746998 -1.93601004 0 P 0 
L 1.89053002 -1.93501004 1.89743996 -1.93501004 0 P 0 
L 1.89053002 -1.93401004 1.89741998 -1.93401004 0 P 0 
L 1.89053002 -1.93301004 1.8974 -1.93301004 0 P 0 
L 1.89053002 -1.93201004 1.8974 -1.93201004 0 P 0 
L 1.89053002 -1.93101004 1.8974 -1.93101004 0 P 0 
L 1.89053002 -1.93001004 1.8974 -1.93001004 0 P 0 
L 1.89053002 -1.92901004 1.8974 -1.92901004 0 P 0 
L 1.89053002 -1.92801004 1.89753002 -1.92801004 0 P 0 
L 1.89053002 -1.92701004 1.89793996 -1.92701004 0 P 0 
L 1.89053002 -1.92601004 1.91713002 -1.92601004 0 P 0 
L 1.89053002 -1.92501004 1.91628996 -1.92501004 0 P 0 
L 1.89053002 -1.92401004 1.91513996 -1.92401004 0 P 0 
L 1.89053002 -1.92301004 1.91321998 -1.92301004 0 P 0 
L 1.89053002 -1.92201004 1.90551004 -1.92201004 0 P 0 
L 1.89438996 -1.97246004 1.91331004 -1.97246004 0 P 0 
L 1.89106998 -1.97146004 1.89973002 -1.97146004 0 P 0 
L 1.88878002 -1.97046004 1.8949 -1.97046004 0 P 0 
L 1.88698002 -1.96946004 1.89206998 -1.96946004 0 P 0 
L 1.88546004 -1.96846004 1.88986998 -1.96846004 0 P 0 
L 1.88416998 -1.96746004 1.88808996 -1.96746004 0 P 0 
L 1.88288002 -1.96646004 1.88655 -1.96646004 0 P 0 
L 1.88176998 -1.96546004 1.88518002 -1.96546004 0 P 0 
L 1.88068996 -1.96446004 1.88393996 -1.96446004 0 P 0 
L 1.87968996 -1.96346004 1.88286004 -1.96346004 0 P 0 
L 1.87878002 -1.96246004 1.88186004 -1.96246004 0 P 0 
L 1.8786 -1.92046004 1.88126998 -1.92046004 0 P 0 
L 1.87946998 -1.91946004 1.88223002 -1.91946004 0 P 0 
L 1.88048002 -1.91846004 1.88321004 -1.91846004 0 P 0 
L 1.88153996 -1.91746004 1.88436998 -1.91746004 0 P 0 
L 1.88273002 -1.91646004 1.88558996 -1.91646004 0 P 0 
L 1.88406004 -1.91546004 1.88696998 -1.91546004 0 P 0 
L 1.88548996 -1.91446004 1.88853002 -1.91446004 0 P 0 
L 1.88718002 -1.91346004 1.89041998 -1.91346004 0 P 0 
L 1.90896004 -1.92963996 1.90921998 -1.92991998 0 P 0 
L 1.90921998 -1.92991998 1.90945 -1.93021998 0 P 0 
L 1.90945 -1.93021998 1.90966004 -1.93053002 0 P 0 
L 1.90966004 -1.93053002 1.90983002 -1.93086004 0 P 0 
L 1.90983002 -1.93086004 1.90998002 -1.93121004 0 P 0 
L 1.90998002 -1.93121004 1.9101 -1.93156998 0 P 0 
L 1.9101 -1.93156998 1.91018996 -1.93193996 0 P 0 
L 1.91018996 -1.93193996 1.91023996 -1.93231004 0 P 0 
L 1.91023996 -1.93231004 1.91026998 -1.93265 0 P 0 
L 1.91026998 -1.93265 1.91026004 -1.93298002 0 P 0 
L 1.91026004 -1.93298002 1.91023002 -1.93331004 0 P 0 
L 1.91023002 -1.93331004 1.91016998 -1.93363996 0 P 0 
L 1.91016998 -1.93363996 1.91008996 -1.93396004 0 P 0 
L 1.91008996 -1.93396004 1.90998002 -1.93428002 0 P 0 
L 1.90998002 -1.93428002 1.90983996 -1.93458002 0 P 0 
L 1.90983996 -1.93458002 1.90968996 -1.93486998 0 P 0 
L 1.90968996 -1.93486998 1.90951004 -1.93516004 0 P 0 
L 1.90951004 -1.93516004 1.90921004 -1.93556004 0 P 0 
L 1.90921004 -1.93556004 1.90888002 -1.93593002 0 P 0 
L 1.90888002 -1.93593002 1.90853002 -1.93626998 0 P 0 
L 1.90853002 -1.93626998 1.90815 -1.93658996 0 P 0 
L 1.90815 -1.93658996 1.90773996 -1.93686998 0 P 0 
L 1.90773996 -1.93686998 1.90731998 -1.93711998 0 P 0 
L 1.90731998 -1.93711998 1.90686998 -1.93733996 0 P 0 
L 1.90686998 -1.93733996 1.90615 -1.93761004 0 P 0 
L 1.90615 -1.93761004 1.90541998 -1.93783002 0 P 0 
L 1.90541998 -1.93783002 1.90466004 -1.93798002 0 P 0 
L 1.90466004 -1.93798002 1.9039 -1.93808002 0 P 0 
L 1.9039 -1.93808002 1.90311998 -1.9381 0 P 0 
L 1.90311998 -1.9381 1.90196004 -1.93808002 0 P 0 
L 1.90196004 -1.93808002 1.90078996 -1.93798996 0 P 0 
L 1.90078996 -1.93798996 1.90068002 -1.93798002 0 P 0 
L 1.90068002 -1.93798002 1.90058002 -1.93795 0 P 0 
L 1.90058002 -1.93795 1.90046998 -1.93791998 0 P 0 
L 1.90046998 -1.93791998 1.90038002 -1.93788002 0 P 0 
L 1.90038002 -1.93788002 1.90028002 -1.93783002 0 P 0 
L 1.90028002 -1.93783002 1.90018996 -1.93778002 0 P 0 
L 1.90018996 -1.93778002 1.9001 -1.93771004 0 P 0 
L 1.9001 -1.93771004 1.90001998 -1.93763996 0 P 0 
L 1.90001998 -1.93763996 1.89988002 -1.93748002 0 P 0 
L 1.89988002 -1.93748002 1.89978002 -1.93733996 0 P 0 
L 1.89978002 -1.93733996 1.89961998 -1.93703996 0 P 0 
L 1.89961998 -1.93703996 1.89956998 -1.93688002 0 P 0 
L 1.89956998 -1.93688002 1.89951998 -1.93671004 0 P 0 
L 1.89951998 -1.93671004 1.89948996 -1.93655 0 P 0 
L 1.89948996 -1.93655 1.89946998 -1.93636998 0 P 0 
L 1.89946998 -1.93636998 1.8994 -1.93323002 0 P 0 
L 1.8994 -1.93323002 1.8994 -1.92833002 0 P 0 
L 1.8994 -1.92833002 1.90353996 -1.92833002 0 P 0 
L 1.90353996 -1.92833002 1.90436998 -1.92835 0 P 0 
L 1.90436998 -1.92835 1.9052 -1.92843002 0 P 0 
L 1.9052 -1.92843002 1.90603002 -1.92853996 0 P 0 
L 1.90603002 -1.92853996 1.90683996 -1.92871004 0 P 0 
L 1.90683996 -1.92871004 1.90751004 -1.9289 0 P 0 
L 1.90751004 -1.9289 1.90818002 -1.92913002 0 P 0 
L 1.90818002 -1.92913002 1.90851998 -1.92928996 0 P 0 
L 1.90851998 -1.92928996 1.90868002 -1.92938996 0 P 0 
L 1.90868002 -1.92938996 1.90883002 -1.92951004 0 P 0 
L 1.90883002 -1.92951004 1.90896004 -1.92963996 0 P 0 
L 1.91188996 -1.96001004 1.91638996 -1.96001004 0 P 0 
L 1.91156998 -1.95901004 1.91926998 -1.95901004 0 P 0 
L 1.91125 -1.95801004 1.91891998 -1.95801004 0 P 0 
L 1.91091998 -1.95701004 1.91853002 -1.95701004 0 P 0 
L 1.9106 -1.95601004 1.91811004 -1.95601004 0 P 0 
L 1.91025 -1.95501004 1.91765 -1.95501004 0 P 0 
L 1.90988996 -1.95401004 1.91718996 -1.95401004 0 P 0 
L 1.90953002 -1.95301004 1.91673002 -1.95301004 0 P 0 
L 1.90918002 -1.95201004 1.91626998 -1.95201004 0 P 0 
L 1.90881998 -1.95101004 1.91576004 -1.95101004 0 P 0 
L 1.90841004 -1.95001004 1.91523996 -1.95001004 0 P 0 
L 1.90793996 -1.94901004 1.91471004 -1.94901004 0 P 0 
L 1.90738996 -1.94801004 1.91418002 -1.94801004 0 P 0 
L 1.90676998 -1.94701004 1.9136 -1.94701004 0 P 0 
L 1.90598996 -1.94601004 1.91261004 -1.94601004 0 P 0 
L 1.90495 -1.94501004 1.91175 -1.94501004 0 P 0 
L 1.90325 -1.94401004 1.91133002 -1.94401004 0 P 0 
L 1.90456004 -1.94001004 1.91383002 -1.94001004 0 P 0 
L 1.90801004 -1.93901004 1.91523002 -1.93901004 0 P 0 
L 1.90956998 -1.93801004 1.91635 -1.93801004 0 P 0 
L 1.9106 -1.93701004 1.91718002 -1.93701004 0 P 0 
L 1.91133996 -1.93601004 1.91781004 -1.93601004 0 P 0 
L 1.91183996 -1.93501004 1.91826004 -1.93501004 0 P 0 
L 1.91213002 -1.93401004 1.9186 -1.93401004 0 P 0 
L 1.91226004 -1.93301004 1.9188 -1.93301004 0 P 0 
L 1.91221998 -1.93201004 1.9189 -1.93201004 0 P 0 
L 1.91201998 -1.93101004 1.9189 -1.93101004 0 P 0 
L 1.91163996 -1.93001004 1.91878996 -1.93001004 0 P 0 
L 1.91105 -1.92901004 1.91856998 -1.92901004 0 P 0 
L 1.91013996 -1.92801004 1.91823002 -1.92801004 0 P 0 
L 1.90816998 -1.92701004 1.91776004 -1.92701004 0 P 0 
L 1.90313996 -1.94011004 1.90316998 -1.9401 0 P 0 
L 1.90316998 -1.9401 1.9032 -1.9401 0 P 0 
L 1.9032 -1.9401 1.90398002 -1.94006998 0 P 0 
L 1.90398002 -1.94006998 1.90406004 -1.94006998 0 P 0 
L 1.90406004 -1.94006998 1.90413996 -1.94006004 0 P 0 
L 1.90413996 -1.94006004 1.9049 -1.93996998 0 P 0 
L 1.9049 -1.93996998 1.90493996 -1.93996004 0 P 0 
L 1.90493996 -1.93996004 1.90498996 -1.93996004 0 P 0 
L 1.90498996 -1.93996004 1.90506998 -1.93993996 0 P 0 
L 1.90506998 -1.93993996 1.90581998 -1.93978002 0 P 0 
L 1.90581998 -1.93978002 1.90586004 -1.93978002 0 P 0 
L 1.90586004 -1.93978002 1.90593996 -1.93976004 0 P 0 
L 1.90593996 -1.93976004 1.90596998 -1.93973996 0 P 0 
L 1.90596998 -1.93973996 1.90671004 -1.93953002 0 P 0 
L 1.90671004 -1.93953002 1.90678996 -1.93951004 0 P 0 
L 1.90678996 -1.93951004 1.90758996 -1.93921004 0 P 0 
L 1.90758996 -1.93921004 1.90766004 -1.93916998 0 P 0 
L 1.90766004 -1.93916998 1.9077 -1.93915 0 P 0 
L 1.9077 -1.93915 1.90773996 -1.93913996 0 P 0 
L 1.90773996 -1.93913996 1.90818996 -1.93891998 0 P 0 
L 1.90818996 -1.93891998 1.90821998 -1.9389 0 P 0 
L 1.90821998 -1.9389 1.90826004 -1.93888996 0 P 0 
L 1.90826004 -1.93888996 1.90828996 -1.93886998 0 P 0 
L 1.90828996 -1.93886998 1.90833002 -1.93885 0 P 0 
L 1.90833002 -1.93885 1.90875 -1.9386 0 P 0 
L 1.90875 -1.9386 1.90883002 -1.93856004 0 P 0 
L 1.90883002 -1.93856004 1.90888996 -1.93851004 0 P 0 
L 1.90888996 -1.93851004 1.90928996 -1.93823002 0 P 0 
L 1.90928996 -1.93823002 1.90933002 -1.9382 0 P 0 
L 1.90933002 -1.9382 1.90936004 -1.93818002 0 P 0 
L 1.90936004 -1.93818002 1.90938996 -1.93815 0 P 0 
L 1.90938996 -1.93815 1.90941998 -1.93813002 0 P 0 
L 1.90941998 -1.93813002 1.9098 -1.93781998 0 P 0 
L 1.9098 -1.93781998 1.90986004 -1.93776004 0 P 0 
L 1.90986004 -1.93776004 1.90988996 -1.93773996 0 P 0 
L 1.90988996 -1.93773996 1.90991998 -1.93771004 0 P 0 
L 1.90991998 -1.93771004 1.91028002 -1.93736004 0 P 0 
L 1.91028002 -1.93736004 1.91038996 -1.93725 0 P 0 
L 1.91038996 -1.93725 1.91071004 -1.93688002 0 P 0 
L 1.91071004 -1.93688002 1.91073996 -1.93685 0 P 0 
L 1.91073996 -1.93685 1.91116004 -1.9363 0 P 0 
L 1.91116004 -1.9363 1.9112 -1.93623002 0 P 0 
L 1.9112 -1.93623002 1.91138002 -1.93595 0 P 0 
L 1.91138002 -1.93595 1.9114 -1.93591004 0 P 0 
L 1.9114 -1.93591004 1.91143996 -1.93585 0 P 0 
L 1.91143996 -1.93585 1.91146004 -1.93581004 0 P 0 
L 1.91146004 -1.93581004 1.91161004 -1.93551998 0 P 0 
L 1.91161004 -1.93551998 1.91163002 -1.93548996 0 P 0 
L 1.91163002 -1.93548996 1.91165 -1.93545 0 P 0 
L 1.91165 -1.93545 1.91166004 -1.93541004 0 P 0 
L 1.91166004 -1.93541004 1.91168002 -1.93538002 0 P 0 
L 1.91168002 -1.93538002 1.91181004 -1.93506998 0 P 0 
L 1.91181004 -1.93506998 1.91183996 -1.935 0 P 0 
L 1.91183996 -1.935 1.91186004 -1.93496004 0 P 0 
L 1.91186004 -1.93496004 1.91186998 -1.93493002 0 P 0 
L 1.91186998 -1.93493002 1.91198002 -1.93461004 0 P 0 
L 1.91198002 -1.93461004 1.91198996 -1.93456998 0 P 0 
L 1.91198996 -1.93456998 1.912 -1.93453996 0 P 0 
L 1.912 -1.93453996 1.9121 -1.93413996 0 P 0 
L 1.9121 -1.93413996 1.91211998 -1.9341 0 P 0 
L 1.91211998 -1.9341 1.91211998 -1.93406004 0 P 0 
L 1.91211998 -1.93406004 1.91213002 -1.93401998 0 P 0 
L 1.91213002 -1.93401998 1.91213996 -1.93398996 0 P 0 
L 1.91213996 -1.93398996 1.9122 -1.93366004 0 P 0 
L 1.9122 -1.93366004 1.91221004 -1.93358002 0 P 0 
L 1.91221004 -1.93358002 1.91221004 -1.93353996 0 P 0 
L 1.91221004 -1.93353996 1.91221998 -1.9335 0 P 0 
L 1.91221998 -1.9335 1.91225 -1.93316998 0 P 0 
L 1.91225 -1.93316998 1.91226004 -1.93308996 0 P 0 
L 1.91226004 -1.93308996 1.91226004 -1.93268002 0 P 0 
L 1.91226004 -1.93268002 1.91226998 -1.93263996 0 P 0 
L 1.91226998 -1.93263996 1.91226998 -1.9326 0 P 0 
L 1.91226998 -1.9326 1.91226004 -1.93251998 0 P 0 
L 1.91226004 -1.93251998 1.91223996 -1.93218996 0 P 0 
L 1.91223996 -1.93218996 1.91223996 -1.93215 0 P 0 
L 1.91223996 -1.93215 1.91223002 -1.9321 0 P 0 
L 1.91223002 -1.9321 1.91223002 -1.93206004 0 P 0 
L 1.91223002 -1.93206004 1.91221998 -1.93201998 0 P 0 
L 1.91221998 -1.93201998 1.91216998 -1.93163996 0 P 0 
L 1.91216998 -1.93163996 1.91216004 -1.9316 0 P 0 
L 1.91216004 -1.9316 1.91213996 -1.93151004 0 P 0 
L 1.91213996 -1.93151004 1.91213002 -1.93146998 0 P 0 
L 1.91213002 -1.93146998 1.91205 -1.93111004 0 P 0 
L 1.91205 -1.93111004 1.91203996 -1.93106004 0 P 0 
L 1.91203996 -1.93106004 1.91203002 -1.93101998 0 P 0 
L 1.91203002 -1.93101998 1.91201004 -1.93098002 0 P 0 
L 1.91201004 -1.93098002 1.912 -1.93093996 0 P 0 
L 1.912 -1.93093996 1.91188002 -1.93058002 0 P 0 
L 1.91188002 -1.93058002 1.91186998 -1.93053996 0 P 0 
L 1.91186998 -1.93053996 1.91185 -1.9305 0 P 0 
L 1.91185 -1.9305 1.91183996 -1.93046004 0 P 0 
L 1.91183996 -1.93046004 1.91181998 -1.93043002 0 P 0 
L 1.91181998 -1.93043002 1.91166998 -1.93008002 0 P 0 
L 1.91166998 -1.93008002 1.91166004 -1.93003996 0 P 0 
L 1.91166004 -1.93003996 1.9116 -1.92991998 0 P 0 
L 1.9116 -1.92991998 1.91141998 -1.92958996 0 P 0 
L 1.91141998 -1.92958996 1.9114 -1.92955 0 P 0 
L 1.9114 -1.92955 1.91138002 -1.92951998 0 P 0 
L 1.91138002 -1.92951998 1.91133002 -1.92945 0 P 0 
L 1.91133002 -1.92945 1.91113002 -1.92913002 0 P 0 
L 1.91113002 -1.92913002 1.91111004 -1.92908996 0 P 0 
L 1.91111004 -1.92908996 1.91108996 -1.92906004 0 P 0 
L 1.91108996 -1.92906004 1.91106004 -1.92901998 0 P 0 
L 1.91106004 -1.92901998 1.91103002 -1.92898996 0 P 0 
L 1.91103002 -1.92898996 1.9108 -1.92868996 0 P 0 
L 1.9108 -1.92868996 1.91076998 -1.92866004 0 P 0 
L 1.91076998 -1.92866004 1.91075 -1.92861998 0 P 0 
L 1.91075 -1.92861998 1.91068996 -1.92856004 0 P 0 
L 1.91068996 -1.92856004 1.91043002 -1.92828002 0 P 0 
L 1.91043002 -1.92828002 1.91035 -1.9282 0 P 0 
L 1.91035 -1.9282 1.91033002 -1.92816998 0 P 0 
L 1.91033002 -1.92816998 1.91018996 -1.92803996 0 P 0 
L 1.91018996 -1.92803996 1.91018002 -1.92803996 0 P 0 
L 1.91018002 -1.92803996 1.91016004 -1.92801998 0 P 0 
L 1.91016004 -1.92801998 1.91011998 -1.92798996 0 P 0 
L 1.91011998 -1.92798996 1.91006004 -1.92793002 0 P 0 
L 1.91006004 -1.92793002 1.90991004 -1.92781998 0 P 0 
L 1.90991004 -1.92781998 1.90988002 -1.9278 0 P 0 
L 1.90988002 -1.9278 1.90983996 -1.92776998 0 P 0 
L 1.90983996 -1.92776998 1.90976998 -1.92771998 0 P 0 
L 1.90976998 -1.92771998 1.90961004 -1.92761998 0 P 0 
L 1.90961004 -1.92761998 1.90953996 -1.92756998 0 P 0 
L 1.90953996 -1.92756998 1.9095 -1.92755 0 P 0 
L 1.9095 -1.92755 1.90946998 -1.92753002 0 P 0 
L 1.90946998 -1.92753002 1.9093 -1.92743996 0 P 0 
L 1.9093 -1.92743996 1.90926004 -1.92741998 0 P 0 
L 1.90926004 -1.92741998 1.90923002 -1.9274 0 P 0 
L 1.90923002 -1.9274 1.90915 -1.92736998 0 P 0 
L 1.90915 -1.92736998 1.90896998 -1.92728996 0 P 0 
L 1.90896998 -1.92728996 1.90893996 -1.92728002 0 P 0 
L 1.90893996 -1.92728002 1.9089 -1.92726004 0 P 0 
L 1.9089 -1.92726004 1.90886998 -1.92725 0 P 0 
L 1.90886998 -1.92725 1.90883002 -1.92723996 0 P 0 
L 1.90883002 -1.92723996 1.90816004 -1.92701004 0 P 0 
L 1.90816004 -1.92701004 1.90813996 -1.927 0 P 0 
L 1.90813996 -1.927 1.9081 -1.92698996 0 P 0 
L 1.9081 -1.92698996 1.90803996 -1.92696998 0 P 0 
L 1.90803996 -1.92696998 1.90736998 -1.92678002 0 P 0 
L 1.90736998 -1.92678002 1.90723996 -1.92675 0 P 0 
L 1.90723996 -1.92675 1.90643002 -1.92658996 0 P 0 
L 1.90643002 -1.92658996 1.90636998 -1.92656998 0 P 0 
L 1.90636998 -1.92656998 1.90633996 -1.92656998 0 P 0 
L 1.90633996 -1.92656998 1.90631004 -1.92656004 0 P 0 
L 1.90631004 -1.92656004 1.90548996 -1.92645 0 P 0 
L 1.90548996 -1.92645 1.90543996 -1.92643996 0 P 0 
L 1.90543996 -1.92643996 1.9054 -1.92643002 0 P 0 
L 1.9054 -1.92643002 1.90538002 -1.92643002 0 P 0 
L 1.90538002 -1.92643002 1.90455 -1.92636004 0 P 0 
L 1.90455 -1.92636004 1.90443002 -1.92636004 0 P 0 
L 1.90443002 -1.92636004 1.9036 -1.92633002 0 P 0 
L 1.9036 -1.92633002 1.8994 -1.92633002 0 P 0 
L 1.8994 -1.92633002 1.89798002 -1.92691004 0 P 0 
L 1.89798002 -1.92691004 1.8974 -1.92833002 0 P 0 
L 1.8974 -1.92833002 1.8974 -1.93328002 0 P 0 
L 1.8974 -1.93328002 1.89748002 -1.93643002 0 P 0 
L 1.89748002 -1.93643002 1.89748002 -1.93656004 0 P 0 
L 1.89748002 -1.93656004 1.8975 -1.93673002 0 P 0 
L 1.8975 -1.93673002 1.89751004 -1.93681004 0 P 0 
L 1.89751004 -1.93681004 1.89751998 -1.9369 0 P 0 
L 1.89751998 -1.9369 1.89755 -1.93706004 0 P 0 
L 1.89755 -1.93706004 1.89758002 -1.93718996 0 P 0 
L 1.89758002 -1.93718996 1.89758996 -1.93723002 0 P 0 
L 1.89758996 -1.93723002 1.89763002 -1.9374 0 P 0 
L 1.89763002 -1.9374 1.89763996 -1.93743996 0 P 0 
L 1.89763996 -1.93743996 1.89766004 -1.93748002 0 P 0 
L 1.89766004 -1.93748002 1.89768002 -1.93756004 0 P 0 
L 1.89768002 -1.93756004 1.89773996 -1.93771998 0 P 0 
L 1.89773996 -1.93771998 1.89776004 -1.93776004 0 P 0 
L 1.89776004 -1.93776004 1.89776998 -1.9378 0 P 0 
L 1.89776998 -1.9378 1.89781004 -1.93788002 0 P 0 
L 1.89781004 -1.93788002 1.89788002 -1.93803996 0 P 0 
L 1.89788002 -1.93803996 1.8979 -1.93808002 0 P 0 
L 1.8979 -1.93808002 1.89791998 -1.93811004 0 P 0 
L 1.89791998 -1.93811004 1.89796004 -1.93818996 0 P 0 
L 1.89796004 -1.93818996 1.89803996 -1.93833996 0 P 0 
L 1.89803996 -1.93833996 1.89813996 -1.93848002 0 P 0 
L 1.89813996 -1.93848002 1.89823002 -1.93861998 0 P 0 
L 1.89823002 -1.93861998 1.89828002 -1.93868996 0 P 0 
L 1.89828002 -1.93868996 1.89831004 -1.93873002 0 P 0 
L 1.89831004 -1.93873002 1.89833996 -1.93876004 0 P 0 
L 1.89833996 -1.93876004 1.8984 -1.93883996 0 P 0 
L 1.8984 -1.93883996 1.89848996 -1.93893002 0 P 0 
L 1.89848996 -1.93893002 1.89851004 -1.93896004 0 P 0 
L 1.89851004 -1.93896004 1.89868002 -1.93913002 0 P 0 
L 1.89868002 -1.93913002 1.89871004 -1.93915 0 P 0 
L 1.89871004 -1.93915 1.89878996 -1.93921998 0 P 0 
L 1.89878996 -1.93921998 1.89885 -1.93928002 0 P 0 
L 1.89885 -1.93928002 1.89888002 -1.9393 0 P 0 
L 1.89888002 -1.9393 1.89891998 -1.93931998 0 P 0 
L 1.89891998 -1.93931998 1.89901004 -1.93938996 0 P 0 
L 1.89901004 -1.93938996 1.89903996 -1.93941004 0 P 0 
L 1.89903996 -1.93941004 1.89906998 -1.93943996 0 P 0 
L 1.89906998 -1.93943996 1.8991 -1.93946004 0 P 0 
L 1.8991 -1.93946004 1.89913996 -1.93948002 0 P 0 
L 1.89913996 -1.93948002 1.89923002 -1.93953996 0 P 0 
L 1.89923002 -1.93953996 1.89926998 -1.93956004 0 P 0 
L 1.89926998 -1.93956004 1.8993 -1.93958002 0 P 0 
L 1.8993 -1.93958002 1.89933996 -1.9396 0 P 0 
L 1.89933996 -1.9396 1.89936998 -1.93961004 0 P 0 
L 1.89936998 -1.93961004 1.89938002 -1.93961004 0 P 0 
L 1.89938002 -1.93961004 1.89946998 -1.93966004 0 P 0 
L 1.89946998 -1.93966004 1.89953996 -1.9397 0 P 0 
L 1.89953996 -1.9397 1.89971998 -1.93976998 0 P 0 
L 1.89971998 -1.93976998 1.89975 -1.93978996 0 P 0 
L 1.89975 -1.93978996 1.89978996 -1.9398 0 P 0 
L 1.89978996 -1.9398 1.89986998 -1.93983002 0 P 0 
L 1.89986998 -1.93983002 1.89996998 -1.93986004 0 P 0 
L 1.89996998 -1.93986004 1.90001004 -1.93986998 0 P 0 
L 1.90001004 -1.93986998 1.90005 -1.93988996 0 P 0 
L 1.90005 -1.93988996 1.90013002 -1.9399 0 P 0 
L 1.90013002 -1.9399 1.90023002 -1.93993002 0 P 0 
L 1.90023002 -1.93993002 1.90023996 -1.93993002 0 P 0 
L 1.90023996 -1.93993002 1.90028002 -1.93993996 0 P 0 
L 1.90028002 -1.93993996 1.90031004 -1.93995 0 P 0 
L 1.90031004 -1.93995 1.90036004 -1.93995 0 P 0 
L 1.90036004 -1.93995 1.9004 -1.93996004 0 P 0 
L 1.9004 -1.93996004 1.9005 -1.93996998 0 P 0 
L 1.9005 -1.93996998 1.90061004 -1.93998996 0 P 0 
L 1.90061004 -1.93998996 1.90063996 -1.93998996 0 P 0 
L 1.90063996 -1.93998996 1.90181004 -1.94006998 0 P 0 
L 1.90181004 -1.94006998 1.90183996 -1.94008002 0 P 0 
L 1.90183996 -1.94008002 1.90191004 -1.94008002 0 P 0 
L 1.90191004 -1.94008002 1.90308002 -1.9401 0 P 0 
L 1.90308002 -1.9401 1.90311004 -1.9401 0 P 0 
L 1.90311004 -1.9401 1.90313996 -1.94011004 0 P 0 
L 1.90841004 -1.97146004 1.91683996 -1.97146004 0 P 0 
L 1.9135 -1.97046004 1.91931004 -1.97046004 0 P 0 
L 1.91655 -1.96946004 1.92131004 -1.96946004 0 P 0 
L 1.91891998 -1.96846004 1.92301004 -1.96846004 0 P 0 
L 1.92088996 -1.96746004 1.9245 -1.96746004 0 P 0 
L 1.92251004 -1.96646004 1.9258 -1.96646004 0 P 0 
L 1.92391004 -1.96546004 1.92696004 -1.96546004 0 P 0 
L 1.92513002 -1.96446004 1.92803002 -1.96446004 0 P 0 
L 1.9262 -1.96346004 1.92898996 -1.96346004 0 P 0 
L 1.92713996 -1.96246004 1.92986004 -1.96246004 0 P 0 
L 1.928 -1.96146004 1.93068996 -1.96146004 0 P 0 
L 1.92878002 -1.96046004 1.93143002 -1.96046004 0 P 0 
L 1.92951004 -1.95946004 1.93216004 -1.95946004 0 P 0 
L 1.93016998 -1.95846004 1.93278996 -1.95846004 0 P 0 
L 1.93078002 -1.95746004 1.93341004 -1.95746004 0 P 0 
L 1.93133002 -1.95646004 1.93396004 -1.95646004 0 P 0 
L 1.93185 -1.95546004 1.93448996 -1.95546004 0 P 0 
L 1.93231004 -1.95446004 1.93495 -1.95446004 0 P 0 
L 1.93275 -1.95346004 1.93541004 -1.95346004 0 P 0 
L 1.93311998 -1.95246004 1.93586004 -1.95246004 0 P 0 
L 1.93348002 -1.95146004 1.93628996 -1.95146004 0 P 0 
L 1.93376998 -1.95046004 1.93666004 -1.95046004 0 P 0 
L 1.93405 -1.94946004 1.93693002 -1.94946004 0 P 0 
L 1.93428002 -1.94846004 1.93715 -1.94846004 0 P 0 
L 1.93446998 -1.94746004 1.93733002 -1.94746004 0 P 0 
L 1.93466004 -1.94646004 1.93743002 -1.94646004 0 P 0 
L 1.93478996 -1.94546004 1.93748996 -1.94546004 0 P 0 
L 1.9349 -1.94446998 1.93751998 -1.94446998 0 P 0 
L 1.93496998 -1.94346004 1.93755 -1.94346004 0 P 0 
L 1.93501998 -1.94246004 1.93758002 -1.94246004 0 P 0 
L 1.93505 -1.94146998 1.93758996 -1.94146998 0 P 0 
L 1.93503002 -1.94046004 1.93755 -1.94046004 0 P 0 
L 1.935 -1.93946004 1.93751998 -1.93946004 0 P 0 
L 1.93491998 -1.93846004 1.93748002 -1.93846004 0 P 0 
L 1.93481004 -1.93746004 1.93738996 -1.93746004 0 P 0 
L 1.93468996 -1.93646004 1.93726998 -1.93646004 0 P 0 
L 1.93451004 -1.93546004 1.93716004 -1.93546004 0 P 0 
L 1.93433002 -1.93446004 1.93703996 -1.93446004 0 P 0 
L 1.93408996 -1.93346004 1.93685 -1.93346004 0 P 0 
L 1.93383002 -1.93246004 1.93666004 -1.93246004 0 P 0 
L 1.93353002 -1.93146004 1.93638996 -1.93146004 0 P 0 
L 1.9332 -1.93046004 1.93611998 -1.93046004 0 P 0 
L 1.93283996 -1.92946004 1.93576998 -1.92946004 0 P 0 
L 1.93241004 -1.92846004 1.93541004 -1.92846004 0 P 0 
L 1.93198996 -1.92746004 1.93498002 -1.92746004 0 P 0 
L 1.93146998 -1.92646004 1.93451004 -1.92646004 0 P 0 
L 1.93096004 -1.92546004 1.93398002 -1.92546004 0 P 0 
L 1.93035 -1.92446998 1.93338002 -1.92446998 0 P 0 
L 1.92973002 -1.92346004 1.93275 -1.92346004 0 P 0 
L 1.92903002 -1.92246004 1.93201004 -1.92246004 0 P 0 
L 1.92831004 -1.92146004 1.93125 -1.92146004 0 P 0 
L 1.92746998 -1.92046004 1.93041004 -1.92046004 0 P 0 
L 1.92661004 -1.91946004 1.92948996 -1.91946004 0 P 0 
L 1.92558996 -1.91846004 1.92851004 -1.91846004 0 P 0 
L 1.9245 -1.91746004 1.92741998 -1.91746004 0 P 0 
L 1.92328996 -1.91646004 1.92621998 -1.91646004 0 P 0 
L 1.92188002 -1.91546004 1.92491998 -1.91546004 0 P 0 
L 1.92026004 -1.91446004 1.92358996 -1.91446004 0 P 0 
L 1.91835 -1.91346004 1.92208002 -1.91346004 0 P 0 
L 1.82446998 -2.08323996 1.87608002 -2.08323996 0 P 0 
L 1.82403002 -2.08223996 1.87601004 -2.08223996 0 P 0 
L 1.8234 -2.08123996 1.87591004 -2.08123996 0 P 0 
L 1.82256004 -2.08023996 1.87578002 -2.08023996 0 P 0 
L 1.82166004 -2.07923996 1.87558996 -2.07923996 0 P 0 
L 1.82061998 -2.07823996 1.87533002 -2.07823996 0 P 0 
L 1.81946004 -2.07723996 1.87498996 -2.07723996 0 P 0 
L 1.81818002 -2.07623996 1.8746 -2.07623996 0 P 0 
L 1.8168 -2.07523996 1.87416998 -2.07523996 0 P 0 
L 1.81541998 -2.07423996 1.87371004 -2.07423996 0 P 0 
L 1.81403002 -2.07323996 1.87316998 -2.07323996 0 P 0 
L 1.81265 -2.07223996 1.87261004 -2.07223996 0 P 0 
L 1.81126998 -2.07123996 1.87196004 -2.07123996 0 P 0 
L 1.80986004 -2.07023996 1.87128002 -2.07023996 0 P 0 
L 1.80843996 -2.06923996 1.87051998 -2.06923996 0 P 0 
L 1.80703002 -2.06823996 1.8697 -2.06823996 0 P 0 
L 1.80561004 -2.06723996 1.86883002 -2.06723996 0 P 0 
L 1.8042 -2.06623996 1.86796004 -2.06623996 0 P 0 
L 1.80278002 -2.06523996 1.86705 -2.06523996 0 P 0 
L 1.80136004 -2.06423996 1.86608002 -2.06423996 0 P 0 
L 1.79995 -2.06323996 1.8651 -2.06323996 0 P 0 
L 1.79865 -2.06223996 1.86411004 -2.06223996 0 P 0 
L 1.79735 -2.06123996 1.86301998 -2.06123996 0 P 0 
L 1.79605 -2.06023996 1.86193002 -2.06023996 0 P 0 
L 1.79475 -2.05923996 1.86083996 -2.05923996 0 P 0 
L 1.79345 -2.05823996 1.85966998 -2.05823996 0 P 0 
L 1.79215 -2.05723996 1.85846004 -2.05723996 0 P 0 
L 1.79088002 -2.05623996 1.85726004 -2.05623996 0 P 0 
L 1.78971998 -2.05523996 1.85598996 -2.05523996 0 P 0 
L 1.78856004 -2.05423996 1.85461998 -2.05423996 0 P 0 
L 1.7874 -2.05323996 1.85326004 -2.05323996 0 P 0 
L 1.78623002 -2.05223996 1.8519 -2.05223996 0 P 0 
L 1.78506998 -2.05123996 1.85053996 -2.05123996 0 P 0 
L 1.78398002 -2.05023996 1.84918002 -2.05023996 0 P 0 
L 1.783 -2.04923996 1.84781004 -2.04923996 0 P 0 
L 1.87086004 -2.03023996 1.87535 -2.03023996 0 P 0 
L 1.91633002 -1.91473002 1.9183 -1.91565 0 P 0 
L 1.9183 -1.91565 1.92018996 -1.91673002 0 P 0 
L 1.92018996 -1.91673002 1.92196998 -1.91796998 0 P 0 
L 1.92196998 -1.91796998 1.92365 -1.91936004 0 P 0 
L 1.92365 -1.91936004 1.9252 -1.92088002 0 P 0 
L 1.9252 -1.92088002 1.92661004 -1.92253996 0 P 0 
L 1.92661004 -1.92253996 1.92795 -1.92436998 0 P 0 
L 1.92795 -1.92436998 1.92913996 -1.9263 0 P 0 
L 1.92913996 -1.9263 1.93018002 -1.92831998 0 P 0 
L 1.93018002 -1.92831998 1.93106998 -1.93041004 0 P 0 
L 1.93106998 -1.93041004 1.93178996 -1.93256004 0 P 0 
L 1.93178996 -1.93256004 1.93236004 -1.93476004 0 P 0 
L 1.93236004 -1.93476004 1.93276004 -1.93703996 0 P 0 
L 1.93276004 -1.93703996 1.93298996 -1.93933996 0 P 0 
L 1.93298996 -1.93933996 1.93306004 -1.94165 0 P 0 
L 1.93306004 -1.94165 1.93295 -1.94396998 0 P 0 
L 1.93295 -1.94396998 1.93268002 -1.94626004 0 P 0 
L 1.93268002 -1.94626004 1.93223002 -1.94853996 0 P 0 
L 1.93223002 -1.94853996 1.93161998 -1.95071998 0 P 0 
L 1.93161998 -1.95071998 1.93085 -1.95285 0 P 0 
L 1.93085 -1.95285 1.92991004 -1.95491004 0 P 0 
L 1.92991004 -1.95491004 1.92881004 -1.95688996 0 P 0 
L 1.92881004 -1.95688996 1.92756004 -1.95878002 0 P 0 
L 1.92756004 -1.95878002 1.92616004 -1.96056998 0 P 0 
L 1.92616004 -1.96056998 1.92493996 -1.9619 0 P 0 
L 1.92493996 -1.9619 1.92361998 -1.96313996 0 P 0 
L 1.92361998 -1.96313996 1.9222 -1.96426004 0 P 0 
L 1.9222 -1.96426004 1.9207 -1.96526998 0 P 0 
L 1.9207 -1.96526998 1.91911004 -1.96616998 0 P 0 
L 1.91911004 -1.96616998 1.91686998 -1.96721004 0 P 0 
L 1.91686998 -1.96721004 1.91456004 -1.96806998 0 P 0 
L 1.91456004 -1.96806998 1.91218996 -1.96876004 0 P 0 
L 1.91218996 -1.96876004 1.90975 -1.96926998 0 P 0 
L 1.90975 -1.96926998 1.90725 -1.9696 0 P 0 
L 1.90725 -1.9696 1.90473002 -1.96973996 0 P 0 
L 1.90473002 -1.96973996 1.9022 -1.96968996 0 P 0 
L 1.9022 -1.96968996 1.89966998 -1.96945 0 P 0 
L 1.89966998 -1.96945 1.89778002 -1.96913002 0 P 0 
L 1.89778002 -1.96913002 1.89591998 -1.96868996 0 P 0 
L 1.89591998 -1.96868996 1.8941 -1.96811004 0 P 0 
L 1.8941 -1.96811004 1.89231004 -1.96741004 0 P 0 
L 1.89231004 -1.96741004 1.89058002 -1.96658002 0 P 0 
L 1.89058002 -1.96658002 1.88875 -1.96553996 0 P 0 
L 1.88875 -1.96553996 1.88698996 -1.96435 0 P 0 
L 1.88698996 -1.96435 1.88533996 -1.96303002 0 P 0 
L 1.88533996 -1.96303002 1.88378996 -1.9616 0 P 0 
L 1.88378996 -1.9616 1.88235 -1.96003996 0 P 0 
L 1.88235 -1.96003996 1.88103002 -1.95838996 0 P 0 
L 1.88103002 -1.95838996 1.87983996 -1.95663002 0 P 0 
L 1.87983996 -1.95663002 1.87861998 -1.95446998 0 P 0 
L 1.87861998 -1.95446998 1.87758002 -1.9522 0 P 0 
L 1.87758002 -1.9522 1.87673996 -1.94986004 0 P 0 
L 1.87673996 -1.94986004 1.8761 -1.94745 0 P 0 
L 1.8761 -1.94745 1.87568002 -1.945 0 P 0 
L 1.87568002 -1.945 1.87546004 -1.94248996 0 P 0 
L 1.87546004 -1.94248996 1.87546004 -1.93998996 0 P 0 
L 1.87546004 -1.93998996 1.87566998 -1.93748996 0 P 0 
L 1.87566998 -1.93748996 1.87608996 -1.93501998 0 P 0 
L 1.87608996 -1.93501998 1.87671998 -1.9326 0 P 0 
L 1.87671998 -1.9326 1.87755 -1.93023002 0 P 0 
L 1.87755 -1.93023002 1.8786 -1.92793002 0 P 0 
L 1.8786 -1.92793002 1.87981998 -1.92575 0 P 0 
L 1.87981998 -1.92575 1.88123002 -1.92368002 0 P 0 
L 1.88123002 -1.92368002 1.88281004 -1.92175 0 P 0 
L 1.88281004 -1.92175 1.88455 -1.91996004 0 P 0 
L 1.88455 -1.91996004 1.88643002 -1.91831998 0 P 0 
L 1.88643002 -1.91831998 1.88845 -1.91686004 0 P 0 
L 1.88845 -1.91686004 1.88986998 -1.91598996 0 P 0 
L 1.88986998 -1.91598996 1.89135 -1.91523002 0 P 0 
L 1.89135 -1.91523002 1.89288002 -1.91458996 0 P 0 
L 1.89288002 -1.91458996 1.89446998 -1.91406004 0 P 0 
L 1.89446998 -1.91406004 1.89688996 -1.91343996 0 P 0 
L 1.89688996 -1.91343996 1.89935 -1.91298996 0 P 0 
L 1.89935 -1.91298996 1.90183996 -1.91271004 0 P 0 
L 1.90183996 -1.91271004 1.9044 -1.91261004 0 P 0 
L 1.9044 -1.91261004 1.90695 -1.91268002 0 P 0 
L 1.90695 -1.91268002 1.90948996 -1.91291998 0 P 0 
L 1.90948996 -1.91291998 1.91181998 -1.91331998 0 P 0 
L 1.91181998 -1.91331998 1.91408996 -1.91393002 0 P 0 
L 1.91408996 -1.91393002 1.91633002 -1.91473002 0 P 0 
L 1.89498002 -1.90801998 1.8922 -1.90893002 0 P 0 
L 1.8922 -1.90893002 1.88948002 -1.91003002 0 P 0 
L 1.88948002 -1.91003002 1.88686004 -1.91133002 0 P 0 
L 1.88686004 -1.91133002 1.88431004 -1.91283996 0 P 0 
L 1.88431004 -1.91283996 1.88201004 -1.91446004 0 P 0 
L 1.88201004 -1.91446004 1.87985 -1.91626998 0 P 0 
L 1.87985 -1.91626998 1.87785 -1.91826004 0 P 0 
L 1.87785 -1.91826004 1.87601998 -1.92041004 0 P 0 
L 1.87601998 -1.92041004 1.87441004 -1.92266998 0 P 0 
L 1.87441004 -1.92266998 1.87298996 -1.92505 0 P 0 
L 1.87298996 -1.92505 1.87178002 -1.92756004 0 P 0 
L 1.87178002 -1.92756004 1.87078996 -1.93015 0 P 0 
L 1.87078996 -1.93015 1.87 -1.93286998 0 P 0 
L 1.87 -1.93286998 1.86943996 -1.93563996 0 P 0 
L 1.86943996 -1.93563996 1.86908996 -1.93845 0 P 0 
L 1.86908996 -1.93845 1.86898002 -1.94128996 0 P 0 
L 1.86898002 -1.94128996 1.86911998 -1.94485 0 P 0 
L 1.86911998 -1.94485 1.86953996 -1.94841004 0 P 0 
L 1.86953996 -1.94841004 1.86996004 -1.95048996 0 P 0 
L 1.86996004 -1.95048996 1.87053002 -1.95251998 0 P 0 
L 1.87053002 -1.95251998 1.87125 -1.95451998 0 P 0 
L 1.87125 -1.95451998 1.87211004 -1.95643002 0 P 0 
L 1.87211004 -1.95643002 1.8731 -1.95826004 0 P 0 
L 1.8731 -1.95826004 1.87423996 -1.96001998 0 P 0 
L 1.87423996 -1.96001998 1.87636998 -1.96278996 0 P 0 
L 1.87636998 -1.96278996 1.87871998 -1.96536998 0 P 0 
L 1.87871998 -1.96536998 1.88145 -1.96788002 0 P 0 
L 1.88145 -1.96788002 1.88436998 -1.97015 0 P 0 
L 1.88436998 -1.97015 1.88621004 -1.97135 0 P 0 
L 1.88621004 -1.97135 1.88813002 -1.97238002 0 P 0 
L 1.88813002 -1.97238002 1.89013002 -1.97326004 0 P 0 
L 1.89013002 -1.97326004 1.89228002 -1.97398996 0 P 0 
L 1.89228002 -1.97398996 1.89446998 -1.97455 0 P 0 
L 1.89446998 -1.97455 1.89671004 -1.97493996 0 P 0 
L 1.89671004 -1.97493996 1.90076998 -1.97533996 0 P 0 
L 1.90076998 -1.97533996 1.90485 -1.97546998 0 P 0 
L 1.90485 -1.97546998 1.90821004 -1.97531998 0 P 0 
L 1.90821004 -1.97531998 1.91153996 -1.97488996 0 P 0 
L 1.91153996 -1.97488996 1.91481998 -1.97418996 0 P 0 
L 1.91481998 -1.97418996 1.9171 -1.9735 0 P 0 
L 1.9171 -1.9735 1.91933002 -1.97266004 0 P 0 
L 1.91933002 -1.97266004 1.92148002 -1.97166004 0 P 0 
L 1.92148002 -1.97166004 1.92356998 -1.97048996 0 P 0 
L 1.92356998 -1.97048996 1.92553996 -1.96918996 0 P 0 
L 1.92553996 -1.96918996 1.92741004 -1.96773996 0 P 0 
L 1.92741004 -1.96773996 1.92916004 -1.96616998 0 P 0 
L 1.92916004 -1.96616998 1.93081004 -1.96446004 0 P 0 
L 1.93081004 -1.96446004 1.93236998 -1.96256998 0 P 0 
L 1.93236998 -1.96256998 1.93381004 -1.96058996 0 P 0 
L 1.93381004 -1.96058996 1.93511998 -1.95851004 0 P 0 
L 1.93511998 -1.95851004 1.93628996 -1.95633996 0 P 0 
L 1.93628996 -1.95633996 1.93803996 -1.95251998 0 P 0 
L 1.93803996 -1.95251998 1.93858002 -1.95101998 0 P 0 
L 1.93858002 -1.95101998 1.93898996 -1.94948002 0 P 0 
L 1.93898996 -1.94948002 1.93928996 -1.94786998 0 P 0 
L 1.93928996 -1.94786998 1.93946004 -1.94625 0 P 0 
L 1.93946004 -1.94625 1.9396 -1.94178002 0 P 0 
L 1.9396 -1.94178002 1.93946004 -1.93803996 0 P 0 
L 1.93946004 -1.93803996 1.93905 -1.9343 0 P 0 
L 1.93905 -1.9343 1.93863996 -1.93213996 0 P 0 
L 1.93863996 -1.93213996 1.93808002 -1.93001998 0 P 0 
L 1.93808002 -1.93001998 1.93736004 -1.92795 0 P 0 
L 1.93736004 -1.92795 1.93653002 -1.92601004 0 P 0 
L 1.93653002 -1.92601004 1.93555 -1.92415 0 P 0 
L 1.93555 -1.92415 1.93441998 -1.92236004 0 P 0 
L 1.93441998 -1.92236004 1.9331 -1.92056004 0 P 0 
L 1.9331 -1.92056004 1.93166998 -1.91885 0 P 0 
L 1.93166998 -1.91885 1.93011998 -1.91723002 0 P 0 
L 1.93011998 -1.91723002 1.92896004 -1.91615 0 P 0 
L 1.92896004 -1.91615 1.92775 -1.91511004 0 P 0 
L 1.92775 -1.91511004 1.92493002 -1.91295 0 P 0 
L 1.92493002 -1.91295 1.9221 -1.91108002 0 P 0 
L 1.9221 -1.91108002 1.92095 -1.91043002 0 P 0 
L 1.92095 -1.91043002 1.91975 -1.90985 0 P 0 
L 1.91975 -1.90985 1.91796004 -1.90913996 0 P 0 
L 1.91796004 -1.90913996 1.91613002 -1.90856004 0 P 0 
L 1.91613002 -1.90856004 1.91423996 -1.9081 0 P 0 
L 1.91423996 -1.9081 1.91086004 -1.90751998 0 P 0 
L 1.91086004 -1.90751998 1.90743002 -1.90716004 0 P 0 
L 1.90743002 -1.90716004 1.90401004 -1.90701004 0 P 0 
L 1.90401004 -1.90701004 1.90058002 -1.90708002 0 P 0 
L 1.90058002 -1.90708002 1.8987 -1.90726004 0 P 0 
L 1.8987 -1.90726004 1.89683002 -1.90756998 0 P 0 
L 1.89683002 -1.90756998 1.89498002 -1.90801998 0 P 0 
L 1.86643002 -2.02923996 1.87525 -2.02923996 0 P 0 
L 1.86176998 -2.02823996 1.87515 -2.02823996 0 P 0 
L 1.85588996 -2.02723996 1.87505 -2.02723996 0 P 0 
L 1.78365 -2.00523996 1.87281004 -2.00523996 0 P 0 
L 1.78451004 -2.00423996 1.87271004 -2.00423996 0 P 0 
L 1.78546998 -2.00323996 1.87261004 -2.00323996 0 P 0 
L 1.78655 -2.00223996 1.8725 -2.00223996 0 P 0 
L 1.78776004 -2.00123996 1.8724 -2.00123996 0 P 0 
L 1.78915 -2.00023996 1.8723 -2.00023996 0 P 0 
L 1.79078996 -1.99923996 1.8722 -1.99923996 0 P 0 
L 1.79263996 -1.99823996 1.87208996 -1.99823996 0 P 0 
L 1.79458996 -1.99723996 1.87198996 -1.99723996 0 P 0 
L 1.79686998 -1.99623996 1.87188002 -1.99623996 0 P 0 
L 1.79946004 -1.99523996 1.87178002 -1.99523996 0 P 0 
L 1.80231004 -1.99423996 1.86961998 -1.99423996 0 P 0 
L 1.80596004 -1.99323996 1.86218002 -1.99323996 0 P 0 
L 1.81051004 -1.99223996 1.85398002 -1.99223996 0 P 0 
L 1.81676004 -1.99123996 1.84395 -1.99123996 0 P 0 
L 1.87786998 -1.96146004 1.88093996 -1.96146004 0 P 0 
L 1.8771 -1.96046004 1.88013002 -1.96046004 0 P 0 
L 1.87633996 -1.95946004 1.87933996 -1.95946004 0 P 0 
L 1.87561998 -1.95846004 1.87866998 -1.95846004 0 P 0 
L 1.87496998 -1.95746004 1.87801998 -1.95746004 0 P 0 
L 1.8744 -1.95646004 1.87745 -1.95646004 0 P 0 
L 1.87386998 -1.95546004 1.87688002 -1.95546004 0 P 0 
L 1.87341998 -1.95446004 1.87641998 -1.95446004 0 P 0 
L 1.87298996 -1.95346004 1.87596004 -1.95346004 0 P 0 
L 1.87263002 -1.95246004 1.87555 -1.95246004 0 P 0 
L 1.87231004 -1.95146004 1.87518996 -1.95146004 0 P 0 
L 1.87203002 -1.95046004 1.87483002 -1.95046004 0 P 0 
L 1.87178996 -1.94946004 1.87456998 -1.94946004 0 P 0 
L 1.87158996 -1.94846004 1.87431004 -1.94846004 0 P 0 
L 1.87143996 -1.94746004 1.87408002 -1.94746004 0 P 0 
L 1.87133002 -1.94646004 1.8739 -1.94646004 0 P 0 
L 1.87121004 -1.94546004 1.87373002 -1.94546004 0 P 0 
L 1.8711 -1.94446998 1.87361998 -1.94446998 0 P 0 
L 1.87106998 -1.94346004 1.87353996 -1.94346004 0 P 0 
L 1.87103002 -1.94246004 1.87346004 -1.94246004 0 P 0 
L 1.87098996 -1.94146998 1.87346004 -1.94146998 0 P 0 
L 1.87101004 -1.94046004 1.87346004 -1.94046004 0 P 0 
L 1.87106004 -1.93946004 1.87348996 -1.93946004 0 P 0 
L 1.87111004 -1.93846004 1.87358002 -1.93846004 0 P 0 
L 1.87123002 -1.93746004 1.87366004 -1.93746004 0 P 0 
L 1.87135 -1.93646004 1.87381998 -1.93646004 0 P 0 
L 1.87151004 -1.93546004 1.87398996 -1.93546004 0 P 0 
L 1.87171998 -1.93446004 1.87416998 -1.93446004 0 P 0 
L 1.87191998 -1.93346004 1.87443002 -1.93346004 0 P 0 
L 1.8722 -1.93246004 1.87468996 -1.93246004 0 P 0 
L 1.87248996 -1.93146004 1.875 -1.93146004 0 P 0 
L 1.87281004 -1.93046004 1.87535 -1.93046004 0 P 0 
L 1.87318996 -1.92946004 1.87571004 -1.92946004 0 P 0 
L 1.87356998 -1.92846004 1.87616004 -1.92846004 0 P 0 
L 1.87405 -1.92746004 1.87661004 -1.92746004 0 P 0 
L 1.87453002 -1.92646004 1.87711998 -1.92646004 0 P 0 
L 1.87506998 -1.92546004 1.87768996 -1.92546004 0 P 0 
L 1.87566004 -1.92446998 1.87826998 -1.92446998 0 P 0 
L 1.87628996 -1.92346004 1.87896004 -1.92346004 0 P 0 
L 1.87701004 -1.92246004 1.87963996 -1.92246004 0 P 0 
L 1.87775 -1.92146004 1.88046004 -1.92146004 0 P 0 
L 1.90483996 -1.97346004 1.9009 -1.97333996 0 P 0 
L 1.9009 -1.97333996 1.89698002 -1.97295 0 P 0 
L 1.89698002 -1.97295 1.89488996 -1.97258996 0 P 0 
L 1.89488996 -1.97258996 1.89285 -1.97206998 0 P 0 
L 1.89285 -1.97206998 1.89086004 -1.97138996 0 P 0 
L 1.89086004 -1.97138996 1.889 -1.97058002 0 P 0 
L 1.889 -1.97058002 1.88723002 -1.96961998 0 P 0 
L 1.88723002 -1.96961998 1.88553002 -1.96851998 0 P 0 
L 1.88553002 -1.96851998 1.88273996 -1.96636004 0 P 0 
L 1.88273996 -1.96636004 1.88013996 -1.96396004 0 P 0 
L 1.88013996 -1.96396004 1.8779 -1.9615 0 P 0 
L 1.8779 -1.9615 1.87588002 -1.95886998 0 P 0 
L 1.87588002 -1.95886998 1.87483002 -1.95723996 0 P 0 
L 1.87483002 -1.95723996 1.8739 -1.95553996 0 P 0 
L 1.8739 -1.95553996 1.87311004 -1.95376998 0 P 0 
L 1.87311004 -1.95376998 1.87243002 -1.95191004 0 P 0 
L 1.87243002 -1.95191004 1.8719 -1.95001998 0 P 0 
L 1.8719 -1.95001998 1.87151998 -1.9481 0 P 0 
L 1.87151998 -1.9481 1.87111004 -1.94468996 0 P 0 
L 1.87111004 -1.94468996 1.87098002 -1.94128996 0 P 0 
L 1.87098002 -1.94128996 1.87108996 -1.93861004 0 P 0 
L 1.87108996 -1.93861004 1.87141004 -1.93596998 0 P 0 
L 1.87141004 -1.93596998 1.87195 -1.93335 0 P 0 
L 1.87195 -1.93335 1.87268996 -1.93078996 0 P 0 
L 1.87268996 -1.93078996 1.87361998 -1.92835 0 P 0 
L 1.87361998 -1.92835 1.87475 -1.926 0 P 0 
L 1.87475 -1.926 1.87608996 -1.92376004 0 P 0 
L 1.87608996 -1.92376004 1.8776 -1.92163996 0 P 0 
L 1.8776 -1.92163996 1.87931998 -1.91961998 0 P 0 
L 1.87931998 -1.91961998 1.8812 -1.91775 0 P 0 
L 1.8812 -1.91775 1.88323002 -1.91605 0 P 0 
L 1.88323002 -1.91605 1.8854 -1.91451998 0 P 0 
L 1.8854 -1.91451998 1.88781004 -1.91308996 0 P 0 
L 1.88781004 -1.91308996 1.89031004 -1.91186004 0 P 0 
L 1.89031004 -1.91186004 1.89288002 -1.9108 0 P 0 
L 1.89288002 -1.9108 1.89553002 -1.90995 0 P 0 
L 1.89553002 -1.90995 1.89723002 -1.90953002 0 P 0 
L 1.89723002 -1.90953002 1.89896004 -1.90923996 0 P 0 
L 1.89896004 -1.90923996 1.90068996 -1.90908002 0 P 0 
L 1.90068996 -1.90908002 1.90398996 -1.90901004 0 P 0 
L 1.90398996 -1.90901004 1.90728002 -1.90915 0 P 0 
L 1.90728002 -1.90915 1.91058996 -1.90951004 0 P 0 
L 1.91058996 -1.90951004 1.91383996 -1.91006004 0 P 0 
L 1.91383996 -1.91006004 1.91558996 -1.91048996 0 P 0 
L 1.91558996 -1.91048996 1.91728996 -1.91101998 0 P 0 
L 1.91728996 -1.91101998 1.91895 -1.91168002 0 P 0 
L 1.91895 -1.91168002 1.92001998 -1.9122 0 P 0 
L 1.92001998 -1.9122 1.92105 -1.91278996 0 P 0 
L 1.92105 -1.91278996 1.92376998 -1.91458002 0 P 0 
L 1.92376998 -1.91458002 1.92648996 -1.91666998 0 P 0 
L 1.92648996 -1.91666998 1.92763002 -1.91763996 0 P 0 
L 1.92763002 -1.91763996 1.92871004 -1.91865 0 P 0 
L 1.92871004 -1.91865 1.93018002 -1.92018996 0 P 0 
L 1.93018002 -1.92018996 1.93153002 -1.9218 0 P 0 
L 1.93153002 -1.9218 1.93276998 -1.92348996 0 P 0 
L 1.93276998 -1.92348996 1.93381004 -1.92515 0 P 0 
L 1.93381004 -1.92515 1.93471998 -1.92686998 0 P 0 
L 1.93471998 -1.92686998 1.9355 -1.92866998 0 P 0 
L 1.9355 -1.92866998 1.93616998 -1.93061004 0 P 0 
L 1.93616998 -1.93061004 1.93668996 -1.93258002 0 P 0 
L 1.93668996 -1.93258002 1.93706998 -1.93458996 0 P 0 
L 1.93706998 -1.93458996 1.93746998 -1.93818996 0 P 0 
L 1.93746998 -1.93818996 1.9376 -1.94178996 0 P 0 
L 1.9376 -1.94178996 1.93746004 -1.94611004 0 P 0 
L 1.93746004 -1.94611004 1.93731004 -1.94758996 0 P 0 
L 1.93731004 -1.94758996 1.93705 -1.94903996 0 P 0 
L 1.93705 -1.94903996 1.93666998 -1.95041998 0 P 0 
L 1.93666998 -1.95041998 1.93618002 -1.95176004 0 P 0 
L 1.93618002 -1.95176004 1.9345 -1.95545 0 P 0 
L 1.9345 -1.95545 1.93338996 -1.9575 0 P 0 
L 1.93338996 -1.9575 1.93216004 -1.95946998 0 P 0 
L 1.93216004 -1.95946998 1.93078996 -1.96133996 0 P 0 
L 1.93078996 -1.96133996 1.92931004 -1.96311998 0 P 0 
L 1.92931004 -1.96311998 1.92776998 -1.96473002 0 P 0 
L 1.92776998 -1.96473002 1.92613002 -1.96621004 0 P 0 
L 1.92613002 -1.96621004 1.92438002 -1.96756004 0 P 0 
L 1.92438002 -1.96756004 1.92253002 -1.96878002 0 P 0 
L 1.92253002 -1.96878002 1.92056998 -1.96986998 0 P 0 
L 1.92056998 -1.96986998 1.91855 -1.97081998 0 P 0 
L 1.91855 -1.97081998 1.91646004 -1.97161004 0 P 0 
L 1.91646004 -1.97161004 1.91433002 -1.97223996 0 P 0 
L 1.91433002 -1.97223996 1.9112 -1.97291004 0 P 0 
L 1.9112 -1.97291004 1.90803996 -1.97331998 0 P 0 
L 1.90803996 -1.97331998 1.90483996 -1.97346004 0 P 0 
L 1.90476004 -1.97173996 1.9048 -1.97173996 0 P 0 
L 1.9048 -1.97173996 1.90483996 -1.97173002 0 P 0 
L 1.90483996 -1.97173002 1.90736004 -1.9716 0 P 0 
L 1.90736004 -1.9716 1.9074 -1.97158996 0 P 0 
L 1.9074 -1.97158996 1.90746998 -1.97158996 0 P 0 
L 1.90746998 -1.97158996 1.90751004 -1.97158002 0 P 0 
L 1.90751004 -1.97158002 1.91001004 -1.97126004 0 P 0 
L 1.91001004 -1.97126004 1.91005 -1.97125 0 P 0 
L 1.91005 -1.97125 1.91008002 -1.97123996 0 P 0 
L 1.91008002 -1.97123996 1.91011998 -1.97123996 0 P 0 
L 1.91011998 -1.97123996 1.91016004 -1.97123002 0 P 0 
L 1.91016004 -1.97123002 1.9126 -1.97071998 0 P 0 
L 1.9126 -1.97071998 1.9126 -1.97071004 0 P 0 
L 1.9126 -1.97071004 1.91266998 -1.97071004 0 P 0 
L 1.91266998 -1.97071004 1.91271004 -1.97068996 0 P 0 
L 1.91271004 -1.97068996 1.91275 -1.97068002 0 P 0 
L 1.91275 -1.97068002 1.91511998 -1.96998996 0 P 0 
L 1.91511998 -1.96998996 1.91515 -1.96998996 0 P 0 
L 1.91515 -1.96998996 1.91518996 -1.96996998 0 P 0 
L 1.91518996 -1.96996998 1.91523002 -1.96996004 0 P 0 
L 1.91523002 -1.96996004 1.91526004 -1.96995 0 P 0 
L 1.91526004 -1.96995 1.91756998 -1.96908002 0 P 0 
L 1.91756998 -1.96908002 1.91761004 -1.96906998 0 P 0 
L 1.91761004 -1.96906998 1.91768002 -1.96903996 0 P 0 
L 1.91768002 -1.96903996 1.91771004 -1.96901998 0 P 0 
L 1.91771004 -1.96901998 1.91995 -1.96798002 0 P 0 
L 1.91995 -1.96798002 1.92001998 -1.96795 0 P 0 
L 1.92001998 -1.96795 1.92005 -1.96793002 0 P 0 
L 1.92005 -1.96793002 1.92008996 -1.96791004 0 P 0 
L 1.92008996 -1.96791004 1.92168002 -1.96701998 0 P 0 
L 1.92168002 -1.96701998 1.92171998 -1.967 0 P 0 
L 1.92171998 -1.967 1.92175 -1.96698002 0 P 0 
L 1.92175 -1.96698002 1.92178996 -1.96695 0 P 0 
L 1.92178996 -1.96695 1.92181998 -1.96693002 0 P 0 
L 1.92181998 -1.96693002 1.92331998 -1.96591998 0 P 0 
L 1.92331998 -1.96591998 1.92336004 -1.9659 0 P 0 
L 1.92336004 -1.9659 1.92341998 -1.96586004 0 P 0 
L 1.92341998 -1.96586004 1.92345 -1.96583002 0 P 0 
L 1.92345 -1.96583002 1.92486004 -1.9647 0 P 0 
L 1.92486004 -1.9647 1.92493002 -1.96465 0 P 0 
L 1.92493002 -1.96465 1.92496004 -1.96463002 0 P 0 
L 1.92496004 -1.96463002 1.92498996 -1.9646 0 P 0 
L 1.92498996 -1.9646 1.92631004 -1.96336998 0 P 0 
L 1.92631004 -1.96336998 1.9264 -1.96328002 0 P 0 
L 1.9264 -1.96328002 1.92641998 -1.96325 0 P 0 
L 1.92641998 -1.96325 1.92763996 -1.96191998 0 P 0 
L 1.92763996 -1.96191998 1.92766998 -1.96188996 0 P 0 
L 1.92766998 -1.96188996 1.92768996 -1.96186004 0 P 0 
L 1.92768996 -1.96186004 1.92771998 -1.96183002 0 P 0 
L 1.92771998 -1.96183002 1.92773996 -1.9618 0 P 0 
L 1.92773996 -1.9618 1.92913996 -1.96001004 0 P 0 
L 1.92913996 -1.96001004 1.92918996 -1.95995 0 P 0 
L 1.92918996 -1.95995 1.92921004 -1.95991004 0 P 0 
L 1.92921004 -1.95991004 1.92923002 -1.95988002 0 P 0 
L 1.92923002 -1.95988002 1.93048002 -1.95798996 0 P 0 
L 1.93048002 -1.95798996 1.93051998 -1.95793002 0 P 0 
L 1.93051998 -1.95793002 1.93053996 -1.95788996 0 P 0 
L 1.93053996 -1.95788996 1.93056004 -1.95786004 0 P 0 
L 1.93056004 -1.95786004 1.93166004 -1.95588002 0 P 0 
L 1.93166004 -1.95588002 1.93171004 -1.95576998 0 P 0 
L 1.93171004 -1.95576998 1.93173002 -1.95573996 0 P 0 
L 1.93173002 -1.95573996 1.93266998 -1.95366998 0 P 0 
L 1.93266998 -1.95366998 1.93271004 -1.95356998 0 P 0 
L 1.93271004 -1.95356998 1.93273002 -1.95353002 0 P 0 
L 1.93273002 -1.95353002 1.9335 -1.9514 0 P 0 
L 1.9335 -1.9514 1.93351004 -1.95136998 0 P 0 
L 1.93351004 -1.95136998 1.93353002 -1.95133002 0 P 0 
L 1.93353002 -1.95133002 1.93355 -1.95125 0 P 0 
L 1.93355 -1.95125 1.93416004 -1.94906998 0 P 0 
L 1.93416004 -1.94906998 1.93416998 -1.94903002 0 P 0 
L 1.93416998 -1.94903002 1.93418002 -1.949 0 P 0 
L 1.93418002 -1.949 1.93418002 -1.94896004 0 P 0 
L 1.93418002 -1.94896004 1.93418996 -1.94891998 0 P 0 
L 1.93418996 -1.94891998 1.93463996 -1.94665 0 P 0 
L 1.93463996 -1.94665 1.93463996 -1.94661004 0 P 0 
L 1.93463996 -1.94661004 1.93465 -1.94656998 0 P 0 
L 1.93465 -1.94656998 1.93466004 -1.9465 0 P 0 
L 1.93466004 -1.9465 1.93493996 -1.9442 0 P 0 
L 1.93493996 -1.9442 1.93493996 -1.94413002 0 P 0 
L 1.93493996 -1.94413002 1.93495 -1.94408996 0 P 0 
L 1.93495 -1.94408996 1.93495 -1.94406004 0 P 0 
L 1.93495 -1.94406004 1.93505 -1.94173996 0 P 0 
L 1.93505 -1.94173996 1.93506004 -1.94171004 0 P 0 
L 1.93506004 -1.94171004 1.93506004 -1.9416 0 P 0 
L 1.93506004 -1.9416 1.93498996 -1.93928996 0 P 0 
L 1.93498996 -1.93928996 1.93498996 -1.93921004 0 P 0 
L 1.93498996 -1.93921004 1.93498002 -1.93913996 0 P 0 
L 1.93498002 -1.93913996 1.93475 -1.93683996 0 P 0 
L 1.93475 -1.93683996 1.93473996 -1.93676998 0 P 0 
L 1.93473996 -1.93676998 1.93473002 -1.93673002 0 P 0 
L 1.93473002 -1.93673002 1.93473002 -1.93668996 0 P 0 
L 1.93473002 -1.93668996 1.93433002 -1.93441004 0 P 0 
L 1.93433002 -1.93441004 1.93431998 -1.93436998 0 P 0 
L 1.93431998 -1.93436998 1.93431004 -1.93433996 0 P 0 
L 1.93431004 -1.93433996 1.93428996 -1.93426004 0 P 0 
L 1.93428996 -1.93426004 1.93373002 -1.93206004 0 P 0 
L 1.93373002 -1.93206004 1.93368996 -1.93191998 0 P 0 
L 1.93368996 -1.93191998 1.93296004 -1.92976998 0 P 0 
L 1.93296004 -1.92976998 1.93293996 -1.9297 0 P 0 
L 1.93293996 -1.9297 1.93291004 -1.92963002 0 P 0 
L 1.93291004 -1.92963002 1.93201998 -1.92753996 0 P 0 
L 1.93201998 -1.92753996 1.93196998 -1.92743002 0 P 0 
L 1.93196998 -1.92743002 1.93196004 -1.9274 0 P 0 
L 1.93196004 -1.9274 1.93091998 -1.92538996 0 P 0 
L 1.93091998 -1.92538996 1.9309 -1.92536004 0 P 0 
L 1.9309 -1.92536004 1.93088002 -1.92531998 0 P 0 
L 1.93088002 -1.92531998 1.93086004 -1.92528996 0 P 0 
L 1.93086004 -1.92528996 1.93083996 -1.92525 0 P 0 
L 1.93083996 -1.92525 1.92965 -1.92331998 0 P 0 
L 1.92965 -1.92331998 1.92956998 -1.9232 0 P 0 
L 1.92956998 -1.9232 1.92823002 -1.92136004 0 P 0 
L 1.92823002 -1.92136004 1.92818002 -1.9213 0 P 0 
L 1.92818002 -1.9213 1.92816004 -1.92126998 0 P 0 
L 1.92816004 -1.92126998 1.92813002 -1.92123996 0 P 0 
L 1.92813002 -1.92123996 1.92671998 -1.91958002 0 P 0 
L 1.92671998 -1.91958002 1.9266 -1.91946004 0 P 0 
L 1.9266 -1.91946004 1.92505 -1.91793002 0 P 0 
L 1.92505 -1.91793002 1.92498996 -1.91786998 0 P 0 
L 1.92498996 -1.91786998 1.92493002 -1.91781998 0 P 0 
L 1.92493002 -1.91781998 1.92325 -1.91643002 0 P 0 
L 1.92325 -1.91643002 1.92318996 -1.91636998 0 P 0 
L 1.92318996 -1.91636998 1.92311998 -1.91631998 0 P 0 
L 1.92311998 -1.91631998 1.92133002 -1.91508002 0 P 0 
L 1.92133002 -1.91508002 1.92126004 -1.91503996 0 P 0 
L 1.92126004 -1.91503996 1.92121998 -1.91501004 0 P 0 
L 1.92121998 -1.91501004 1.92118002 -1.91498996 0 P 0 
L 1.92118002 -1.91498996 1.91928996 -1.91391004 0 P 0 
L 1.91928996 -1.91391004 1.91926004 -1.91388996 0 P 0 
L 1.91926004 -1.91388996 1.91913996 -1.91383002 0 P 0 
L 1.91913996 -1.91383002 1.91716998 -1.91291004 0 P 0 
L 1.91716998 -1.91291004 1.91711998 -1.91288996 0 P 0 
L 1.91711998 -1.91288996 1.91705 -1.91286004 0 P 0 
L 1.91705 -1.91286004 1.917 -1.91285 0 P 0 
L 1.917 -1.91285 1.91476998 -1.91203996 0 P 0 
L 1.91476998 -1.91203996 1.91468996 -1.91201998 0 P 0 
L 1.91468996 -1.91201998 1.91465 -1.912 0 P 0 
L 1.91465 -1.912 1.9146 -1.91198996 0 P 0 
L 1.9146 -1.91198996 1.91233002 -1.91138996 0 P 0 
L 1.91233002 -1.91138996 1.91228002 -1.91138002 0 P 0 
L 1.91228002 -1.91138002 1.91223996 -1.91136998 0 P 0 
L 1.91223996 -1.91136998 1.91216004 -1.91136004 0 P 0 
L 1.91216004 -1.91136004 1.90983002 -1.91095 0 P 0 
L 1.90983002 -1.91095 1.9098 -1.91093996 0 P 0 
L 1.9098 -1.91093996 1.90976004 -1.91093996 0 P 0 
L 1.90976004 -1.91093996 1.90971998 -1.91093002 0 P 0 
L 1.90971998 -1.91093002 1.90968002 -1.91093002 0 P 0 
L 1.90968002 -1.91093002 1.90713996 -1.91068996 0 P 0 
L 1.90713996 -1.91068996 1.9071 -1.91068002 0 P 0 
L 1.9071 -1.91068002 1.907 -1.91068002 0 P 0 
L 1.907 -1.91068002 1.90445 -1.91061004 0 P 0 
L 1.90445 -1.91061004 1.90431004 -1.91061004 0 P 0 
L 1.90431004 -1.91061004 1.90176004 -1.91071004 0 P 0 
L 1.90176004 -1.91071004 1.90173002 -1.91071998 0 P 0 
L 1.90173002 -1.91071998 1.90166004 -1.91071998 0 P 0 
L 1.90166004 -1.91071998 1.90161998 -1.91073002 0 P 0 
L 1.90161998 -1.91073002 1.89913002 -1.911 0 P 0 
L 1.89913002 -1.911 1.89906004 -1.91101004 0 P 0 
L 1.89906004 -1.91101004 1.89901998 -1.91101998 0 P 0 
L 1.89901998 -1.91101998 1.89898996 -1.91101998 0 P 0 
L 1.89898996 -1.91101998 1.89653002 -1.91146998 0 P 0 
L 1.89653002 -1.91146998 1.8965 -1.91148002 0 P 0 
L 1.8965 -1.91148002 1.89646004 -1.91148002 0 P 0 
L 1.89646004 -1.91148002 1.8964 -1.9115 0 P 0 
L 1.8964 -1.9115 1.89396998 -1.91211998 0 P 0 
L 1.89396998 -1.91211998 1.89393996 -1.91213002 0 P 0 
L 1.89393996 -1.91213002 1.89383002 -1.91216004 0 P 0 
L 1.89383002 -1.91216004 1.89225 -1.91268996 0 P 0 
L 1.89225 -1.91268996 1.89218002 -1.91271998 0 P 0 
L 1.89218002 -1.91271998 1.89211004 -1.91273996 0 P 0 
L 1.89211004 -1.91273996 1.8921 -1.91273996 0 P 0 
L 1.8921 -1.91273996 1.89058002 -1.91338996 0 P 0 
L 1.89058002 -1.91338996 1.89043996 -1.91345 0 P 0 
L 1.89043996 -1.91345 1.88896004 -1.91421004 0 P 0 
L 1.88896004 -1.91421004 1.88893002 -1.91423002 0 P 0 
L 1.88893002 -1.91423002 1.8889 -1.91423996 0 P 0 
L 1.8889 -1.91423996 1.88886004 -1.91426004 0 P 0 
L 1.88886004 -1.91426004 1.88883002 -1.91428002 0 P 0 
L 1.88883002 -1.91428002 1.88741004 -1.91515 0 P 0 
L 1.88741004 -1.91515 1.88733996 -1.91518996 0 P 0 
L 1.88733996 -1.91518996 1.88728002 -1.91523996 0 P 0 
L 1.88728002 -1.91523996 1.88526004 -1.9167 0 P 0 
L 1.88526004 -1.9167 1.88521998 -1.91673002 0 P 0 
L 1.88521998 -1.91673002 1.88518996 -1.91675 0 P 0 
L 1.88518996 -1.91675 1.88516004 -1.91678002 0 P 0 
L 1.88516004 -1.91678002 1.88511998 -1.91681004 0 P 0 
L 1.88511998 -1.91681004 1.88323002 -1.91845 0 P 0 
L 1.88323002 -1.91845 1.8832 -1.91846998 0 P 0 
L 1.8832 -1.91846998 1.88311004 -1.91856004 0 P 0 
L 1.88311004 -1.91856004 1.88136998 -1.92036004 0 P 0 
L 1.88136998 -1.92036004 1.88128002 -1.92045 0 P 0 
L 1.88128002 -1.92045 1.88125 -1.92048996 0 P 0 
L 1.88125 -1.92048996 1.87968002 -1.92241998 0 P 0 
L 1.87968002 -1.92241998 1.87965 -1.92245 0 P 0 
L 1.87965 -1.92245 1.87961998 -1.92248996 0 P 0 
L 1.87961998 -1.92248996 1.87956998 -1.92256004 0 P 0 
L 1.87956998 -1.92256004 1.87816998 -1.92461998 0 P 0 
L 1.87816998 -1.92461998 1.8781 -1.92473002 0 P 0 
L 1.8781 -1.92473002 1.87808002 -1.92476998 0 P 0 
L 1.87808002 -1.92476998 1.87685 -1.92695 0 P 0 
L 1.87685 -1.92695 1.87683002 -1.92698996 0 P 0 
L 1.87683002 -1.92698996 1.87681004 -1.92701998 0 P 0 
L 1.87681004 -1.92701998 1.87678996 -1.92706998 0 P 0 
L 1.87678996 -1.92706998 1.87676998 -1.92711004 0 P 0 
L 1.87676998 -1.92711004 1.87573002 -1.92941004 0 P 0 
L 1.87573002 -1.92941004 1.87571004 -1.92945 0 P 0 
L 1.87571004 -1.92945 1.8757 -1.92948996 0 P 0 
L 1.8757 -1.92948996 1.87568002 -1.92951998 0 P 0 
L 1.87568002 -1.92951998 1.87566998 -1.92956998 0 P 0 
L 1.87566998 -1.92956998 1.87483996 -1.93193002 0 P 0 
L 1.87483996 -1.93193002 1.87481004 -1.93201004 0 P 0 
L 1.87481004 -1.93201004 1.87478996 -1.93208996 0 P 0 
L 1.87478996 -1.93208996 1.87416004 -1.93451998 0 P 0 
L 1.87416004 -1.93451998 1.87413996 -1.93456004 0 P 0 
L 1.87413996 -1.93456004 1.87413002 -1.9346 0 P 0 
L 1.87413002 -1.9346 1.87413002 -1.93463996 0 P 0 
L 1.87413002 -1.93463996 1.87411998 -1.93468002 0 P 0 
L 1.87411998 -1.93468002 1.8737 -1.93715 0 P 0 
L 1.8737 -1.93715 1.87368996 -1.93718996 0 P 0 
L 1.87368996 -1.93718996 1.87368002 -1.93723996 0 P 0 
L 1.87368002 -1.93723996 1.87368002 -1.93731998 0 P 0 
L 1.87368002 -1.93731998 1.87346998 -1.93981998 0 P 0 
L 1.87346998 -1.93981998 1.87346004 -1.93986004 0 P 0 
L 1.87346004 -1.93986004 1.87346004 -1.94258002 0 P 0 
L 1.87346004 -1.94258002 1.87346998 -1.94266004 0 P 0 
L 1.87346998 -1.94266004 1.87368002 -1.94516998 0 P 0 
L 1.87368002 -1.94516998 1.87368996 -1.94521004 0 P 0 
L 1.87368996 -1.94521004 1.87368996 -1.94525 0 P 0 
L 1.87368996 -1.94525 1.87371004 -1.94533996 0 P 0 
L 1.87371004 -1.94533996 1.87413996 -1.94778996 0 P 0 
L 1.87413996 -1.94778996 1.87413996 -1.94783996 0 P 0 
L 1.87413996 -1.94783996 1.87416998 -1.94796004 0 P 0 
L 1.87416998 -1.94796004 1.87481004 -1.95036998 0 P 0 
L 1.87481004 -1.95036998 1.87483996 -1.95048996 0 P 0 
L 1.87483996 -1.95048996 1.87486004 -1.95053002 0 P 0 
L 1.87486004 -1.95053002 1.8757 -1.95288002 0 P 0 
L 1.8757 -1.95288002 1.87571004 -1.95291998 0 P 0 
L 1.87571004 -1.95291998 1.87575 -1.953 0 P 0 
L 1.87575 -1.953 1.87576004 -1.95303996 0 P 0 
L 1.87576004 -1.95303996 1.8768 -1.9553 0 P 0 
L 1.8768 -1.9553 1.87686004 -1.95541998 0 P 0 
L 1.87686004 -1.95541998 1.87688002 -1.95545 0 P 0 
L 1.87688002 -1.95545 1.8781 -1.95761004 0 P 0 
L 1.8781 -1.95761004 1.87811998 -1.95761004 0 P 0 
L 1.87811998 -1.95761004 1.8781 -1.95761998 0 P 0 
L 1.8781 -1.95761998 1.87813996 -1.95768996 0 P 0 
L 1.87813996 -1.95768996 1.87816998 -1.95771998 0 P 0 
L 1.87816998 -1.95771998 1.87818996 -1.95775 0 P 0 
L 1.87818996 -1.95775 1.87938002 -1.95951004 0 P 0 
L 1.87938002 -1.95951004 1.87943996 -1.9596 0 P 0 
L 1.87943996 -1.9596 1.87946998 -1.95963002 0 P 0 
L 1.87946998 -1.95963002 1.88078002 -1.96128996 0 P 0 
L 1.88078002 -1.96128996 1.88081004 -1.96131998 0 P 0 
L 1.88081004 -1.96131998 1.88083002 -1.96135 0 P 0 
L 1.88083002 -1.96135 1.88086004 -1.96136998 0 P 0 
L 1.88086004 -1.96136998 1.88088002 -1.9614 0 P 0 
L 1.88088002 -1.9614 1.88231998 -1.96295 0 P 0 
L 1.88231998 -1.96295 1.88233996 -1.96298002 0 P 0 
L 1.88233996 -1.96298002 1.8824 -1.96303996 0 P 0 
L 1.8824 -1.96303996 1.88243002 -1.96306004 0 P 0 
L 1.88243002 -1.96306004 1.88398002 -1.9645 0 P 0 
L 1.88398002 -1.9645 1.88401004 -1.96451998 0 P 0 
L 1.88401004 -1.96451998 1.88403002 -1.96455 0 P 0 
L 1.88403002 -1.96455 1.88406998 -1.96458002 0 P 0 
L 1.88406998 -1.96458002 1.88408996 -1.9646 0 P 0 
L 1.88408996 -1.9646 1.88575 -1.96591004 0 P 0 
L 1.88575 -1.96591004 1.88578002 -1.96593996 0 P 0 
L 1.88578002 -1.96593996 1.88586998 -1.966 0 P 0 
L 1.88586998 -1.966 1.88761998 -1.96718996 0 P 0 
L 1.88761998 -1.96718996 1.88766004 -1.96721004 0 P 0 
L 1.88766004 -1.96721004 1.88775 -1.96726998 0 P 0 
L 1.88775 -1.96726998 1.88958996 -1.96831998 0 P 0 
L 1.88958996 -1.96831998 1.88965 -1.96836004 0 P 0 
L 1.88965 -1.96836004 1.88968002 -1.96836998 0 P 0 
L 1.88968002 -1.96836998 1.88971998 -1.96838996 0 P 0 
L 1.88971998 -1.96838996 1.89145 -1.96921998 0 P 0 
L 1.89145 -1.96921998 1.89151004 -1.96925 0 P 0 
L 1.89151004 -1.96925 1.89155 -1.96926004 0 P 0 
L 1.89155 -1.96926004 1.89158002 -1.96926998 0 P 0 
L 1.89158002 -1.96926998 1.89336004 -1.96996998 0 P 0 
L 1.89336004 -1.96996998 1.89336004 -1.96998002 0 P 0 
L 1.89336004 -1.96998002 1.89346004 -1.97001004 0 P 0 
L 1.89346004 -1.97001004 1.89348996 -1.97001998 0 P 0 
L 1.89348996 -1.97001998 1.89531998 -1.9706 0 P 0 
L 1.89531998 -1.9706 1.89536004 -1.97061004 0 P 0 
L 1.89536004 -1.97061004 1.89541998 -1.97063002 0 P 0 
L 1.89541998 -1.97063002 1.89546004 -1.97063002 0 P 0 
L 1.89546004 -1.97063002 1.89731998 -1.97108002 0 P 0 
L 1.89731998 -1.97108002 1.89741998 -1.9711 0 P 0 
L 1.89741998 -1.9711 1.89746004 -1.9711 0 P 0 
L 1.89746004 -1.9711 1.89746004 -1.97111004 0 P 0 
L 1.89746004 -1.97111004 1.89933996 -1.97141998 0 P 0 
L 1.89933996 -1.97141998 1.89936998 -1.97143002 0 P 0 
L 1.89936998 -1.97143002 1.89941004 -1.97143002 0 P 0 
L 1.89941004 -1.97143002 1.89945 -1.97143996 0 P 0 
L 1.89945 -1.97143996 1.89948002 -1.97143996 0 P 0 
L 1.89948002 -1.97143996 1.90201004 -1.97168002 0 P 0 
L 1.90201004 -1.97168002 1.90205 -1.97168002 0 P 0 
L 1.90205 -1.97168002 1.90208996 -1.97168996 0 P 0 
L 1.90208996 -1.97168996 1.90216004 -1.97168996 0 P 0 
L 1.90216004 -1.97168996 1.90468996 -1.97173996 0 P 0 
L 1.90468996 -1.97173996 1.90476004 -1.97173996 0 P 0 
L 1.80616004 -2.12823996 1.83348996 -2.12823996 0 P 0 
L 1.79591998 -2.12723996 1.8396 -2.12723996 0 P 0 
L 1.78818002 -2.12623996 1.84465 -2.12623996 0 P 0 
L 1.82003996 -2.09123996 1.87618996 -2.09123996 0 P 0 
L 1.82198996 -2.09023996 1.8762 -2.09023996 0 P 0 
L 1.82325 -2.08923996 1.8762 -2.08923996 0 P 0 
L 1.82411998 -2.08823996 1.87618996 -2.08823996 0 P 0 
L 1.82463002 -2.08723996 1.87616998 -2.08723996 0 P 0 
L 1.82488002 -2.08623996 1.87615 -2.08623996 0 P 0 
L 1.82493002 -2.08523996 1.87613002 -2.08523996 0 P 0 
L 1.82476998 -2.08423996 1.87611004 -2.08423996 0 P 0 
L 1.64846004 -2.08295 1.73316998 -2.08295 0 P 0 
L 1.64811998 -2.08195 1.73356998 -2.08195 0 P 0 
L 1.64776998 -2.08095 1.73398002 -2.08095 0 P 0 
L 1.64743002 -2.07995 1.73438002 -2.07995 0 P 0 
L 1.64708996 -2.07895 1.73478996 -2.07895 0 P 0 
L 1.64673996 -2.07795 1.7352 -2.07795 0 P 0 
L 1.6464 -2.07695 1.7356 -2.07695 0 P 0 
L 1.64605 -2.07595 1.73601004 -2.07595 0 P 0 
L 1.64571004 -2.07495 1.73641004 -2.07495 0 P 0 
L 1.64536004 -2.07395 1.73681004 -2.07395 0 P 0 
L 1.64501998 -2.07295 1.73721998 -2.07295 0 P 0 
L 1.64466998 -2.07195 1.73761998 -2.07195 0 P 0 
L 1.64433002 -2.07095 1.73803002 -2.07095 0 P 0 
L 1.64398002 -2.06995 1.69251004 -2.06995 0 P 0 
L 1.69583002 -2.06995 1.73843996 -2.06995 0 P 0 
L 1.64363002 -2.06895 1.69168002 -2.06895 0 P 0 
L 1.69671998 -2.06895 1.73883996 -2.06895 0 P 0 
L 1.64328996 -2.06795 1.69136004 -2.06795 0 P 0 
L 1.69708996 -2.06795 1.73925 -2.06795 0 P 0 
L 1.64293996 -2.06695 1.69108002 -2.06695 0 P 0 
L 1.69738002 -2.06695 1.73965 -2.06695 0 P 0 
L 1.64258996 -2.06595 1.6908 -2.06595 0 P 0 
L 1.69768002 -2.06595 1.74006004 -2.06595 0 P 0 
L 1.64223996 -2.06495 1.69051998 -2.06495 0 P 0 
L 1.69796998 -2.06495 1.74046004 -2.06495 0 P 0 
L 1.6419 -2.06395 1.69023002 -2.06395 0 P 0 
L 1.69826998 -2.06395 1.74086004 -2.06395 0 P 0 
L 1.64155 -2.06295 1.68996004 -2.06295 0 P 0 
L 1.69856004 -2.06295 1.74126998 -2.06295 0 P 0 
L 1.6412 -2.06195 1.68966998 -2.06195 0 P 0 
L 1.69886004 -2.06195 1.74168002 -2.06195 0 P 0 
L 1.64085 -2.06095 1.68938996 -2.06095 0 P 0 
L 1.69915 -2.06095 1.74208002 -2.06095 0 P 0 
L 1.6405 -2.05995 1.68911004 -2.05995 0 P 0 
L 1.69945 -2.05995 1.74248002 -2.05995 0 P 0 
L 1.64016004 -2.05895 1.68883002 -2.05895 0 P 0 
L 1.69973996 -2.05895 1.74288996 -2.05895 0 P 0 
L 1.63981004 -2.05795 1.68855 -2.05795 0 P 0 
L 1.70003996 -2.05795 1.74328996 -2.05795 0 P 0 
L 1.63946004 -2.05695 1.68826998 -2.05695 0 P 0 
L 1.70033002 -2.05695 1.7437 -2.05695 0 P 0 
L 1.63911004 -2.05595 1.68798996 -2.05595 0 P 0 
L 1.70063002 -2.05595 1.7441 -2.05595 0 P 0 
L 1.63876998 -2.05495 1.68771004 -2.05495 0 P 0 
L 1.70091998 -2.05495 1.74451004 -2.05495 0 P 0 
L 1.63841998 -2.05395 1.68741998 -2.05395 0 P 0 
L 1.70121998 -2.05395 1.74491004 -2.05395 0 P 0 
L 1.63806998 -2.05295 1.68713996 -2.05295 0 P 0 
L 1.70151004 -2.05295 1.74531004 -2.05295 0 P 0 
L 1.63771998 -2.05195 1.68686004 -2.05195 0 P 0 
L 1.70181004 -2.05195 1.74571998 -2.05195 0 P 0 
L 1.63738002 -2.05095 1.68658002 -2.05095 0 P 0 
L 1.7021 -2.05095 1.74611998 -2.05095 0 P 0 
L 1.63703002 -2.04995 1.6863 -2.04995 0 P 0 
L 1.7024 -2.04995 1.74653002 -2.04995 0 P 0 
L 1.63668002 -2.04895 1.68601998 -2.04895 0 P 0 
L 1.70268996 -2.04895 1.74693002 -2.04895 0 P 0 
L 1.63633002 -2.04795 1.68573996 -2.04795 0 P 0 
L 1.70298996 -2.04795 1.74733002 -2.04795 0 P 0 
L 1.63598002 -2.04695 1.68546004 -2.04695 0 P 0 
L 1.70328002 -2.04695 1.74773996 -2.04695 0 P 0 
L 1.63563996 -2.04595 1.68518002 -2.04595 0 P 0 
L 1.70358002 -2.04595 1.74813996 -2.04595 0 P 0 
L 1.63528996 -2.04495 1.6849 -2.04495 0 P 0 
L 1.70386998 -2.04495 1.74855 -2.04495 0 P 0 
L 1.63493996 -2.04395 1.68461004 -2.04395 0 P 0 
L 1.70416998 -2.04395 1.74895 -2.04395 0 P 0 
L 1.63458996 -2.04295 1.68433002 -2.04295 0 P 0 
L 1.70446004 -2.04295 1.74936004 -2.04295 0 P 0 
L 1.63425 -2.04195 1.68405 -2.04195 0 P 0 
L 1.70475 -2.04195 1.74976004 -2.04195 0 P 0 
L 1.6339 -2.04095 1.68376998 -2.04095 0 P 0 
L 1.70503002 -2.04095 1.75016004 -2.04095 0 P 0 
L 1.63355 -2.03995 1.68348996 -2.03995 0 P 0 
L 1.70531998 -2.03995 1.75056998 -2.03995 0 P 0 
L 1.6332 -2.03895 1.68321004 -2.03895 0 P 0 
L 1.7056 -2.03895 1.75096998 -2.03895 0 P 0 
L 1.63286004 -2.03795 1.68293002 -2.03795 0 P 0 
L 1.70588996 -2.03795 1.75138002 -2.03795 0 P 0 
L 1.63251004 -2.03695 1.68266004 -2.03695 0 P 0 
L 1.70618002 -2.03695 1.75178002 -2.03695 0 P 0 
L 1.63216004 -2.03595 1.68238002 -2.03595 0 P 0 
L 1.70646998 -2.03595 1.75218996 -2.03595 0 P 0 
L 1.63181004 -2.03495 1.6821 -2.03495 0 P 0 
L 1.70675 -2.03495 1.75258996 -2.03495 0 P 0 
L 1.63146998 -2.03395 1.68183002 -2.03395 0 P 0 
L 1.70703996 -2.03395 1.75298996 -2.03395 0 P 0 
L 1.63111998 -2.03295 1.68155 -2.03295 0 P 0 
L 1.70733002 -2.03295 1.7534 -2.03295 0 P 0 
L 1.63076998 -2.03195 1.68126998 -2.03195 0 P 0 
L 1.70761004 -2.03195 1.75381004 -2.03195 0 P 0 
L 1.63041998 -2.03095 1.68098996 -2.03095 0 P 0 
L 1.7079 -2.03095 1.75421004 -2.03095 0 P 0 
L 1.63006998 -2.02995 1.68071004 -2.02995 0 P 0 
L 1.70818996 -2.02995 1.75461004 -2.02995 0 P 0 
L 1.62973002 -2.02895 1.68043996 -2.02895 0 P 0 
L 1.70846998 -2.02895 1.75501998 -2.02895 0 P 0 
L 1.62938002 -2.02795 1.68016004 -2.02795 0 P 0 
L 1.70876004 -2.02795 1.75541998 -2.02795 0 P 0 
L 1.62903002 -2.02695 1.67988002 -2.02695 0 P 0 
L 1.70905 -2.02695 1.75583002 -2.02695 0 P 0 
L 1.62868002 -2.02595 1.6796 -2.02595 0 P 0 
L 1.70933996 -2.02595 1.75623002 -2.02595 0 P 0 
L 1.62831004 -2.02495 1.67933002 -2.02495 0 P 0 
L 1.70961998 -2.02495 1.75663996 -2.02495 0 P 0 
L 1.62793996 -2.02395 1.67905 -2.02395 0 P 0 
L 1.70991004 -2.02395 1.75703996 -2.02395 0 P 0 
L 1.62756998 -2.02295 1.67876998 -2.02295 0 P 0 
L 1.7102 -2.02295 1.75743996 -2.02295 0 P 0 
L 1.6272 -2.02195 1.6785 -2.02195 0 P 0 
L 1.71048002 -2.02195 1.75785 -2.02195 0 P 0 
L 1.62683002 -2.02095 1.67821998 -2.02095 0 P 0 
L 1.71076004 -2.02095 1.75825 -2.02095 0 P 0 
L 1.62646998 -2.01995 1.67793996 -2.01995 0 P 0 
L 1.71101004 -2.01995 1.75866004 -2.01995 0 P 0 
L 1.6261 -2.01895 1.67766004 -2.01895 0 P 0 
L 1.71126998 -2.01895 1.75906004 -2.01895 0 P 0 
L 1.62573002 -2.01795 1.67738996 -2.01795 0 P 0 
L 1.71151998 -2.01795 1.75946998 -2.01795 0 P 0 
L 1.62536004 -2.01695 1.67711004 -2.01695 0 P 0 
L 1.71176998 -2.01695 1.75986998 -2.01695 0 P 0 
L 1.62498996 -2.01595 1.67683002 -2.01595 0 P 0 
L 1.71203002 -2.01595 1.76026998 -2.01595 0 P 0 
L 1.62461998 -2.01495 1.67656004 -2.01495 0 P 0 
L 1.71228002 -2.01495 1.76068002 -2.01495 0 P 0 
L 1.62425 -2.01395 1.67628002 -2.01395 0 P 0 
L 1.71253996 -2.01395 1.76108002 -2.01395 0 P 0 
L 1.62388002 -2.01295 1.67601998 -2.01295 0 P 0 
L 1.71278996 -2.01295 1.76148996 -2.01295 0 P 0 
L 1.62351004 -2.01195 1.67576998 -2.01195 0 P 0 
L 1.71305 -2.01195 1.76188996 -2.01195 0 P 0 
L 1.62313996 -2.01095 1.67551998 -2.01095 0 P 0 
L 1.7133 -2.01095 1.76228996 -2.01095 0 P 0 
L 1.62276998 -2.00995 1.67528002 -2.00995 0 P 0 
L 1.71355 -2.00995 1.7627 -2.00995 0 P 0 
L 1.6224 -2.00895 1.67503002 -2.00895 0 P 0 
L 1.71381004 -2.00895 1.7631 -2.00895 0 P 0 
L 1.62203002 -2.00795 1.67478996 -2.00795 0 P 0 
L 1.71406004 -2.00795 1.76351004 -2.00795 0 P 0 
L 1.62166004 -2.00695 1.67453996 -2.00695 0 P 0 
L 1.71431004 -2.00695 1.76391004 -2.00695 0 P 0 
L 1.62128996 -2.00595 1.67428996 -2.00595 0 P 0 
L 1.71453996 -2.00595 1.76431998 -2.00595 0 P 0 
L 1.62091004 -2.00495 1.67405 -2.00495 0 P 0 
L 1.71476998 -2.00495 1.76471998 -2.00495 0 P 0 
L 1.62051998 -2.00395 1.6738 -2.00395 0 P 0 
L 1.715 -2.00395 1.76511998 -2.00395 0 P 0 
L 1.62013002 -2.00295 1.67355 -2.00295 0 P 0 
L 1.71523002 -2.00295 1.76553002 -2.00295 0 P 0 
L 1.61973996 -2.00195 1.67331004 -2.00195 0 P 0 
L 1.71546004 -2.00195 1.76593996 -2.00195 0 P 0 
L 1.61935 -2.00095 1.67306004 -2.00095 0 P 0 
L 1.71568996 -2.00095 1.76633996 -2.00095 0 P 0 
L 1.61896004 -1.99995 1.67283996 -1.99995 0 P 0 
L 1.71591998 -1.99995 1.76673996 -1.99995 0 P 0 
L 1.61856998 -1.99895 1.67261998 -1.99895 0 P 0 
L 1.71613996 -1.99895 1.76715 -1.99895 0 P 0 
L 1.71638002 -1.99795 1.76755 -1.99795 0 P 0 
L 1.7166 -1.99695 1.76796004 -1.99695 0 P 0 
L 1.71683002 -1.99595 1.76836004 -1.99595 0 P 0 
L 1.71866998 -1.99495 1.76876998 -1.99495 0 P 0 
L 1.78213996 -2.04823996 1.84641998 -2.04823996 0 P 0 
L 1.78138002 -2.04723996 1.84498996 -2.04723996 0 P 0 
L 1.78071004 -2.04623996 1.84356004 -2.04623996 0 P 0 
L 1.7801 -2.04523996 1.84213996 -2.04523996 0 P 0 
L 1.77956004 -2.04423996 1.84071004 -2.04423996 0 P 0 
L 1.77908996 -2.04323996 1.83928002 -2.04323996 0 P 0 
L 1.77866004 -2.04223996 1.83786004 -2.04223996 0 P 0 
L 1.77831004 -2.04123996 1.83658996 -2.04123996 0 P 0 
L 1.77796004 -2.04023996 1.83536004 -2.04023996 0 P 0 
L 1.77761004 -2.03923996 1.83428002 -2.03923996 0 P 0 
L 1.77733996 -2.03823996 1.83321998 -2.03823996 0 P 0 
L 1.77706998 -2.03723996 1.83236998 -2.03723996 0 P 0 
L 1.7768 -2.03623996 1.83171004 -2.03623996 0 P 0 
L 1.7766 -2.03523996 1.83121004 -2.03523996 0 P 0 
L 1.77641004 -2.03423996 1.83085 -2.03423996 0 P 0 
L 1.77621004 -2.03323996 1.83071004 -2.03323996 0 P 0 
L 1.77608002 -2.03223996 1.83076998 -2.03223996 0 P 0 
L 1.77596004 -2.03123996 1.83106004 -2.03123996 0 P 0 
L 1.77583996 -2.03023996 1.83158996 -2.03023996 0 P 0 
L 1.77576004 -2.02923996 1.83238002 -2.02923996 0 P 0 
L 1.7757 -2.02823996 1.83356998 -2.02823996 0 P 0 
L 1.7757 -2.02723996 1.83591998 -2.02723996 0 P 0 
L 1.77571998 -2.02623996 1.87495 -2.02623996 0 P 0 
L 1.7758 -2.02523996 1.87485 -2.02523996 0 P 0 
L 1.77588996 -2.02423996 1.87475 -2.02423996 0 P 0 
L 1.77605 -2.02323996 1.87465 -2.02323996 0 P 0 
L 1.77621004 -2.02223996 1.87455 -2.02223996 0 P 0 
L 1.7764 -2.02123996 1.87445 -2.02123996 0 P 0 
L 1.77665 -2.02023996 1.87433996 -2.02023996 0 P 0 
L 1.7769 -2.01923996 1.87425 -2.01923996 0 P 0 
L 1.7772 -2.01823996 1.87413996 -2.01823996 0 P 0 
L 1.77753002 -2.01723996 1.87405 -2.01723996 0 P 0 
L 1.77786004 -2.01623996 1.87393996 -2.01623996 0 P 0 
L 1.77823002 -2.01523996 1.87383996 -2.01523996 0 P 0 
L 1.77863996 -2.01423996 1.87373996 -2.01423996 0 P 0 
L 1.77903996 -2.01323996 1.87363996 -2.01323996 0 P 0 
L 1.7795 -2.01223996 1.87353996 -2.01223996 0 P 0 
L 1.77998996 -2.01123996 1.87343996 -2.01123996 0 P 0 
L 1.78046998 -2.01023996 1.87333002 -2.01023996 0 P 0 
L 1.78103996 -2.00923996 1.87323002 -2.00923996 0 P 0 
L 1.78161004 -2.00823996 1.87311998 -2.00823996 0 P 0 
L 1.78221004 -2.00723996 1.87301998 -2.00723996 0 P 0 
L 1.78288002 -2.00623996 1.87291998 -2.00623996 0 P 0 
L 1.64213996 -2.14795 1.70566004 -2.14795 0 P 0 
L 1.64518996 -2.14695 1.7062 -2.14695 0 P 0 
L 1.64728996 -2.14595 1.70673996 -2.14595 0 P 0 
L 1.64906998 -2.14495 1.70728002 -2.14495 0 P 0 
L 1.65058002 -2.14395 1.70783002 -2.14395 0 P 0 
L 1.6519 -2.14295 1.70836998 -2.14295 0 P 0 
L 1.65311998 -2.14195 1.70881998 -2.14195 0 P 0 
L 1.65416998 -2.14095 1.70926998 -2.14095 0 P 0 
L 1.65508996 -2.13995 1.70973002 -2.13995 0 P 0 
L 1.65588002 -2.13895 1.71018002 -2.13895 0 P 0 
L 1.65658002 -2.13795 1.71063002 -2.13795 0 P 0 
L 1.65726998 -2.13695 1.71108996 -2.13695 0 P 0 
L 1.65791998 -2.13595 1.71153996 -2.13595 0 P 0 
L 1.65853002 -2.13495 1.71198996 -2.13495 0 P 0 
L 1.65913002 -2.13395 1.71245 -2.13395 0 P 0 
L 1.65968002 -2.13295 1.7129 -2.13295 0 P 0 
L 1.66021998 -2.13195 1.71331004 -2.13195 0 P 0 
L 1.66071998 -2.13095 1.71371998 -2.13095 0 P 0 
L 1.66121004 -2.12995 1.71411998 -2.12995 0 P 0 
L 1.66166998 -2.12895 1.71453002 -2.12895 0 P 0 
L 1.66201004 -2.12795 1.71493996 -2.12795 0 P 0 
L 1.66223996 -2.12695 1.71533996 -2.12695 0 P 0 
L 1.66235 -2.12595 1.71575 -2.12595 0 P 0 
L 1.66236004 -2.12495 1.71615 -2.12495 0 P 0 
L 1.66228002 -2.12395 1.71656004 -2.12395 0 P 0 
L 1.66211998 -2.12295 1.71696004 -2.12295 0 P 0 
L 1.66188002 -2.12195 1.71736004 -2.12195 0 P 0 
L 1.66156004 -2.12095 1.71776998 -2.12095 0 P 0 
L 1.66121004 -2.11995 1.71818002 -2.11995 0 P 0 
L 1.66086998 -2.11895 1.71858002 -2.11895 0 P 0 
L 1.66053002 -2.11795 1.71898996 -2.11795 0 P 0 
L 1.66018002 -2.11695 1.71938996 -2.11695 0 P 0 
L 1.65983996 -2.11595 1.7198 -2.11595 0 P 0 
L 1.65948996 -2.11495 1.7202 -2.11495 0 P 0 
L 1.65913996 -2.11395 1.72061004 -2.11395 0 P 0 
L 1.6588 -2.11295 1.72101004 -2.11295 0 P 0 
L 1.65846004 -2.11195 1.72141998 -2.11195 0 P 0 
L 1.65811004 -2.11095 1.72181998 -2.11095 0 P 0 
L 1.65776998 -2.10995 1.72223002 -2.10995 0 P 0 
L 1.65741998 -2.10895 1.72263002 -2.10895 0 P 0 
L 1.65708002 -2.10795 1.72303996 -2.10795 0 P 0 
L 1.65673002 -2.10695 1.72343996 -2.10695 0 P 0 
L 1.65638996 -2.10595 1.72385 -2.10595 0 P 0 
L 1.65605 -2.10495 1.72425 -2.10495 0 P 0 
L 1.6557 -2.10395 1.72466004 -2.10395 0 P 0 
L 1.65536004 -2.10295 1.72506998 -2.10295 0 P 0 
L 1.65501004 -2.10195 1.72546998 -2.10195 0 P 0 
L 1.65466998 -2.10095 1.72588002 -2.10095 0 P 0 
L 1.65431998 -2.09995 1.72628002 -2.09995 0 P 0 
L 1.65398002 -2.09895 1.72668996 -2.09895 0 P 0 
L 1.65363002 -2.09795 1.72708996 -2.09795 0 P 0 
L 1.65328996 -2.09695 1.72748996 -2.09695 0 P 0 
L 1.65293996 -2.09595 1.7279 -2.09595 0 P 0 
L 1.6526 -2.09495 1.72831004 -2.09495 0 P 0 
L 1.65225 -2.09395 1.72871004 -2.09395 0 P 0 
L 1.65191004 -2.09295 1.72911998 -2.09295 0 P 0 
L 1.65156998 -2.09195 1.72951998 -2.09195 0 P 0 
L 1.65121998 -2.09095 1.72993002 -2.09095 0 P 0 
L 1.65088002 -2.08995 1.73033002 -2.08995 0 P 0 
L 1.65053002 -2.08895 1.73073996 -2.08895 0 P 0 
L 1.65018996 -2.08795 1.73113996 -2.08795 0 P 0 
L 1.64983996 -2.08695 1.73155 -2.08695 0 P 0 
L 1.6495 -2.08595 1.73195 -2.08595 0 P 0 
L 1.64915 -2.08495 1.73236004 -2.08495 0 P 0 
L 1.64881004 -2.08395 1.73276004 -2.08395 0 P 0 
L 1.81726998 -1.98915 1.81196004 -1.9899 0 P 0 
L 1.81196004 -1.9899 1.80668996 -1.99096998 0 P 0 
L 1.80668996 -1.99096998 1.8019 -1.99226004 0 P 0 
L 1.8019 -1.99226004 1.79718996 -1.99391004 0 P 0 
L 1.79718996 -1.99391004 1.79316004 -1.99568002 0 P 0 
L 1.79316004 -1.99568002 1.78926998 -1.99778002 0 P 0 
L 1.78926998 -1.99778002 1.78771004 -1.99878002 0 P 0 
L 1.78771004 -1.99878002 1.78623002 -1.99988002 0 P 0 
L 1.78623002 -1.99988002 1.78481004 -2.00108002 0 P 0 
L 1.78481004 -2.00108002 1.78346998 -2.00238996 0 P 0 
L 1.78346998 -2.00238996 1.78228996 -2.00371998 0 P 0 
L 1.78228996 -2.00371998 1.78121004 -2.00513002 0 P 0 
L 1.78121004 -2.00513002 1.78023002 -2.00661004 0 P 0 
L 1.78023002 -2.00661004 1.77868002 -2.00933996 0 P 0 
L 1.77868002 -2.00933996 1.77731998 -2.01216998 0 P 0 
L 1.77731998 -2.01216998 1.77611004 -2.01516004 0 P 0 
L 1.77611004 -2.01516004 1.77508996 -2.01823002 0 P 0 
L 1.77508996 -2.01823002 1.77436998 -2.02111004 0 P 0 
L 1.77436998 -2.02111004 1.77388996 -2.02406004 0 P 0 
L 1.77388996 -2.02406004 1.77371998 -2.02603996 0 P 0 
L 1.77371998 -2.02603996 1.77368996 -2.02801998 0 P 0 
L 1.77368996 -2.02801998 1.7738 -2.03001998 0 P 0 
L 1.7738 -2.03001998 1.7742 -2.03338996 0 P 0 
L 1.7742 -2.03338996 1.77485 -2.03671004 0 P 0 
L 1.77485 -2.03671004 1.77573002 -2.03993996 0 P 0 
L 1.77573002 -2.03993996 1.77683996 -2.04308002 0 P 0 
L 1.77683996 -2.04308002 1.7776 -2.04481998 0 P 0 
L 1.7776 -2.04481998 1.7785 -2.04648996 0 P 0 
L 1.7785 -2.04648996 1.77953002 -2.04808996 0 P 0 
L 1.77953002 -2.04808996 1.78061004 -2.04953996 0 P 0 
L 1.78061004 -2.04953996 1.78181004 -2.05091004 0 P 0 
L 1.78181004 -2.05091004 1.78311004 -2.05218996 0 P 0 
L 1.78311004 -2.05218996 1.78988996 -2.05801998 0 P 0 
L 1.78988996 -2.05801998 1.79883996 -2.06491004 0 P 0 
L 1.79883996 -2.06491004 1.80976998 -2.07261004 0 P 0 
L 1.80976998 -2.07261004 1.81753002 -2.07823002 0 P 0 
L 1.81753002 -2.07823002 1.81896998 -2.07943002 0 P 0 
L 1.81896998 -2.07943002 1.82033002 -2.08073002 0 P 0 
L 1.82033002 -2.08073002 1.82156998 -2.08213996 0 P 0 
L 1.82156998 -2.08213996 1.82186004 -2.08251004 0 P 0 
L 1.82186004 -2.08251004 1.82211004 -2.0829 0 P 0 
L 1.82211004 -2.0829 1.82233002 -2.08331004 0 P 0 
L 1.82233002 -2.08331004 1.82253002 -2.08373996 0 P 0 
L 1.82253002 -2.08373996 1.82268002 -2.08418002 0 P 0 
L 1.82268002 -2.08418002 1.82281004 -2.08463002 0 P 0 
L 1.82281004 -2.08463002 1.8229 -2.0851 0 P 0 
L 1.8229 -2.0851 1.82293002 -2.08533996 0 P 0 
L 1.82293002 -2.08533996 1.82293996 -2.08558996 0 P 0 
L 1.82293996 -2.08558996 1.82291998 -2.08583996 0 P 0 
L 1.82291998 -2.08583996 1.82288002 -2.08608002 0 P 0 
L 1.82288002 -2.08608002 1.82283002 -2.08631998 0 P 0 
L 1.82283002 -2.08631998 1.82275 -2.08656004 0 P 0 
L 1.82275 -2.08656004 1.82265 -2.08678996 0 P 0 
L 1.82265 -2.08678996 1.82253996 -2.087 0 P 0 
L 1.82253996 -2.087 1.8224 -2.08721004 0 P 0 
L 1.8224 -2.08721004 1.82225 -2.08741004 0 P 0 
L 1.82225 -2.08741004 1.82208996 -2.08758996 0 P 0 
L 1.82208996 -2.08758996 1.8216 -2.08803996 0 P 0 
L 1.8216 -2.08803996 1.82106998 -2.08845 0 P 0 
L 1.82106998 -2.08845 1.82051004 -2.08881004 0 P 0 
L 1.82051004 -2.08881004 1.81991998 -2.08911998 0 P 0 
L 1.81991998 -2.08911998 1.81931004 -2.08936998 0 P 0 
L 1.81931004 -2.08936998 1.81868002 -2.08958002 0 P 0 
L 1.81868002 -2.08958002 1.81803002 -2.08973002 0 P 0 
L 1.81803002 -2.08973002 1.81736004 -2.08981998 0 P 0 
L 1.81736004 -2.08981998 1.81293002 -2.09001998 0 P 0 
L 1.81293002 -2.09001998 1.80846998 -2.08986004 0 P 0 
L 1.80846998 -2.08986004 1.80256998 -2.08923002 0 P 0 
L 1.80256998 -2.08923002 1.79668002 -2.08818996 0 P 0 
L 1.79668002 -2.08818996 1.78223002 -2.08458002 0 P 0 
L 1.78223002 -2.08458002 1.77788996 -2.08338002 0 P 0 
L 1.77788996 -2.08338002 1.77415 -2.08246004 0 P 0 
L 1.77415 -2.08246004 1.77095 -2.08175 0 P 0 
L 1.77095 -2.08175 1.7709 -2.08173996 0 P 0 
L 1.7709 -2.08173996 1.77076998 -2.08173996 0 P 0 
L 1.77076998 -2.08173996 1.77068996 -2.08176004 0 P 0 
L 1.77068996 -2.08176004 1.77053002 -2.08183996 0 P 0 
L 1.77053002 -2.08183996 1.77043002 -2.08193996 0 P 0 
L 1.77043002 -2.08193996 1.77036998 -2.08201998 0 P 0 
L 1.77036998 -2.08201998 1.77031998 -2.08211998 0 P 0 
L 1.77031998 -2.08211998 1.7703 -2.08216998 0 P 0 
L 1.7703 -2.08216998 1.77028996 -2.08223002 0 P 0 
L 1.77028996 -2.08223002 1.77028002 -2.08228002 0 P 0 
L 1.77028002 -2.08228002 1.77028002 -2.08238996 0 P 0 
L 1.77028002 -2.08238996 1.77056998 -2.08838996 0 P 0 
L 1.77056998 -2.08838996 1.77096004 -2.09526004 0 P 0 
L 1.77096004 -2.09526004 1.77153996 -2.1033 0 P 0 
L 1.77153996 -2.1033 1.77236004 -2.11291004 0 P 0 
L 1.77236004 -2.11291004 1.77311004 -2.1194 0 P 0 
L 1.77311004 -2.1194 1.77383002 -2.12398002 0 P 0 
L 1.77383002 -2.12398002 1.77386004 -2.12411004 0 P 0 
L 1.77386004 -2.12411004 1.7739 -2.12423002 0 P 0 
L 1.7739 -2.12423002 1.77395 -2.12436004 0 P 0 
L 1.77395 -2.12436004 1.77401004 -2.12448002 0 P 0 
L 1.77401004 -2.12448002 1.77408002 -2.12458996 0 P 0 
L 1.77408002 -2.12458996 1.77416004 -2.1247 0 P 0 
L 1.77416004 -2.1247 1.77425 -2.1248 0 P 0 
L 1.77425 -2.1248 1.77435 -2.12488996 0 P 0 
L 1.77435 -2.12488996 1.77445 -2.12496998 0 P 0 
L 1.77445 -2.12496998 1.77456998 -2.12505 0 P 0 
L 1.77456998 -2.12505 1.77571004 -2.12568996 0 P 0 
L 1.77571004 -2.12568996 1.7769 -2.12623996 0 P 0 
L 1.7769 -2.12623996 1.77813002 -2.12668996 0 P 0 
L 1.77813002 -2.12668996 1.7794 -2.12703996 0 P 0 
L 1.7794 -2.12703996 1.78068996 -2.12728996 0 P 0 
L 1.78068996 -2.12728996 1.79791998 -2.12951004 0 P 0 
L 1.79791998 -2.12951004 1.81536004 -2.13106004 0 P 0 
L 1.81536004 -2.13106004 1.82125 -2.13123996 0 P 0 
L 1.82125 -2.13123996 1.82716004 -2.13098996 0 P 0 
L 1.82716004 -2.13098996 1.83583996 -2.12998002 0 P 0 
L 1.83583996 -2.12998002 1.84445 -2.12836004 0 P 0 
L 1.84445 -2.12836004 1.84911998 -2.12711004 0 P 0 
L 1.84911998 -2.12711004 1.85366004 -2.12548002 0 P 0 
L 1.85366004 -2.12548002 1.85806998 -2.12348002 0 P 0 
L 1.85806998 -2.12348002 1.86078996 -2.12196998 0 P 0 
L 1.86078996 -2.12196998 1.8634 -2.12026998 0 P 0 
L 1.8634 -2.12026998 1.86586998 -2.11836998 0 P 0 
L 1.86586998 -2.11836998 1.86821004 -2.11628002 0 P 0 
L 1.86821004 -2.11628002 1.87026004 -2.11413002 0 P 0 
L 1.87026004 -2.11413002 1.8721 -2.11181998 0 P 0 
L 1.8721 -2.11181998 1.87375 -2.10936004 0 P 0 
L 1.87375 -2.10936004 1.87516998 -2.10673996 0 P 0 
L 1.87516998 -2.10673996 1.87605 -2.10483996 0 P 0 
L 1.87605 -2.10483996 1.87683996 -2.10291004 0 P 0 
L 1.87683996 -2.10291004 1.8772 -2.10188002 0 P 0 
L 1.8772 -2.10188002 1.87748996 -2.10083002 0 P 0 
L 1.87748996 -2.10083002 1.87771004 -2.09976998 0 P 0 
L 1.87771004 -2.09976998 1.87798002 -2.09788996 0 P 0 
L 1.87798002 -2.09788996 1.87811998 -2.09601004 0 P 0 
L 1.87811998 -2.09601004 1.87821004 -2.08966998 0 P 0 
L 1.87821004 -2.08966998 1.8781 -2.08353996 0 P 0 
L 1.8781 -2.08353996 1.87798002 -2.08166004 0 P 0 
L 1.87798002 -2.08166004 1.87773002 -2.07976998 0 P 0 
L 1.87773002 -2.07976998 1.87753002 -2.07873996 0 P 0 
L 1.87753002 -2.07873996 1.87726998 -2.07773996 0 P 0 
L 1.87726998 -2.07773996 1.87695 -2.07673996 0 P 0 
L 1.87695 -2.07673996 1.87628996 -2.07505 0 P 0 
L 1.87628996 -2.07505 1.87553002 -2.07338002 0 P 0 
L 1.87553002 -2.07338002 1.87441004 -2.07133996 0 P 0 
L 1.87441004 -2.07133996 1.87313996 -2.06938002 0 P 0 
L 1.87313996 -2.06938002 1.87171004 -2.06751004 0 P 0 
L 1.87171004 -2.06751004 1.8688 -2.06416004 0 P 0 
L 1.8688 -2.06416004 1.86566998 -2.06095 0 P 0 
L 1.86566998 -2.06095 1.86181998 -2.05741998 0 P 0 
L 1.86181998 -2.05741998 1.85778002 -2.05406998 0 P 0 
L 1.85778002 -2.05406998 1.84833996 -2.04715 0 P 0 
L 1.84833996 -2.04715 1.83913996 -2.0407 0 P 0 
L 1.83913996 -2.0407 1.83686004 -2.0389 0 P 0 
L 1.83686004 -2.0389 1.83471998 -2.03691998 0 P 0 
L 1.83471998 -2.03691998 1.83428002 -2.03643002 0 P 0 
L 1.83428002 -2.03643002 1.83386998 -2.0359 0 P 0 
L 1.83386998 -2.0359 1.83351004 -2.03535 0 P 0 
L 1.83351004 -2.03535 1.83318996 -2.03476004 0 P 0 
L 1.83318996 -2.03476004 1.83291998 -2.03415 0 P 0 
L 1.83291998 -2.03415 1.83283996 -2.03393996 0 P 0 
L 1.83283996 -2.03393996 1.83278002 -2.03371004 0 P 0 
L 1.83278002 -2.03371004 1.83273002 -2.03348996 0 P 0 
L 1.83273002 -2.03348996 1.83271004 -2.03326004 0 P 0 
L 1.83271004 -2.03326004 1.8327 -2.03303002 0 P 0 
L 1.8327 -2.03303002 1.83271004 -2.0328 0 P 0 
L 1.83271004 -2.0328 1.83275 -2.03258002 0 P 0 
L 1.83275 -2.03258002 1.83278996 -2.03235 0 P 0 
L 1.83278996 -2.03235 1.83286004 -2.03213002 0 P 0 
L 1.83286004 -2.03213002 1.83293996 -2.03191998 0 P 0 
L 1.83293996 -2.03191998 1.83305 -2.03171004 0 P 0 
L 1.83305 -2.03171004 1.83325 -2.03135 0 P 0 
L 1.83325 -2.03135 1.83348996 -2.03101998 0 P 0 
L 1.83348996 -2.03101998 1.83375 -2.03071004 0 P 0 
L 1.83375 -2.03071004 1.83403002 -2.03041004 0 P 0 
L 1.83403002 -2.03041004 1.83433996 -2.03015 0 P 0 
L 1.83433996 -2.03015 1.83466998 -2.02991004 0 P 0 
L 1.83466998 -2.02991004 1.83501998 -2.02968996 0 P 0 
L 1.83501998 -2.02968996 1.83538002 -2.02951004 0 P 0 
L 1.83538002 -2.02951004 1.83576004 -2.02936004 0 P 0 
L 1.83576004 -2.02936004 1.83615 -2.02923996 0 P 0 
L 1.83615 -2.02923996 1.83655 -2.02915 0 P 0 
L 1.83655 -2.02915 1.8392 -2.02873996 0 P 0 
L 1.8392 -2.02873996 1.84188002 -2.0285 0 P 0 
L 1.84188002 -2.0285 1.84458002 -2.02841004 0 P 0 
L 1.84458002 -2.02841004 1.84993996 -2.02858002 0 P 0 
L 1.84993996 -2.02858002 1.85526998 -2.02916004 0 P 0 
L 1.85526998 -2.02916004 1.86155 -2.03023002 0 P 0 
L 1.86155 -2.03023002 1.86778002 -2.03158002 0 P 0 
L 1.86778002 -2.03158002 1.8713 -2.03238996 0 P 0 
L 1.8713 -2.03238996 1.87428996 -2.03303002 0 P 0 
L 1.87428996 -2.03303002 1.8769 -2.03356004 0 P 0 
L 1.8769 -2.03356004 1.87691998 -2.03356998 0 P 0 
L 1.87691998 -2.03356998 1.87696004 -2.03356998 0 P 0 
L 1.87696004 -2.03356998 1.87696998 -2.03356004 0 P 0 
L 1.87696998 -2.03356004 1.87701004 -2.03356004 0 P 0 
L 1.87701004 -2.03356004 1.87703996 -2.03353996 0 P 0 
L 1.87703996 -2.03353996 1.87706004 -2.03353002 0 P 0 
L 1.87706004 -2.03353002 1.87706998 -2.03351998 0 P 0 
L 1.87706998 -2.03351998 1.87708996 -2.03351004 0 P 0 
L 1.87708996 -2.03351004 1.8771 -2.03348996 0 P 0 
L 1.8771 -2.03348996 1.87711004 -2.03348002 0 P 0 
L 1.87711004 -2.03348002 1.87721998 -2.0333 0 P 0 
L 1.87721998 -2.0333 1.87731998 -2.0331 0 P 0 
L 1.87731998 -2.0331 1.8774 -2.0329 0 P 0 
L 1.8774 -2.0329 1.87746004 -2.03268996 0 P 0 
L 1.87746004 -2.03268996 1.87751004 -2.03248002 0 P 0 
L 1.87751004 -2.03248002 1.87753002 -2.03226998 0 P 0 
L 1.87753002 -2.03226998 1.87753996 -2.03205 0 P 0 
L 1.87753996 -2.03205 1.87753002 -2.03183002 0 P 0 
L 1.87753002 -2.03183002 1.87565 -2.01323996 0 P 0 
L 1.87565 -2.01323996 1.87371004 -1.99451998 0 P 0 
L 1.87371004 -1.99451998 1.8737 -1.99438996 0 P 0 
L 1.8737 -1.99438996 1.87366998 -1.99426998 0 P 0 
L 1.87366998 -1.99426998 1.87363002 -1.99415 0 P 0 
L 1.87363002 -1.99415 1.87358002 -1.99403002 0 P 0 
L 1.87358002 -1.99403002 1.87351998 -1.99391004 0 P 0 
L 1.87351998 -1.99391004 1.87346004 -1.9938 0 P 0 
L 1.87346004 -1.9938 1.87338002 -1.9937 0 P 0 
L 1.87338002 -1.9937 1.87328996 -1.9936 0 P 0 
L 1.87328996 -1.9936 1.8732 -1.99351004 0 P 0 
L 1.8732 -1.99351004 1.8731 -1.99343002 0 P 0 
L 1.8731 -1.99343002 1.87298996 -1.99335 0 P 0 
L 1.87298996 -1.99335 1.87248002 -1.99305 0 P 0 
L 1.87248002 -1.99305 1.87193996 -1.99278002 0 P 0 
L 1.87193996 -1.99278002 1.87136998 -1.99256998 0 P 0 
L 1.87136998 -1.99256998 1.87078996 -1.99241004 0 P 0 
L 1.87078996 -1.99241004 1.8702 -1.9923 0 P 0 
L 1.8702 -1.9923 1.85876004 -1.99076004 0 P 0 
L 1.85876004 -1.99076004 1.84691998 -1.98943002 0 P 0 
L 1.84691998 -1.98943002 1.83693002 -1.98876004 0 P 0 
L 1.83693002 -1.98876004 1.8318 -1.98863002 0 P 0 
L 1.8318 -1.98863002 1.82623002 -1.98866998 0 P 0 
L 1.82623002 -1.98866998 1.82106004 -1.98883996 0 P 0 
L 1.82106004 -1.98883996 1.81726998 -1.98915 0 P 0 
L 1.78061004 -2.12523996 1.84838002 -2.12523996 0 P 0 
L 1.77733002 -2.12423996 1.85121004 -2.12423996 0 P 0 
L 1.77573996 -2.12323996 1.85376998 -2.12323996 0 P 0 
L 1.77558002 -2.12223996 1.85596998 -2.12223996 0 P 0 
L 1.77541998 -2.12123996 1.85798996 -2.12123996 0 P 0 
L 1.77526998 -2.12023996 1.85978996 -2.12023996 0 P 0 
L 1.77511004 -2.11923996 1.86131998 -2.11923996 0 P 0 
L 1.77498996 -2.11823996 1.86276004 -2.11823996 0 P 0 
L 1.77486998 -2.11723996 1.86406998 -2.11723996 0 P 0 
L 1.77475 -2.11623996 1.86526004 -2.11623996 0 P 0 
L 1.77463996 -2.11523996 1.86638002 -2.11523996 0 P 0 
L 1.77451998 -2.11423996 1.8674 -2.11423996 0 P 0 
L 1.77441004 -2.11323996 1.86835 -2.11323996 0 P 0 
L 1.77431004 -2.11223996 1.86921004 -2.11223996 0 P 0 
L 1.77421998 -2.11123996 1.87001004 -2.11123996 0 P 0 
L 1.77413996 -2.11023996 1.87075 -2.11023996 0 P 0 
L 1.77405 -2.10923996 1.87141998 -2.10923996 0 P 0 
L 1.77396998 -2.10823996 1.87208002 -2.10823996 0 P 0 
L 1.77388002 -2.10723996 1.87261998 -2.10723996 0 P 0 
L 1.7738 -2.10623996 1.87316998 -2.10623996 0 P 0 
L 1.77371004 -2.10523996 1.87366004 -2.10523996 0 P 0 
L 1.77363002 -2.10423996 1.87411998 -2.10423996 0 P 0 
L 1.77353996 -2.10323996 1.87453996 -2.10323996 0 P 0 
L 1.77346998 -2.10223996 1.87495 -2.10223996 0 P 0 
L 1.7734 -2.10123996 1.8753 -2.10123996 0 P 0 
L 1.77333002 -2.10023996 1.87556998 -2.10023996 0 P 0 
L 1.77325 -2.09923996 1.87576998 -2.09923996 0 P 0 
L 1.77318002 -2.09823996 1.87591998 -2.09823996 0 P 0 
L 1.77311004 -2.09723996 1.87603002 -2.09723996 0 P 0 
L 1.77303996 -2.09623996 1.8761 -2.09623996 0 P 0 
L 1.77296998 -2.09523996 1.87613002 -2.09523996 0 P 0 
L 1.77291004 -2.09423996 1.87613996 -2.09423996 0 P 0 
L 1.77285 -2.09323996 1.87616004 -2.09323996 0 P 0 
L 1.77278996 -2.09223996 1.87616998 -2.09223996 0 P 0 
L 1.77273002 -2.09123996 1.80256998 -2.09123996 0 P 0 
L 1.77268002 -2.09023996 1.7968 -2.09023996 0 P 0 
L 1.77261998 -2.08923996 1.79263002 -2.08923996 0 P 0 
L 1.77256004 -2.08823996 1.78861998 -2.08823996 0 P 0 
L 1.77251004 -2.08723996 1.7846 -2.08723996 0 P 0 
L 1.77246004 -2.08623996 1.7807 -2.08623996 0 P 0 
L 1.77241998 -2.08523996 1.77705 -2.08523996 0 P 0 
L 1.77236998 -2.08423996 1.77293996 -2.08423996 0 P 0 
L 1.62463996 -2.18195 1.65948996 -2.18195 0 P 0 
L 1.61963996 -2.18095 1.66483002 -2.18095 0 P 0 
L 1.61818002 -1.99795 1.6724 -1.99795 0 P 0 
L 1.61778996 -1.99695 1.67218002 -1.99695 0 P 0 
L 1.6174 -1.99595 1.67196004 -1.99595 0 P 0 
L 1.61701004 -1.99495 1.67173996 -1.99495 0 P 0 
L 1.61391998 -2.15695 1.70026004 -2.15695 0 P 0 
L 1.61386004 -2.15595 1.70088002 -2.15595 0 P 0 
L 1.61381004 -2.15495 1.70151004 -2.15495 0 P 0 
L 1.61375 -2.15395 1.70213996 -2.15395 0 P 0 
L 1.6137 -2.15295 1.70276004 -2.15295 0 P 0 
L 1.61365 -2.15195 1.70338996 -2.15195 0 P 0 
L 1.6136 -2.15095 1.70401004 -2.15095 0 P 0 
L 1.61355 -2.14995 1.70456998 -2.14995 0 P 0 
L 1.61348996 -2.14895 1.70511998 -2.14895 0 P 0 
L 1.61343996 -2.14795 1.61738002 -2.14795 0 P 0 
L 1.55341004 -2.08286998 1.60538002 -2.08286998 0 P 0 
L 1.55286004 -2.08186998 1.60526998 -2.08186998 0 P 0 
L 1.5521 -2.08086998 1.6051 -2.08086998 0 P 0 
L 1.55126998 -2.07986998 1.6049 -2.07986998 0 P 0 
L 1.55033996 -2.07886998 1.60463996 -2.07886998 0 P 0 
L 1.54928996 -2.07786998 1.60433002 -2.07786998 0 P 0 
L 1.54806998 -2.07686998 1.60398996 -2.07686998 0 P 0 
L 1.5467 -2.07586998 1.60356998 -2.07586998 0 P 0 
L 1.54531004 -2.07486998 1.6031 -2.07486998 0 P 0 
L 1.54391004 -2.07386998 1.60258996 -2.07386998 0 P 0 
L 1.54251004 -2.07286998 1.60201004 -2.07286998 0 P 0 
L 1.54111998 -2.07186998 1.60138002 -2.07186998 0 P 0 
L 1.53971998 -2.07086998 1.60068002 -2.07086998 0 P 0 
L 1.53833002 -2.06986998 1.59993002 -2.06986998 0 P 0 
L 1.53693002 -2.06886998 1.59908002 -2.06886998 0 P 0 
L 1.53556004 -2.06786998 1.59821004 -2.06786998 0 P 0 
L 1.53418996 -2.06686998 1.59733996 -2.06686998 0 P 0 
L 1.53281998 -2.06586998 1.59646998 -2.06586998 0 P 0 
L 1.53145 -2.06486998 1.5955 -2.06486998 0 P 0 
L 1.53008002 -2.06386998 1.59453002 -2.06386998 0 P 0 
L 1.52871004 -2.06286998 1.59356004 -2.06286998 0 P 0 
L 1.52733996 -2.06186998 1.59253002 -2.06186998 0 P 0 
L 1.52596998 -2.06086998 1.59145 -2.06086998 0 P 0 
L 1.5246 -2.05986998 1.59038002 -2.05986998 0 P 0 
L 1.52323002 -2.05886998 1.5893 -2.05886998 0 P 0 
L 1.52186004 -2.05786998 1.58813996 -2.05786998 0 P 0 
L 1.52053996 -2.05686998 1.58696004 -2.05686998 0 P 0 
L 1.51935 -2.05586998 1.58576998 -2.05586998 0 P 0 
L 1.51816004 -2.05486998 1.58456998 -2.05486998 0 P 0 
L 1.51706998 -2.05386998 1.58321004 -2.05386998 0 P 0 
L 1.51603996 -2.05286998 1.58185 -2.05286998 0 P 0 
L 1.51501998 -2.05186998 1.58048996 -2.05186998 0 P 0 
L 1.51408996 -2.05086998 1.57913002 -2.05086998 0 P 0 
L 1.5132 -2.04986998 1.57776998 -2.04986998 0 P 0 
L 1.51231998 -2.04886998 1.57641998 -2.04886998 0 P 0 
L 1.51151004 -2.04786998 1.57505 -2.04786998 0 P 0 
L 1.51075 -2.04686998 1.57365 -2.04686998 0 P 0 
L 1.51008002 -2.04586998 1.57223002 -2.04586998 0 P 0 
L 1.50945 -2.04486998 1.57081004 -2.04486998 0 P 0 
L 1.50888002 -2.04386998 1.56938996 -2.04386998 0 P 0 
L 1.50836004 -2.04286998 1.56796998 -2.04286998 0 P 0 
L 1.5079 -2.04186998 1.56655 -2.04186998 0 P 0 
L 1.50748002 -2.04086998 1.56518996 -2.04086998 0 P 0 
L 1.50708996 -2.03986998 1.564 -2.03986998 0 P 0 
L 1.50676004 -2.03886998 1.56296998 -2.03886998 0 P 0 
L 1.50641998 -2.03786998 1.56206004 -2.03786998 0 P 0 
L 1.50616998 -2.03686998 1.56125 -2.03686998 0 P 0 
L 1.50591004 -2.03586998 1.56066998 -2.03586998 0 P 0 
L 1.5057 -2.03486998 1.56031998 -2.03486998 0 P 0 
L 1.50551998 -2.03386998 1.56016004 -2.03386998 0 P 0 
L 1.50533996 -2.03286998 1.56016998 -2.03286998 0 P 0 
L 1.50523996 -2.03186998 1.56036004 -2.03186998 0 P 0 
L 1.50513002 -2.03086998 1.56071998 -2.03086998 0 P 0 
L 1.50506998 -2.02986998 1.56131004 -2.02986998 0 P 0 
L 1.50503996 -2.02886998 1.5622 -2.02886998 0 P 0 
L 1.50501004 -2.02786998 1.56355 -2.02786998 0 P 0 
L 1.50501998 -2.02686998 1.5657 -2.02686998 0 P 0 
L 1.50506998 -2.02586998 1.60378996 -2.02586998 0 P 0 
L 1.50511998 -2.02486998 1.60371004 -2.02486998 0 P 0 
L 1.50521004 -2.02386998 1.60363996 -2.02386998 0 P 0 
L 1.50533996 -2.02286998 1.60356998 -2.02286998 0 P 0 
L 1.50546998 -2.02186998 1.6035 -2.02186998 0 P 0 
L 1.50563996 -2.02086998 1.60343002 -2.02086998 0 P 0 
L 1.50585 -2.01986998 1.60336004 -2.01986998 0 P 0 
L 1.50606004 -2.01886998 1.60328996 -2.01886998 0 P 0 
L 1.50633002 -2.01786998 1.60321998 -2.01786998 0 P 0 
L 1.50661998 -2.01686998 1.60315 -2.01686998 0 P 0 
L 1.50691004 -2.01586998 1.60308002 -2.01586998 0 P 0 
L 1.50726998 -2.01486998 1.603 -2.01486998 0 P 0 
L 1.50766004 -2.01386998 1.60293002 -2.01386998 0 P 0 
L 1.50808996 -2.01286998 1.60285 -2.01286998 0 P 0 
L 1.50856998 -2.01186998 1.60278002 -2.01186998 0 P 0 
L 1.50908996 -2.01086998 1.6027 -2.01086998 0 P 0 
L 1.50966004 -2.00986998 1.60261998 -2.00986998 0 P 0 
L 1.51028996 -2.00886998 1.60255 -2.00886998 0 P 0 
L 1.51096998 -2.00786998 1.60246998 -2.00786998 0 P 0 
L 1.51171998 -2.00686998 1.6024 -2.00686998 0 P 0 
L 1.51253996 -2.00586998 1.60233002 -2.00586998 0 P 0 
L 1.51343996 -2.00486998 1.60225 -2.00486998 0 P 0 
L 1.5144 -2.00386998 1.60218002 -2.00386998 0 P 0 
L 1.51551998 -2.00286998 1.6021 -2.00286998 0 P 0 
L 1.51663996 -2.00186998 1.60203002 -2.00186998 0 P 0 
L 1.51795 -2.00086998 1.60195 -2.00086998 0 P 0 
L 1.51928996 -1.99986998 1.60183996 -1.99986998 0 P 0 
L 1.52086998 -1.99886998 1.60173002 -1.99886998 0 P 0 
L 1.52258996 -1.99786998 1.60156998 -1.99786998 0 P 0 
L 1.52451004 -1.99686998 1.60138996 -1.99686998 0 P 0 
L 1.52686998 -1.99586998 1.60106998 -1.99586998 0 P 0 
L 1.52976004 -1.99486998 1.59943996 -1.99486998 0 P 0 
L 1.53283002 -1.99386998 1.59543002 -1.99386998 0 P 0 
L 1.53678996 -1.99286998 1.59003996 -1.99286998 0 P 0 
L 1.54173996 -1.99186998 1.58073996 -1.99186998 0 P 0 
L 1.55036998 -1.99086998 1.56493002 -1.99086998 0 P 0 
L 1.6036 -2.03086998 1.60413996 -2.03086998 0 P 0 
L 1.59891004 -2.02986998 1.60406998 -2.02986998 0 P 0 
L 1.59435 -2.02886998 1.604 -2.02886998 0 P 0 
L 1.58838996 -2.02786998 1.60393002 -2.02786998 0 P 0 
L 1.57981004 -2.02686998 1.60386004 -2.02686998 0 P 0 
L 1.54575 -1.98923996 1.53931998 -1.99021998 0 P 0 
L 1.53931998 -1.99021998 1.53298996 -1.99171998 0 P 0 
L 1.53298996 -1.99171998 1.52678996 -1.99373996 0 P 0 
L 1.52678996 -1.99373996 1.52376998 -1.995 0 P 0 
L 1.52376998 -1.995 1.52086998 -1.99651004 0 P 0 
L 1.52086998 -1.99651004 1.5181 -1.99826004 0 P 0 
L 1.5181 -1.99826004 1.51548002 -2.00023002 0 P 0 
L 1.51548002 -2.00023002 1.51301004 -2.00243002 0 P 0 
L 1.51301004 -2.00243002 1.51128996 -2.00423002 0 P 0 
L 1.51128996 -2.00423002 1.50971998 -2.00616004 0 P 0 
L 1.50971998 -2.00616004 1.50831004 -2.00821004 0 P 0 
L 1.50831004 -2.00821004 1.50706998 -2.01036998 0 P 0 
L 1.50706998 -2.01036998 1.50598996 -2.01261998 0 P 0 
L 1.50598996 -2.01261998 1.50508996 -2.01496998 0 P 0 
L 1.50508996 -2.01496998 1.5042 -2.01801004 0 P 0 
L 1.5042 -2.01801004 1.50355 -2.02111004 0 P 0 
L 1.50355 -2.02111004 1.50313996 -2.02426004 0 P 0 
L 1.50313996 -2.02426004 1.50298996 -2.02743002 0 P 0 
L 1.50298996 -2.02743002 1.50308996 -2.03063002 0 P 0 
L 1.50308996 -2.03063002 1.50338002 -2.03326998 0 P 0 
L 1.50338002 -2.03326998 1.50385 -2.03588002 0 P 0 
L 1.50385 -2.03588002 1.50451004 -2.03845 0 P 0 
L 1.50451004 -2.03845 1.50535 -2.04096998 0 P 0 
L 1.50535 -2.04096998 1.50633002 -2.0433 0 P 0 
L 1.50633002 -2.0433 1.5075 -2.04553002 0 P 0 
L 1.5075 -2.04553002 1.50883996 -2.04766998 0 P 0 
L 1.50883996 -2.04766998 1.51036998 -2.04968996 0 P 0 
L 1.51036998 -2.04968996 1.51323002 -2.05291998 0 P 0 
L 1.51323002 -2.05291998 1.51631998 -2.05593996 0 P 0 
L 1.51631998 -2.05593996 1.51961998 -2.05871004 0 P 0 
L 1.51961998 -2.05871004 1.53591004 -2.0706 0 P 0 
L 1.53591004 -2.0706 1.54668002 -2.07831004 0 P 0 
L 1.54668002 -2.07831004 1.54793996 -2.07933996 0 P 0 
L 1.54793996 -2.07933996 1.54911998 -2.08046998 0 P 0 
L 1.54911998 -2.08046998 1.55021004 -2.08168002 0 P 0 
L 1.55021004 -2.08168002 1.5512 -2.08298996 0 P 0 
L 1.5512 -2.08298996 1.55136004 -2.08323002 0 P 0 
L 1.55136004 -2.08323002 1.5515 -2.08348002 0 P 0 
L 1.5515 -2.08348002 1.55161004 -2.08373996 0 P 0 
L 1.55161004 -2.08373996 1.5517 -2.08401998 0 P 0 
L 1.5517 -2.08401998 1.55176998 -2.0843 0 P 0 
L 1.55176998 -2.0843 1.55181004 -2.08458002 0 P 0 
L 1.55181004 -2.08458002 1.55183002 -2.08486998 0 P 0 
L 1.55183002 -2.08486998 1.55181998 -2.08516004 0 P 0 
L 1.55181998 -2.08516004 1.55178996 -2.08545 0 P 0 
L 1.55178996 -2.08545 1.55173996 -2.08573002 0 P 0 
L 1.55173996 -2.08573002 1.55166004 -2.086 0 P 0 
L 1.55166004 -2.086 1.55156004 -2.08628002 0 P 0 
L 1.55156004 -2.08628002 1.55136998 -2.08666998 0 P 0 
L 1.55136998 -2.08666998 1.55115 -2.08703996 0 P 0 
L 1.55115 -2.08703996 1.5509 -2.08738996 0 P 0 
L 1.5509 -2.08738996 1.55063002 -2.08771998 0 P 0 
L 1.55063002 -2.08771998 1.55033002 -2.08803002 0 P 0 
L 1.55033002 -2.08803002 1.55 -2.08831004 0 P 0 
L 1.55 -2.08831004 1.54966004 -2.08856004 0 P 0 
L 1.54966004 -2.08856004 1.54928996 -2.08878996 0 P 0 
L 1.54928996 -2.08878996 1.5489 -2.08898996 0 P 0 
L 1.5489 -2.08898996 1.54786004 -2.08941004 0 P 0 
L 1.54786004 -2.08941004 1.54678996 -2.08973996 0 P 0 
L 1.54678996 -2.08973996 1.54568002 -2.08998002 0 P 0 
L 1.54568002 -2.08998002 1.54456998 -2.09011998 0 P 0 
L 1.54456998 -2.09011998 1.54343996 -2.09016998 0 P 0 
L 1.54343996 -2.09016998 1.53906998 -2.09003002 0 P 0 
L 1.53906998 -2.09003002 1.53468002 -2.08961998 0 P 0 
L 1.53468002 -2.08961998 1.52908996 -2.08878996 0 P 0 
L 1.52908996 -2.08878996 1.52351004 -2.08766004 0 P 0 
L 1.52351004 -2.08766004 1.51005 -2.08418996 0 P 0 
L 1.51005 -2.08418996 1.50631004 -2.08318002 0 P 0 
L 1.50631004 -2.08318002 1.50308002 -2.08238996 0 P 0 
L 1.50308002 -2.08238996 1.50033996 -2.08183002 0 P 0 
L 1.50033996 -2.08183002 1.5003 -2.08181998 0 P 0 
L 1.5003 -2.08181998 1.50016004 -2.08181998 0 P 0 
L 1.50016004 -2.08181998 1.50011998 -2.08183002 0 P 0 
L 1.50011998 -2.08183002 1.50006998 -2.08183996 0 P 0 
L 1.50006998 -2.08183996 1.50003002 -2.08186004 0 P 0 
L 1.50003002 -2.08186004 1.49998996 -2.08186998 0 P 0 
L 1.49998996 -2.08186998 1.49995 -2.08188996 0 P 0 
L 1.49995 -2.08188996 1.49991004 -2.08191998 0 P 0 
L 1.49991004 -2.08191998 1.49988002 -2.08195 0 P 0 
L 1.49988002 -2.08195 1.49983996 -2.08198002 0 P 0 
L 1.49983996 -2.08198002 1.4997 -2.08213996 0 P 0 
L 1.4997 -2.08213996 1.49956004 -2.08231998 0 P 0 
L 1.49956004 -2.08231998 1.49943996 -2.0825 0 P 0 
L 1.49943996 -2.0825 1.49933996 -2.0827 0 P 0 
L 1.49933996 -2.0827 1.49925 -2.0829 0 P 0 
L 1.49925 -2.0829 1.49918996 -2.08311004 0 P 0 
L 1.49918996 -2.08311004 1.49913996 -2.08333002 0 P 0 
L 1.49913996 -2.08333002 1.49911004 -2.08355 0 P 0 
L 1.49911004 -2.08355 1.4991 -2.08376998 0 P 0 
L 1.4991 -2.08376998 1.49911004 -2.08398996 0 P 0 
L 1.49911004 -2.08398996 1.50071004 -2.10395 0 P 0 
L 1.50071004 -2.10395 1.5024 -2.12403996 0 P 0 
L 1.5024 -2.12403996 1.50241998 -2.12418002 0 P 0 
L 1.50241998 -2.12418002 1.50246004 -2.12431004 0 P 0 
L 1.50246004 -2.12431004 1.50248996 -2.12445 0 P 0 
L 1.50248996 -2.12445 1.50255 -2.12456998 0 P 0 
L 1.50255 -2.12456998 1.50261004 -2.1247 0 P 0 
L 1.50261004 -2.1247 1.50276998 -2.12491998 0 P 0 
L 1.50276998 -2.12491998 1.50286004 -2.12501998 0 P 0 
L 1.50286004 -2.12501998 1.50296998 -2.12511998 0 P 0 
L 1.50296998 -2.12511998 1.50308002 -2.12521004 0 P 0 
L 1.50308002 -2.12521004 1.50318996 -2.12528002 0 P 0 
L 1.50318996 -2.12528002 1.50331998 -2.12535 0 P 0 
L 1.50331998 -2.12535 1.50343996 -2.1254 0 P 0 
L 1.50343996 -2.1254 1.50391998 -2.12556004 0 P 0 
L 1.50391998 -2.12556004 1.5044 -2.12568996 0 P 0 
L 1.5044 -2.12568996 1.50848002 -2.12648996 0 P 0 
L 1.50848002 -2.12648996 1.51328996 -2.12738002 0 P 0 
L 1.51328996 -2.12738002 1.51873996 -2.12833996 0 P 0 
L 1.51873996 -2.12833996 1.52606004 -2.12945 0 P 0 
L 1.52606004 -2.12945 1.53343996 -2.13023002 0 P 0 
L 1.53343996 -2.13023002 1.54886998 -2.13086998 0 P 0 
L 1.54886998 -2.13086998 1.56305 -2.1303 0 P 0 
L 1.56305 -2.1303 1.56666004 -2.12988996 0 P 0 
L 1.56666004 -2.12988996 1.57023002 -2.12926998 0 P 0 
L 1.57023002 -2.12926998 1.5738 -2.12843002 0 P 0 
L 1.5738 -2.12843002 1.57945 -2.12668996 0 P 0 
L 1.57945 -2.12668996 1.58498002 -2.12456998 0 P 0 
L 1.58498002 -2.12456998 1.58793996 -2.12318002 0 P 0 
L 1.58793996 -2.12318002 1.59078996 -2.12156004 0 P 0 
L 1.59078996 -2.12156004 1.59348996 -2.11971998 0 P 0 
L 1.59348996 -2.11971998 1.59525 -2.11833002 0 P 0 
L 1.59525 -2.11833002 1.5969 -2.11681998 0 P 0 
L 1.5969 -2.11681998 1.59846004 -2.11521004 0 P 0 
L 1.59846004 -2.11521004 1.59991004 -2.11348002 0 P 0 
L 1.59991004 -2.11348002 1.60175 -2.11093996 0 P 0 
L 1.60175 -2.11093996 1.60338002 -2.10826998 0 P 0 
L 1.60338002 -2.10826998 1.60481004 -2.10548002 0 P 0 
L 1.60481004 -2.10548002 1.60573002 -2.10321004 0 P 0 
L 1.60573002 -2.10321004 1.60646004 -2.10088002 0 P 0 
L 1.60646004 -2.10088002 1.60698002 -2.09848996 0 P 0 
L 1.60698002 -2.09848996 1.60756004 -2.09421998 0 P 0 
L 1.60756004 -2.09421998 1.6078 -2.08991004 0 P 0 
L 1.6078 -2.08991004 1.60768996 -2.08565 0 P 0 
L 1.60768996 -2.08565 1.60723002 -2.08141998 0 P 0 
L 1.60723002 -2.08141998 1.60691998 -2.07968002 0 P 0 
L 1.60691998 -2.07968002 1.60646998 -2.07796998 0 P 0 
L 1.60646998 -2.07796998 1.60591998 -2.0763 0 P 0 
L 1.60591998 -2.0763 1.60523002 -2.07466998 0 P 0 
L 1.60523002 -2.07466998 1.60411998 -2.07246998 0 P 0 
L 1.60411998 -2.07246998 1.60281004 -2.07038002 0 P 0 
L 1.60281004 -2.07038002 1.60131998 -2.06838996 0 P 0 
L 1.60131998 -2.06838996 1.59803996 -2.06461998 0 P 0 
L 1.59803996 -2.06461998 1.59455 -2.06101998 0 P 0 
L 1.59455 -2.06101998 1.59031998 -2.05708996 0 P 0 
L 1.59031998 -2.05708996 1.58586004 -2.05333996 0 P 0 
L 1.58586004 -2.05333996 1.57588002 -2.04598996 0 P 0 
L 1.57588002 -2.04598996 1.56685 -2.03963996 0 P 0 
L 1.56685 -2.03963996 1.56578002 -2.03878996 0 P 0 
L 1.56578002 -2.03878996 1.56476998 -2.03786004 0 P 0 
L 1.56476998 -2.03786004 1.56383002 -2.03686998 0 P 0 
L 1.56383002 -2.03686998 1.56295 -2.0358 0 P 0 
L 1.56295 -2.0358 1.56276998 -2.03555 0 P 0 
L 1.56276998 -2.03555 1.56261004 -2.03528002 0 P 0 
L 1.56261004 -2.03528002 1.56246998 -2.035 0 P 0 
L 1.56246998 -2.035 1.56236004 -2.03471998 0 P 0 
L 1.56236004 -2.03471998 1.56226998 -2.03441998 0 P 0 
L 1.56226998 -2.03441998 1.5622 -2.03411998 0 P 0 
L 1.5622 -2.03411998 1.56216004 -2.03381998 0 P 0 
L 1.56216004 -2.03381998 1.56213996 -2.03351004 0 P 0 
L 1.56213996 -2.03351004 1.56215 -2.0332 0 P 0 
L 1.56215 -2.0332 1.56218002 -2.03288996 0 P 0 
L 1.56218002 -2.03288996 1.56225 -2.03253996 0 P 0 
L 1.56225 -2.03253996 1.56233996 -2.03221004 0 P 0 
L 1.56233996 -2.03221004 1.56246004 -2.03186998 0 P 0 
L 1.56246004 -2.03186998 1.56261004 -2.03156004 0 P 0 
L 1.56261004 -2.03156004 1.56278996 -2.03125 0 P 0 
L 1.56278996 -2.03125 1.56298002 -2.03096004 0 P 0 
L 1.56298002 -2.03096004 1.56321004 -2.03068996 0 P 0 
L 1.56321004 -2.03068996 1.56345 -2.03043996 0 P 0 
L 1.56345 -2.03043996 1.56371004 -2.0302 0 P 0 
L 1.56371004 -2.0302 1.56416004 -2.02986004 0 P 0 
L 1.56416004 -2.02986004 1.56463002 -2.02955 0 P 0 
L 1.56463002 -2.02955 1.56511998 -2.02928002 0 P 0 
L 1.56511998 -2.02928002 1.56561998 -2.02903002 0 P 0 
L 1.56561998 -2.02903002 1.56611998 -2.02883996 0 P 0 
L 1.56611998 -2.02883996 1.56663996 -2.02866998 0 P 0 
L 1.56663996 -2.02866998 1.56716004 -2.02855 0 P 0 
L 1.56716004 -2.02855 1.5677 -2.02846998 0 P 0 
L 1.5677 -2.02846998 1.56926998 -2.02835 0 P 0 
L 1.56926998 -2.02835 1.57085 -2.02833996 0 P 0 
L 1.57085 -2.02833996 1.57725 -2.02866998 0 P 0 
L 1.57725 -2.02866998 1.58205 -2.02906004 0 P 0 
L 1.58205 -2.02906004 1.58746998 -2.02975 0 P 0 
L 1.58746998 -2.02975 1.59271004 -2.03056998 0 P 0 
L 1.59271004 -2.03056998 1.59681004 -2.03143002 0 P 0 
L 1.59681004 -2.03143002 1.60016004 -2.03221998 0 P 0 
L 1.60016004 -2.03221998 1.60308002 -2.03281004 0 P 0 
L 1.60308002 -2.03281004 1.60553996 -2.03323996 0 P 0 
L 1.60553996 -2.03323996 1.60568996 -2.03323996 0 P 0 
L 1.60568996 -2.03323996 1.60576998 -2.03321998 0 P 0 
L 1.60576998 -2.03321998 1.60586004 -2.03316004 0 P 0 
L 1.60586004 -2.03316004 1.6059 -2.03313996 0 P 0 
L 1.6059 -2.03313996 1.60591998 -2.03311004 0 P 0 
L 1.60591998 -2.03311004 1.60598996 -2.03303996 0 P 0 
L 1.60598996 -2.03303996 1.60605 -2.03296998 0 P 0 
L 1.60605 -2.03296998 1.6061 -2.03288996 0 P 0 
L 1.6061 -2.03288996 1.60618002 -2.03273002 0 P 0 
L 1.60618002 -2.03273002 1.60621004 -2.03263002 0 P 0 
L 1.60621004 -2.03263002 1.60623002 -2.03253996 0 P 0 
L 1.60623002 -2.03253996 1.60625 -2.03236004 0 P 0 
L 1.60625 -2.03236004 1.60623996 -2.03226004 0 P 0 
L 1.60623996 -2.03226004 1.60508002 -2.01578002 0 P 0 
L 1.60508002 -2.01578002 1.60393996 -2.00068002 0 P 0 
L 1.60393996 -2.00068002 1.60368002 -1.99833996 0 P 0 
L 1.60368002 -1.99833996 1.60326998 -1.99601004 0 P 0 
L 1.60326998 -1.99601004 1.60321004 -1.99576998 0 P 0 
L 1.60321004 -1.99576998 1.60313996 -1.99553002 0 P 0 
L 1.60313996 -1.99553002 1.60303996 -1.9953 0 P 0 
L 1.60303996 -1.9953 1.60293002 -1.99508002 0 P 0 
L 1.60293002 -1.99508002 1.60281004 -1.99486004 0 P 0 
L 1.60281004 -1.99486004 1.60261998 -1.9946 0 P 0 
L 1.60261998 -1.9946 1.60241004 -1.99435 0 P 0 
L 1.60241004 -1.99435 1.60218002 -1.99411998 0 P 0 
L 1.60218002 -1.99411998 1.60191998 -1.99391004 0 P 0 
L 1.60191998 -1.99391004 1.60161004 -1.99368996 0 P 0 
L 1.60161004 -1.99368996 1.60128996 -1.99348996 0 P 0 
L 1.60128996 -1.99348996 1.60095 -1.99331998 0 P 0 
L 1.60095 -1.99331998 1.6006 -1.99316004 0 P 0 
L 1.6006 -1.99316004 1.59966004 -1.99283002 0 P 0 
L 1.59966004 -1.99283002 1.59871004 -1.99255 0 P 0 
L 1.59871004 -1.99255 1.5933 -1.99135 0 P 0 
L 1.5933 -1.99135 1.5878 -1.9905 0 P 0 
L 1.5878 -1.9905 1.57285 -1.98915 0 P 0 
L 1.57285 -1.98915 1.55763996 -1.98861004 0 P 0 
L 1.55763996 -1.98861004 1.55171004 -1.98876004 0 P 0 
L 1.55171004 -1.98876004 1.54575 -1.98923996 0 P 0 
L 1.53011998 -2.12786998 1.5666 -2.12786998 0 P 0 
L 1.52236004 -2.12686998 1.57168002 -2.12686998 0 P 0 
L 1.51621998 -2.12586998 1.5753 -2.12586998 0 P 0 
L 1.51071004 -2.12486998 1.57856004 -2.12486998 0 P 0 
L 1.50553002 -2.12386998 1.58121004 -2.12386998 0 P 0 
L 1.50431004 -2.12286998 1.58381998 -2.12286998 0 P 0 
L 1.50423002 -2.12186998 1.58601998 -2.12186998 0 P 0 
L 1.50413996 -2.12086998 1.58796004 -2.12086998 0 P 0 
L 1.50406004 -2.11986998 1.58971004 -2.11986998 0 P 0 
L 1.50396998 -2.11886998 1.59118002 -2.11886998 0 P 0 
L 1.50388996 -2.11786998 1.5926 -2.11786998 0 P 0 
L 1.50381004 -2.11686998 1.59386004 -2.11686998 0 P 0 
L 1.50371998 -2.11586998 1.59496998 -2.11586998 0 P 0 
L 1.50363996 -2.11486998 1.59601004 -2.11486998 0 P 0 
L 1.50355 -2.11386998 1.59696998 -2.11386998 0 P 0 
L 1.50346998 -2.11286998 1.59781004 -2.11286998 0 P 0 
L 1.50338002 -2.11186998 1.5986 -2.11186998 0 P 0 
L 1.5033 -2.11086998 1.59933002 -2.11086998 0 P 0 
L 1.50321004 -2.10986998 1.60005 -2.10986998 0 P 0 
L 1.50313002 -2.10886998 1.60066998 -2.10886998 0 P 0 
L 1.50305 -2.10786998 1.60128002 -2.10786998 0 P 0 
L 1.50296004 -2.10686998 1.60185 -2.10686998 0 P 0 
L 1.50288002 -2.10586998 1.60236004 -2.10586998 0 P 0 
L 1.50278996 -2.10486998 1.60286998 -2.10486998 0 P 0 
L 1.50271004 -2.10386998 1.6033 -2.10386998 0 P 0 
L 1.50263002 -2.10286998 1.60371004 -2.10286998 0 P 0 
L 1.50255 -2.10186998 1.60405 -2.10186998 0 P 0 
L 1.50246998 -2.10086998 1.60436004 -2.10086998 0 P 0 
L 1.50238996 -2.09986998 1.60463002 -2.09986998 0 P 0 
L 1.50231004 -2.09886998 1.60485 -2.09886998 0 P 0 
L 1.50223002 -2.09786998 1.60505 -2.09786998 0 P 0 
L 1.50215 -2.09686998 1.60518002 -2.09686998 0 P 0 
L 1.50206998 -2.09586998 1.60531998 -2.09586998 0 P 0 
L 1.50198996 -2.09486998 1.60545 -2.09486998 0 P 0 
L 1.50191004 -2.09386998 1.60558002 -2.09386998 0 P 0 
L 1.50183002 -2.09286998 1.60563002 -2.09286998 0 P 0 
L 1.50175 -2.09186998 1.53725 -2.09186998 0 P 0 
L 1.54638996 -2.09186998 1.60568996 -2.09186998 0 P 0 
L 1.50166998 -2.09086998 1.5295 -2.09086998 0 P 0 
L 1.54956998 -2.09086998 1.60573996 -2.09086998 0 P 0 
L 1.50158996 -2.08986998 1.52436004 -2.08986998 0 P 0 
L 1.55125 -2.08986998 1.60578996 -2.08986998 0 P 0 
L 1.50151004 -2.08886998 1.52021004 -2.08886998 0 P 0 
L 1.55226998 -2.08886998 1.60576998 -2.08886998 0 P 0 
L 1.50143002 -2.08786998 1.51633002 -2.08786998 0 P 0 
L 1.55298002 -2.08786998 1.60573996 -2.08786998 0 P 0 
L 1.50133996 -2.08686998 1.51246004 -2.08686998 0 P 0 
L 1.55346998 -2.08686998 1.60571998 -2.08686998 0 P 0 
L 1.50126998 -2.08586998 1.50861998 -2.08586998 0 P 0 
L 1.55375 -2.08586998 1.60568996 -2.08586998 0 P 0 
L 1.50118002 -2.08486998 1.50481004 -2.08486998 0 P 0 
L 1.55383002 -2.08486998 1.60558996 -2.08486998 0 P 0 
L 1.55371998 -2.08386998 1.60548996 -2.08386998 0 P 0 
L 1.54886998 -2.12886998 1.53358996 -2.12823996 0 P 0 
L 1.53358996 -2.12823996 1.52631998 -2.12746998 0 P 0 
L 1.52631998 -2.12746998 1.51906004 -2.12636998 0 P 0 
L 1.51906004 -2.12636998 1.51363002 -2.12541004 0 P 0 
L 1.51363002 -2.12541004 1.50886998 -2.12451998 0 P 0 
L 1.50886998 -2.12451998 1.50483996 -2.12373996 0 P 0 
L 1.50483996 -2.12373996 1.50448996 -2.12365 0 P 0 
L 1.50448996 -2.12365 1.50438002 -2.12361004 0 P 0 
L 1.50438002 -2.12361004 1.5027 -2.10378002 0 P 0 
L 1.5027 -2.10378002 1.50111998 -2.08403002 0 P 0 
L 1.50111998 -2.08403002 1.50263996 -2.08433996 0 P 0 
L 1.50263996 -2.08433996 1.50581004 -2.08511004 0 P 0 
L 1.50581004 -2.08511004 1.50955 -2.08611998 0 P 0 
L 1.50955 -2.08611998 1.52306004 -2.08961004 0 P 0 
L 1.52306004 -2.08961004 1.52311004 -2.08961998 0 P 0 
L 1.52311004 -2.08961998 1.52875 -2.09076004 0 P 0 
L 1.52875 -2.09076004 1.5288 -2.09076004 0 P 0 
L 1.5288 -2.09076004 1.53443996 -2.09161004 0 P 0 
L 1.53443996 -2.09161004 1.53893996 -2.09203002 0 P 0 
L 1.53893996 -2.09203002 1.54346004 -2.09216998 0 P 0 
L 1.54346004 -2.09216998 1.54473996 -2.09211004 0 P 0 
L 1.54473996 -2.09211004 1.54603002 -2.09195 0 P 0 
L 1.54603002 -2.09195 1.54728996 -2.09166998 0 P 0 
L 1.54728996 -2.09166998 1.54853002 -2.09128996 0 P 0 
L 1.54853002 -2.09128996 1.54973002 -2.09081004 0 P 0 
L 1.54973002 -2.09081004 1.55026998 -2.09053996 0 P 0 
L 1.55026998 -2.09053996 1.55076998 -2.09023002 0 P 0 
L 1.55076998 -2.09023002 1.55118002 -2.08991998 0 P 0 
L 1.55118002 -2.08991998 1.55118002 -2.08991004 0 P 0 
L 1.55118002 -2.08991004 1.5512 -2.08991004 0 P 0 
L 1.5512 -2.08991004 1.55125 -2.08986998 0 P 0 
L 1.55125 -2.08986998 1.55131004 -2.08981998 0 P 0 
L 1.55131004 -2.08981998 1.55126998 -2.08978002 0 P 0 
L 1.55126998 -2.08978002 1.55136004 -2.08978002 0 P 0 
L 1.55136004 -2.08978002 1.5517 -2.08948996 0 P 0 
L 1.5517 -2.08948996 1.55206004 -2.08911998 0 P 0 
L 1.55206004 -2.08911998 1.55205 -2.08911004 0 P 0 
L 1.55205 -2.08911004 1.55206004 -2.08911004 0 P 0 
L 1.55206004 -2.08911004 1.55211998 -2.08906004 0 P 0 
L 1.55211998 -2.08906004 1.55248996 -2.08861004 0 P 0 
L 1.55248996 -2.08861004 1.55283996 -2.08811998 0 P 0 
L 1.55283996 -2.08811998 1.55313996 -2.08761004 0 P 0 
L 1.55313996 -2.08761004 1.5534 -2.08706998 0 P 0 
L 1.5534 -2.08706998 1.55356004 -2.08663002 0 P 0 
L 1.55356004 -2.08663002 1.55368996 -2.08618996 0 P 0 
L 1.55368996 -2.08618996 1.55376998 -2.08573996 0 P 0 
L 1.55376998 -2.08573996 1.55378002 -2.08565 0 P 0 
L 1.55378002 -2.08565 1.55381998 -2.08528002 0 P 0 
L 1.55381998 -2.08528002 1.55383002 -2.08481998 0 P 0 
L 1.55383002 -2.08481998 1.5538 -2.08436998 0 P 0 
L 1.5538 -2.08436998 1.55373002 -2.08391998 0 P 0 
L 1.55373002 -2.08391998 1.55361998 -2.08346998 0 P 0 
L 1.55361998 -2.08346998 1.55348002 -2.08303996 0 P 0 
L 1.55348002 -2.08303996 1.5533 -2.08261004 0 P 0 
L 1.5533 -2.08261004 1.55308996 -2.08221004 0 P 0 
L 1.55308996 -2.08221004 1.55283996 -2.08183002 0 P 0 
L 1.55283996 -2.08183002 1.55175 -2.0804 0 P 0 
L 1.55175 -2.0804 1.55055 -2.07908002 0 P 0 
L 1.55055 -2.07908002 1.54926004 -2.07783996 0 P 0 
L 1.54926004 -2.07783996 1.54788996 -2.07671998 0 P 0 
L 1.54788996 -2.07671998 1.53706998 -2.06898002 0 P 0 
L 1.53706998 -2.06898002 1.52085 -2.05713996 0 P 0 
L 1.52085 -2.05713996 1.51766004 -2.05445 0 P 0 
L 1.51766004 -2.05445 1.51468002 -2.05153996 0 P 0 
L 1.51468002 -2.05153996 1.51191998 -2.04841998 0 P 0 
L 1.51191998 -2.04841998 1.51048996 -2.04651998 0 P 0 
L 1.51048996 -2.04651998 1.50923002 -2.04453002 0 P 0 
L 1.50923002 -2.04453002 1.50813996 -2.04245 0 P 0 
L 1.50813996 -2.04245 1.50721998 -2.04026004 0 P 0 
L 1.50721998 -2.04026004 1.50643002 -2.03788002 0 P 0 
L 1.50643002 -2.03788002 1.50581004 -2.03545 0 P 0 
L 1.50581004 -2.03545 1.50536004 -2.03298996 0 P 0 
L 1.50536004 -2.03298996 1.50508996 -2.0305 0 P 0 
L 1.50508996 -2.0305 1.50498996 -2.02745 0 P 0 
L 1.50498996 -2.02745 1.50513996 -2.02443996 0 P 0 
L 1.50513996 -2.02443996 1.50551998 -2.02145 0 P 0 
L 1.50551998 -2.02145 1.50613996 -2.0185 0 P 0 
L 1.50613996 -2.0185 1.50698996 -2.01561004 0 P 0 
L 1.50698996 -2.01561004 1.50783002 -2.01341004 0 P 0 
L 1.50783002 -2.01341004 1.50883002 -2.0113 0 P 0 
L 1.50883002 -2.0113 1.51 -2.00928002 0 P 0 
L 1.51 -2.00928002 1.51133002 -2.00736004 0 P 0 
L 1.51133002 -2.00736004 1.5128 -2.00555 0 P 0 
L 1.5128 -2.00555 1.5144 -2.00386004 0 P 0 
L 1.5144 -2.00386004 1.51675 -2.00176998 0 P 0 
L 1.51675 -2.00176998 1.51923002 -1.9999 0 P 0 
L 1.51923002 -1.9999 1.52186004 -1.99823996 0 P 0 
L 1.52186004 -1.99823996 1.52461998 -1.99681004 0 P 0 
L 1.52461998 -1.99681004 1.52748996 -1.99561004 0 P 0 
L 1.52748996 -1.99561004 1.53353002 -1.99363996 0 P 0 
L 1.53353002 -1.99363996 1.5397 -1.99218002 0 P 0 
L 1.5397 -1.99218002 1.54598002 -1.99123002 0 P 0 
L 1.54598002 -1.99123002 1.55181004 -1.99075 0 P 0 
L 1.55181004 -1.99075 1.55763002 -1.99061998 0 P 0 
L 1.55763002 -1.99061998 1.57273002 -1.99113996 0 P 0 
L 1.57273002 -1.99113996 1.58755 -1.99248996 0 P 0 
L 1.58755 -1.99248996 1.59293002 -1.99331998 0 P 0 
L 1.59293002 -1.99331998 1.59821004 -1.99448996 0 P 0 
L 1.59821004 -1.99448996 1.59905 -1.99473002 0 P 0 
L 1.59905 -1.99473002 1.59986004 -1.99501998 0 P 0 
L 1.59986004 -1.99501998 1.60008002 -1.99511998 0 P 0 
L 1.60008002 -1.99511998 1.6003 -1.99523002 0 P 0 
L 1.6003 -1.99523002 1.60051004 -1.99536004 0 P 0 
L 1.60051004 -1.99536004 1.60071004 -1.9955 0 P 0 
L 1.60071004 -1.9955 1.60083002 -1.99561004 0 P 0 
L 1.60083002 -1.99561004 1.60093996 -1.99571004 0 P 0 
L 1.60093996 -1.99571004 1.60103996 -1.99583002 0 P 0 
L 1.60103996 -1.99583002 1.60111998 -1.99595 0 P 0 
L 1.60111998 -1.99595 1.60116998 -1.99601998 0 P 0 
L 1.60116998 -1.99601998 1.60121004 -1.99611004 0 P 0 
L 1.60121004 -1.99611004 1.60125 -1.99621004 0 P 0 
L 1.60125 -1.99621004 1.60128002 -1.9963 0 P 0 
L 1.60128002 -1.9963 1.60131004 -1.99641004 0 P 0 
L 1.60131004 -1.99641004 1.6017 -1.99861998 0 P 0 
L 1.6017 -1.99861998 1.60195 -2.00086998 0 P 0 
L 1.60195 -2.00086998 1.60308002 -2.01593002 0 P 0 
L 1.60308002 -2.01593002 1.60415 -2.03096998 0 P 0 
L 1.60415 -2.03096998 1.60345 -2.03083996 0 P 0 
L 1.60345 -2.03083996 1.60058996 -2.03026004 0 P 0 
L 1.60058996 -2.03026004 1.59723002 -2.02948002 0 P 0 
L 1.59723002 -2.02948002 1.59721998 -2.02948002 0 P 0 
L 1.59721998 -2.02948002 1.59306998 -2.0286 0 P 0 
L 1.59306998 -2.0286 1.58776004 -2.02776998 0 P 0 
L 1.58776004 -2.02776998 1.58226004 -2.02708002 0 P 0 
L 1.58226004 -2.02708002 1.57738002 -2.02666998 0 P 0 
L 1.57738002 -2.02666998 1.5709 -2.02633996 0 P 0 
L 1.5709 -2.02633996 1.56918996 -2.02635 0 P 0 
L 1.56918996 -2.02635 1.56746998 -2.02648996 0 P 0 
L 1.56746998 -2.02648996 1.56678996 -2.02658996 0 P 0 
L 1.56678996 -2.02658996 1.56611998 -2.02673996 0 P 0 
L 1.56611998 -2.02673996 1.56546004 -2.02695 0 P 0 
L 1.56546004 -2.02695 1.56481998 -2.0272 0 P 0 
L 1.56481998 -2.0272 1.56418996 -2.0275 0 P 0 
L 1.56418996 -2.0275 1.56358002 -2.02785 0 P 0 
L 1.56358002 -2.02785 1.563 -2.02823002 0 P 0 
L 1.563 -2.02823002 1.56245 -2.02865 0 P 0 
L 1.56245 -2.02865 1.56206998 -2.02898996 0 P 0 
L 1.56206998 -2.02898996 1.56171004 -2.02936004 0 P 0 
L 1.56171004 -2.02936004 1.56138002 -2.02976004 0 P 0 
L 1.56138002 -2.02976004 1.56108996 -2.03018996 0 P 0 
L 1.56108996 -2.03018996 1.56083002 -2.03063996 0 P 0 
L 1.56083002 -2.03063996 1.56061998 -2.0311 0 P 0 
L 1.56061998 -2.0311 1.56043996 -2.03158996 0 P 0 
L 1.56043996 -2.03158996 1.5603 -2.03208002 0 P 0 
L 1.5603 -2.03208002 1.5602 -2.0326 0 P 0 
L 1.5602 -2.0326 1.56015 -2.03308002 0 P 0 
L 1.56015 -2.03308002 1.56013996 -2.03353996 0 P 0 
L 1.56013996 -2.03353996 1.56016004 -2.03391004 0 P 0 
L 1.56016004 -2.03391004 1.56048002 -2.03391004 0 P 0 
L 1.56048002 -2.03391004 1.56016004 -2.03393002 0 P 0 
L 1.56016004 -2.03393002 1.56016998 -2.03401004 0 P 0 
L 1.56016998 -2.03401004 1.56023002 -2.03448002 0 P 0 
L 1.56023002 -2.03448002 1.56025 -2.03456004 0 P 0 
L 1.56025 -2.03456004 1.56033002 -2.03493002 0 P 0 
L 1.56033002 -2.03493002 1.56046998 -2.03538002 0 P 0 
L 1.56046998 -2.03538002 1.56063996 -2.03581998 0 P 0 
L 1.56063996 -2.03581998 1.56085 -2.03623996 0 P 0 
L 1.56085 -2.03623996 1.56108996 -2.03663996 0 P 0 
L 1.56108996 -2.03663996 1.56136004 -2.03701998 0 P 0 
L 1.56136004 -2.03701998 1.56233002 -2.03818996 0 P 0 
L 1.56233002 -2.03818996 1.56336998 -2.03928996 0 P 0 
L 1.56336998 -2.03928996 1.56448002 -2.04031004 0 P 0 
L 1.56448002 -2.04031004 1.56566004 -2.04123996 0 P 0 
L 1.56566004 -2.04123996 1.57471004 -2.04761998 0 P 0 
L 1.57471004 -2.04761998 1.58461998 -2.05491004 0 P 0 
L 1.58461998 -2.05491004 1.58898996 -2.05858996 0 P 0 
L 1.58898996 -2.05858996 1.59315 -2.06245 0 P 0 
L 1.59315 -2.06245 1.59656998 -2.06596998 0 P 0 
L 1.59656998 -2.06596998 1.59976004 -2.06965 0 P 0 
L 1.59976004 -2.06965 1.60116004 -2.07151004 0 P 0 
L 1.60116004 -2.07151004 1.60238002 -2.07346004 0 P 0 
L 1.60238002 -2.07346004 1.60341998 -2.0755 0 P 0 
L 1.60341998 -2.0755 1.60403996 -2.077 0 P 0 
L 1.60403996 -2.077 1.60456004 -2.07853996 0 P 0 
L 1.60456004 -2.07853996 1.60496004 -2.08011004 0 P 0 
L 1.60496004 -2.08011004 1.60525 -2.0817 0 P 0 
L 1.60525 -2.0817 1.60568996 -2.08578002 0 P 0 
L 1.60568996 -2.08578002 1.60578996 -2.08988002 0 P 0 
L 1.60578996 -2.08988002 1.60556998 -2.09403002 0 P 0 
L 1.60556998 -2.09403002 1.60501004 -2.09813996 0 P 0 
L 1.60501004 -2.09813996 1.60451998 -2.10036998 0 P 0 
L 1.60451998 -2.10036998 1.60383996 -2.10253996 0 P 0 
L 1.60383996 -2.10253996 1.60298996 -2.10465 0 P 0 
L 1.60298996 -2.10465 1.60163996 -2.1073 0 P 0 
L 1.60163996 -2.1073 1.60008002 -2.10983002 0 P 0 
L 1.60008002 -2.10983002 1.59833002 -2.11225 0 P 0 
L 1.59833002 -2.11225 1.59696998 -2.11386998 0 P 0 
L 1.59696998 -2.11386998 1.59551004 -2.11538996 0 P 0 
L 1.59551004 -2.11538996 1.59395 -2.1168 0 P 0 
L 1.59395 -2.1168 1.59231004 -2.11811004 0 P 0 
L 1.59231004 -2.11811004 1.58973002 -2.11986004 0 P 0 
L 1.58973002 -2.11986004 1.58701998 -2.1214 0 P 0 
L 1.58701998 -2.1214 1.5842 -2.12273002 0 P 0 
L 1.5842 -2.12273002 1.5788 -2.1248 0 P 0 
L 1.5788 -2.1248 1.57326998 -2.12648996 0 P 0 
L 1.57326998 -2.12648996 1.56983002 -2.12731004 0 P 0 
L 1.56983002 -2.12731004 1.56638002 -2.12791004 0 P 0 
L 1.56638002 -2.12791004 1.56288996 -2.1283 0 P 0 
L 1.56288996 -2.1283 1.54886998 -2.12886998 0 P 0 
L 1.35851998 -2.06545 1.47866004 -2.06545 0 P 0 
L 1.35936004 -2.06445 1.47871004 -2.06445 0 P 0 
L 1.36041004 -2.06345 1.47875 -2.06345 0 P 0 
L 1.36163996 -2.06245 1.4788 -2.06245 0 P 0 
L 1.36293996 -2.06145 1.47883996 -2.06145 0 P 0 
L 1.36436004 -2.06045 1.47888996 -2.06045 0 P 0 
L 1.36598002 -2.05945 1.47893996 -2.05945 0 P 0 
L 1.36776004 -2.05845 1.47898996 -2.05845 0 P 0 
L 1.36971004 -2.05745 1.47903002 -2.05745 0 P 0 
L 1.37166004 -2.05645 1.47908002 -2.05645 0 P 0 
L 1.37391004 -2.05545 1.47911998 -2.05545 0 P 0 
L 1.37616998 -2.05445 1.47916998 -2.05445 0 P 0 
L 1.37873002 -2.05345 1.47921004 -2.05345 0 P 0 
L 1.38136004 -2.05245 1.47926004 -2.05245 0 P 0 
L 1.36875 -2.03345 1.37108996 -2.03345 0 P 0 
L 1.36886004 -2.03245 1.37385 -2.03245 0 P 0 
L 1.36896998 -2.03145 1.37678002 -2.03145 0 P 0 
L 1.36908996 -2.03045 1.3797 -2.03045 0 P 0 
L 1.36921004 -2.02945 1.38261998 -2.02945 0 P 0 
L 1.36933002 -2.02845 1.38638996 -2.02845 0 P 0 
L 1.36946004 -2.02745 1.39023996 -2.02745 0 P 0 
L 1.36958002 -2.02645 1.39503002 -2.02645 0 P 0 
L 1.3697 -2.02545 1.40068002 -2.02545 0 P 0 
L 1.36981998 -2.02445 1.41053996 -2.02445 0 P 0 
L 1.36993996 -2.02345 1.47993996 -2.02345 0 P 0 
L 1.37008002 -2.02245 1.47988002 -2.02245 0 P 0 
L 1.37021004 -2.02145 1.47978002 -2.02145 0 P 0 
L 1.37033996 -2.02045 1.47968002 -2.02045 0 P 0 
L 1.37046998 -2.01945 1.47953002 -2.01945 0 P 0 
L 1.3706 -2.01845 1.47936004 -2.01845 0 P 0 
L 1.37073002 -2.01745 1.47918002 -2.01745 0 P 0 
L 1.37086004 -2.01645 1.47893002 -2.01645 0 P 0 
L 1.37098996 -2.01545 1.47868002 -2.01545 0 P 0 
L 1.37113002 -2.01445 1.4784 -2.01445 0 P 0 
L 1.37126998 -2.01345 1.47806004 -2.01345 0 P 0 
L 1.3714 -2.01245 1.47773002 -2.01245 0 P 0 
L 1.37153996 -2.01145 1.47733002 -2.01145 0 P 0 
L 1.37168002 -2.01045 1.47691004 -2.01045 0 P 0 
L 1.37181004 -2.00945 1.47641004 -2.00945 0 P 0 
L 1.37195 -2.00845 1.47588996 -2.00845 0 P 0 
L 1.37208002 -2.00745 1.47528002 -2.00745 0 P 0 
L 1.37221004 -2.00645 1.47463996 -2.00645 0 P 0 
L 1.37235 -2.00545 1.47391998 -2.00545 0 P 0 
L 1.37248996 -2.00445 1.47311004 -2.00445 0 P 0 
L 1.37261998 -2.00345 1.47225 -2.00345 0 P 0 
L 1.37276004 -2.00245 1.47126998 -2.00245 0 P 0 
L 1.3729 -2.00145 1.4702 -2.00145 0 P 0 
L 1.37303002 -2.00045 1.46903996 -2.00045 0 P 0 
L 1.37316998 -1.99945 1.46775 -1.99945 0 P 0 
L 1.3733 -1.99845 1.46625 -1.99845 0 P 0 
L 1.37343996 -1.99745 1.46455 -1.99745 0 P 0 
L 1.37356998 -1.99645 1.46253996 -1.99645 0 P 0 
L 1.37753002 -1.99545 1.46041004 -1.99545 0 P 0 
L 1.38218996 -1.99445 1.45781004 -1.99445 0 P 0 
L 1.42925 -2.08345 1.47785 -2.08345 0 P 0 
L 1.42931998 -2.08245 1.47788996 -2.08245 0 P 0 
L 1.42938002 -2.08145 1.47793002 -2.08145 0 P 0 
L 1.42945 -2.08045 1.47796998 -2.08045 0 P 0 
L 1.42951004 -2.07945 1.47801004 -2.07945 0 P 0 
L 1.42958002 -2.07845 1.47806004 -2.07845 0 P 0 
L 1.42963996 -2.07745 1.4781 -2.07745 0 P 0 
L 1.4297 -2.07645 1.47815 -2.07645 0 P 0 
L 1.42976998 -2.07545 1.4782 -2.07545 0 P 0 
L 1.42983002 -2.07445 1.47825 -2.07445 0 P 0 
L 1.4299 -2.07345 1.47828996 -2.07345 0 P 0 
L 1.42963996 -2.07245 1.47833996 -2.07245 0 P 0 
L 1.42918996 -2.07145 1.47838002 -2.07145 0 P 0 
L 1.38425 -2.05145 1.47931004 -2.05145 0 P 0 
L 1.38731998 -2.05045 1.47933996 -2.05045 0 P 0 
L 1.39088002 -2.04945 1.47938002 -2.04945 0 P 0 
L 1.3947 -2.04845 1.47941004 -2.04845 0 P 0 
L 1.39851004 -2.04745 1.47945 -2.04745 0 P 0 
L 1.40233002 -2.04645 1.47948002 -2.04645 0 P 0 
L 1.40608002 -2.04545 1.47951004 -2.04545 0 P 0 
L 1.40983002 -2.04445 1.47955 -2.04445 0 P 0 
L 1.41306998 -2.04345 1.47958996 -2.04345 0 P 0 
L 1.41591998 -2.04245 1.47961998 -2.04245 0 P 0 
L 1.41876998 -2.04145 1.47965 -2.04145 0 P 0 
L 1.42133996 -2.04045 1.47968996 -2.04045 0 P 0 
L 1.42361998 -2.03945 1.47971998 -2.03945 0 P 0 
L 1.42591004 -2.03845 1.47975 -2.03845 0 P 0 
L 1.42805 -2.03745 1.47978002 -2.03745 0 P 0 
L 1.42936004 -2.03645 1.47981004 -2.03645 0 P 0 
L 1.43003002 -2.03545 1.47983002 -2.03545 0 P 0 
L 1.43081998 -2.03445 1.47986004 -2.03445 0 P 0 
L 1.43121004 -2.03345 1.47988002 -2.03345 0 P 0 
L 1.43141998 -2.03245 1.4799 -2.03245 0 P 0 
L 1.43146998 -2.03145 1.47993002 -2.03145 0 P 0 
L 1.43136004 -2.03045 1.47996004 -2.03045 0 P 0 
L 1.43108002 -2.02945 1.47998002 -2.02945 0 P 0 
L 1.4306 -2.02845 1.48001004 -2.02845 0 P 0 
L 1.42986998 -2.02745 1.48001004 -2.02745 0 P 0 
L 1.42875 -2.02645 1.47998996 -2.02645 0 P 0 
L 1.42658996 -2.02545 1.47996998 -2.02545 0 P 0 
L 1.42203996 -2.02445 1.47996004 -2.02445 0 P 0 
L 1.38748002 -1.99345 1.45483002 -1.99345 0 P 0 
L 1.39331998 -1.99245 1.45108996 -1.99245 0 P 0 
L 1.40051004 -1.99145 1.44503002 -1.99145 0 P 0 
L 1.38096998 -2.12745 1.4051 -2.12745 0 P 0 
L 1.37671004 -2.12645 1.41113996 -2.12645 0 P 0 
L 1.3736 -2.12545 1.41238996 -2.12545 0 P 0 
L 1.37096998 -2.12445 1.41268002 -2.12445 0 P 0 
L 1.36876998 -2.12345 1.41296998 -2.12345 0 P 0 
L 1.36685 -2.12245 1.41326998 -2.12245 0 P 0 
L 1.36516004 -2.12145 1.41356004 -2.12145 0 P 0 
L 1.36366004 -2.12045 1.41385 -2.12045 0 P 0 
L 1.36225 -2.11945 1.41413996 -2.11945 0 P 0 
L 1.361 -2.11845 1.41443002 -2.11845 0 P 0 
L 1.35983002 -2.11745 1.41471998 -2.11745 0 P 0 
L 1.35876004 -2.11645 1.41501004 -2.11645 0 P 0 
L 1.42661998 -2.12445 1.47693002 -2.12445 0 P 0 
L 1.42665 -2.12345 1.47693002 -2.12345 0 P 0 
L 1.4267 -2.12245 1.47693002 -2.12245 0 P 0 
L 1.42675 -2.12145 1.47693002 -2.12145 0 P 0 
L 1.42681004 -2.12045 1.47693002 -2.12045 0 P 0 
L 1.42686998 -2.11945 1.47693002 -2.11945 0 P 0 
L 1.42691998 -2.11845 1.47693002 -2.11845 0 P 0 
L 1.42698996 -2.11745 1.47693002 -2.11745 0 P 0 
L 1.42705 -2.11645 1.47693002 -2.11645 0 P 0 
L 1.42711004 -2.11545 1.47693002 -2.11545 0 P 0 
L 1.42716998 -2.11445 1.47693002 -2.11445 0 P 0 
L 1.42723002 -2.11345 1.47693996 -2.11345 0 P 0 
L 1.4273 -2.11245 1.47695 -2.11245 0 P 0 
L 1.42736998 -2.11145 1.47696004 -2.11145 0 P 0 
L 1.42743996 -2.11045 1.47698002 -2.11045 0 P 0 
L 1.42751004 -2.10945 1.47698996 -2.10945 0 P 0 
L 1.42758002 -2.10845 1.47701004 -2.10845 0 P 0 
L 1.42765 -2.10745 1.47703002 -2.10745 0 P 0 
L 1.42771004 -2.10645 1.47703996 -2.10645 0 P 0 
L 1.42778002 -2.10545 1.47706998 -2.10545 0 P 0 
L 1.42783996 -2.10445 1.4771 -2.10445 0 P 0 
L 1.42791004 -2.10345 1.47713002 -2.10345 0 P 0 
L 1.42798002 -2.10245 1.47716004 -2.10245 0 P 0 
L 1.42805 -2.10145 1.4772 -2.10145 0 P 0 
L 1.42811004 -2.10045 1.47723002 -2.10045 0 P 0 
L 1.40953002 -2.09945 1.41973002 -2.09945 0 P 0 
L 1.42818002 -2.09945 1.47726004 -2.09945 0 P 0 
L 1.41618002 -2.09845 1.41996998 -2.09845 0 P 0 
L 1.42825 -2.09845 1.47728996 -2.09845 0 P 0 
L 1.42831998 -2.09745 1.47733002 -2.09745 0 P 0 
L 1.42838996 -2.09645 1.47736004 -2.09645 0 P 0 
L 1.42846004 -2.09545 1.47738996 -2.09545 0 P 0 
L 1.42851998 -2.09445 1.47741998 -2.09445 0 P 0 
L 1.42858996 -2.09345 1.47746004 -2.09345 0 P 0 
L 1.42866004 -2.09245 1.4775 -2.09245 0 P 0 
L 1.42873002 -2.09145 1.47753996 -2.09145 0 P 0 
L 1.42878996 -2.09045 1.47758002 -2.09045 0 P 0 
L 1.42886004 -2.08945 1.47761998 -2.08945 0 P 0 
L 1.42893002 -2.08845 1.47766004 -2.08845 0 P 0 
L 1.42898996 -2.08745 1.4777 -2.08745 0 P 0 
L 1.42906004 -2.08645 1.47773002 -2.08645 0 P 0 
L 1.42911998 -2.08545 1.47776998 -2.08545 0 P 0 
L 1.42918996 -2.08445 1.47781004 -2.08445 0 P 0 
L 1.61686004 -2.17995 1.66846004 -2.17995 0 P 0 
L 1.61591004 -2.17895 1.67158996 -2.17895 0 P 0 
L 1.61553996 -2.17795 1.67431998 -2.17795 0 P 0 
L 1.61526998 -2.17695 1.67675 -2.17695 0 P 0 
L 1.61508002 -2.17595 1.67903996 -2.17595 0 P 0 
L 1.61496998 -2.17495 1.68108002 -2.17495 0 P 0 
L 1.61491004 -2.17395 1.68295 -2.17395 0 P 0 
L 1.61485 -2.17295 1.68458996 -2.17295 0 P 0 
L 1.61478996 -2.17195 1.6861 -2.17195 0 P 0 
L 1.61473002 -2.17095 1.6875 -2.17095 0 P 0 
L 1.61466998 -2.16995 1.68876998 -2.16995 0 P 0 
L 1.61461004 -2.16895 1.68998002 -2.16895 0 P 0 
L 1.61455 -2.16795 1.69108002 -2.16795 0 P 0 
L 1.61448996 -2.16695 1.69211998 -2.16695 0 P 0 
L 1.61443002 -2.16595 1.69316004 -2.16595 0 P 0 
L 1.61436998 -2.16495 1.69411998 -2.16495 0 P 0 
L 1.61431004 -2.16395 1.69498996 -2.16395 0 P 0 
L 1.61425 -2.16295 1.69586004 -2.16295 0 P 0 
L 1.61418996 -2.16195 1.69673002 -2.16195 0 P 0 
L 1.61413002 -2.16095 1.69746998 -2.16095 0 P 0 
L 1.61406998 -2.15995 1.6982 -2.15995 0 P 0 
L 1.61401998 -2.15895 1.69893996 -2.15895 0 P 0 
L 1.61396998 -2.15795 1.69963002 -2.15795 0 P 0 
L 1.64433002 -2.18295 1.63151004 -2.18271004 0 P 0 
L 1.63151004 -2.18271004 1.62658002 -2.18226998 0 P 0 
L 1.62658002 -2.18226998 1.62168996 -2.18146998 0 P 0 
L 1.62168996 -2.18146998 1.6201 -2.1811 0 P 0 
L 1.6201 -2.1811 1.61853996 -2.18061004 0 P 0 
L 1.61853996 -2.18061004 1.61701004 -2.18001998 0 P 0 
L 1.61701004 -2.18001998 1.61686004 -2.17995 0 P 0 
L 1.61686004 -2.17995 1.61671004 -2.17986998 0 P 0 
L 1.61671004 -2.17986998 1.61656998 -2.17976998 0 P 0 
L 1.61656998 -2.17976998 1.61643996 -2.17966998 0 P 0 
L 1.61643996 -2.17966998 1.61631998 -2.17955 0 P 0 
L 1.61631998 -2.17955 1.61621004 -2.17943002 0 P 0 
L 1.61621004 -2.17943002 1.6161 -2.1793 0 P 0 
L 1.6161 -2.1793 1.61601004 -2.17915 0 P 0 
L 1.61601004 -2.17915 1.61593002 -2.179 0 P 0 
L 1.61593002 -2.179 1.61586004 -2.17885 0 P 0 
L 1.61586004 -2.17885 1.61553002 -2.17791004 0 P 0 
L 1.61553002 -2.17791004 1.61526998 -2.17696004 0 P 0 
L 1.61526998 -2.17696004 1.61508996 -2.17598996 0 P 0 
L 1.61508996 -2.17598996 1.61496998 -2.17496998 0 P 0 
L 1.61496998 -2.17496998 1.61408002 -2.16011004 0 P 0 
L 1.61408002 -2.16011004 1.61341998 -2.14758996 0 P 0 
L 1.61341998 -2.14758996 1.6202 -2.14821004 0 P 0 
L 1.6202 -2.14821004 1.62023002 -2.14821004 0 P 0 
L 1.62023002 -2.14821004 1.63216998 -2.14893996 0 P 0 
L 1.63216998 -2.14893996 1.6349 -2.14893002 0 P 0 
L 1.6349 -2.14893002 1.63761998 -2.14873002 0 P 0 
L 1.63761998 -2.14873002 1.64031998 -2.14835 0 P 0 
L 1.64031998 -2.14835 1.64198996 -2.14798996 0 P 0 
L 1.64198996 -2.14798996 1.64363002 -2.14751998 0 P 0 
L 1.64363002 -2.14751998 1.64523002 -2.14693002 0 P 0 
L 1.64523002 -2.14693002 1.64678996 -2.14623002 0 P 0 
L 1.64678996 -2.14623002 1.64888002 -2.14506998 0 P 0 
L 1.64888002 -2.14506998 1.65086998 -2.14376004 0 P 0 
L 1.65086998 -2.14376004 1.65093996 -2.14371004 0 P 0 
L 1.65093996 -2.14371004 1.65275 -2.14228996 0 P 0 
L 1.65275 -2.14228996 1.6539 -2.14123996 0 P 0 
L 1.6539 -2.14123996 1.65496004 -2.14011004 0 P 0 
L 1.65496004 -2.14011004 1.65591998 -2.13891004 0 P 0 
L 1.65591998 -2.13891004 1.65755 -2.13653996 0 P 0 
L 1.65755 -2.13653996 1.65901998 -2.13415 0 P 0 
L 1.65901998 -2.13415 1.65903002 -2.13413002 0 P 0 
L 1.65903002 -2.13413002 1.66035 -2.13171998 0 P 0 
L 1.66035 -2.13171998 1.66155 -2.12925 0 P 0 
L 1.66155 -2.12925 1.66183996 -2.12851998 0 P 0 
L 1.66183996 -2.12851998 1.66206998 -2.12776004 0 P 0 
L 1.66206998 -2.12776004 1.66223996 -2.12696998 0 P 0 
L 1.66223996 -2.12696998 1.66233996 -2.12618002 0 P 0 
L 1.66233996 -2.12618002 1.66236998 -2.12538996 0 P 0 
L 1.66236998 -2.12538996 1.66233002 -2.12436004 0 P 0 
L 1.66233002 -2.12436004 1.66221004 -2.12335 0 P 0 
L 1.66221004 -2.12335 1.662 -2.12235 0 P 0 
L 1.662 -2.12235 1.66171004 -2.12141004 0 P 0 
L 1.66171004 -2.12141004 1.64438996 -2.07113002 0 P 0 
L 1.64438996 -2.07113002 1.62871998 -2.02606004 0 P 0 
L 1.62871998 -2.02606004 1.62116004 -2.00558996 0 P 0 
L 1.62116004 -2.00558996 1.62116004 -2.00556998 0 P 0 
L 1.62116004 -2.00556998 1.61681004 -1.99443996 0 P 0 
L 1.61681004 -1.99443996 1.67163002 -1.99443996 0 P 0 
L 1.67163002 -1.99443996 1.67301004 -2.00076004 0 P 0 
L 1.67301004 -2.00076004 1.67613002 -2.01341998 0 P 0 
L 1.67613002 -2.01341998 1.68331004 -2.03931998 0 P 0 
L 1.68331004 -2.03931998 1.69153002 -2.06856998 0 P 0 
L 1.69153002 -2.06856998 1.6916 -2.06876004 0 P 0 
L 1.6916 -2.06876004 1.69168996 -2.06896998 0 P 0 
L 1.69168996 -2.06896998 1.69181004 -2.06918002 0 P 0 
L 1.69181004 -2.06918002 1.69193002 -2.06936998 0 P 0 
L 1.69193002 -2.06936998 1.69208002 -2.06956004 0 P 0 
L 1.69208002 -2.06956004 1.69223996 -2.06973002 0 P 0 
L 1.69223996 -2.06973002 1.69241998 -2.06988002 0 P 0 
L 1.69241998 -2.06988002 1.6926 -2.07001998 0 P 0 
L 1.6926 -2.07001998 1.6928 -2.07015 0 P 0 
L 1.6928 -2.07015 1.69301004 -2.07025 0 P 0 
L 1.69301004 -2.07025 1.69323002 -2.07033996 0 P 0 
L 1.69323002 -2.07033996 1.69346004 -2.07041004 0 P 0 
L 1.69346004 -2.07041004 1.69368002 -2.07045 0 P 0 
L 1.69368002 -2.07045 1.69391998 -2.07048002 0 P 0 
L 1.69391998 -2.07048002 1.69413996 -2.07048996 0 P 0 
L 1.69413996 -2.07048996 1.6944 -2.07048002 0 P 0 
L 1.6944 -2.07048002 1.69465 -2.07045 0 P 0 
L 1.69465 -2.07045 1.69488996 -2.07038996 0 P 0 
L 1.69488996 -2.07038996 1.69513996 -2.07031998 0 P 0 
L 1.69513996 -2.07031998 1.69536998 -2.07021998 0 P 0 
L 1.69536998 -2.07021998 1.69558996 -2.0701 0 P 0 
L 1.69558996 -2.0701 1.69581004 -2.06996998 0 P 0 
L 1.69581004 -2.06996998 1.69601004 -2.06981998 0 P 0 
L 1.69601004 -2.06981998 1.6962 -2.06965 0 P 0 
L 1.6962 -2.06965 1.69636998 -2.06946004 0 P 0 
L 1.69636998 -2.06946004 1.69653002 -2.06926004 0 P 0 
L 1.69653002 -2.06926004 1.69666004 -2.06905 0 P 0 
L 1.69666004 -2.06905 1.69678996 -2.06883002 0 P 0 
L 1.69678996 -2.06883002 1.69688002 -2.0686 0 P 0 
L 1.69688002 -2.0686 1.69695 -2.0684 0 P 0 
L 1.69695 -2.0684 1.70426004 -2.04365 0 P 0 
L 1.70426004 -2.04365 1.70426004 -2.04363002 0 P 0 
L 1.70426004 -2.04363002 1.71066998 -2.0213 0 P 0 
L 1.71066998 -2.0213 1.71068002 -2.02126004 0 P 0 
L 1.71068002 -2.02126004 1.71431998 -2.00693996 0 P 0 
L 1.71431998 -2.00693996 1.71706004 -1.99496998 0 P 0 
L 1.71706004 -1.99496998 1.74335 -1.9947 0 P 0 
L 1.74335 -1.9947 1.75403002 -1.99461004 0 P 0 
L 1.75403002 -1.99461004 1.76301004 -1.99465 0 P 0 
L 1.76301004 -1.99465 1.76886004 -1.99471004 0 P 0 
L 1.76886004 -1.99471004 1.76883996 -1.99476004 0 P 0 
L 1.76883996 -1.99476004 1.74021004 -2.06556004 0 P 0 
L 1.74021004 -2.06556004 1.71298002 -2.13276998 0 P 0 
L 1.71298002 -2.13276998 1.70836998 -2.14293996 0 P 0 
L 1.70836998 -2.14293996 1.70413996 -2.15076004 0 P 0 
L 1.70413996 -2.15076004 1.69941998 -2.15828996 0 P 0 
L 1.69941998 -2.15828996 1.6967 -2.16198996 0 P 0 
L 1.6967 -2.16198996 1.6937 -2.16541998 0 P 0 
L 1.6937 -2.16541998 1.69041998 -2.1686 0 P 0 
L 1.69041998 -2.1686 1.68793996 -2.17063002 0 P 0 
L 1.68793996 -2.17063002 1.68535 -2.17248002 0 P 0 
L 1.68535 -2.17248002 1.68263996 -2.17413996 0 P 0 
L 1.68263996 -2.17413996 1.67981004 -2.17561004 0 P 0 
L 1.67981004 -2.17561004 1.67525 -2.17761004 0 P 0 
L 1.67525 -2.17761004 1.6706 -2.17931998 0 P 0 
L 1.6706 -2.17931998 1.66586004 -2.18073002 0 P 0 
L 1.66586004 -2.18073002 1.66141998 -2.1817 0 P 0 
L 1.66141998 -2.1817 1.65691998 -2.18228996 0 P 0 
L 1.65691998 -2.18228996 1.64433002 -2.18295 0 P 0 
L 1.61928996 -2.00628002 1.62683996 -2.02673002 0 P 0 
L 1.62683996 -2.02673002 1.6425 -2.07178002 0 P 0 
L 1.6425 -2.07178002 1.65981004 -2.12201998 0 P 0 
L 1.65981004 -2.12201998 1.66006004 -2.12283996 0 P 0 
L 1.66006004 -2.12283996 1.66023002 -2.12368002 0 P 0 
L 1.66023002 -2.12368002 1.66033996 -2.12451998 0 P 0 
L 1.66033996 -2.12451998 1.66036998 -2.12538002 0 P 0 
L 1.66036998 -2.12538002 1.66033996 -2.12601004 0 P 0 
L 1.66033996 -2.12601004 1.66026998 -2.12663996 0 P 0 
L 1.66026998 -2.12663996 1.66013996 -2.12725 0 P 0 
L 1.66013996 -2.12725 1.65995 -2.12786004 0 P 0 
L 1.65995 -2.12786004 1.65971004 -2.12843996 0 P 0 
L 1.65971004 -2.12843996 1.65856998 -2.1308 0 P 0 
L 1.65856998 -2.1308 1.6573 -2.13313002 0 P 0 
L 1.6573 -2.13313002 1.65586998 -2.13545 0 P 0 
L 1.65586998 -2.13545 1.65431004 -2.13771998 0 P 0 
L 1.65431004 -2.13771998 1.65343996 -2.1388 0 P 0 
L 1.65343996 -2.1388 1.65248996 -2.13981998 0 P 0 
L 1.65248996 -2.13981998 1.65146004 -2.14076004 0 P 0 
L 1.65146004 -2.14076004 1.64971004 -2.14213002 0 P 0 
L 1.64971004 -2.14213002 1.64785 -2.14336004 0 P 0 
L 1.64785 -2.14336004 1.64588996 -2.14443996 0 P 0 
L 1.64588996 -2.14443996 1.64446998 -2.14508002 0 P 0 
L 1.64446998 -2.14508002 1.64301004 -2.14561998 0 P 0 
L 1.64301004 -2.14561998 1.64151004 -2.14605 0 P 0 
L 1.64151004 -2.14605 1.63996998 -2.14636998 0 P 0 
L 1.63996998 -2.14636998 1.63741004 -2.14673996 0 P 0 
L 1.63741004 -2.14673996 1.63483002 -2.14693002 0 P 0 
L 1.63483002 -2.14693002 1.63223002 -2.14693996 0 P 0 
L 1.63223002 -2.14693996 1.62036004 -2.14621998 0 P 0 
L 1.62036004 -2.14621998 1.6113 -2.14538002 0 P 0 
L 1.6113 -2.14538002 1.61208996 -2.16023002 0 P 0 
L 1.61208996 -2.16023002 1.61298002 -2.17515 0 P 0 
L 1.61298002 -2.17515 1.6131 -2.17628002 0 P 0 
L 1.6131 -2.17628002 1.61331998 -2.17741004 0 P 0 
L 1.61331998 -2.17741004 1.61361998 -2.17851004 0 P 0 
L 1.61361998 -2.17851004 1.614 -2.17958996 0 P 0 
L 1.614 -2.17958996 1.61413996 -2.17988996 0 P 0 
L 1.61413996 -2.17988996 1.61428996 -2.18018002 0 P 0 
L 1.61428996 -2.18018002 1.61446998 -2.18045 0 P 0 
L 1.61446998 -2.18045 1.61466998 -2.18071004 0 P 0 
L 1.61466998 -2.18071004 1.61488996 -2.18095 0 P 0 
L 1.61488996 -2.18095 1.61511998 -2.18116998 0 P 0 
L 1.61511998 -2.18116998 1.61538002 -2.18138002 0 P 0 
L 1.61538002 -2.18138002 1.61565 -2.18156004 0 P 0 
L 1.61565 -2.18156004 1.61593002 -2.18173002 0 P 0 
L 1.61593002 -2.18173002 1.61623002 -2.18186004 0 P 0 
L 1.61623002 -2.18186004 1.61788002 -2.1825 0 P 0 
L 1.61788002 -2.1825 1.61956998 -2.18301998 0 P 0 
L 1.61956998 -2.18301998 1.6213 -2.18343002 0 P 0 
L 1.6213 -2.18343002 1.62633002 -2.18426004 0 P 0 
L 1.62633002 -2.18426004 1.6314 -2.18471004 0 P 0 
L 1.6314 -2.18471004 1.64436004 -2.18495 0 P 0 
L 1.64436004 -2.18495 1.65711004 -2.18428002 0 P 0 
L 1.65711004 -2.18428002 1.66176998 -2.18366998 0 P 0 
L 1.66176998 -2.18366998 1.66636004 -2.18266998 0 P 0 
L 1.66636004 -2.18266998 1.67123002 -2.18121004 0 P 0 
L 1.67123002 -2.18121004 1.676 -2.17946998 0 P 0 
L 1.676 -2.17946998 1.68068002 -2.17741998 0 P 0 
L 1.68068002 -2.17741998 1.68361998 -2.17588002 0 P 0 
L 1.68361998 -2.17588002 1.68646004 -2.17415 0 P 0 
L 1.68646004 -2.17415 1.68916004 -2.17221998 0 P 0 
L 1.68916004 -2.17221998 1.69175 -2.17008996 0 P 0 
L 1.69175 -2.17008996 1.69515 -2.1668 0 P 0 
L 1.69515 -2.1668 1.69826004 -2.16323996 0 P 0 
L 1.69826004 -2.16323996 1.70108002 -2.15941998 0 P 0 
L 1.70108002 -2.15941998 1.70586004 -2.15176998 0 P 0 
L 1.70586004 -2.15176998 1.71016004 -2.14383002 0 P 0 
L 1.71016004 -2.14383002 1.71481998 -2.13356004 0 P 0 
L 1.71481998 -2.13356004 1.74206998 -2.06631004 0 P 0 
L 1.74206998 -2.06631004 1.77071004 -1.99548002 0 P 0 
L 1.77071004 -1.99548002 1.77088002 -1.99498996 0 P 0 
L 1.77088002 -1.99498996 1.77101998 -1.99448996 0 P 0 
L 1.77101998 -1.99448996 1.77111998 -1.99398996 0 P 0 
L 1.77111998 -1.99398996 1.77118002 -1.99346998 0 P 0 
L 1.77118002 -1.99346998 1.7712 -1.99295 0 P 0 
L 1.7712 -1.99295 1.7712 -1.99293002 0 P 0 
L 1.7712 -1.99293002 1.77118996 -1.99286998 0 P 0 
L 1.77118996 -1.99286998 1.77118002 -1.99286004 0 P 0 
L 1.77118002 -1.99286004 1.77118002 -1.99283996 0 P 0 
L 1.77118002 -1.99283996 1.77111004 -1.99276998 0 P 0 
L 1.77111004 -1.99276998 1.77106998 -1.99275 0 P 0 
L 1.77106998 -1.99275 1.77106004 -1.99273996 0 P 0 
L 1.77106004 -1.99273996 1.771 -1.99273002 0 P 0 
L 1.771 -1.99273002 1.77098002 -1.99273002 0 P 0 
L 1.77098002 -1.99273002 1.76301004 -1.99265 0 P 0 
L 1.76301004 -1.99265 1.75401998 -1.99261004 0 P 0 
L 1.75401998 -1.99261004 1.74333002 -1.9927 0 P 0 
L 1.74333002 -1.9927 1.71546004 -1.99298996 0 P 0 
L 1.71546004 -1.99298996 1.71236998 -2.00646998 0 P 0 
L 1.71236998 -2.00646998 1.70873996 -2.02078002 0 P 0 
L 1.70873996 -2.02078002 1.70233996 -2.04308002 0 P 0 
L 1.70233996 -2.04308002 1.69505 -2.0678 0 P 0 
L 1.69505 -2.0678 1.69501998 -2.06788002 0 P 0 
L 1.69501998 -2.06788002 1.69498996 -2.06795 0 P 0 
L 1.69498996 -2.06795 1.69495 -2.06801998 0 P 0 
L 1.69495 -2.06801998 1.69485 -2.06816004 0 P 0 
L 1.69485 -2.06816004 1.69478996 -2.06821998 0 P 0 
L 1.69478996 -2.06821998 1.69466998 -2.06831998 0 P 0 
L 1.69466998 -2.06831998 1.69453002 -2.0684 0 P 0 
L 1.69453002 -2.0684 1.69445 -2.06843002 0 P 0 
L 1.69445 -2.06843002 1.69438002 -2.06846004 0 P 0 
L 1.69438002 -2.06846004 1.69428996 -2.06846998 0 P 0 
L 1.69428996 -2.06846998 1.69421004 -2.06848996 0 P 0 
L 1.69421004 -2.06848996 1.69406998 -2.06848996 0 P 0 
L 1.69406998 -2.06848996 1.69395 -2.06846998 0 P 0 
L 1.69395 -2.06846998 1.69383002 -2.06843002 0 P 0 
L 1.69383002 -2.06843002 1.69373002 -2.06836998 0 P 0 
L 1.69373002 -2.06836998 1.69363002 -2.06828996 0 P 0 
L 1.69363002 -2.06828996 1.69358996 -2.06823996 0 P 0 
L 1.69358996 -2.06823996 1.69355 -2.0682 0 P 0 
L 1.69355 -2.0682 1.69351998 -2.06815 0 P 0 
L 1.69351998 -2.06815 1.69346004 -2.06803996 0 P 0 
L 1.69346004 -2.06803996 1.69343996 -2.06798002 0 P 0 
L 1.69343996 -2.06798002 1.68523002 -2.03878002 0 P 0 
L 1.68523002 -2.03878002 1.67806998 -2.01291998 0 P 0 
L 1.67806998 -2.01291998 1.67496004 -2.00031004 0 P 0 
L 1.67496004 -2.00031004 1.67323002 -1.99243996 0 P 0 
L 1.67323002 -1.99243996 1.61388002 -1.99243996 0 P 0 
L 1.61388002 -1.99243996 1.61928996 -2.00628002 0 P 0 
L 1.35018002 -2.08345 1.39488996 -2.08345 0 P 0 
L 1.35026004 -2.08245 1.39586004 -2.08245 0 P 0 
L 1.35041004 -2.08145 1.39708996 -2.08145 0 P 0 
L 1.35058996 -2.08045 1.39853002 -2.08045 0 P 0 
L 1.35083996 -2.07945 1.40031998 -2.07945 0 P 0 
L 1.35116998 -2.07845 1.40271004 -2.07845 0 P 0 
L 1.35158002 -2.07745 1.40561998 -2.07745 0 P 0 
L 1.35203002 -2.07645 1.4092 -2.07645 0 P 0 
L 1.35248002 -2.07545 1.41288996 -2.07545 0 P 0 
L 1.35293002 -2.07445 1.4164 -2.07445 0 P 0 
L 1.35338996 -2.07345 1.41975 -2.07345 0 P 0 
L 1.35393996 -2.07245 1.42293996 -2.07245 0 P 0 
L 1.35448996 -2.07145 1.42606998 -2.07145 0 P 0 
L 1.35505 -2.07045 1.47843002 -2.07045 0 P 0 
L 1.3557 -2.06945 1.47846998 -2.06945 0 P 0 
L 1.35635 -2.06845 1.47851998 -2.06845 0 P 0 
L 1.35701998 -2.06745 1.47856998 -2.06745 0 P 0 
L 1.35776998 -2.06645 1.47861004 -2.06645 0 P 0 
L 1.29346998 -2.00516004 1.33388996 -2.00516004 0 P 0 
L 1.29448996 -2.00416004 1.33385 -2.00416004 0 P 0 
L 1.29551004 -2.00316004 1.33381004 -2.00316004 0 P 0 
L 1.29653996 -2.00216004 1.33376004 -2.00216004 0 P 0 
L 1.29756004 -2.00116004 1.33371004 -2.00116004 0 P 0 
L 1.29861998 -2.00016004 1.33366004 -2.00016004 0 P 0 
L 1.29973002 -1.99916004 1.3336 -1.99916004 0 P 0 
L 1.30101004 -1.99816004 1.33355 -1.99816004 0 P 0 
L 1.30238996 -1.99716004 1.3335 -1.99716004 0 P 0 
L 1.30393996 -1.99616004 1.33345 -1.99616004 0 P 0 
L 1.30571004 -1.99516004 1.33338996 -1.99516004 0 P 0 
L 1.3077 -1.99416004 1.33333002 -1.99416004 0 P 0 
L 1.31001004 -1.99316004 1.33328002 -1.99316004 0 P 0 
L 1.31288002 -1.99216004 1.33321998 -1.99216004 0 P 0 
L 1.31688996 -1.99116004 1.33316004 -1.99116004 0 P 0 
L 1.39798996 -1.98971998 1.39326998 -1.99043002 0 P 0 
L 1.39326998 -1.99043002 1.38806998 -1.9913 0 P 0 
L 1.38806998 -1.9913 1.38316004 -1.9922 0 P 0 
L 1.38316004 -1.9922 1.37946004 -1.99296998 0 P 0 
L 1.37946004 -1.99296998 1.3718 -1.99466998 0 P 0 
L 1.3718 -1.99466998 1.36896004 -2.01553996 0 P 0 
L 1.36896004 -2.01553996 1.36791004 -2.02358996 0 P 0 
L 1.36791004 -2.02358996 1.36708002 -2.03043002 0 P 0 
L 1.36708002 -2.03043002 1.36638996 -2.03646004 0 P 0 
L 1.36638996 -2.03646004 1.36638002 -2.03648996 0 P 0 
L 1.36638002 -2.03648996 1.36638996 -2.03653002 0 P 0 
L 1.36638996 -2.03653002 1.36638996 -2.03656998 0 P 0 
L 1.36638996 -2.03656998 1.3664 -2.03663996 0 P 0 
L 1.3664 -2.03663996 1.36641998 -2.03666998 0 P 0 
L 1.36641998 -2.03666998 1.36643002 -2.03671004 0 P 0 
L 1.36643002 -2.03671004 1.36648996 -2.0368 0 P 0 
L 1.36648996 -2.0368 1.36656004 -2.03686004 0 P 0 
L 1.36656004 -2.03686004 1.3666 -2.03688996 0 P 0 
L 1.3666 -2.03688996 1.36663002 -2.03691004 0 P 0 
L 1.36663002 -2.03691004 1.36666004 -2.03691004 0 P 0 
L 1.36666004 -2.03691004 1.36671004 -2.03693002 0 P 0 
L 1.36671004 -2.03693002 1.36676998 -2.03693002 0 P 0 
L 1.36676998 -2.03693002 1.36685 -2.03691998 0 P 0 
L 1.36685 -2.03691998 1.36895 -2.03628002 0 P 0 
L 1.36895 -2.03628002 1.37143002 -2.03545 0 P 0 
L 1.37143002 -2.03545 1.37428996 -2.03441004 0 P 0 
L 1.37428996 -2.03441004 1.38346004 -2.03126998 0 P 0 
L 1.38346004 -2.03126998 1.39251998 -2.02891998 0 P 0 
L 1.39251998 -2.02891998 1.40156004 -2.02731998 0 P 0 
L 1.40156004 -2.02731998 1.41068002 -2.02643996 0 P 0 
L 1.41068002 -2.02643996 1.41566998 -2.02628002 0 P 0 
L 1.41566998 -2.02628002 1.42066004 -2.02633996 0 P 0 
L 1.42066004 -2.02633996 1.42221004 -2.02646998 0 P 0 
L 1.42221004 -2.02646998 1.42375 -2.02671998 0 P 0 
L 1.42375 -2.02671998 1.42525 -2.0271 0 P 0 
L 1.42525 -2.0271 1.42671998 -2.02761004 0 P 0 
L 1.42671998 -2.02761004 1.42706004 -2.02776004 0 P 0 
L 1.42706004 -2.02776004 1.42738002 -2.02793002 0 P 0 
L 1.42738002 -2.02793002 1.42768002 -2.02813996 0 P 0 
L 1.42768002 -2.02813996 1.42796998 -2.02836004 0 P 0 
L 1.42796998 -2.02836004 1.42823002 -2.02861004 0 P 0 
L 1.42823002 -2.02861004 1.42848002 -2.02888996 0 P 0 
L 1.42848002 -2.02888996 1.4287 -2.02918002 0 P 0 
L 1.4287 -2.02918002 1.42888996 -2.02948996 0 P 0 
L 1.42888996 -2.02948996 1.42906004 -2.02981004 0 P 0 
L 1.42906004 -2.02981004 1.4292 -2.03015 0 P 0 
L 1.4292 -2.03015 1.42931998 -2.0305 0 P 0 
L 1.42931998 -2.0305 1.4294 -2.03086004 0 P 0 
L 1.4294 -2.03086004 1.42945 -2.03121998 0 P 0 
L 1.42945 -2.03121998 1.42946998 -2.03158002 0 P 0 
L 1.42946998 -2.03158002 1.42946004 -2.03195 0 P 0 
L 1.42946004 -2.03195 1.42941998 -2.03231004 0 P 0 
L 1.42941998 -2.03231004 1.42935 -2.03266998 0 P 0 
L 1.42935 -2.03266998 1.42925 -2.03301998 0 P 0 
L 1.42925 -2.03301998 1.42911998 -2.03336004 0 P 0 
L 1.42911998 -2.03336004 1.42896004 -2.03368996 0 P 0 
L 1.42896004 -2.03368996 1.42875 -2.03405 0 P 0 
L 1.42875 -2.03405 1.42851004 -2.03438996 0 P 0 
L 1.42851004 -2.03438996 1.42825 -2.03471004 0 P 0 
L 1.42825 -2.03471004 1.42796004 -2.03501004 0 P 0 
L 1.42796004 -2.03501004 1.42765 -2.03528996 0 P 0 
L 1.42765 -2.03528996 1.42731998 -2.03553996 0 P 0 
L 1.42731998 -2.03553996 1.42696998 -2.03576004 0 P 0 
L 1.42696998 -2.03576004 1.4266 -2.03596004 0 P 0 
L 1.4266 -2.03596004 1.41951004 -2.03906004 0 P 0 
L 1.41951004 -2.03906004 1.4109 -2.04208996 0 P 0 
L 1.4109 -2.04208996 1.40178002 -2.04451998 0 P 0 
L 1.40178002 -2.04451998 1.3878 -2.04818996 0 P 0 
L 1.3878 -2.04818996 1.38176998 -2.05015 0 P 0 
L 1.38176998 -2.05015 1.3758 -2.05243002 0 P 0 
L 1.3758 -2.05243002 1.37086998 -2.0546 0 P 0 
L 1.37086998 -2.0546 1.36603996 -2.05708002 0 P 0 
L 1.36603996 -2.05708002 1.36356004 -2.05856004 0 P 0 
L 1.36356004 -2.05856004 1.36118996 -2.06023002 0 P 0 
L 1.36118996 -2.06023002 1.35895 -2.06206004 0 P 0 
L 1.35895 -2.06206004 1.35805 -2.06291004 0 P 0 
L 1.35805 -2.06291004 1.35721998 -2.06385 0 P 0 
L 1.35721998 -2.06385 1.35518996 -2.06655 0 P 0 
L 1.35518996 -2.06655 1.3532 -2.06961998 0 P 0 
L 1.3532 -2.06961998 1.35156004 -2.07263002 0 P 0 
L 1.35156004 -2.07263002 1.34951004 -2.07718002 0 P 0 
L 1.34951004 -2.07718002 1.34911004 -2.07825 0 P 0 
L 1.34911004 -2.07825 1.34878996 -2.07935 0 P 0 
L 1.34878996 -2.07935 1.34853002 -2.08046998 0 P 0 
L 1.34853002 -2.08046998 1.34825 -2.08238002 0 P 0 
L 1.34825 -2.08238002 1.34811998 -2.08431004 0 P 0 
L 1.34811998 -2.08431004 1.348 -2.09128996 0 P 0 
L 1.348 -2.09128996 1.3481 -2.09761004 0 P 0 
L 1.3481 -2.09761004 1.34823002 -2.09961004 0 P 0 
L 1.34823002 -2.09961004 1.34846998 -2.10161004 0 P 0 
L 1.34846998 -2.10161004 1.34876998 -2.10321998 0 P 0 
L 1.34876998 -2.10321998 1.3492 -2.10478996 0 P 0 
L 1.3492 -2.10478996 1.3498 -2.10648996 0 P 0 
L 1.3498 -2.10648996 1.3505 -2.10815 0 P 0 
L 1.3505 -2.10815 1.35178996 -2.11066004 0 P 0 
L 1.35178996 -2.11066004 1.35328002 -2.11305 0 P 0 
L 1.35328002 -2.11305 1.35496998 -2.1153 0 P 0 
L 1.35496998 -2.1153 1.35685 -2.1174 0 P 0 
L 1.35685 -2.1174 1.35891998 -2.11933996 0 P 0 
L 1.35891998 -2.11933996 1.36126998 -2.12121998 0 P 0 
L 1.36126998 -2.12121998 1.36373996 -2.12293002 0 P 0 
L 1.36373996 -2.12293002 1.36633002 -2.12446004 0 P 0 
L 1.36633002 -2.12446004 1.36901004 -2.1258 0 P 0 
L 1.36901004 -2.1258 1.3718 -2.12695 0 P 0 
L 1.3718 -2.12695 1.37578996 -2.12828002 0 P 0 
L 1.37578996 -2.12828002 1.37986998 -2.12928996 0 P 0 
L 1.37986998 -2.12928996 1.38401998 -2.12998996 0 P 0 
L 1.38401998 -2.12998996 1.3882 -2.13036004 0 P 0 
L 1.3882 -2.13036004 1.39443002 -2.13045 0 P 0 
L 1.39443002 -2.13045 1.40066004 -2.13006998 0 P 0 
L 1.40066004 -2.13006998 1.40685 -2.12923002 0 P 0 
L 1.40685 -2.12923002 1.41371004 -2.12801998 0 P 0 
L 1.41371004 -2.12801998 1.41583002 -2.12081004 0 P 0 
L 1.41583002 -2.12081004 1.41953996 -2.10798996 0 P 0 
L 1.41953996 -2.10798996 1.42135 -2.10126998 0 P 0 
L 1.42135 -2.10126998 1.42236998 -2.097 0 P 0 
L 1.42236998 -2.097 1.42238996 -2.09691004 0 P 0 
L 1.42238996 -2.09691004 1.4224 -2.09681998 0 P 0 
L 1.4224 -2.09681998 1.4224 -2.09673996 0 P 0 
L 1.4224 -2.09673996 1.42238002 -2.09656004 0 P 0 
L 1.42238002 -2.09656004 1.42235 -2.09648002 0 P 0 
L 1.42235 -2.09648002 1.42233002 -2.09638996 0 P 0 
L 1.42233002 -2.09638996 1.42225 -2.09623002 0 P 0 
L 1.42225 -2.09623002 1.4222 -2.09616004 0 P 0 
L 1.4222 -2.09616004 1.42213996 -2.09608996 0 P 0 
L 1.42213996 -2.09608996 1.42208996 -2.09601998 0 P 0 
L 1.42208996 -2.09601998 1.42203996 -2.09598996 0 P 0 
L 1.42203996 -2.09598996 1.42198996 -2.09595 0 P 0 
L 1.42198996 -2.09595 1.42188996 -2.09588996 0 P 0 
L 1.42188996 -2.09588996 1.42183002 -2.09586004 0 P 0 
L 1.42183002 -2.09586004 1.42178002 -2.09585 0 P 0 
L 1.42178002 -2.09585 1.42171998 -2.09583002 0 P 0 
L 1.42171998 -2.09583002 1.42166004 -2.09581998 0 P 0 
L 1.42166004 -2.09581998 1.42153996 -2.09581998 0 P 0 
L 1.42153996 -2.09581998 1.41978002 -2.09591004 0 P 0 
L 1.41978002 -2.09591004 1.41763996 -2.09615 0 P 0 
L 1.41763996 -2.09615 1.41521998 -2.09658002 0 P 0 
L 1.41521998 -2.09658002 1.4107 -2.09733002 0 P 0 
L 1.4107 -2.09733002 1.40613002 -2.09775 0 P 0 
L 1.40613002 -2.09775 1.40481004 -2.09778002 0 P 0 
L 1.40481004 -2.09778002 1.40348996 -2.09771998 0 P 0 
L 1.40348996 -2.09771998 1.40216998 -2.09756004 0 P 0 
L 1.40216998 -2.09756004 1.40086998 -2.0973 0 P 0 
L 1.40086998 -2.0973 1.39958996 -2.09695 0 P 0 
L 1.39958996 -2.09695 1.39895 -2.09671998 0 P 0 
L 1.39895 -2.09671998 1.39831998 -2.09643002 0 P 0 
L 1.39831998 -2.09643002 1.39773002 -2.0961 0 P 0 
L 1.39773002 -2.0961 1.39716004 -2.09571004 0 P 0 
L 1.39716004 -2.09571004 1.39663002 -2.09528002 0 P 0 
L 1.39663002 -2.09528002 1.39613996 -2.0948 0 P 0 
L 1.39613996 -2.0948 1.39568002 -2.09428002 0 P 0 
L 1.39568002 -2.09428002 1.39533996 -2.09381998 0 P 0 
L 1.39533996 -2.09381998 1.39505 -2.09333996 0 P 0 
L 1.39505 -2.09333996 1.39478996 -2.09281998 0 P 0 
L 1.39478996 -2.09281998 1.39456998 -2.09228996 0 P 0 
L 1.39456998 -2.09228996 1.3944 -2.09173996 0 P 0 
L 1.3944 -2.09173996 1.39428002 -2.09118996 0 P 0 
L 1.39428002 -2.09118996 1.39421004 -2.09061998 0 P 0 
L 1.39421004 -2.09061998 1.39418002 -2.09003996 0 P 0 
L 1.39418002 -2.09003996 1.39421004 -2.08943002 0 P 0 
L 1.39421004 -2.08943002 1.39428002 -2.08883002 0 P 0 
L 1.39428002 -2.08883002 1.39441004 -2.08823002 0 P 0 
L 1.39441004 -2.08823002 1.3946 -2.08765 0 P 0 
L 1.3946 -2.08765 1.39483002 -2.08708002 0 P 0 
L 1.39483002 -2.08708002 1.39511004 -2.08653996 0 P 0 
L 1.39511004 -2.08653996 1.39555 -2.08583996 0 P 0 
L 1.39555 -2.08583996 1.39603996 -2.08518002 0 P 0 
L 1.39603996 -2.08518002 1.39658002 -2.08456004 0 P 0 
L 1.39658002 -2.08456004 1.39716004 -2.08396998 0 P 0 
L 1.39716004 -2.08396998 1.39778002 -2.08343002 0 P 0 
L 1.39778002 -2.08343002 1.39878996 -2.08266998 0 P 0 
L 1.39878996 -2.08266998 1.39985 -2.08196998 0 P 0 
L 1.39985 -2.08196998 1.40096004 -2.08135 0 P 0 
L 1.40096004 -2.08135 1.40211998 -2.08081004 0 P 0 
L 1.40211998 -2.08081004 1.40503002 -2.07971004 0 P 0 
L 1.40503002 -2.07971004 1.40801998 -2.07881998 0 P 0 
L 1.40801998 -2.07881998 1.41128996 -2.07796004 0 P 0 
L 1.41128996 -2.07796004 1.41506004 -2.07691998 0 P 0 
L 1.41506004 -2.07691998 1.41871998 -2.07585 0 P 0 
L 1.41871998 -2.07585 1.42165 -2.07495 0 P 0 
L 1.42165 -2.07495 1.42791998 -2.07295 0 P 0 
L 1.42791998 -2.07295 1.42731998 -2.08241004 0 P 0 
L 1.42731998 -2.08241004 1.42701004 -2.08708002 0 P 0 
L 1.42701004 -2.08708002 1.42658002 -2.09353996 0 P 0 
L 1.42658002 -2.09353996 1.4261 -2.10055 0 P 0 
L 1.4261 -2.10055 1.42566998 -2.10706004 0 P 0 
L 1.42566998 -2.10706004 1.42525 -2.11306004 0 P 0 
L 1.42525 -2.11306004 1.42491998 -2.11851998 0 P 0 
L 1.42491998 -2.11851998 1.42466004 -2.1231 0 P 0 
L 1.42466004 -2.1231 1.42461004 -2.12471004 0 P 0 
L 1.42461004 -2.12471004 1.4246 -2.12716004 0 P 0 
L 1.4246 -2.12716004 1.47893002 -2.12716004 0 P 0 
L 1.47893002 -2.12716004 1.47893002 -2.11358002 0 P 0 
L 1.47893002 -2.11358002 1.47905 -2.10616998 0 P 0 
L 1.47905 -2.10616998 1.47943996 -2.09385 0 P 0 
L 1.47943996 -2.09385 1.48 -2.07968996 0 P 0 
L 1.48 -2.07968996 1.48066004 -2.0655 0 P 0 
L 1.48066004 -2.0655 1.4813 -2.05168996 0 P 0 
L 1.4813 -2.05168996 1.48175 -2.03873996 0 P 0 
L 1.48175 -2.03873996 1.48201998 -2.02785 0 P 0 
L 1.48201998 -2.02785 1.48191998 -2.02286004 0 P 0 
L 1.48191998 -2.02286004 1.48165 -2.01995 0 P 0 
L 1.48165 -2.01995 1.48115 -2.01708002 0 P 0 
L 1.48115 -2.01708002 1.48043996 -2.01425 0 P 0 
L 1.48043996 -2.01425 1.47951004 -2.01146998 0 P 0 
L 1.47951004 -2.01146998 1.47866998 -2.00946998 0 P 0 
L 1.47866998 -2.00946998 1.47768002 -2.00753996 0 P 0 
L 1.47768002 -2.00753996 1.47655 -2.00568002 0 P 0 
L 1.47655 -2.00568002 1.47528002 -2.00391998 0 P 0 
L 1.47528002 -2.00391998 1.47388002 -2.00225 0 P 0 
L 1.47388002 -2.00225 1.47228996 -2.00063002 0 P 0 
L 1.47228996 -2.00063002 1.4706 -1.99911998 0 P 0 
L 1.4706 -1.99911998 1.4688 -1.99773002 0 P 0 
L 1.4688 -1.99773002 1.46691004 -1.99648002 0 P 0 
L 1.46691004 -1.99648002 1.46491998 -1.99535 0 P 0 
L 1.46491998 -1.99535 1.46098996 -1.99351004 0 P 0 
L 1.46098996 -1.99351004 1.45693002 -1.99196998 0 P 0 
L 1.45693002 -1.99196998 1.45276004 -1.99076004 0 P 0 
L 1.45276004 -1.99076004 1.44953996 -1.99006004 0 P 0 
L 1.44953996 -1.99006004 1.44628996 -1.98956004 0 P 0 
L 1.44628996 -1.98956004 1.44298002 -1.98923996 0 P 0 
L 1.44298002 -1.98923996 1.42695 -1.98856998 0 P 0 
L 1.42695 -1.98856998 1.41038996 -1.98865 0 P 0 
L 1.41038996 -1.98865 1.4042 -1.98901004 0 P 0 
L 1.4042 -1.98901004 1.39798996 -1.98971998 0 P 0 
L 1.35778996 -2.11545 1.4153 -2.11545 0 P 0 
L 1.35688996 -2.11445 1.41558996 -2.11445 0 P 0 
L 1.35608002 -2.11345 1.41588002 -2.11345 0 P 0 
L 1.35533002 -2.11245 1.41616998 -2.11245 0 P 0 
L 1.35463996 -2.11145 1.41646004 -2.11145 0 P 0 
L 1.35401004 -2.11045 1.41675 -2.11045 0 P 0 
L 1.35341004 -2.10945 1.41703996 -2.10945 0 P 0 
L 1.3529 -2.10845 1.41733002 -2.10845 0 P 0 
L 1.35238002 -2.10745 1.41761998 -2.10745 0 P 0 
L 1.35195 -2.10645 1.41788002 -2.10645 0 P 0 
L 1.35155 -2.10545 1.41816004 -2.10545 0 P 0 
L 1.3512 -2.10445 1.41841998 -2.10445 0 P 0 
L 1.35091004 -2.10345 1.41868996 -2.10345 0 P 0 
L 1.35066004 -2.10245 1.41896004 -2.10245 0 P 0 
L 1.35046998 -2.10145 1.41923002 -2.10145 0 P 0 
L 1.35033996 -2.10045 1.41948996 -2.10045 0 P 0 
L 1.35021998 -2.09945 1.40141004 -2.09945 0 P 0 
L 1.35016004 -2.09845 1.39791004 -2.09845 0 P 0 
L 1.3501 -2.09745 1.39616004 -2.09745 0 P 0 
L 1.35008002 -2.09645 1.39496004 -2.09645 0 P 0 
L 1.35006998 -2.09545 1.39406004 -2.09545 0 P 0 
L 1.35005 -2.09445 1.39338002 -2.09445 0 P 0 
L 1.35003996 -2.09345 1.39288002 -2.09345 0 P 0 
L 1.35001998 -2.09245 1.39253002 -2.09245 0 P 0 
L 1.35001004 -2.09145 1.3923 -2.09145 0 P 0 
L 1.35001998 -2.09045 1.3922 -2.09045 0 P 0 
L 1.35003002 -2.08945 1.3922 -2.08945 0 P 0 
L 1.35005 -2.08845 1.39231998 -2.08845 0 P 0 
L 1.35006998 -2.08745 1.39256004 -2.08745 0 P 0 
L 1.35008002 -2.08645 1.39293002 -2.08645 0 P 0 
L 1.3501 -2.08545 1.39343002 -2.08545 0 P 0 
L 1.35011004 -2.08445 1.39408996 -2.08445 0 P 0 
L 1.39438002 -2.12845 1.3883 -2.12836004 0 P 0 
L 1.3883 -2.12836004 1.38426998 -2.128 0 P 0 
L 1.38426998 -2.128 1.38028002 -2.12733002 0 P 0 
L 1.38028002 -2.12733002 1.37635 -2.12636004 0 P 0 
L 1.37635 -2.12636004 1.37248996 -2.12508002 0 P 0 
L 1.37248996 -2.12508002 1.36983996 -2.12398002 0 P 0 
L 1.36983996 -2.12398002 1.36728996 -2.1227 0 P 0 
L 1.36728996 -2.1227 1.36481998 -2.12123996 0 P 0 
L 1.36481998 -2.12123996 1.36246004 -2.11961004 0 P 0 
L 1.36246004 -2.11961004 1.36023002 -2.11781998 0 P 0 
L 1.36023002 -2.11781998 1.35828996 -2.116 0 P 0 
L 1.35828996 -2.116 1.35651998 -2.11403002 0 P 0 
L 1.35651998 -2.11403002 1.35493002 -2.11191004 0 P 0 
L 1.35493002 -2.11191004 1.35353002 -2.10966998 0 P 0 
L 1.35353002 -2.10966998 1.35231004 -2.10731004 0 P 0 
L 1.35231004 -2.10731004 1.35166998 -2.10576998 0 P 0 
L 1.35166998 -2.10576998 1.35111004 -2.1042 0 P 0 
L 1.35111004 -2.1042 1.35071998 -2.10276004 0 P 0 
L 1.35071998 -2.10276004 1.35045 -2.1013 0 P 0 
L 1.35045 -2.1013 1.35021998 -2.09943002 0 P 0 
L 1.35021998 -2.09943002 1.3501 -2.09753002 0 P 0 
L 1.3501 -2.09753002 1.35001004 -2.09128002 0 P 0 
L 1.35001004 -2.09128002 1.35011998 -2.0844 0 P 0 
L 1.35011998 -2.0844 1.35023996 -2.08258996 0 P 0 
L 1.35023996 -2.08258996 1.3505 -2.08083996 0 P 0 
L 1.3505 -2.08083996 1.35071998 -2.07985 0 P 0 
L 1.35071998 -2.07985 1.35101004 -2.07888002 0 P 0 
L 1.35101004 -2.07888002 1.35136004 -2.07793002 0 P 0 
L 1.35136004 -2.07793002 1.35335 -2.07351998 0 P 0 
L 1.35335 -2.07351998 1.35491998 -2.07065 0 P 0 
L 1.35491998 -2.07065 1.35683002 -2.0677 0 P 0 
L 1.35683002 -2.0677 1.35876998 -2.06511004 0 P 0 
L 1.35876998 -2.06511004 1.35948996 -2.0643 0 P 0 
L 1.35948996 -2.0643 1.36026998 -2.06356004 0 P 0 
L 1.36026998 -2.06356004 1.3624 -2.06181998 0 P 0 
L 1.3624 -2.06181998 1.36465 -2.06023996 0 P 0 
L 1.36465 -2.06023996 1.36701004 -2.05883002 0 P 0 
L 1.36701004 -2.05883002 1.37173002 -2.05641004 0 P 0 
L 1.37173002 -2.05641004 1.37656004 -2.05426998 0 P 0 
L 1.37656004 -2.05426998 1.38243002 -2.05203996 0 P 0 
L 1.38243002 -2.05203996 1.38836004 -2.0501 0 P 0 
L 1.38836004 -2.0501 1.4023 -2.04645 0 P 0 
L 1.4023 -2.04645 1.41148996 -2.044 0 P 0 
L 1.41148996 -2.044 1.42016998 -2.04095 0 P 0 
L 1.42016998 -2.04095 1.42016998 -2.04093996 0 P 0 
L 1.42016998 -2.04093996 1.42021004 -2.04093996 0 P 0 
L 1.42021004 -2.04093996 1.42023996 -2.04093002 0 P 0 
L 1.42023996 -2.04093002 1.42746998 -2.03776004 0 P 0 
L 1.42746998 -2.03776004 1.42753002 -2.03773002 0 P 0 
L 1.42753002 -2.03773002 1.42796998 -2.03748996 0 P 0 
L 1.42796998 -2.03748996 1.42846004 -2.03718996 0 P 0 
L 1.42846004 -2.03718996 1.42891998 -2.03683996 0 P 0 
L 1.42891998 -2.03683996 1.42935 -2.03646004 0 P 0 
L 1.42935 -2.03646004 1.42975 -2.03603996 0 P 0 
L 1.42975 -2.03603996 1.43011004 -2.0356 0 P 0 
L 1.43011004 -2.0356 1.43016004 -2.03553002 0 P 0 
L 1.43016004 -2.03553002 1.4299 -2.03535 0 P 0 
L 1.4299 -2.03535 1.43028002 -2.03535 0 P 0 
L 1.43028002 -2.03535 1.43043996 -2.03513002 0 P 0 
L 1.43043996 -2.03513002 1.43048002 -2.03506004 0 P 0 
L 1.43048002 -2.03506004 1.43041998 -2.03501998 0 P 0 
L 1.43041998 -2.03501998 1.4305 -2.03501998 0 P 0 
L 1.4305 -2.03501998 1.43073002 -2.03463002 0 P 0 
L 1.43073002 -2.03463002 1.43096004 -2.03415 0 P 0 
L 1.43096004 -2.03415 1.43115 -2.03365 0 P 0 
L 1.43115 -2.03365 1.4313 -2.03313002 0 P 0 
L 1.4313 -2.03313002 1.4314 -2.03261004 0 P 0 
L 1.4314 -2.03261004 1.43146004 -2.03208002 0 P 0 
L 1.43146004 -2.03208002 1.43146998 -2.03155 0 P 0 
L 1.43146998 -2.03155 1.43143996 -2.03101004 0 P 0 
L 1.43143996 -2.03101004 1.43143002 -2.03093002 0 P 0 
L 1.43143002 -2.03093002 1.43136004 -2.03048996 0 P 0 
L 1.43136004 -2.03048996 1.43125 -2.02996998 0 P 0 
L 1.43125 -2.02996998 1.43108002 -2.02946004 0 P 0 
L 1.43108002 -2.02946004 1.43086998 -2.02896004 0 P 0 
L 1.43086998 -2.02896004 1.43063002 -2.02848996 0 P 0 
L 1.43063002 -2.02848996 1.43033996 -2.02803996 0 P 0 
L 1.43033996 -2.02803996 1.43001998 -2.02761004 0 P 0 
L 1.43001998 -2.02761004 1.42966004 -2.02721004 0 P 0 
L 1.42966004 -2.02721004 1.42928002 -2.02685 0 P 0 
L 1.42928002 -2.02685 1.42886004 -2.02651998 0 P 0 
L 1.42886004 -2.02651998 1.42841998 -2.02623002 0 P 0 
L 1.42841998 -2.02623002 1.42795 -2.02596998 0 P 0 
L 1.42795 -2.02596998 1.42746004 -2.02575 0 P 0 
L 1.42746004 -2.02575 1.42583002 -2.02518002 0 P 0 
L 1.42583002 -2.02518002 1.42416004 -2.02476004 0 P 0 
L 1.42416004 -2.02476004 1.42245 -2.02448002 0 P 0 
L 1.42245 -2.02448002 1.42075 -2.02435 0 P 0 
L 1.42075 -2.02435 1.41565 -2.02428002 0 P 0 
L 1.41565 -2.02428002 1.4156 -2.02428002 0 P 0 
L 1.4156 -2.02428002 1.41055 -2.02445 0 P 0 
L 1.41055 -2.02445 1.41048002 -2.02445 0 P 0 
L 1.41048002 -2.02445 1.40128996 -2.02533996 0 P 0 
L 1.40128996 -2.02533996 1.39208996 -2.02696998 0 P 0 
L 1.39208996 -2.02696998 1.38288002 -2.02936004 0 P 0 
L 1.38288002 -2.02936004 1.37363002 -2.03251998 0 P 0 
L 1.37363002 -2.03251998 1.37076998 -2.03356004 0 P 0 
L 1.37076998 -2.03356004 1.36865 -2.03426998 0 P 0 
L 1.36865 -2.03426998 1.36906004 -2.03066998 0 P 0 
L 1.36906004 -2.03066998 1.36988996 -2.02383996 0 P 0 
L 1.36988996 -2.02383996 1.37095 -2.01581004 0 P 0 
L 1.37095 -2.01581004 1.37358996 -1.99631998 0 P 0 
L 1.37358996 -1.99631998 1.37988002 -1.99491998 0 P 0 
L 1.37988002 -1.99491998 1.38353996 -1.99416998 0 P 0 
L 1.38353996 -1.99416998 1.38841998 -1.99326998 0 P 0 
L 1.38841998 -1.99326998 1.39358002 -1.9924 0 P 0 
L 1.39358002 -1.9924 1.39825 -1.9917 0 P 0 
L 1.39825 -1.9917 1.40436998 -1.991 0 P 0 
L 1.40436998 -1.991 1.41045 -1.99065 0 P 0 
L 1.41045 -1.99065 1.42691004 -1.99056998 0 P 0 
L 1.42691004 -1.99056998 1.44283996 -1.99123996 0 P 0 
L 1.44283996 -1.99123996 1.44603996 -1.99153996 0 P 0 
L 1.44603996 -1.99153996 1.44918002 -1.99203002 0 P 0 
L 1.44918002 -1.99203002 1.45226004 -1.9927 0 P 0 
L 1.45226004 -1.9927 1.4563 -1.99386998 0 P 0 
L 1.4563 -1.99386998 1.46021004 -1.99535 0 P 0 
L 1.46021004 -1.99535 1.464 -1.99713002 0 P 0 
L 1.464 -1.99713002 1.46586004 -1.99818996 0 P 0 
L 1.46586004 -1.99818996 1.46763996 -1.99936004 0 P 0 
L 1.46763996 -1.99936004 1.46931998 -2.00066004 0 P 0 
L 1.46931998 -2.00066004 1.47091004 -2.00206998 0 P 0 
L 1.47091004 -2.00206998 1.47238996 -2.00358996 0 P 0 
L 1.47238996 -2.00358996 1.4737 -2.00515 0 P 0 
L 1.4737 -2.00515 1.47488002 -2.00678996 0 P 0 
L 1.47488002 -2.00678996 1.47593996 -2.00851004 0 P 0 
L 1.47593996 -2.00851004 1.47686004 -2.01031004 0 P 0 
L 1.47686004 -2.01031004 1.47763996 -2.01216998 0 P 0 
L 1.47763996 -2.01216998 1.47851998 -2.01481004 0 P 0 
L 1.47851998 -2.01481004 1.47918996 -2.01748996 0 P 0 
L 1.47918996 -2.01748996 1.47966004 -2.02021998 0 P 0 
L 1.47966004 -2.02021998 1.47993002 -2.02296998 0 P 0 
L 1.47993002 -2.02296998 1.48001998 -2.02783996 0 P 0 
L 1.48001998 -2.02783996 1.47975 -2.03868996 0 P 0 
L 1.47975 -2.03868996 1.4793 -2.05161004 0 P 0 
L 1.4793 -2.05161004 1.47866004 -2.06543002 0 P 0 
L 1.47866004 -2.06543002 1.47801004 -2.07961004 0 P 0 
L 1.47801004 -2.07961004 1.47743996 -2.09378996 0 P 0 
L 1.47743996 -2.09378996 1.47705 -2.10613002 0 P 0 
L 1.47705 -2.10613002 1.47693002 -2.11356004 0 P 0 
L 1.47693002 -2.11356004 1.47693002 -2.12516004 0 P 0 
L 1.47693002 -2.12516004 1.42661004 -2.12516004 0 P 0 
L 1.42661004 -2.12516004 1.42661004 -2.12473996 0 P 0 
L 1.42661004 -2.12473996 1.42666004 -2.12318002 0 P 0 
L 1.42666004 -2.12318002 1.42691004 -2.11863996 0 P 0 
L 1.42691004 -2.11863996 1.42725 -2.1132 0 P 0 
L 1.42725 -2.1132 1.42766004 -2.1072 0 P 0 
L 1.42766004 -2.1072 1.42766004 -2.10718996 0 P 0 
L 1.42766004 -2.10718996 1.4281 -2.10068996 0 P 0 
L 1.4281 -2.10068996 1.42858002 -2.09368002 0 P 0 
L 1.42858002 -2.09368002 1.42901004 -2.08721004 0 P 0 
L 1.42901004 -2.08721004 1.42901004 -2.0872 0 P 0 
L 1.42901004 -2.0872 1.42931004 -2.08256004 0 P 0 
L 1.42931004 -2.08256004 1.42991998 -2.07308002 0 P 0 
L 1.42991998 -2.07308002 1.42916004 -2.07136998 0 P 0 
L 1.42916004 -2.07136998 1.42731998 -2.07105 0 P 0 
L 1.42731998 -2.07105 1.42105 -2.07303996 0 P 0 
L 1.42105 -2.07303996 1.41815 -2.07393002 0 P 0 
L 1.41815 -2.07393002 1.41451004 -2.075 0 P 0 
L 1.41451004 -2.075 1.41076004 -2.07603002 0 P 0 
L 1.41076004 -2.07603002 1.40748002 -2.0769 0 P 0 
L 1.40748002 -2.0769 1.40438996 -2.07781004 0 P 0 
L 1.40438996 -2.07781004 1.40431998 -2.07783996 0 P 0 
L 1.40431998 -2.07783996 1.40133996 -2.07896998 0 P 0 
L 1.40133996 -2.07896998 1.40005 -2.07956998 0 P 0 
L 1.40005 -2.07956998 1.39881998 -2.08026004 0 P 0 
L 1.39881998 -2.08026004 1.39763996 -2.08103002 0 P 0 
L 1.39763996 -2.08103002 1.39651998 -2.08188002 0 P 0 
L 1.39651998 -2.08188002 1.39578996 -2.08251004 0 P 0 
L 1.39578996 -2.08251004 1.39573996 -2.08256004 0 P 0 
L 1.39573996 -2.08256004 1.3951 -2.08318996 0 P 0 
L 1.3951 -2.08318996 1.39446998 -2.08393002 0 P 0 
L 1.39446998 -2.08393002 1.3939 -2.08471004 0 P 0 
L 1.3939 -2.08471004 1.39336998 -2.08553996 0 P 0 
L 1.39336998 -2.08553996 1.39301004 -2.08623996 0 P 0 
L 1.39301004 -2.08623996 1.39271004 -2.08696998 0 P 0 
L 1.39271004 -2.08696998 1.39248002 -2.08771998 0 P 0 
L 1.39248002 -2.08771998 1.39231004 -2.08848996 0 P 0 
L 1.39231004 -2.08848996 1.39221004 -2.08926004 0 P 0 
L 1.39221004 -2.08926004 1.39218002 -2.09003996 0 P 0 
L 1.39218002 -2.09003996 1.39221004 -2.0908 0 P 0 
L 1.39221004 -2.0908 1.39231004 -2.09153002 0 P 0 
L 1.39231004 -2.09153002 1.39246998 -2.09226004 0 P 0 
L 1.39246998 -2.09226004 1.39268996 -2.09296998 0 P 0 
L 1.39268996 -2.09296998 1.39296004 -2.09365 0 P 0 
L 1.39296004 -2.09365 1.3933 -2.09431004 0 P 0 
L 1.3933 -2.09431004 1.39368996 -2.09493996 0 P 0 
L 1.39368996 -2.09493996 1.39411998 -2.09553996 0 P 0 
L 1.39411998 -2.09553996 1.39468996 -2.09618002 0 P 0 
L 1.39468996 -2.09618002 1.3953 -2.09678002 0 P 0 
L 1.3953 -2.09678002 1.39596004 -2.09731998 0 P 0 
L 1.39596004 -2.09731998 1.39666998 -2.0978 0 P 0 
L 1.39666998 -2.0978 1.39673996 -2.09783996 0 P 0 
L 1.39673996 -2.09783996 1.39741004 -2.09821998 0 P 0 
L 1.39741004 -2.09821998 1.39748996 -2.09825 0 P 0 
L 1.39748996 -2.09825 1.39818996 -2.09856998 0 P 0 
L 1.39818996 -2.09856998 1.39898996 -2.09886004 0 P 0 
L 1.39898996 -2.09886004 1.39906998 -2.09888002 0 P 0 
L 1.39906998 -2.09888002 1.40043996 -2.09888002 0 P 0 
L 1.40043996 -2.09888002 1.40033996 -2.09923002 0 P 0 
L 1.40033996 -2.09923002 1.40041998 -2.09925 0 P 0 
L 1.40041998 -2.09925 1.40186004 -2.09953002 0 P 0 
L 1.40186004 -2.09953002 1.40331004 -2.09971004 0 P 0 
L 1.40331004 -2.09971004 1.40478002 -2.09978002 0 P 0 
L 1.40478002 -2.09978002 1.40625 -2.09975 0 P 0 
L 1.40625 -2.09975 1.41096004 -2.09931004 0 P 0 
L 1.41096004 -2.09931004 1.41556998 -2.09855 0 P 0 
L 1.41556998 -2.09855 1.41791998 -2.09813002 0 P 0 
L 1.41791998 -2.09813002 1.41995 -2.09791004 0 P 0 
L 1.41995 -2.09791004 1.4201 -2.0979 0 P 0 
L 1.4201 -2.0979 1.41941004 -2.10078002 0 P 0 
L 1.41941004 -2.10078002 1.41761004 -2.10745 0 P 0 
L 1.41761004 -2.10745 1.41391004 -2.12025 0 P 0 
L 1.41391004 -2.12025 1.41215 -2.12626998 0 P 0 
L 1.41215 -2.12626998 1.40655 -2.12725 0 P 0 
L 1.40655 -2.12725 1.40046004 -2.12808002 0 P 0 
L 1.40046004 -2.12808002 1.39438002 -2.12845 0 P 0 
L 1.15303002 -2.08283002 1.20788996 -2.08283002 0 P 0 
L 1.15398996 -2.08183002 1.20795 -2.08183002 0 P 0 
L 1.15483002 -2.08083002 1.208 -2.08083002 0 P 0 
L 1.15555 -2.07983002 1.20805 -2.07983002 0 P 0 
L 1.15621998 -2.07883002 1.2081 -2.07883002 0 P 0 
L 1.15681998 -2.07783002 1.20816004 -2.07783002 0 P 0 
L 1.15733002 -2.07683002 1.20821004 -2.07683002 0 P 0 
L 1.15778996 -2.07583002 1.20826004 -2.07583002 0 P 0 
L 1.15818002 -2.07483002 1.20831004 -2.07483002 0 P 0 
L 1.15853996 -2.07383002 1.20836998 -2.07383002 0 P 0 
L 1.15881998 -2.07283002 1.20841998 -2.07283002 0 P 0 
L 1.1591 -2.07183002 1.20846998 -2.07183002 0 P 0 
L 1.15938002 -2.07083002 1.20853002 -2.07083002 0 P 0 
L 1.1596 -2.06983002 1.20858002 -2.06983002 0 P 0 
L 1.15981004 -2.06883002 1.20863996 -2.06883002 0 P 0 
L 1.16001004 -2.06783002 1.20868996 -2.06783002 0 P 0 
L 1.1602 -2.06683002 1.20875 -2.06683002 0 P 0 
L 1.16033996 -2.06583002 1.2088 -2.06583002 0 P 0 
L 1.16048996 -2.06483002 1.20886004 -2.06483002 0 P 0 
L 1.16063996 -2.06383002 1.20891998 -2.06383002 0 P 0 
L 1.16078002 -2.06283002 1.20896998 -2.06283002 0 P 0 
L 1.16088996 -2.06183002 1.20903002 -2.06183002 0 P 0 
L 1.16098996 -2.06083002 1.20908002 -2.06083002 0 P 0 
L 1.16108996 -2.05983002 1.20913996 -2.05983002 0 P 0 
L 1.16118002 -2.05883002 1.20918996 -2.05883002 0 P 0 
L 1.16128002 -2.05783002 1.20925 -2.05783002 0 P 0 
L 1.16133996 -2.05683002 1.2093 -2.05683002 0 P 0 
L 1.1614 -2.05583002 1.20936004 -2.05583002 0 P 0 
L 1.16146004 -2.05483002 1.20941004 -2.05483002 0 P 0 
L 1.16151998 -2.05383002 1.20946998 -2.05383002 0 P 0 
L 1.16158002 -2.05283002 1.20951998 -2.05283002 0 P 0 
L 1.16163996 -2.05183002 1.20958002 -2.05183002 0 P 0 
L 1.1617 -2.05083002 1.20963996 -2.05083002 0 P 0 
L 1.16175 -2.04983002 1.2097 -2.04983002 0 P 0 
L 1.16181004 -2.04883002 1.20975 -2.04883002 0 P 0 
L 1.16186998 -2.04783002 1.20981004 -2.04783002 0 P 0 
L 1.16193002 -2.04683002 1.20986998 -2.04683002 0 P 0 
L 1.16198996 -2.04583002 1.20993002 -2.04583002 0 P 0 
L 1.16205 -2.04483002 1.20998996 -2.04483002 0 P 0 
L 1.16211004 -2.04383002 1.21005 -2.04383002 0 P 0 
L 1.16215 -2.04283002 1.2101 -2.04283002 0 P 0 
L 1.1622 -2.04183002 1.21016004 -2.04183002 0 P 0 
L 1.16225 -2.04083002 1.21021998 -2.04083002 0 P 0 
L 1.16228996 -2.03983002 1.21028002 -2.03983002 0 P 0 
L 1.16233996 -2.03883002 1.21033996 -2.03883002 0 P 0 
L 1.16238002 -2.03783002 1.2104 -2.03783002 0 P 0 
L 1.16243002 -2.03683002 1.21046004 -2.03683002 0 P 0 
L 1.16246998 -2.03583002 1.21051004 -2.03583002 0 P 0 
L 1.16251998 -2.03483002 1.21056998 -2.03483002 0 P 0 
L 1.16256998 -2.03383002 1.21063996 -2.03383002 0 P 0 
L 1.16261004 -2.03283002 1.2107 -2.03283002 0 P 0 
L 1.16266004 -2.03183002 1.21076004 -2.03183002 0 P 0 
L 1.1627 -2.03083002 1.21083002 -2.03083002 0 P 0 
L 1.16015 -1.97631004 1.17066004 -1.97631004 0 P 0 
L 1.15961998 -1.97531004 1.17026004 -1.97531004 0 P 0 
L 1.1591 -1.97431004 1.16986998 -1.97431004 0 P 0 
L 1.15856998 -1.97331004 1.16946998 -1.97331004 0 P 0 
L 1.15803996 -1.97231004 1.16903002 -1.97231004 0 P 0 
L 1.15746998 -1.97131004 1.16858996 -1.97131004 0 P 0 
L 1.1569 -1.97031004 1.16815 -1.97031004 0 P 0 
L 1.15631998 -1.96931004 1.16771004 -1.96931004 0 P 0 
L 1.15573996 -1.96831004 1.16726998 -1.96831004 0 P 0 
L 1.15516004 -1.96731004 1.16681998 -1.96731004 0 P 0 
L 1.15458996 -1.96631004 1.16638002 -1.96631004 0 P 0 
L 1.15398002 -1.96531004 1.16593996 -1.96531004 0 P 0 
L 1.1533 -1.96431004 1.16548996 -1.96431004 0 P 0 
L 1.15261998 -1.96331004 1.16503002 -1.96331004 0 P 0 
L 1.15193996 -1.96231004 1.16448002 -1.96231004 0 P 0 
L 1.15126004 -1.96131004 1.16393002 -1.96131004 0 P 0 
L 1.15058002 -1.96031004 1.16338002 -1.96031004 0 P 0 
L 1.1499 -1.95931004 1.16283002 -1.95931004 0 P 0 
L 1.1491 -1.95831004 1.16228996 -1.95831004 0 P 0 
L 1.14831004 -1.95731004 1.16173996 -1.95731004 0 P 0 
L 1.14751004 -1.95631004 1.16118996 -1.95631004 0 P 0 
L 1.14671004 -1.95531004 1.16063996 -1.95531004 0 P 0 
L 1.14591998 -1.95431004 1.16008996 -1.95431004 0 P 0 
L 1.14511998 -1.95331004 1.15943996 -1.95331004 0 P 0 
L 1.1442 -1.95231004 1.15878002 -1.95231004 0 P 0 
L 1.14326998 -1.95131004 1.15811004 -1.95131004 0 P 0 
L 1.14233996 -1.95031004 1.15745 -1.95031004 0 P 0 
L 1.14141004 -1.94931004 1.15678002 -1.94931004 0 P 0 
L 1.14048996 -1.94831004 1.15611998 -1.94831004 0 P 0 
L 1.1395 -1.94731004 1.15545 -1.94731004 0 P 0 
L 1.13843002 -1.94631004 1.15478996 -1.94631004 0 P 0 
L 1.13736004 -1.94531004 1.15411998 -1.94531004 0 P 0 
L 1.13628996 -1.94431004 1.15333002 -1.94431004 0 P 0 
L 1.13521004 -1.94331004 1.15253002 -1.94331004 0 P 0 
L 1.13413996 -1.94231004 1.15173996 -1.94231004 0 P 0 
L 1.13306998 -1.94131004 1.15093996 -1.94131004 0 P 0 
L 1.132 -1.94031004 1.15013996 -1.94031004 0 P 0 
L 1.13081004 -1.93931004 1.14935 -1.93931004 0 P 0 
L 1.12958002 -1.93831004 1.14855 -1.93831004 0 P 0 
L 1.12833996 -1.93731004 1.14775 -1.93731004 0 P 0 
L 1.1271 -1.93631004 1.14688996 -1.93631004 0 P 0 
L 1.12586004 -1.93531004 1.14593996 -1.93531004 0 P 0 
L 1.12461998 -1.93431004 1.14498996 -1.93431004 0 P 0 
L 1.12338002 -1.93331004 1.14405 -1.93331004 0 P 0 
L 1.12203002 -1.93231004 1.1431 -1.93231004 0 P 0 
L 1.1206 -1.93131004 1.14216004 -1.93131004 0 P 0 
L 1.11916004 -1.93031004 1.14121004 -1.93031004 0 P 0 
L 1.11771998 -1.92931004 1.14026998 -1.92931004 0 P 0 
L 1.11628996 -1.92831004 1.13931998 -1.92831004 0 P 0 
L 1.11483996 -1.92731004 1.13838002 -1.92731004 0 P 0 
L 1.11338996 -1.92631004 1.13743002 -1.92631004 0 P 0 
L 1.11171998 -1.92531004 1.13648996 -1.92531004 0 P 0 
L 1.11005 -1.92431004 1.13538002 -1.92431004 0 P 0 
L 1.10838002 -1.92331004 1.13426998 -1.92331004 0 P 0 
L 1.1067 -1.92231004 1.13315 -1.92231004 0 P 0 
L 1.10503002 -1.92131004 1.13203002 -1.92131004 0 P 0 
L 1.10336004 -1.92031004 1.13091998 -1.92031004 0 P 0 
L 1.1015 -1.91931004 1.1298 -1.91931004 0 P 0 
L 1.09955 -1.91831004 1.12868002 -1.91831004 0 P 0 
L 1.16275 -2.02983002 1.21088996 -2.02983002 0 P 0 
L 1.16278996 -2.02883002 1.21095 -2.02883002 0 P 0 
L 1.16283996 -2.02783002 1.21101004 -2.02783002 0 P 0 
L 1.16226998 -2.02683002 1.21108002 -2.02683002 0 P 0 
L 1.16153996 -2.02583002 1.21113996 -2.02583002 0 P 0 
L 1.15846004 -2.02483002 1.2112 -2.02483002 0 P 0 
L 1.10036004 -2.00383002 1.21255 -2.00383002 0 P 0 
L 1.10226004 -2.00283002 1.2126 -2.00283002 0 P 0 
L 1.10433996 -2.00183002 1.21266998 -2.00183002 0 P 0 
L 1.1065 -2.00083002 1.21273002 -2.00083002 0 P 0 
L 1.10886998 -1.99983002 1.21278996 -1.99983002 0 P 0 
L 1.11138002 -1.99883002 1.21285 -1.99883002 0 P 0 
L 1.11436998 -1.99783002 1.21288002 -1.99783002 0 P 0 
L 1.11748996 -1.99683002 1.21255 -1.99683002 0 P 0 
L 1.12061998 -1.99583002 1.2089 -1.99583002 0 P 0 
L 1.12433996 -1.99483002 1.2036 -1.99483002 0 P 0 
L 1.12863996 -1.99383002 1.19728002 -1.99383002 0 P 0 
L 1.13295 -1.99283002 1.19096998 -1.99283002 0 P 0 
L 1.13985 -1.99183002 1.18111998 -1.99183002 0 P 0 
L 1.14948002 -1.99083002 1.1651 -1.99083002 0 P 0 
L 1.24218002 -2.08316004 1.29143996 -2.08316004 0 P 0 
L 1.24223002 -2.08216004 1.29151004 -2.08216004 0 P 0 
L 1.24228002 -2.08116004 1.29158996 -2.08116004 0 P 0 
L 1.24233996 -2.08016004 1.29166004 -2.08016004 0 P 0 
L 1.24238996 -2.07916004 1.29173002 -2.07916004 0 P 0 
L 1.24245 -2.07816004 1.29181004 -2.07816004 0 P 0 
L 1.2425 -2.07716004 1.29188002 -2.07716004 0 P 0 
L 1.24256004 -2.07616004 1.29195 -2.07616004 0 P 0 
L 1.24261004 -2.07516004 1.29203002 -2.07516004 0 P 0 
L 1.24266998 -2.07416004 1.2921 -2.07416004 0 P 0 
L 1.24271998 -2.07316004 1.29216998 -2.07316004 0 P 0 
L 1.24278002 -2.07216004 1.29223996 -2.07216004 0 P 0 
L 1.24283002 -2.07116004 1.29231998 -2.07116004 0 P 0 
L 1.24288002 -2.07016004 1.29238996 -2.07016004 0 P 0 
L 1.24293002 -2.06916004 1.29246004 -2.06916004 0 P 0 
L 1.24296998 -2.06816004 1.29253002 -2.06816004 0 P 0 
L 1.24301998 -2.06716004 1.29261004 -2.06716004 0 P 0 
L 1.24306004 -2.06616004 1.2927 -2.06616004 0 P 0 
L 1.24311004 -2.06516004 1.29281004 -2.06516004 0 P 0 
L 1.24315 -2.06416004 1.29291998 -2.06416004 0 P 0 
L 1.2432 -2.06316004 1.29303002 -2.06316004 0 P 0 
L 1.24323996 -2.06216004 1.29315 -2.06216004 0 P 0 
L 1.24328996 -2.06116004 1.29331998 -2.06116004 0 P 0 
L 1.24333002 -2.06016004 1.2935 -2.06016004 0 P 0 
L 1.24338002 -2.05916004 1.29366998 -2.05916004 0 P 0 
L 1.24341998 -2.05816004 1.29385 -2.05816004 0 P 0 
L 1.24346998 -2.05716004 1.29408996 -2.05716004 0 P 0 
L 1.24351004 -2.05616004 1.29433996 -2.05616004 0 P 0 
L 1.24355 -2.05516004 1.29458996 -2.05516004 0 P 0 
L 1.2436 -2.05416004 1.29485 -2.05416004 0 P 0 
L 1.24363996 -2.05316004 1.29516998 -2.05316004 0 P 0 
L 1.24368996 -2.05216004 1.29551998 -2.05216004 0 P 0 
L 1.24373002 -2.05116004 1.29586004 -2.05116004 0 P 0 
L 1.24378002 -2.05016004 1.29621004 -2.05016004 0 P 0 
L 1.24383002 -2.04916004 1.29663996 -2.04916004 0 P 0 
L 1.24386998 -2.04816004 1.29708002 -2.04816004 0 P 0 
L 1.24391004 -2.04716004 1.29753002 -2.04716004 0 P 0 
L 1.24396004 -2.04616004 1.29796998 -2.04616004 0 P 0 
L 1.244 -2.04516004 1.29851004 -2.04516004 0 P 0 
L 1.24405 -2.04416004 1.2991 -2.04416004 0 P 0 
L 1.24408996 -2.04316004 1.29975 -2.04316004 0 P 0 
L 1.24413996 -2.04216004 1.3005 -2.04216004 0 P 0 
L 1.24418002 -2.04116004 1.30131998 -2.04116004 0 P 0 
L 1.24423002 -2.04016004 1.30223002 -2.04016004 0 P 0 
L 1.24426998 -2.03916004 1.30326998 -2.03916004 0 P 0 
L 1.24431998 -2.03816004 1.30446004 -2.03816004 0 P 0 
L 1.24436004 -2.03716004 1.30581998 -2.03716004 0 P 0 
L 1.24441004 -2.03616004 1.30738002 -2.03616004 0 P 0 
L 1.24445 -2.03516004 1.30923002 -2.03516004 0 P 0 
L 1.24448996 -2.03416004 1.31156004 -2.03416004 0 P 0 
L 1.24453996 -2.03316004 1.31478996 -2.03316004 0 P 0 
L 1.24458996 -2.03216004 1.32013002 -2.03216004 0 P 0 
L 1.24461998 -2.03116004 1.33481004 -2.03116004 0 P 0 
L 1.24463996 -2.03016004 1.33478002 -2.03016004 0 P 0 
L 1.24466004 -2.02916004 1.33473996 -2.02916004 0 P 0 
L 1.24468002 -2.02816004 1.33471004 -2.02816004 0 P 0 
L 1.2447 -2.02716004 1.33468002 -2.02716004 0 P 0 
L 1.24471998 -2.02616004 1.33463996 -2.02616004 0 P 0 
L 1.24473996 -2.02516004 1.3346 -2.02516004 0 P 0 
L 1.24476004 -2.02416004 1.33456998 -2.02416004 0 P 0 
L 1.24478002 -2.02316004 1.33453002 -2.02316004 0 P 0 
L 1.2448 -2.02216004 1.3345 -2.02216004 0 P 0 
L 1.24481998 -2.02116004 1.33446998 -2.02116004 0 P 0 
L 1.24483996 -2.02016004 1.33443002 -2.02016004 0 P 0 
L 1.24486004 -2.01916004 1.3344 -2.01916004 0 P 0 
L 1.24488002 -2.01816004 1.33436004 -2.01816004 0 P 0 
L 1.2449 -2.01716004 1.33433002 -2.01716004 0 P 0 
L 1.24491998 -2.01616004 1.33428996 -2.01616004 0 P 0 
L 1.24493996 -2.01516004 1.33426004 -2.01516004 0 P 0 
L 1.24496004 -2.01416004 1.33421998 -2.01416004 0 P 0 
L 1.24498002 -2.01316004 1.33418996 -2.01316004 0 P 0 
L 1.245 -2.01216004 1.33415 -2.01216004 0 P 0 
L 1.24501998 -2.01116004 1.33411998 -2.01116004 0 P 0 
L 1.24503996 -2.01016004 1.33408002 -2.01016004 0 P 0 
L 1.24506004 -2.00916004 1.33403996 -2.00916004 0 P 0 
L 1.24508002 -2.00816004 1.334 -2.00816004 0 P 0 
L 1.2451 -2.00716004 1.33396004 -2.00716004 0 P 0 
L 1.24511998 -2.00616004 1.33393002 -2.00616004 0 P 0 
L 1.24513996 -2.00516004 1.29098996 -2.00516004 0 P 0 
L 1.24513996 -2.00416004 1.29033002 -2.00416004 0 P 0 
L 1.24513996 -2.00316004 1.29005 -2.00316004 0 P 0 
L 1.24513996 -2.00216004 1.29005 -2.00216004 0 P 0 
L 1.24513996 -2.00116004 1.29005 -2.00116004 0 P 0 
L 1.24515 -2.00016004 1.29005 -2.00016004 0 P 0 
L 1.24515 -1.99916004 1.29005 -1.99916004 0 P 0 
L 1.24515 -1.99816004 1.29005 -1.99816004 0 P 0 
L 1.24515 -1.99716004 1.29005 -1.99716004 0 P 0 
L 1.24515 -1.99616004 1.29005 -1.99616004 0 P 0 
L 1.24515 -1.99516004 1.29005 -1.99516004 0 P 0 
L 1.16085 -2.02753002 1.1601 -2.04393002 0 P 0 
L 1.1601 -2.04393002 1.15928996 -2.05771998 0 P 0 
L 1.15928996 -2.05771998 1.15883996 -2.06228002 0 P 0 
L 1.15883996 -2.06228002 1.15818002 -2.06681998 0 P 0 
L 1.15818002 -2.06681998 1.15751004 -2.07006998 0 P 0 
L 1.15751004 -2.07006998 1.15661004 -2.07328996 0 P 0 
L 1.15661004 -2.07328996 1.15616004 -2.07453996 0 P 0 
L 1.15616004 -2.07453996 1.15563002 -2.07576998 0 P 0 
L 1.15563002 -2.07576998 1.15501998 -2.07696004 0 P 0 
L 1.15501998 -2.07696004 1.15433002 -2.0781 0 P 0 
L 1.15433002 -2.0781 1.1534 -2.07941998 0 P 0 
L 1.1534 -2.07941998 1.15236004 -2.08066004 0 P 0 
L 1.15236004 -2.08066004 1.15123002 -2.08181998 0 P 0 
L 1.15123002 -2.08181998 1.15001004 -2.08286998 0 P 0 
L 1.15001004 -2.08286998 1.14871004 -2.08383002 0 P 0 
L 1.14871004 -2.08383002 1.14733002 -2.08468002 0 P 0 
L 1.14733002 -2.08468002 1.14591004 -2.0854 0 P 0 
L 1.14591004 -2.0854 1.14443996 -2.086 0 P 0 
L 1.14443996 -2.086 1.14291004 -2.08648002 0 P 0 
L 1.14291004 -2.08648002 1.14136004 -2.08683002 0 P 0 
L 1.14136004 -2.08683002 1.13976998 -2.08703996 0 P 0 
L 1.13976998 -2.08703996 1.13816004 -2.08713002 0 P 0 
L 1.13816004 -2.08713002 1.13656998 -2.08708002 0 P 0 
L 1.13656998 -2.08708002 1.13498996 -2.0869 0 P 0 
L 1.13498996 -2.0869 1.13341998 -2.08658996 0 P 0 
L 1.13341998 -2.08658996 1.13188996 -2.08615 0 P 0 
L 1.13188996 -2.08615 1.1304 -2.08558996 0 P 0 
L 1.1304 -2.08558996 1.12895 -2.08488996 0 P 0 
L 1.12895 -2.08488996 1.12756998 -2.08408002 0 P 0 
L 1.12756998 -2.08408002 1.12625 -2.08315 0 P 0 
L 1.12625 -2.08315 1.12501004 -2.08211998 0 P 0 
L 1.12501004 -2.08211998 1.12386004 -2.081 0 P 0 
L 1.12386004 -2.081 1.12281004 -2.07978002 0 P 0 
L 1.12281004 -2.07978002 1.12183996 -2.07846998 0 P 0 
L 1.12183996 -2.07846998 1.1211 -2.07726004 0 P 0 
L 1.1211 -2.07726004 1.12046998 -2.07598996 0 P 0 
L 1.12046998 -2.07598996 1.11996004 -2.07466998 0 P 0 
L 1.11996004 -2.07466998 1.11955 -2.07331004 0 P 0 
L 1.11955 -2.07331004 1.11926998 -2.07191004 0 P 0 
L 1.11926998 -2.07191004 1.11868002 -2.06693996 0 P 0 
L 1.11868002 -2.06693996 1.11848002 -2.06191004 0 P 0 
L 1.11848002 -2.06191004 1.11871004 -2.05668002 0 P 0 
L 1.11871004 -2.05668002 1.11936004 -2.05148002 0 P 0 
L 1.11936004 -2.05148002 1.11978996 -2.04936998 0 P 0 
L 1.11978996 -2.04936998 1.12036998 -2.0473 0 P 0 
L 1.12036998 -2.0473 1.12108996 -2.04528002 0 P 0 
L 1.12108996 -2.04528002 1.12196004 -2.04331998 0 P 0 
L 1.12196004 -2.04331998 1.1229 -2.04153996 0 P 0 
L 1.1229 -2.04153996 1.12396998 -2.03985 0 P 0 
L 1.12396998 -2.03985 1.12516998 -2.03823002 0 P 0 
L 1.12516998 -2.03823002 1.12735 -2.03573996 0 P 0 
L 1.12735 -2.03573996 1.12973002 -2.03345 0 P 0 
L 1.12973002 -2.03345 1.13223996 -2.03141998 0 P 0 
L 1.13223996 -2.03141998 1.13491998 -2.02961004 0 P 0 
L 1.13491998 -2.02961004 1.13611004 -2.02893002 0 P 0 
L 1.13611004 -2.02893002 1.13735 -2.02833996 0 P 0 
L 1.13735 -2.02833996 1.13861998 -2.02781998 0 P 0 
L 1.13861998 -2.02781998 1.13993996 -2.0274 0 P 0 
L 1.13993996 -2.0274 1.14191004 -2.02693002 0 P 0 
L 1.14191004 -2.02693002 1.14391004 -2.02663002 0 P 0 
L 1.14391004 -2.02663002 1.14935 -2.02626004 0 P 0 
L 1.14935 -2.02626004 1.15471004 -2.0263 0 P 0 
L 1.15471004 -2.0263 1.15591004 -2.02638996 0 P 0 
L 1.15591004 -2.02638996 1.1571 -2.02656998 0 P 0 
L 1.1571 -2.02656998 1.15828002 -2.02683996 0 P 0 
L 1.15828002 -2.02683996 1.16085 -2.02753002 0 P 0 
L 1.13876998 -2.14783002 1.20233002 -2.14783002 0 P 0 
L 1.14236998 -2.14683002 1.20266004 -2.14683002 0 P 0 
L 1.14481004 -2.14583002 1.20296004 -2.14583002 0 P 0 
L 1.1467 -2.14483002 1.20325 -2.14483002 0 P 0 
L 1.14826004 -2.14383002 1.20353002 -2.14383002 0 P 0 
L 1.1496 -2.14283002 1.20373996 -2.14283002 0 P 0 
L 1.15078996 -2.14183002 1.20395 -2.14183002 0 P 0 
L 1.15186004 -2.14083002 1.20415 -2.14083002 0 P 0 
L 1.15278996 -2.13983002 1.20431998 -2.13983002 0 P 0 
L 1.15361998 -2.13883002 1.20446004 -2.13883002 0 P 0 
L 1.15436004 -2.13783002 1.20458002 -2.13783002 0 P 0 
L 1.155 -2.13683002 1.20466998 -2.13683002 0 P 0 
L 1.15556998 -2.13583002 1.20475 -2.13583002 0 P 0 
L 1.15608996 -2.13483002 1.20481998 -2.13483002 0 P 0 
L 1.15653996 -2.13383002 1.20488996 -2.13383002 0 P 0 
L 1.15691004 -2.13283002 1.20496004 -2.13283002 0 P 0 
L 1.15723996 -2.13183002 1.20503002 -2.13183002 0 P 0 
L 1.15751998 -2.13083002 1.2051 -2.13083002 0 P 0 
L 1.15773002 -2.12983002 1.20516004 -2.12983002 0 P 0 
L 1.15793002 -2.12883002 1.20523002 -2.12883002 0 P 0 
L 1.15806004 -2.12783002 1.2053 -2.12783002 0 P 0 
L 1.15816998 -2.12683002 1.20536998 -2.12683002 0 P 0 
L 1.15821004 -2.12583002 1.20543996 -2.12583002 0 P 0 
L 1.11716004 -2.12483002 1.12726004 -2.12483002 0 P 0 
L 1.15823996 -2.12483002 1.20551004 -2.12483002 0 P 0 
L 1.10911998 -2.12383002 1.1352 -2.12383002 0 P 0 
L 1.15821998 -2.12383002 1.20556998 -2.12383002 0 P 0 
L 1.10468996 -2.12283002 1.14018996 -2.12283002 0 P 0 
L 1.1582 -2.12283002 1.20563996 -2.12283002 0 P 0 
L 1.10131004 -2.12183002 1.14366998 -2.12183002 0 P 0 
L 1.15818002 -2.12183002 1.2057 -2.12183002 0 P 0 
L 1.15808996 -2.12083002 1.20576004 -2.12083002 0 P 0 
L 1.15781004 -2.11983002 1.20583002 -2.11983002 0 P 0 
L 1.15721004 -2.11883002 1.20588002 -2.11883002 0 P 0 
L 1.14146004 -2.08883002 1.20758002 -2.08883002 0 P 0 
L 1.14525 -2.08783002 1.20763002 -2.08783002 0 P 0 
L 1.14751004 -2.08683002 1.20768002 -2.08683002 0 P 0 
L 1.14928002 -2.08583002 1.20773002 -2.08583002 0 P 0 
L 1.15073002 -2.08483002 1.20778996 -2.08483002 0 P 0 
L 1.15196004 -2.08383002 1.20783996 -2.08383002 0 P 0 
L 1.13818996 -2.08913002 1.13826998 -2.08913002 0 P 0 
L 1.13826998 -2.08913002 1.13988002 -2.08903996 0 P 0 
L 1.13988002 -2.08903996 1.13996004 -2.08903996 0 P 0 
L 1.13996004 -2.08903996 1.14001004 -2.08903002 0 P 0 
L 1.14001004 -2.08903002 1.14005 -2.08901998 0 P 0 
L 1.14005 -2.08901998 1.14163002 -2.08881004 0 P 0 
L 1.14163002 -2.08881004 1.14166998 -2.0888 0 P 0 
L 1.14166998 -2.0888 1.14171004 -2.0888 0 P 0 
L 1.14171004 -2.0888 1.14178996 -2.08878002 0 P 0 
L 1.14178996 -2.08878002 1.14335 -2.08843002 0 P 0 
L 1.14335 -2.08843002 1.14351004 -2.08838996 0 P 0 
L 1.14351004 -2.08838996 1.14503002 -2.08791004 0 P 0 
L 1.14503002 -2.08791004 1.14511004 -2.08788996 0 P 0 
L 1.14511004 -2.08788996 1.14515 -2.08786998 0 P 0 
L 1.14515 -2.08786998 1.14518996 -2.08786004 0 P 0 
L 1.14518996 -2.08786004 1.14666004 -2.08725 0 P 0 
L 1.14666004 -2.08725 1.14673996 -2.08721998 0 P 0 
L 1.14673996 -2.08721998 1.14678002 -2.0872 0 P 0 
L 1.14678002 -2.0872 1.14681998 -2.08718996 0 P 0 
L 1.14681998 -2.08718996 1.14823996 -2.08646998 0 P 0 
L 1.14823996 -2.08646998 1.14826998 -2.08645 0 P 0 
L 1.14826998 -2.08645 1.14835 -2.08641004 0 P 0 
L 1.14835 -2.08641004 1.14838002 -2.08638002 0 P 0 
L 1.14838002 -2.08638002 1.14976004 -2.08553002 0 P 0 
L 1.14976004 -2.08553002 1.14978996 -2.08551004 0 P 0 
L 1.14978996 -2.08551004 1.14983002 -2.08548996 0 P 0 
L 1.14983002 -2.08548996 1.14988996 -2.08543996 0 P 0 
L 1.14988996 -2.08543996 1.1512 -2.08448996 0 P 0 
L 1.1512 -2.08448996 1.15126004 -2.08443996 0 P 0 
L 1.15126004 -2.08443996 1.15128996 -2.08441004 0 P 0 
L 1.15128996 -2.08441004 1.15131998 -2.08438996 0 P 0 
L 1.15131998 -2.08438996 1.15253996 -2.08333002 0 P 0 
L 1.15253996 -2.08333002 1.15256998 -2.0833 0 P 0 
L 1.15256998 -2.0833 1.1526 -2.08328002 0 P 0 
L 1.1526 -2.08328002 1.15263002 -2.08323996 0 P 0 
L 1.15263002 -2.08323996 1.15266004 -2.08321998 0 P 0 
L 1.15266004 -2.08321998 1.15378996 -2.08206004 0 P 0 
L 1.15378996 -2.08206004 1.15376004 -2.08203996 0 P 0 
L 1.15376004 -2.08203996 1.15381998 -2.08203996 0 P 0 
L 1.15381998 -2.08203996 1.15383996 -2.082 0 P 0 
L 1.15383996 -2.082 1.15386998 -2.08196998 0 P 0 
L 1.15386998 -2.08196998 1.1539 -2.08195 0 P 0 
L 1.1539 -2.08195 1.15493002 -2.08071004 0 P 0 
L 1.15493002 -2.08071004 1.15493002 -2.0807 0 P 0 
L 1.15493002 -2.0807 1.15496004 -2.08066998 0 P 0 
L 1.15496004 -2.08066998 1.15498002 -2.08063996 0 P 0 
L 1.15498002 -2.08063996 1.15501004 -2.08061004 0 P 0 
L 1.15501004 -2.08061004 1.15503002 -2.08058002 0 P 0 
L 1.15503002 -2.08058002 1.15596004 -2.07926004 0 P 0 
L 1.15596004 -2.07926004 1.15603996 -2.07913996 0 P 0 
L 1.15603996 -2.07913996 1.15673002 -2.07798996 0 P 0 
L 1.15673002 -2.07798996 1.15676998 -2.07793002 0 P 0 
L 1.15676998 -2.07793002 1.15678996 -2.07786998 0 P 0 
L 1.15678996 -2.07786998 1.15741004 -2.07668996 0 P 0 
L 1.15741004 -2.07668996 1.15743996 -2.07663002 0 P 0 
L 1.15743996 -2.07663002 1.15746004 -2.07656998 0 P 0 
L 1.15746004 -2.07656998 1.15746998 -2.07656998 0 P 0 
L 1.15746998 -2.07656998 1.158 -2.07533996 0 P 0 
L 1.158 -2.07533996 1.15801004 -2.07531004 0 P 0 
L 1.15801004 -2.07531004 1.15803002 -2.07528002 0 P 0 
L 1.15803002 -2.07528002 1.15805 -2.07521998 0 P 0 
L 1.15805 -2.07521998 1.15848996 -2.07396004 0 P 0 
L 1.15848996 -2.07396004 1.15841004 -2.07393002 0 P 0 
L 1.15841004 -2.07393002 1.15851004 -2.07393002 0 P 0 
L 1.15851004 -2.07393002 1.15851998 -2.0739 0 P 0 
L 1.15851998 -2.0739 1.15853002 -2.07386004 0 P 0 
L 1.15853002 -2.07386004 1.15853996 -2.07383002 0 P 0 
L 1.15853996 -2.07383002 1.15943996 -2.07061004 0 P 0 
L 1.15943996 -2.07061004 1.15945 -2.07058002 0 P 0 
L 1.15945 -2.07058002 1.15946004 -2.07053996 0 P 0 
L 1.15946004 -2.07053996 1.15946998 -2.07051004 0 P 0 
L 1.15946998 -2.07051004 1.15946998 -2.07046998 0 P 0 
L 1.15946998 -2.07046998 1.16013996 -2.06723002 0 P 0 
L 1.16013996 -2.06723002 1.16013996 -2.0672 0 P 0 
L 1.16013996 -2.0672 1.16016004 -2.06713996 0 P 0 
L 1.16016004 -2.06713996 1.16016004 -2.06711004 0 P 0 
L 1.16016004 -2.06711004 1.16081998 -2.06256004 0 P 0 
L 1.16081998 -2.06256004 1.16081998 -2.06253996 0 P 0 
L 1.16081998 -2.06253996 1.16083002 -2.0625 0 P 0 
L 1.16083002 -2.0625 1.16083002 -2.06246998 0 P 0 
L 1.16083002 -2.06246998 1.16126998 -2.05791004 0 P 0 
L 1.16126998 -2.05791004 1.16128002 -2.0579 0 P 0 
L 1.16128002 -2.0579 1.16128002 -2.05783996 0 P 0 
L 1.16128002 -2.05783996 1.1621 -2.04405 0 P 0 
L 1.1621 -2.04405 1.1621 -2.04401998 0 P 0 
L 1.1621 -2.04401998 1.16285 -2.02761998 0 P 0 
L 1.16285 -2.02761998 1.16136998 -2.0256 0 P 0 
L 1.16136998 -2.0256 1.15878996 -2.02491004 0 P 0 
L 1.15878996 -2.02491004 1.15878002 -2.0249 0 P 0 
L 1.15878002 -2.0249 1.15871998 -2.02488996 0 P 0 
L 1.15871998 -2.02488996 1.15755 -2.02461998 0 P 0 
L 1.15755 -2.02461998 1.15746998 -2.0246 0 P 0 
L 1.15746998 -2.0246 1.1574 -2.0246 0 P 0 
L 1.1574 -2.0246 1.15621004 -2.02441004 0 P 0 
L 1.15621004 -2.02441004 1.15616998 -2.02441004 0 P 0 
L 1.15616998 -2.02441004 1.1561 -2.0244 0 P 0 
L 1.1561 -2.0244 1.15606004 -2.02438996 0 P 0 
L 1.15606004 -2.02438996 1.15486004 -2.0243 0 P 0 
L 1.15486004 -2.0243 1.15471998 -2.0243 0 P 0 
L 1.15471998 -2.0243 1.14936004 -2.02426004 0 P 0 
L 1.14936004 -2.02426004 1.14928996 -2.02426004 0 P 0 
L 1.14928996 -2.02426004 1.14925 -2.02426998 0 P 0 
L 1.14925 -2.02426998 1.14921004 -2.02426998 0 P 0 
L 1.14921004 -2.02426998 1.14376998 -2.02463996 0 P 0 
L 1.14376998 -2.02463996 1.1437 -2.02463996 0 P 0 
L 1.1437 -2.02463996 1.14365 -2.02465 0 P 0 
L 1.14365 -2.02465 1.14361004 -2.02465 0 P 0 
L 1.14361004 -2.02465 1.14161998 -2.02495 0 P 0 
L 1.14161998 -2.02495 1.14161004 -2.02495 0 P 0 
L 1.14161004 -2.02495 1.14153002 -2.02496998 0 P 0 
L 1.14153002 -2.02496998 1.14148996 -2.02496998 0 P 0 
L 1.14148996 -2.02496998 1.14143996 -2.02498996 0 P 0 
L 1.14143996 -2.02498996 1.13946998 -2.02545 0 P 0 
L 1.13946998 -2.02545 1.13943996 -2.02546998 0 P 0 
L 1.13943996 -2.02546998 1.1394 -2.02546998 0 P 0 
L 1.1394 -2.02546998 1.13933002 -2.0255 0 P 0 
L 1.13933002 -2.0255 1.13801004 -2.02591998 0 P 0 
L 1.13801004 -2.02591998 1.13798002 -2.02593002 0 P 0 
L 1.13798002 -2.02593002 1.13793996 -2.02593996 0 P 0 
L 1.13793996 -2.02593996 1.13788002 -2.02596998 0 P 0 
L 1.13788002 -2.02596998 1.1366 -2.02648002 0 P 0 
L 1.1366 -2.02648002 1.13653996 -2.0265 0 P 0 
L 1.13653996 -2.0265 1.13648002 -2.02653002 0 P 0 
L 1.13648002 -2.02653002 1.13523996 -2.02713002 0 P 0 
L 1.13523996 -2.02713002 1.13518002 -2.02716004 0 P 0 
L 1.13518002 -2.02716004 1.13515 -2.02716998 0 P 0 
L 1.13515 -2.02716998 1.13511998 -2.02718996 0 P 0 
L 1.13511998 -2.02718996 1.13393002 -2.02786998 0 P 0 
L 1.13393002 -2.02786998 1.13388996 -2.02788996 0 P 0 
L 1.13388996 -2.02788996 1.1338 -2.02795 0 P 0 
L 1.1338 -2.02795 1.13111998 -2.02976004 0 P 0 
L 1.13111998 -2.02976004 1.13105 -2.02981004 0 P 0 
L 1.13105 -2.02981004 1.13101004 -2.02983996 0 P 0 
L 1.13101004 -2.02983996 1.13098002 -2.02986004 0 P 0 
L 1.13098002 -2.02986004 1.12846998 -2.03188996 0 P 0 
L 1.12846998 -2.03188996 1.12838002 -2.03198002 0 P 0 
L 1.12838002 -2.03198002 1.12833996 -2.03201004 0 P 0 
L 1.12833996 -2.03201004 1.12596004 -2.0343 0 P 0 
L 1.12596004 -2.0343 1.12593996 -2.03433002 0 P 0 
L 1.12593996 -2.03433002 1.1259 -2.03436004 0 P 0 
L 1.1259 -2.03436004 1.12588002 -2.03438996 0 P 0 
L 1.12588002 -2.03438996 1.12585 -2.03443002 0 P 0 
L 1.12585 -2.03443002 1.12366998 -2.03691004 0 P 0 
L 1.12366998 -2.03691004 1.12363996 -2.03695 0 P 0 
L 1.12363996 -2.03695 1.12361998 -2.03698002 0 P 0 
L 1.12361998 -2.03698002 1.12358996 -2.03701004 0 P 0 
L 1.12358996 -2.03701004 1.12356998 -2.03703996 0 P 0 
L 1.12356998 -2.03703996 1.12236998 -2.03865 0 P 0 
L 1.12236998 -2.03865 1.12233996 -2.03868996 0 P 0 
L 1.12233996 -2.03868996 1.12233002 -2.03871004 0 P 0 
L 1.12233002 -2.03871004 1.12228996 -2.03878002 0 P 0 
L 1.12228996 -2.03878002 1.12121004 -2.04046998 0 P 0 
L 1.12121004 -2.04046998 1.12118996 -2.0405 0 P 0 
L 1.12118996 -2.0405 1.12116998 -2.04053996 0 P 0 
L 1.12116998 -2.04053996 1.12115 -2.04056998 0 P 0 
L 1.12115 -2.04056998 1.12113996 -2.04061004 0 P 0 
L 1.12113996 -2.04061004 1.12018996 -2.04238002 0 P 0 
L 1.12018996 -2.04238002 1.12016004 -2.04245 0 P 0 
L 1.12016004 -2.04245 1.12013996 -2.04248002 0 P 0 
L 1.12013996 -2.04248002 1.12013002 -2.04251004 0 P 0 
L 1.12013002 -2.04251004 1.11926004 -2.04446998 0 P 0 
L 1.11926004 -2.04446998 1.11925 -2.0445 0 P 0 
L 1.11925 -2.0445 1.11923002 -2.04453996 0 P 0 
L 1.11923002 -2.04453996 1.11921998 -2.04458002 0 P 0 
L 1.11921998 -2.04458002 1.11921004 -2.04461004 0 P 0 
L 1.11921004 -2.04461004 1.11848002 -2.04663002 0 P 0 
L 1.11848002 -2.04663002 1.11846998 -2.04666004 0 P 0 
L 1.11846998 -2.04666004 1.11846004 -2.0467 0 P 0 
L 1.11846004 -2.0467 1.11843996 -2.04676998 0 P 0 
L 1.11843996 -2.04676998 1.11786004 -2.04883996 0 P 0 
L 1.11786004 -2.04883996 1.11785 -2.04886998 0 P 0 
L 1.11785 -2.04886998 1.11783996 -2.04891004 0 P 0 
L 1.11783996 -2.04891004 1.11783996 -2.04893996 0 P 0 
L 1.11783996 -2.04893996 1.11783002 -2.04896998 0 P 0 
L 1.11783002 -2.04896998 1.11783002 -2.04898002 0 P 0 
L 1.11783002 -2.04898002 1.1174 -2.05108002 0 P 0 
L 1.1174 -2.05108002 1.1174 -2.05111998 0 P 0 
L 1.1174 -2.05111998 1.11738996 -2.05116004 0 P 0 
L 1.11738996 -2.05116004 1.11738002 -2.05118996 0 P 0 
L 1.11738002 -2.05118996 1.11738002 -2.05123002 0 P 0 
L 1.11738002 -2.05123002 1.11673002 -2.05643002 0 P 0 
L 1.11673002 -2.05643002 1.11671998 -2.05646998 0 P 0 
L 1.11671998 -2.05646998 1.11671998 -2.05655 0 P 0 
L 1.11671998 -2.05655 1.11671004 -2.05658996 0 P 0 
L 1.11671004 -2.05658996 1.11648996 -2.06181998 0 P 0 
L 1.11648996 -2.06181998 1.11648002 -2.06186998 0 P 0 
L 1.11648002 -2.06186998 1.11648002 -2.06195 0 P 0 
L 1.11648002 -2.06195 1.11648996 -2.06198996 0 P 0 
L 1.11648996 -2.06198996 1.11668002 -2.06696998 0 P 0 
L 1.11668002 -2.06696998 1.11768002 -2.06696998 0 P 0 
L 1.11768002 -2.06696998 1.11668002 -2.06701004 0 P 0 
L 1.11668002 -2.06701004 1.11668002 -2.06713002 0 P 0 
L 1.11668002 -2.06713002 1.11668996 -2.06716998 0 P 0 
L 1.11668996 -2.06716998 1.11728002 -2.07215 0 P 0 
L 1.11728002 -2.07215 1.11728996 -2.07218996 0 P 0 
L 1.11728996 -2.07218996 1.11728996 -2.07223002 0 P 0 
L 1.11728996 -2.07223002 1.11731004 -2.07231004 0 P 0 
L 1.11731004 -2.07231004 1.11758996 -2.07371004 0 P 0 
L 1.11758996 -2.07371004 1.1176 -2.07375 0 P 0 
L 1.1176 -2.07375 1.11761004 -2.0738 0 P 0 
L 1.11761004 -2.0738 1.11761998 -2.07383996 0 P 0 
L 1.11761998 -2.07383996 1.11763996 -2.07388002 0 P 0 
L 1.11763996 -2.07388002 1.11803996 -2.07523996 0 P 0 
L 1.11803996 -2.07523996 1.11806004 -2.07531998 0 P 0 
L 1.11806004 -2.07531998 1.11808002 -2.07536004 0 P 0 
L 1.11808002 -2.07536004 1.11808996 -2.07541004 0 P 0 
L 1.11808996 -2.07541004 1.11861004 -2.07673002 0 P 0 
L 1.11861004 -2.07673002 1.11863996 -2.07681004 0 P 0 
L 1.11863996 -2.07681004 1.11866004 -2.07683996 0 P 0 
L 1.11866004 -2.07683996 1.11868002 -2.07688002 0 P 0 
L 1.11868002 -2.07688002 1.11931004 -2.07815 0 P 0 
L 1.11931004 -2.07815 1.11935 -2.07823002 0 P 0 
L 1.11935 -2.07823002 1.1194 -2.0783 0 P 0 
L 1.1194 -2.0783 1.12013996 -2.07951998 0 P 0 
L 1.12013996 -2.07951998 1.12021004 -2.07961998 0 P 0 
L 1.12021004 -2.07961998 1.12023002 -2.07965 0 P 0 
L 1.12023002 -2.07965 1.12023002 -2.07966004 0 P 0 
L 1.12023002 -2.07966004 1.1212 -2.08096998 0 P 0 
L 1.1212 -2.08096998 1.12123996 -2.08103002 0 P 0 
L 1.12123996 -2.08103002 1.12126998 -2.08106004 0 P 0 
L 1.12126998 -2.08106004 1.12128996 -2.08108996 0 P 0 
L 1.12128996 -2.08108996 1.12235 -2.08231004 0 P 0 
L 1.12235 -2.08231004 1.12238002 -2.08233996 0 P 0 
L 1.12238002 -2.08233996 1.1224 -2.08236998 0 P 0 
L 1.1224 -2.08236998 1.12246004 -2.08243002 0 P 0 
L 1.12246004 -2.08243002 1.12361004 -2.08355 0 P 0 
L 1.12361004 -2.08355 1.12366998 -2.08361004 0 P 0 
L 1.12366998 -2.08361004 1.1237 -2.08363002 0 P 0 
L 1.1237 -2.08363002 1.12373002 -2.08366004 0 P 0 
L 1.12373002 -2.08366004 1.12496998 -2.08468996 0 P 0 
L 1.12496998 -2.08468996 1.125 -2.08471004 0 P 0 
L 1.125 -2.08471004 1.12503002 -2.08473996 0 P 0 
L 1.12503002 -2.08473996 1.12506998 -2.08476004 0 P 0 
L 1.12506998 -2.08476004 1.1251 -2.08478996 0 P 0 
L 1.1251 -2.08478996 1.12641998 -2.08571004 0 P 0 
L 1.12641998 -2.08571004 1.12645 -2.08573002 0 P 0 
L 1.12645 -2.08573002 1.12648002 -2.08576004 0 P 0 
L 1.12648002 -2.08576004 1.12651004 -2.08578002 0 P 0 
L 1.12651004 -2.08578002 1.12655 -2.0858 0 P 0 
L 1.12655 -2.0858 1.12793996 -2.08661004 0 P 0 
L 1.12793996 -2.08661004 1.12801004 -2.08665 0 P 0 
L 1.12801004 -2.08665 1.12805 -2.08666998 0 P 0 
L 1.12805 -2.08666998 1.12808002 -2.08668996 0 P 0 
L 1.12808002 -2.08668996 1.12808996 -2.08668996 0 P 0 
L 1.12808996 -2.08668996 1.12953996 -2.08738996 0 P 0 
L 1.12953996 -2.08738996 1.12961998 -2.08743002 0 P 0 
L 1.12961998 -2.08743002 1.12965 -2.08743996 0 P 0 
L 1.12965 -2.08743996 1.1297 -2.08746004 0 P 0 
L 1.1297 -2.08746004 1.13118002 -2.08801998 0 P 0 
L 1.13118002 -2.08801998 1.13133996 -2.08808002 0 P 0 
L 1.13133996 -2.08808002 1.13286998 -2.08851004 0 P 0 
L 1.13286998 -2.08851004 1.13295 -2.08853996 0 P 0 
L 1.13295 -2.08853996 1.13303996 -2.08855 0 P 0 
L 1.13303996 -2.08855 1.1346 -2.08886004 0 P 0 
L 1.1346 -2.08886004 1.13471998 -2.08888996 0 P 0 
L 1.13471998 -2.08888996 1.13476004 -2.08888996 0 P 0 
L 1.13476004 -2.08888996 1.13633996 -2.08906998 0 P 0 
L 1.13633996 -2.08906998 1.13638996 -2.08908002 0 P 0 
L 1.13638996 -2.08908002 1.13651004 -2.08908002 0 P 0 
L 1.13651004 -2.08908002 1.1381 -2.08913002 0 P 0 
L 1.1381 -2.08913002 1.13818996 -2.08913002 0 P 0 
L 1.31623996 -1.98923996 1.3135 -1.98988002 0 P 0 
L 1.3135 -1.98988002 1.31078996 -1.99071004 0 P 0 
L 1.31078996 -1.99071004 1.30813002 -1.99175 0 P 0 
L 1.30813002 -1.99175 1.30553996 -1.99296998 0 P 0 
L 1.30553996 -1.99296998 1.30308996 -1.99431998 0 P 0 
L 1.30308996 -1.99431998 1.30073996 -1.99585 0 P 0 
L 1.30073996 -1.99585 1.29863996 -1.99746004 0 P 0 
L 1.29863996 -1.99746004 1.29666004 -1.99923996 0 P 0 
L 1.29666004 -1.99923996 1.29205 -2.00375 0 P 0 
L 1.29205 -2.00375 1.29205 -1.99243996 0 P 0 
L 1.29205 -1.99243996 1.24316004 -1.99243996 0 P 0 
L 1.24316004 -1.99243996 1.24313996 -2.00521004 0 P 0 
L 1.24313996 -2.00521004 1.24261004 -2.03151004 0 P 0 
L 1.24261004 -2.03151004 1.24086998 -2.07046004 0 P 0 
L 1.24086998 -2.07046004 1.23873996 -2.10921004 0 P 0 
L 1.23873996 -2.10921004 1.23811998 -2.11641998 0 P 0 
L 1.23811998 -2.11641998 1.23711998 -2.12361998 0 P 0 
L 1.23711998 -2.12361998 1.23655 -2.12716004 0 P 0 
L 1.23655 -2.12716004 1.29205 -2.12716004 0 P 0 
L 1.29205 -2.12716004 1.29206998 -2.11766004 0 P 0 
L 1.29206998 -2.11766004 1.29238996 -2.10283996 0 P 0 
L 1.29238996 -2.10283996 1.29336004 -2.08431004 0 P 0 
L 1.29336004 -2.08431004 1.29463996 -2.06673002 0 P 0 
L 1.29463996 -2.06673002 1.29511004 -2.06253002 0 P 0 
L 1.29511004 -2.06253002 1.29583996 -2.05836004 0 P 0 
L 1.29583996 -2.05836004 1.29683002 -2.05446998 0 P 0 
L 1.29683002 -2.05446998 1.29813996 -2.05068996 0 P 0 
L 1.29813996 -2.05068996 1.29978002 -2.04701998 0 P 0 
L 1.29978002 -2.04701998 1.30056998 -2.04556998 0 P 0 
L 1.30056998 -2.04556998 1.30146998 -2.04418996 0 P 0 
L 1.30146998 -2.04418996 1.30246998 -2.04288002 0 P 0 
L 1.30246998 -2.04288002 1.30356998 -2.04165 0 P 0 
L 1.30356998 -2.04165 1.30475 -2.0405 0 P 0 
L 1.30475 -2.0405 1.30603996 -2.03945 0 P 0 
L 1.30603996 -2.03945 1.30773996 -2.03826004 0 P 0 
L 1.30773996 -2.03826004 1.30953002 -2.03723002 0 P 0 
L 1.30953002 -2.03723002 1.31141004 -2.03635 0 P 0 
L 1.31141004 -2.03635 1.31335 -2.03563002 0 P 0 
L 1.31335 -2.03563002 1.31535 -2.03508002 0 P 0 
L 1.31535 -2.03508002 1.31973996 -2.03423002 0 P 0 
L 1.31973996 -2.03423002 1.32416004 -2.03366998 0 P 0 
L 1.32416004 -2.03366998 1.32863002 -2.0334 0 P 0 
L 1.32863002 -2.0334 1.33688002 -2.03318002 0 P 0 
L 1.33688002 -2.03318002 1.33613002 -2.01151004 0 P 0 
L 1.33613002 -2.01151004 1.33581004 -2.00315 0 P 0 
L 1.33581004 -2.00315 1.33543996 -1.99596004 0 P 0 
L 1.33543996 -1.99596004 1.33508002 -1.98971004 0 P 0 
L 1.33508002 -1.98971004 1.33503996 -1.98945 0 P 0 
L 1.33503996 -1.98945 1.335 -1.98931998 0 P 0 
L 1.335 -1.98931998 1.33496004 -1.9892 0 P 0 
L 1.33496004 -1.9892 1.3349 -1.98908002 0 P 0 
L 1.3349 -1.98908002 1.33483996 -1.98896998 0 P 0 
L 1.33483996 -1.98896998 1.33476998 -1.98886004 0 P 0 
L 1.33476998 -1.98886004 1.33468996 -1.98876004 0 P 0 
L 1.33468996 -1.98876004 1.3346 -1.98866998 0 P 0 
L 1.3346 -1.98866998 1.33451004 -1.98858996 0 P 0 
L 1.33451004 -1.98858996 1.3344 -1.98851998 0 P 0 
L 1.3344 -1.98851998 1.3343 -1.98845 0 P 0 
L 1.3343 -1.98845 1.33418002 -1.98838996 0 P 0 
L 1.33418002 -1.98838996 1.33406998 -1.98833996 0 P 0 
L 1.33406998 -1.98833996 1.33395 -1.9883 0 P 0 
L 1.33395 -1.9883 1.33383002 -1.98828002 0 P 0 
L 1.33383002 -1.98828002 1.3337 -1.98826004 0 P 0 
L 1.3337 -1.98826004 1.33356998 -1.98825 0 P 0 
L 1.33356998 -1.98825 1.32756998 -1.98823002 0 P 0 
L 1.32756998 -1.98823002 1.32135 -1.98853996 0 P 0 
L 1.32135 -1.98853996 1.31878996 -1.98881998 0 P 0 
L 1.31878996 -1.98881998 1.31623996 -1.98923996 0 P 0 
L 1.2389 -2.12516004 1.29006004 -2.12516004 0 P 0 
L 1.23906998 -2.12416004 1.29006004 -2.12416004 0 P 0 
L 1.23921004 -2.12316004 1.29006004 -2.12316004 0 P 0 
L 1.23933996 -2.12216004 1.29006004 -2.12216004 0 P 0 
L 1.23948996 -2.12116004 1.29006004 -2.12116004 0 P 0 
L 1.23961998 -2.12016004 1.29006998 -2.12016004 0 P 0 
L 1.23976004 -2.11916004 1.29006998 -2.11916004 0 P 0 
L 1.2399 -2.11816004 1.29006998 -2.11816004 0 P 0 
L 1.24003996 -2.11716004 1.29008002 -2.11716004 0 P 0 
L 1.24015 -2.11616004 1.2901 -2.11616004 0 P 0 
L 1.24023996 -2.11516004 1.29011998 -2.11516004 0 P 0 
L 1.24033002 -2.11416004 1.29013996 -2.11416004 0 P 0 
L 1.24041004 -2.11316004 1.29016004 -2.11316004 0 P 0 
L 1.24048996 -2.11216004 1.29018996 -2.11216004 0 P 0 
L 1.24058002 -2.11116004 1.29021004 -2.11116004 0 P 0 
L 1.24066998 -2.11016004 1.29023002 -2.11016004 0 P 0 
L 1.24075 -2.10916004 1.29025 -2.10916004 0 P 0 
L 1.2408 -2.10816004 1.29026998 -2.10816004 0 P 0 
L 1.24086004 -2.10716004 1.29028996 -2.10716004 0 P 0 
L 1.24091004 -2.10616004 1.29031998 -2.10616004 0 P 0 
L 1.24096998 -2.10516004 1.29033996 -2.10516004 0 P 0 
L 1.24101998 -2.10416004 1.29036004 -2.10416004 0 P 0 
L 1.24108002 -2.10316004 1.29038002 -2.10316004 0 P 0 
L 1.24113002 -2.10216004 1.29041998 -2.10216004 0 P 0 
L 1.24118002 -2.10116004 1.29046998 -2.10116004 0 P 0 
L 1.24123996 -2.10016004 1.29053002 -2.10016004 0 P 0 
L 1.24128996 -2.09916004 1.29058002 -2.09916004 0 P 0 
L 1.24135 -2.09816004 1.29063002 -2.09816004 0 P 0 
L 1.2414 -2.09716004 1.29068002 -2.09716004 0 P 0 
L 1.24146004 -2.09616004 1.29073996 -2.09616004 0 P 0 
L 1.24151004 -2.09516004 1.29078996 -2.09516004 0 P 0 
L 1.24156998 -2.09416004 1.29083996 -2.09416004 0 P 0 
L 1.24161998 -2.09316004 1.2909 -2.09316004 0 P 0 
L 1.24168002 -2.09216004 1.29095 -2.09216004 0 P 0 
L 1.24173002 -2.09116004 1.291 -2.09116004 0 P 0 
L 1.24178996 -2.09016004 1.29105 -2.09016004 0 P 0 
L 1.24183996 -2.08916004 1.2911 -2.08916004 0 P 0 
L 1.2419 -2.08816004 1.29116004 -2.08816004 0 P 0 
L 1.24196004 -2.08716004 1.29121004 -2.08716004 0 P 0 
L 1.24201004 -2.08616004 1.29126998 -2.08616004 0 P 0 
L 1.24206998 -2.08516004 1.29131998 -2.08516004 0 P 0 
L 1.24211998 -2.08416004 1.29136998 -2.08416004 0 P 0 
L 1.2389 -2.12516004 1.2391 -2.12393002 0 P 0 
L 1.2391 -2.12393002 1.2391 -2.1239 0 P 0 
L 1.2391 -2.1239 1.24011004 -2.11665 0 P 0 
L 1.24011004 -2.11665 1.24073002 -2.10935 0 P 0 
L 1.24073002 -2.10935 1.24073996 -2.10931998 0 P 0 
L 1.24073996 -2.10931998 1.24286004 -2.07056004 0 P 0 
L 1.24286004 -2.07056004 1.24461004 -2.03158002 0 P 0 
L 1.24461004 -2.03158002 1.24513996 -2.00523002 0 P 0 
L 1.24513996 -2.00523002 1.24515 -1.99443996 0 P 0 
L 1.24515 -1.99443996 1.29005 -1.99443996 0 P 0 
L 1.29005 -1.99443996 1.29005 -2.00375 0 P 0 
L 1.29005 -2.00375 1.29128002 -2.0056 0 P 0 
L 1.29128002 -2.0056 1.29345 -2.00518002 0 P 0 
L 1.29345 -2.00518002 1.29803002 -2.0007 0 P 0 
L 1.29803002 -2.0007 1.29991998 -1.999 0 P 0 
L 1.29991998 -1.999 1.30188996 -1.99748996 0 P 0 
L 1.30188996 -1.99748996 1.30411998 -1.99603996 0 P 0 
L 1.30411998 -1.99603996 1.30645 -1.99475 0 P 0 
L 1.30645 -1.99475 1.30891998 -1.99358996 0 P 0 
L 1.30891998 -1.99358996 1.31145 -1.9926 0 P 0 
L 1.31145 -1.9926 1.31401998 -1.99181004 0 P 0 
L 1.31401998 -1.99181004 1.31663996 -1.9912 0 P 0 
L 1.31663996 -1.9912 1.31906004 -1.9908 0 P 0 
L 1.31906004 -1.9908 1.32151004 -1.99053002 0 P 0 
L 1.32151004 -1.99053002 1.32761998 -1.99023002 0 P 0 
L 1.32761998 -1.99023002 1.3331 -1.99025 0 P 0 
L 1.3331 -1.99025 1.33345 -1.99608002 0 P 0 
L 1.33345 -1.99608002 1.33381004 -2.00323002 0 P 0 
L 1.33381004 -2.00323002 1.33413002 -2.01158996 0 P 0 
L 1.33413002 -2.01158996 1.33413002 -2.0116 0 P 0 
L 1.33413002 -2.0116 1.33481998 -2.03123002 0 P 0 
L 1.33481998 -2.03123002 1.32853996 -2.0314 0 P 0 
L 1.32853996 -2.0314 1.32398002 -2.03166998 0 P 0 
L 1.32398002 -2.03166998 1.31941998 -2.03225 0 P 0 
L 1.31941998 -2.03225 1.31488996 -2.03313002 0 P 0 
L 1.31488996 -2.03313002 1.31273996 -2.03373002 0 P 0 
L 1.31273996 -2.03373002 1.31063996 -2.0345 0 P 0 
L 1.31063996 -2.0345 1.3086 -2.03545 0 P 0 
L 1.3086 -2.03545 1.30666004 -2.03656998 0 P 0 
L 1.30666004 -2.03656998 1.30658996 -2.03661998 0 P 0 
L 1.30658996 -2.03661998 1.30483002 -2.03786004 0 P 0 
L 1.30483002 -2.03786004 1.30341998 -2.03901004 0 P 0 
L 1.30341998 -2.03901004 1.30336998 -2.03906004 0 P 0 
L 1.30336998 -2.03906004 1.30211998 -2.04026004 0 P 0 
L 1.30211998 -2.04026004 1.30093002 -2.0416 0 P 0 
L 1.30093002 -2.0416 1.29983002 -2.04303996 0 P 0 
L 1.29983002 -2.04303996 1.29978996 -2.0431 0 P 0 
L 1.29978996 -2.0431 1.29885 -2.04453996 0 P 0 
L 1.29885 -2.04453996 1.29798996 -2.04613002 0 P 0 
L 1.29798996 -2.04613002 1.29631998 -2.04986998 0 P 0 
L 1.29631998 -2.04986998 1.29628002 -2.04995 0 P 0 
L 1.29628002 -2.04995 1.29625 -2.05003002 0 P 0 
L 1.29625 -2.05003002 1.29491998 -2.0539 0 P 0 
L 1.29491998 -2.0539 1.29388996 -2.05793996 0 P 0 
L 1.29388996 -2.05793996 1.29386998 -2.05801998 0 P 0 
L 1.29386998 -2.05801998 1.29313996 -2.06221004 0 P 0 
L 1.29313996 -2.06221004 1.29313002 -2.06223996 0 P 0 
L 1.29313002 -2.06223996 1.29311998 -2.0623 0 P 0 
L 1.29311998 -2.0623 1.29265 -2.06655 0 P 0 
L 1.29265 -2.06655 1.29136998 -2.08418996 0 P 0 
L 1.29136998 -2.08418996 1.29038996 -2.10276998 0 P 0 
L 1.29038996 -2.10276998 1.29006998 -2.11763002 0 P 0 
L 1.29006998 -2.11763002 1.29006004 -2.12516004 0 P 0 
L 1.29006004 -2.12516004 1.2389 -2.12516004 0 P 0 
L 1.09846998 -2.00483002 1.21248002 -2.00483002 0 P 0 
L 1.09838002 -2.12083002 1.14708002 -2.12083002 0 P 0 
L 1.11933002 -2.18283002 1.15161998 -2.18283002 0 P 0 
L 1.11001998 -2.18183002 1.15838002 -2.18183002 0 P 0 
L 1.10246998 -2.18083002 1.16333996 -2.18083002 0 P 0 
L 1.04061004 -1.89731004 1.09978002 -1.89731004 0 P 0 
L 1.03565 -1.89631004 1.09821004 -1.89631004 0 P 0 
L 1.03068996 -1.89531004 1.09661004 -1.89531004 0 P 0 
L 1.02573002 -1.89431004 1.09475 -1.89431004 0 P 0 
L 1.019 -1.89331004 1.09288002 -1.89331004 0 P 0 
L 1.01163996 -1.89231004 1.09101998 -1.89231004 0 P 0 
L 0.99518996 -1.89131004 1.08916004 -1.89131004 0 P 0 
L 0.87011998 -1.88331004 1.07278996 -1.88331004 0 P 0 
L 0.86963996 -1.88231004 1.07053002 -1.88231004 0 P 0 
L 0.86916004 -1.88131004 1.06828002 -1.88131004 0 P 0 
L 0.86863002 -1.88031004 1.06603002 -1.88031004 0 P 0 
L 0.86806998 -1.87931004 1.06351004 -1.87931004 0 P 0 
L 0.8675 -1.87831004 1.06076998 -1.87831004 0 P 0 
L 0.86693002 -1.87731004 1.05803996 -1.87731004 0 P 0 
L 0.86631004 -1.87631004 1.05531004 -1.87631004 0 P 0 
L 0.86563996 -1.87531004 1.05256998 -1.87531004 0 P 0 
L 0.86498002 -1.87431004 1.04983996 -1.87431004 0 P 0 
L 0.86431998 -1.87331004 1.0471 -1.87331004 0 P 0 
L 0.86356004 -1.87231004 1.04376004 -1.87231004 0 P 0 
L 0.86278996 -1.87131004 1.04041998 -1.87131004 0 P 0 
L 0.86203002 -1.87031004 1.03708002 -1.87031004 0 P 0 
L 0.86118996 -1.86931004 1.03373996 -1.86931004 0 P 0 
L 0.8603 -1.86831004 1.0304 -1.86831004 0 P 0 
L 0.85941004 -1.86731004 1.02656998 -1.86731004 0 P 0 
L 0.8585 -1.86631004 1.02231998 -1.86631004 0 P 0 
L 0.85756998 -1.86531004 1.01806998 -1.86531004 0 P 0 
L 0.85663002 -1.86431004 1.01381998 -1.86431004 0 P 0 
L 0.85568996 -1.86331004 1.00931998 -1.86331004 0 P 0 
L 0.85481004 -1.86231004 1.00335 -1.86231004 0 P 0 
L 0.85916998 -1.86131004 0.99738002 -1.86131004 0 P 0 
L 0.86716998 -1.86031004 0.99141998 -1.86031004 0 P 0 
L 0.87476998 -1.89731004 0.89943002 -1.89731004 0 P 0 
L 0.87453996 -1.89631004 0.90426004 -1.89631004 0 P 0 
L 0.87431004 -1.89531004 0.9097 -1.89531004 0 P 0 
L 0.87406998 -1.89431004 0.91608002 -1.89431004 0 P 0 
L 0.87383002 -1.89331004 0.92246004 -1.89331004 0 P 0 
L 0.87355 -1.89231004 0.93086004 -1.89231004 0 P 0 
L 0.87323002 -1.89131004 0.95553002 -1.89131004 0 P 0 
L 0.87291004 -1.89031004 1.08728996 -1.89031004 0 P 0 
L 0.87258996 -1.88931004 1.08543002 -1.88931004 0 P 0 
L 0.87223002 -1.88831004 1.08356998 -1.88831004 0 P 0 
L 0.87183002 -1.88731004 1.0817 -1.88731004 0 P 0 
L 0.87143002 -1.88631004 1.07955 -1.88631004 0 P 0 
L 0.87103002 -1.88531004 1.07728996 -1.88531004 0 P 0 
L 0.8706 -1.88431004 1.07503996 -1.88431004 0 P 0 
L 0.87525 -1.85931004 0.98545 -1.85931004 0 P 0 
L 0.88421004 -1.85831004 0.97621004 -1.85831004 0 P 0 
L 0.89393002 -1.85731004 0.96606998 -1.85731004 0 P 0 
L 0.9106 -1.85631004 0.95203002 -1.85631004 0 P 0 
L 1.08716004 -1.91231004 1.12151004 -1.91231004 0 P 0 
L 1.08486004 -1.91131004 1.12018996 -1.91131004 0 P 0 
L 1.08256004 -1.91031004 1.11886004 -1.91031004 0 P 0 
L 1.08023002 -1.90931004 1.11753996 -1.90931004 0 P 0 
L 1.07738002 -1.90831004 1.11621004 -1.90831004 0 P 0 
L 1.07453002 -1.90731004 1.11488996 -1.90731004 0 P 0 
L 1.07168996 -1.90631004 1.11356998 -1.90631004 0 P 0 
L 1.06883996 -1.90531004 1.11223996 -1.90531004 0 P 0 
L 1.066 -1.90431004 1.11076998 -1.90431004 0 P 0 
L 1.06315 -1.90331004 1.1092 -1.90331004 0 P 0 
L 1.0599 -1.90231004 1.10763002 -1.90231004 0 P 0 
L 1.05611998 -1.90131004 1.10606004 -1.90131004 0 P 0 
L 1.05235 -1.90031004 1.10448996 -1.90031004 0 P 0 
L 1.04856998 -1.89931004 1.10291998 -1.89931004 0 P 0 
L 1.04478996 -1.89831004 1.10135 -1.89831004 0 P 0 
L 0.98815 -2.08316004 1.03726998 -2.08316004 0 P 0 
L 0.98818002 -2.08216004 1.03731004 -2.08216004 0 P 0 
L 0.98821998 -2.08116004 1.03735 -2.08116004 0 P 0 
L 0.98825 -2.08016004 1.03738996 -2.08016004 0 P 0 
L 0.98828002 -2.07916004 1.03743002 -2.07916004 0 P 0 
L 0.98831998 -2.07816004 1.03746998 -2.07816004 0 P 0 
L 0.98835 -2.07716004 1.03751004 -2.07716004 0 P 0 
L 0.98838002 -2.07616004 1.03755 -2.07616004 0 P 0 
L 0.98841998 -2.07516004 1.03758002 -2.07516004 0 P 0 
L 0.98845 -2.07416004 1.03761004 -2.07416004 0 P 0 
L 0.98848002 -2.07316004 1.03763996 -2.07316004 0 P 0 
L 0.98851004 -2.07216004 1.03768002 -2.07216004 0 P 0 
L 0.98855 -2.07116004 1.03771004 -2.07116004 0 P 0 
L 0.98858002 -2.07016004 1.03773996 -2.07016004 0 P 0 
L 0.98858996 -2.06916004 1.03776998 -2.06916004 0 P 0 
L 0.98858996 -2.06816004 1.0378 -2.06816004 0 P 0 
L 0.98858996 -2.06716004 1.03783002 -2.06716004 0 P 0 
L 0.98858002 -2.06616004 1.03786004 -2.06616004 0 P 0 
L 0.98856998 -2.06516004 1.0379 -2.06516004 0 P 0 
L 0.98856998 -2.06416004 1.03793002 -2.06416004 0 P 0 
L 0.98856998 -2.06316004 1.03796004 -2.06316004 0 P 0 
L 0.98856004 -2.06216004 1.03798996 -2.06216004 0 P 0 
L 0.98855 -2.06116004 1.03801998 -2.06116004 0 P 0 
L 0.98855 -2.06016004 1.03805 -2.06016004 0 P 0 
L 0.98853996 -2.05916004 1.03808002 -2.05916004 0 P 0 
L 0.98853996 -2.05816004 1.0381 -2.05816004 0 P 0 
L 0.98853002 -2.05716004 1.03811998 -2.05716004 0 P 0 
L 0.98848002 -2.05616004 1.03815 -2.05616004 0 P 0 
L 0.98841004 -2.05516004 1.03818002 -2.05516004 0 P 0 
L 0.98835 -2.05416004 1.0382 -2.05416004 0 P 0 
L 0.98828002 -2.05316004 1.03821998 -2.05316004 0 P 0 
L 0.98821004 -2.05216004 1.03825 -2.05216004 0 P 0 
L 0.98815 -2.05116004 1.03826998 -2.05116004 0 P 0 
L 0.98808996 -2.05016004 1.03828996 -2.05016004 0 P 0 
L 0.98801998 -2.04916004 1.03831998 -2.04916004 0 P 0 
L 0.98796004 -2.04816004 1.03833996 -2.04816004 0 P 0 
L 0.98788996 -2.04716004 1.03836004 -2.04716004 0 P 0 
L 0.98783002 -2.04616004 1.03838996 -2.04616004 0 P 0 
L 0.98768996 -2.04516004 1.0384 -2.04516004 0 P 0 
L 0.98756004 -2.04416004 1.03841004 -2.04416004 0 P 0 
L 0.98738002 -2.04316004 1.03841998 -2.04316004 0 P 0 
L 0.98716004 -2.04216004 1.03843002 -2.04216004 0 P 0 
L 0.98691998 -2.04116004 1.03843996 -2.04116004 0 P 0 
L 0.98661998 -2.04016004 1.03845 -2.04016004 0 P 0 
L 0.98631998 -2.03916004 1.03846004 -2.03916004 0 P 0 
L 0.98593996 -2.03816004 1.03846998 -2.03816004 0 P 0 
L 0.98546998 -2.03716004 1.03848002 -2.03716004 0 P 0 
L 0.98491004 -2.03616004 1.03846998 -2.03616004 0 P 0 
L 0.98425 -2.03516004 1.03846004 -2.03516004 0 P 0 
L 0.98346004 -2.03416004 1.03846004 -2.03416004 0 P 0 
L 0.98251998 -2.03316004 1.03843996 -2.03316004 0 P 0 
L 0.98138002 -2.03216004 1.03843002 -2.03216004 0 P 0 
L 0.97998996 -2.03116004 1.03841998 -2.03116004 0 P 0 
L 0.97813996 -2.03016004 1.03841004 -2.03016004 0 P 0 
L 0.97491004 -2.02916004 1.0384 -2.02916004 0 P 0 
L 0.94763996 -2.00716004 1.03293996 -2.00716004 0 P 0 
L 0.94978996 -2.00616004 1.03231998 -2.00616004 0 P 0 
L 0.95081004 -2.00516004 1.0317 -2.00516004 0 P 0 
L 0.95183002 -2.00416004 1.03098002 -2.00416004 0 P 0 
L 0.95285 -2.00316004 1.03023002 -2.00316004 0 P 0 
L 0.95388996 -2.00216004 1.02936004 -2.00216004 0 P 0 
L 0.95498002 -2.00116004 1.02841998 -2.00116004 0 P 0 
L 0.95621998 -2.00016004 1.02738996 -2.00016004 0 P 0 
L 0.95761998 -1.99916004 1.0262 -1.99916004 0 P 0 
L 0.9592 -1.99816004 1.02486004 -1.99816004 0 P 0 
L 0.96083996 -1.99716004 1.02335 -1.99716004 0 P 0 
L 0.9627 -1.99616004 1.02161004 -1.99616004 0 P 0 
L 0.96468996 -1.99516004 1.01951998 -1.99516004 0 P 0 
L 0.96685 -1.99416004 1.01683002 -1.99416004 0 P 0 
L 0.96936998 -1.99316004 1.01378002 -1.99316004 0 P 0 
L 0.97236998 -1.99216004 1.00981004 -1.99216004 0 P 0 
L 0.97676004 -1.99116004 1.00456998 -1.99116004 0 P 0 
L 1.06713996 -2.08283002 1.12288002 -2.08283002 0 P 0 
L 1.06698996 -2.08183002 1.12193996 -2.08183002 0 P 0 
L 1.06686004 -2.08083002 1.12108996 -2.08083002 0 P 0 
L 1.06673996 -2.07983002 1.12036004 -2.07983002 0 P 0 
L 1.06661998 -2.07883002 1.11971998 -2.07883002 0 P 0 
L 1.06653002 -2.07783002 1.11916004 -2.07783002 0 P 0 
L 1.06648002 -2.07683002 1.11866004 -2.07683002 0 P 0 
L 1.06641998 -2.07583002 1.11826004 -2.07583002 0 P 0 
L 1.06636998 -2.07483002 1.11791998 -2.07483002 0 P 0 
L 1.06631998 -2.07383002 1.11761998 -2.07383002 0 P 0 
L 1.06626004 -2.07283002 1.11741998 -2.07283002 0 P 0 
L 1.06621004 -2.07183002 1.11723996 -2.07183002 0 P 0 
L 1.06616004 -2.07083002 1.11711998 -2.07083002 0 P 0 
L 1.06616004 -2.06983002 1.11701004 -2.06983002 0 P 0 
L 1.06616004 -2.06883002 1.11688996 -2.06883002 0 P 0 
L 1.06616998 -2.06783002 1.11676998 -2.06783002 0 P 0 
L 1.06618002 -2.06683002 1.11666998 -2.06683002 0 P 0 
L 1.06618996 -2.06583002 1.11663002 -2.06583002 0 P 0 
L 1.0662 -2.06483002 1.11658996 -2.06483002 0 P 0 
L 1.06621004 -2.06383002 1.11656004 -2.06383002 0 P 0 
L 1.06623002 -2.06283002 1.11651998 -2.06283002 0 P 0 
L 1.06631004 -2.06183002 1.11648996 -2.06183002 0 P 0 
L 1.06638002 -2.06083002 1.11653002 -2.06083002 0 P 0 
L 1.06645 -2.05983002 1.11656998 -2.05983002 0 P 0 
L 1.06651998 -2.05883002 1.11661998 -2.05883002 0 P 0 
L 1.06658996 -2.05783002 1.11666004 -2.05783002 0 P 0 
L 1.06666998 -2.05683002 1.11671004 -2.05683002 0 P 0 
L 1.06673996 -2.05583002 1.11681004 -2.05583002 0 P 0 
L 1.06686004 -2.05483002 1.11693002 -2.05483002 0 P 0 
L 1.067 -2.05383002 1.11705 -2.05383002 0 P 0 
L 1.06713996 -2.05283002 1.11718002 -2.05283002 0 P 0 
L 1.06728002 -2.05183002 1.11731004 -2.05183002 0 P 0 
L 1.06741998 -2.05083002 1.11746004 -2.05083002 0 P 0 
L 1.06756004 -2.04983002 1.11766004 -2.04983002 0 P 0 
L 1.0677 -2.04883002 1.11786004 -2.04883002 0 P 0 
L 1.06786004 -2.04783002 1.11813996 -2.04783002 0 P 0 
L 1.06806998 -2.04683002 1.11841998 -2.04683002 0 P 0 
L 1.06828002 -2.04583002 1.11876998 -2.04583002 0 P 0 
L 1.06848996 -2.04483002 1.11913002 -2.04483002 0 P 0 
L 1.06871004 -2.04383002 1.11955 -2.04383002 0 P 0 
L 1.06898996 -2.04283002 1.11998996 -2.04283002 0 P 0 
L 1.06928002 -2.04183002 1.12048002 -2.04183002 0 P 0 
L 1.06956004 -2.04083002 1.12101004 -2.04083002 0 P 0 
L 1.06985 -2.03983002 1.12161998 -2.03983002 0 P 0 
L 1.07021004 -2.03883002 1.12225 -2.03883002 0 P 0 
L 1.07056998 -2.03783002 1.12298002 -2.03783002 0 P 0 
L 1.07093002 -2.03683002 1.12373996 -2.03683002 0 P 0 
L 1.07128996 -2.03583002 1.12461998 -2.03583002 0 P 0 
L 1.07173002 -2.03483002 1.12548996 -2.03483002 0 P 0 
L 1.07216998 -2.03383002 1.12646004 -2.03383002 0 P 0 
L 1.07261998 -2.03283002 1.12748996 -2.03283002 0 P 0 
L 1.07308002 -2.03183002 1.12855 -2.03183002 0 P 0 
L 1.07361998 -2.03083002 1.12978996 -2.03083002 0 P 0 
L 1.09761004 -1.91731004 1.12756998 -1.91731004 0 P 0 
L 1.09566004 -1.91631004 1.12645 -1.91631004 0 P 0 
L 1.09371004 -1.91531004 1.12533002 -1.91531004 0 P 0 
L 1.09176004 -1.91431004 1.12416004 -1.91431004 0 P 0 
L 1.08946004 -1.91331004 1.12283996 -1.91331004 0 P 0 
L 1.07415 -2.02983002 1.13101998 -2.02983002 0 P 0 
L 1.07468996 -2.02883002 1.13248996 -2.02883002 0 P 0 
L 1.07528996 -2.02783002 1.134 -2.02783002 0 P 0 
L 1.07591998 -2.02683002 1.13586004 -2.02683002 0 P 0 
L 1.07656004 -2.02583002 1.13828996 -2.02583002 0 P 0 
L 1.07721004 -2.02483002 1.14243002 -2.02483002 0 P 0 
L 1.07795 -2.02383002 1.21126998 -2.02383002 0 P 0 
L 1.07868002 -2.02283002 1.21133002 -2.02283002 0 P 0 
L 1.07941998 -2.02183002 1.2114 -2.02183002 0 P 0 
L 1.08021004 -2.02083002 1.21146004 -2.02083002 0 P 0 
L 1.08103996 -2.01983002 1.21153002 -2.01983002 0 P 0 
L 1.08186998 -2.01883002 1.2116 -2.01883002 0 P 0 
L 1.08273002 -2.01783002 1.21166004 -2.01783002 0 P 0 
L 1.08366998 -2.01683002 1.21173002 -2.01683002 0 P 0 
L 1.0846 -2.01583002 1.2118 -2.01583002 0 P 0 
L 1.08555 -2.01483002 1.21186004 -2.01483002 0 P 0 
L 1.08661004 -2.01383002 1.21193002 -2.01383002 0 P 0 
L 1.08766998 -2.01283002 1.21198996 -2.01283002 0 P 0 
L 1.08873002 -2.01183002 1.21205 -2.01183002 0 P 0 
L 1.0898 -2.01083002 1.21211998 -2.01083002 0 P 0 
L 1.09098996 -2.00983002 1.21218002 -2.00983002 0 P 0 
L 1.09225 -2.00883002 1.21223996 -2.00883002 0 P 0 
L 1.09358996 -2.00783002 1.2123 -2.00783002 0 P 0 
L 1.09506998 -2.00683002 1.21236004 -2.00683002 0 P 0 
L 1.09668996 -2.00583002 1.21241998 -2.00583002 0 P 0 
L 0.98546998 -2.12516004 1.03548996 -2.12516004 0 P 0 
L 0.98558996 -2.12416004 1.03553996 -2.12416004 0 P 0 
L 0.9857 -2.12316004 1.03558002 -2.12316004 0 P 0 
L 0.98581004 -2.12216004 1.03561998 -2.12216004 0 P 0 
L 0.98591004 -2.12116004 1.03566998 -2.12116004 0 P 0 
L 0.98598996 -2.12016004 1.03571004 -2.12016004 0 P 0 
L 0.98608002 -2.11916004 1.03575 -2.11916004 0 P 0 
L 0.98616998 -2.11816004 1.0358 -2.11816004 0 P 0 
L 0.98625 -2.11716004 1.03583996 -2.11716004 0 P 0 
L 0.98633996 -2.11616004 1.03588002 -2.11616004 0 P 0 
L 0.98641998 -2.11516004 1.03593002 -2.11516004 0 P 0 
L 0.98651004 -2.11416004 1.03596998 -2.11416004 0 P 0 
L 0.9866 -2.11316004 1.03601004 -2.11316004 0 P 0 
L 0.98668002 -2.11216004 1.03605 -2.11216004 0 P 0 
L 0.98676998 -2.11116004 1.0361 -2.11116004 0 P 0 
L 0.98685 -2.11016004 1.03613996 -2.11016004 0 P 0 
L 0.98693996 -2.10916004 1.03618002 -2.10916004 0 P 0 
L 0.987 -2.10816004 1.03623002 -2.10816004 0 P 0 
L 0.98705 -2.10716004 1.03626998 -2.10716004 0 P 0 
L 0.9871 -2.10616004 1.03631004 -2.10616004 0 P 0 
L 0.98716004 -2.10516004 1.03636004 -2.10516004 0 P 0 
L 0.9872 -2.10416004 1.0364 -2.10416004 0 P 0 
L 0.98725 -2.10316004 1.03643996 -2.10316004 0 P 0 
L 0.98731004 -2.10216004 1.03648002 -2.10216004 0 P 0 
L 0.98735 -2.10116004 1.03653002 -2.10116004 0 P 0 
L 0.9874 -2.10016004 1.03656998 -2.10016004 0 P 0 
L 0.98746004 -2.09916004 1.03661004 -2.09916004 0 P 0 
L 0.98751004 -2.09816004 1.03666004 -2.09816004 0 P 0 
L 0.98755 -2.09716004 1.0367 -2.09716004 0 P 0 
L 0.9876 -2.09616004 1.03673996 -2.09616004 0 P 0 
L 0.98766004 -2.09516004 1.03678996 -2.09516004 0 P 0 
L 0.9877 -2.09416004 1.03683002 -2.09416004 0 P 0 
L 0.98775 -2.09316004 1.03686998 -2.09316004 0 P 0 
L 0.98781004 -2.09216004 1.03691998 -2.09216004 0 P 0 
L 0.98785 -2.09116004 1.03696004 -2.09116004 0 P 0 
L 0.9879 -2.09016004 1.037 -2.09016004 0 P 0 
L 0.98796004 -2.08916004 1.03703996 -2.08916004 0 P 0 
L 0.98798996 -2.08816004 1.03706998 -2.08816004 0 P 0 
L 0.98801998 -2.08716004 1.03711004 -2.08716004 0 P 0 
L 0.98805 -2.08616004 1.03715 -2.08616004 0 P 0 
L 0.98808996 -2.08516004 1.03718996 -2.08516004 0 P 0 
L 0.98811998 -2.08416004 1.03723002 -2.08416004 0 P 0 
L 1.08216998 -2.15683002 1.19803996 -2.15683002 0 P 0 
L 1.0821 -2.15583002 1.19861004 -2.15583002 0 P 0 
L 1.08201998 -2.15483002 1.19918002 -2.15483002 0 P 0 
L 1.08195 -2.15383002 1.1997 -2.15383002 0 P 0 
L 1.08188996 -2.15283002 1.20018002 -2.15283002 0 P 0 
L 1.08183002 -2.15183002 1.20066004 -2.15183002 0 P 0 
L 1.08176998 -2.15083002 1.20113996 -2.15083002 0 P 0 
L 1.08171998 -2.14983002 1.20153996 -2.14983002 0 P 0 
L 1.08166004 -2.14883002 1.20193002 -2.14883002 0 P 0 
L 1.0816 -2.14783002 1.11538996 -2.14783002 0 P 0 
L 1.08155 -2.14683002 1.10903002 -2.14683002 0 P 0 
L 1.0815 -2.14583002 1.10415 -2.14583002 0 P 0 
L 1.08146004 -2.14483002 1.09953002 -2.14483002 0 P 0 
L 1.08141004 -2.14383002 1.09563996 -2.14383002 0 P 0 
L 1.08136004 -2.14283002 1.09183996 -2.14283002 0 P 0 
L 1.08131004 -2.14183002 1.08821004 -2.14183002 0 P 0 
L 1.08133002 -2.14083002 1.08471998 -2.14083002 0 P 0 
L 1.09586998 -2.11983002 1.14965 -2.11983002 0 P 0 
L 1.09361998 -2.11883002 1.15221998 -2.11883002 0 P 0 
L 1.09158996 -2.11783002 1.20595 -2.11783002 0 P 0 
L 1.08988002 -2.11683002 1.20601004 -2.11683002 0 P 0 
L 1.08823996 -2.11583002 1.20606998 -2.11583002 0 P 0 
L 1.08678996 -2.11483002 1.20613002 -2.11483002 0 P 0 
L 1.08541004 -2.11383002 1.20618996 -2.11383002 0 P 0 
L 1.08416998 -2.11283002 1.20625 -2.11283002 0 P 0 
L 1.08295 -2.11183002 1.20631004 -2.11183002 0 P 0 
L 1.08188002 -2.11083002 1.20638002 -2.11083002 0 P 0 
L 1.08081998 -2.10983002 1.20643996 -2.10983002 0 P 0 
L 1.07986004 -2.10883002 1.2065 -2.10883002 0 P 0 
L 1.07895 -2.10783002 1.20656004 -2.10783002 0 P 0 
L 1.07803002 -2.10683002 1.20661998 -2.10683002 0 P 0 
L 1.07723996 -2.10583002 1.20666998 -2.10583002 0 P 0 
L 1.07646004 -2.10483002 1.20671998 -2.10483002 0 P 0 
L 1.07568002 -2.10383002 1.20678002 -2.10383002 0 P 0 
L 1.075 -2.10283002 1.20683002 -2.10283002 0 P 0 
L 1.07433002 -2.10183002 1.20688002 -2.10183002 0 P 0 
L 1.07366998 -2.10083002 1.20693996 -2.10083002 0 P 0 
L 1.07308996 -2.09983002 1.20698996 -2.09983002 0 P 0 
L 1.07253002 -2.09883002 1.20705 -2.09883002 0 P 0 
L 1.07198002 -2.09783002 1.2071 -2.09783002 0 P 0 
L 1.07146998 -2.09683002 1.20715 -2.09683002 0 P 0 
L 1.07101998 -2.09583002 1.2072 -2.09583002 0 P 0 
L 1.07056998 -2.09483002 1.20726004 -2.09483002 0 P 0 
L 1.07013002 -2.09383002 1.20731004 -2.09383002 0 P 0 
L 1.06976998 -2.09283002 1.20736004 -2.09283002 0 P 0 
L 1.06941998 -2.09183002 1.20741998 -2.09183002 0 P 0 
L 1.06906004 -2.09083002 1.20746998 -2.09083002 0 P 0 
L 1.06876004 -2.08983002 1.20753002 -2.08983002 0 P 0 
L 1.06848996 -2.08883002 1.13443002 -2.08883002 0 P 0 
L 1.06821998 -2.08783002 1.13068002 -2.08783002 0 P 0 
L 1.06795 -2.08683002 1.12836998 -2.08683002 0 P 0 
L 1.06771998 -2.08583002 1.1266 -2.08583002 0 P 0 
L 1.06753002 -2.08483002 1.12516004 -2.08483002 0 P 0 
L 1.06733002 -2.08383002 1.12393996 -2.08383002 0 P 0 
L 0.90273996 -1.85456998 0.89068996 -1.85558002 0 P 0 
L 0.89068996 -1.85558002 0.87421004 -1.85741998 0 P 0 
L 0.87421004 -1.85741998 0.85783002 -1.85946998 0 P 0 
L 0.85783002 -1.85946998 0.85526998 -1.8599 0 P 0 
L 0.85526998 -1.8599 0.85276004 -1.86055 0 P 0 
L 0.85276004 -1.86055 0.85255 -1.86063996 0 P 0 
L 0.85255 -1.86063996 0.85248996 -1.86068996 0 P 0 
L 0.85248996 -1.86068996 0.85243002 -1.86073002 0 P 0 
L 0.85243002 -1.86073002 0.85238002 -1.86078002 0 P 0 
L 0.85238002 -1.86078002 0.85233002 -1.86083996 0 P 0 
L 0.85233002 -1.86083996 0.85225 -1.86096004 0 P 0 
L 0.85225 -1.86096004 0.85218002 -1.8611 0 P 0 
L 0.85218002 -1.8611 0.85216004 -1.86116998 0 P 0 
L 0.85216004 -1.86116998 0.85215 -1.86123996 0 P 0 
L 0.85215 -1.86123996 0.85213996 -1.86136998 0 P 0 
L 0.85213996 -1.86136998 0.85213002 -1.86148996 0 P 0 
L 0.85213002 -1.86148996 0.85213996 -1.86161998 0 P 0 
L 0.85213996 -1.86161998 0.85215 -1.86173996 0 P 0 
L 0.85215 -1.86173996 0.85218002 -1.86186998 0 P 0 
L 0.85218002 -1.86186998 0.85221004 -1.86198996 0 P 0 
L 0.85221004 -1.86198996 0.85225 -1.8621 0 P 0 
L 0.85225 -1.8621 0.85231004 -1.86221998 0 P 0 
L 0.85231004 -1.86221998 0.85236998 -1.86233002 0 P 0 
L 0.85236998 -1.86233002 0.85281998 -1.863 0 P 0 
L 0.85281998 -1.863 0.8533 -1.86363996 0 P 0 
L 0.8533 -1.86363996 0.85383002 -1.86425 0 P 0 
L 0.85383002 -1.86425 0.85736004 -1.86801998 0 P 0 
L 0.85736004 -1.86801998 0.86013002 -1.87113002 0 P 0 
L 0.86013002 -1.87113002 0.86266004 -1.87443002 0 P 0 
L 0.86266004 -1.87443002 0.86501004 -1.87798996 0 P 0 
L 0.86501004 -1.87798996 0.86711998 -1.88171004 0 P 0 
L 0.86711998 -1.88171004 0.86896998 -1.88553996 0 P 0 
L 0.86896998 -1.88553996 0.87055 -1.8895 0 P 0 
L 0.87055 -1.8895 0.8718 -1.89343002 0 P 0 
L 0.8718 -1.89343002 0.87276004 -1.89745 0 P 0 
L 0.87276004 -1.89745 0.87371004 -1.90195 0 P 0 
L 0.87371004 -1.90195 0.87383002 -1.90236004 0 P 0 
L 0.87383002 -1.90236004 0.87396998 -1.90276004 0 P 0 
L 0.87396998 -1.90276004 0.87416004 -1.90313996 0 P 0 
L 0.87416004 -1.90313996 0.87436998 -1.90351004 0 P 0 
L 0.87436998 -1.90351004 0.87443002 -1.9036 0 P 0 
L 0.87443002 -1.9036 0.87456998 -1.90376004 0 P 0 
L 0.87456998 -1.90376004 0.87465 -1.90381998 0 P 0 
L 0.87465 -1.90381998 0.87473002 -1.90388996 0 P 0 
L 0.87473002 -1.90388996 0.87481998 -1.90393996 0 P 0 
L 0.87481998 -1.90393996 0.87491998 -1.90398996 0 P 0 
L 0.87491998 -1.90398996 0.87501004 -1.90403002 0 P 0 
L 0.87501004 -1.90403002 0.87521004 -1.90408996 0 P 0 
L 0.87521004 -1.90408996 0.87531998 -1.9041 0 P 0 
L 0.87531998 -1.9041 0.87573002 -1.90413002 0 P 0 
L 0.87573002 -1.90413002 0.87613996 -1.90411998 0 P 0 
L 0.87613996 -1.90411998 0.87653996 -1.90408002 0 P 0 
L 0.87653996 -1.90408002 0.87695 -1.90401004 0 P 0 
L 0.87695 -1.90401004 0.90756004 -1.89766998 0 P 0 
L 0.90756004 -1.89766998 0.92603996 -1.89478002 0 P 0 
L 0.92603996 -1.89478002 0.93486004 -1.89393996 0 P 0 
L 0.93486004 -1.89393996 0.94371004 -1.8935 0 P 0 
L 0.94371004 -1.8935 0.97045 -1.89308002 0 P 0 
L 0.97045 -1.89308002 0.99468996 -1.89328996 0 P 0 
L 0.99468996 -1.89328996 1.01021004 -1.89413996 0 P 0 
L 1.01021004 -1.89413996 1.0241 -1.89601998 0 P 0 
L 1.0241 -1.89601998 1.04188002 -1.89961004 0 P 0 
L 1.04188002 -1.89961004 1.06095 -1.90466004 0 P 0 
L 1.06095 -1.90466004 1.07963996 -1.91123002 0 P 0 
L 1.07963996 -1.91123002 1.09093996 -1.91613002 0 P 0 
L 1.09093996 -1.91613002 1.10186998 -1.92175 0 P 0 
L 1.10186998 -1.92175 1.11243996 -1.92806998 0 P 0 
L 1.11243996 -1.92806998 1.12163002 -1.93446998 0 P 0 
L 1.12163002 -1.93446998 1.13033002 -1.94148996 0 P 0 
L 1.13033002 -1.94148996 1.1385 -1.94911004 0 P 0 
L 1.1385 -1.94911004 1.14358996 -1.9546 0 P 0 
L 1.14358996 -1.9546 1.14825 -1.96045 0 P 0 
L 1.14825 -1.96045 1.15246998 -1.96663002 0 P 0 
L 1.15246998 -1.96663002 1.15623002 -1.97316004 0 P 0 
L 1.15623002 -1.97316004 1.15895 -1.97831004 0 P 0 
L 1.15895 -1.97831004 1.17358996 -1.97831004 0 P 0 
L 1.17358996 -1.97831004 1.17135 -1.9726 0 P 0 
L 1.17135 -1.9726 1.16696004 -1.96266998 0 P 0 
L 1.16696004 -1.96266998 1.16171998 -1.95313002 0 P 0 
L 1.16171998 -1.95313002 1.1557 -1.94406998 0 P 0 
L 1.1557 -1.94406998 1.14885 -1.93548002 0 P 0 
L 1.14885 -1.93548002 1.13778996 -1.92378002 0 P 0 
L 1.13778996 -1.92378002 1.12576998 -1.91301998 0 P 0 
L 1.12576998 -1.91301998 1.11283996 -1.90326004 0 P 0 
L 1.11283996 -1.90326004 1.09783002 -1.89368996 0 P 0 
L 1.09783002 -1.89368996 1.08213002 -1.88526998 0 P 0 
L 1.08213002 -1.88526998 1.06576998 -1.87801004 0 P 0 
L 1.06576998 -1.87801004 1.04776004 -1.87141998 0 P 0 
L 1.04776004 -1.87141998 1.02938002 -1.86591998 0 P 0 
L 1.02938002 -1.86591998 1.01058002 -1.8615 0 P 0 
L 1.01058002 -1.8615 0.98441998 -1.85711004 0 P 0 
L 0.98441998 -1.85711004 0.95781004 -1.85448996 0 P 0 
L 0.95781004 -1.85448996 0.93061004 -1.85366004 0 P 0 
L 0.93061004 -1.85366004 0.90273996 -1.85456998 0 P 0 
L 1.16015 -1.97631004 1.15798002 -1.97218996 0 P 0 
L 1.15798002 -1.97218996 1.15796004 -1.97216004 0 P 0 
L 1.15796004 -1.97216004 1.15416004 -1.96556998 0 P 0 
L 1.15416004 -1.96556998 1.15411998 -1.96551004 0 P 0 
L 1.15411998 -1.96551004 1.14986004 -1.95926004 0 P 0 
L 1.14986004 -1.95926004 1.14981998 -1.95921004 0 P 0 
L 1.14981998 -1.95921004 1.14511004 -1.9533 0 P 0 
L 1.14511004 -1.9533 1.13991998 -1.9477 0 P 0 
L 1.13991998 -1.9477 1.13986004 -1.94765 0 P 0 
L 1.13986004 -1.94765 1.13163996 -1.93998002 0 P 0 
L 1.13163996 -1.93998002 1.12283002 -1.93286004 0 P 0 
L 1.12283002 -1.93286004 1.11351998 -1.92638996 0 P 0 
L 1.11351998 -1.92638996 1.10283996 -1.92 0 P 0 
L 1.10283996 -1.92 1.0918 -1.91433002 0 P 0 
L 1.0918 -1.91433002 1.08036998 -1.90936004 0 P 0 
L 1.08036998 -1.90936004 1.06153002 -1.90273996 0 P 0 
L 1.06153002 -1.90273996 1.06146004 -1.90273002 0 P 0 
L 1.06146004 -1.90273002 1.04233002 -1.89766004 0 P 0 
L 1.04233002 -1.89766004 1.02443002 -1.89405 0 P 0 
L 1.02443002 -1.89405 1.0104 -1.89213996 0 P 0 
L 1.0104 -1.89213996 0.99475 -1.89128996 0 P 0 
L 0.99475 -1.89128996 0.97045 -1.89108002 0 P 0 
L 0.97045 -1.89108002 0.94365 -1.8915 0 P 0 
L 0.94365 -1.8915 0.94361998 -1.8915 0 P 0 
L 0.94361998 -1.8915 0.93471998 -1.89195 0 P 0 
L 0.93471998 -1.89195 0.92578996 -1.89278996 0 P 0 
L 0.92578996 -1.89278996 0.9072 -1.89571004 0 P 0 
L 0.9072 -1.89571004 0.87656998 -1.90203996 0 P 0 
L 0.87656998 -1.90203996 0.87626998 -1.9021 0 P 0 
L 0.87626998 -1.9021 0.87601998 -1.90211998 0 P 0 
L 0.87601998 -1.90211998 0.87588996 -1.90213002 0 P 0 
L 0.87588996 -1.90213002 0.87583002 -1.90198996 0 P 0 
L 0.87583002 -1.90198996 0.87573002 -1.90175 0 P 0 
L 0.87573002 -1.90175 0.87566004 -1.90146998 0 P 0 
L 0.87566004 -1.90146998 0.87471004 -1.89701004 0 P 0 
L 0.87471004 -1.89701004 0.8747 -1.89698996 0 P 0 
L 0.8747 -1.89698996 0.87373002 -1.89288996 0 P 0 
L 0.87373002 -1.89288996 0.87243002 -1.88881998 0 P 0 
L 0.87243002 -1.88881998 0.8724 -1.88876004 0 P 0 
L 0.8724 -1.88876004 0.8708 -1.88473996 0 P 0 
L 0.8708 -1.88473996 0.8689 -1.88078002 0 P 0 
L 0.8689 -1.88078002 0.86671998 -1.87693996 0 P 0 
L 0.86671998 -1.87693996 0.86428996 -1.87326004 0 P 0 
L 0.86428996 -1.87326004 0.86166998 -1.86985 0 P 0 
L 0.86166998 -1.86985 0.85883996 -1.86668002 0 P 0 
L 0.85883996 -1.86668002 0.85883002 -1.86666004 0 P 0 
L 0.85883002 -1.86666004 0.85531998 -1.86291004 0 P 0 
L 0.85531998 -1.86291004 0.85486004 -1.86238002 0 P 0 
L 0.85486004 -1.86238002 0.85466004 -1.86211998 0 P 0 
L 0.85466004 -1.86211998 0.8557 -1.86186004 0 P 0 
L 0.8557 -1.86186004 0.85811998 -1.86145 0 P 0 
L 0.85811998 -1.86145 0.87443996 -1.85941004 0 P 0 
L 0.87443996 -1.85941004 0.89088996 -1.85756998 0 P 0 
L 0.89088996 -1.85756998 0.90286004 -1.85656998 0 P 0 
L 0.90286004 -1.85656998 0.93061004 -1.85566004 0 P 0 
L 0.93061004 -1.85566004 0.95768002 -1.85648996 0 P 0 
L 0.95768002 -1.85648996 0.98416004 -1.8591 0 P 0 
L 0.98416004 -1.8591 1.01018996 -1.86346004 0 P 0 
L 1.01018996 -1.86346004 1.02886004 -1.86785 0 P 0 
L 1.02886004 -1.86785 1.04711998 -1.87331998 0 P 0 
L 1.04711998 -1.87331998 1.06501004 -1.87986004 0 P 0 
L 1.06501004 -1.87986004 1.08125 -1.88706998 0 P 0 
L 1.08125 -1.88706998 1.09681004 -1.89541998 0 P 0 
L 1.09681004 -1.89541998 1.1117 -1.9049 0 P 0 
L 1.1117 -1.9049 1.1245 -1.91456998 0 P 0 
L 1.1245 -1.91456998 1.13638996 -1.92521004 0 P 0 
L 1.13638996 -1.92521004 1.14733996 -1.93678996 0 P 0 
L 1.14733996 -1.93678996 1.15408002 -1.94525 0 P 0 
L 1.15408002 -1.94525 1.16001004 -1.95416998 0 P 0 
L 1.16001004 -1.95416998 1.16516004 -1.96355 0 P 0 
L 1.16516004 -1.96355 1.1695 -1.97336998 0 P 0 
L 1.1695 -1.97336998 1.17066004 -1.97631004 0 P 0 
L 1.17066004 -1.97631004 1.16015 -1.97631004 0 P 0 
L 0.87563002 -1.90131004 0.8801 -1.90131004 0 P 0 
L 0.87541004 -1.90031004 0.88493996 -1.90031004 0 P 0 
L 0.8752 -1.89931004 0.88976998 -1.89931004 0 P 0 
L 0.87498996 -1.89831004 0.8946 -1.89831004 0 P 0 
L 0.89423002 -2.08316004 0.94355 -2.08316004 0 P 0 
L 0.89428996 -2.08216004 0.9436 -2.08216004 0 P 0 
L 0.89435 -2.08116004 0.94365 -2.08116004 0 P 0 
L 0.89441004 -2.08016004 0.9437 -2.08016004 0 P 0 
L 0.89446004 -2.07916004 0.94375 -2.07916004 0 P 0 
L 0.89451998 -2.07816004 0.94378996 -2.07816004 0 P 0 
L 0.89458002 -2.07716004 0.94383996 -2.07716004 0 P 0 
L 0.89463996 -2.07616004 0.94388996 -2.07616004 0 P 0 
L 0.8947 -2.07516004 0.94393996 -2.07516004 0 P 0 
L 0.89475 -2.07416004 0.94398002 -2.07416004 0 P 0 
L 0.89481004 -2.07316004 0.94403002 -2.07316004 0 P 0 
L 0.89486998 -2.07216004 0.94408002 -2.07216004 0 P 0 
L 0.89493002 -2.07116004 0.94415 -2.07116004 0 P 0 
L 0.89498996 -2.07016004 0.94426004 -2.07016004 0 P 0 
L 0.89505 -2.06916004 0.94436998 -2.06916004 0 P 0 
L 0.8951 -2.06816004 0.94448002 -2.06816004 0 P 0 
L 0.89516004 -2.06716004 0.94458996 -2.06716004 0 P 0 
L 0.89521998 -2.06616004 0.9447 -2.06616004 0 P 0 
L 0.89526998 -2.06516004 0.94481004 -2.06516004 0 P 0 
L 0.89531004 -2.06416004 0.94491998 -2.06416004 0 P 0 
L 0.89535 -2.06316004 0.94503002 -2.06316004 0 P 0 
L 0.8954 -2.06216004 0.94513996 -2.06216004 0 P 0 
L 0.89543996 -2.06116004 0.94531998 -2.06116004 0 P 0 
L 0.89548996 -2.06016004 0.94551004 -2.06016004 0 P 0 
L 0.89553002 -2.05916004 0.9457 -2.05916004 0 P 0 
L 0.89558002 -2.05816004 0.94588996 -2.05816004 0 P 0 
L 0.89561998 -2.05716004 0.94608002 -2.05716004 0 P 0 
L 0.89566998 -2.05616004 0.94626998 -2.05616004 0 P 0 
L 0.89571004 -2.05516004 0.94646998 -2.05516004 0 P 0 
L 0.89575 -2.05416004 0.94666004 -2.05416004 0 P 0 
L 0.8958 -2.05316004 0.94685 -2.05316004 0 P 0 
L 0.89583996 -2.05216004 0.94708002 -2.05216004 0 P 0 
L 0.89588996 -2.05116004 0.94735 -2.05116004 0 P 0 
L 0.89593996 -2.05016004 0.94761998 -2.05016004 0 P 0 
L 0.89598002 -2.04916004 0.9479 -2.04916004 0 P 0 
L 0.89601998 -2.04816004 0.94825 -2.04816004 0 P 0 
L 0.89606998 -2.04716004 0.94858996 -2.04716004 0 P 0 
L 0.89611004 -2.04616004 0.94893002 -2.04616004 0 P 0 
L 0.89616004 -2.04516004 0.94935 -2.04516004 0 P 0 
L 0.8962 -2.04416004 0.94976998 -2.04416004 0 P 0 
L 0.89625 -2.04316004 0.9502 -2.04316004 0 P 0 
L 0.89628002 -2.04216004 0.95068996 -2.04216004 0 P 0 
L 0.89631004 -2.04116004 0.95118996 -2.04116004 0 P 0 
L 0.89633996 -2.04016004 0.95168996 -2.04016004 0 P 0 
L 0.89638002 -2.03916004 0.95228002 -2.03916004 0 P 0 
L 0.89641004 -2.03816004 0.95291004 -2.03816004 0 P 0 
L 0.89643996 -2.03716004 0.95363002 -2.03716004 0 P 0 
L 0.89646998 -2.03616004 0.95445 -2.03616004 0 P 0 
L 0.89651004 -2.03516004 0.95535 -2.03516004 0 P 0 
L 0.89653996 -2.03416004 0.95636998 -2.03416004 0 P 0 
L 0.89656998 -2.03316004 0.95756998 -2.03316004 0 P 0 
L 0.8966 -2.03216004 0.95893996 -2.03216004 0 P 0 
L 0.89663996 -2.03116004 0.96055 -2.03116004 0 P 0 
L 0.89666998 -2.03016004 0.96278002 -2.03016004 0 P 0 
L 0.8967 -2.02916004 0.96676004 -2.02916004 0 P 0 
L 0.89673996 -2.02816004 1.03838996 -2.02816004 0 P 0 
L 0.89676998 -2.02716004 1.03838002 -2.02716004 0 P 0 
L 0.8968 -2.02616004 1.03833996 -2.02616004 0 P 0 
L 0.89683996 -2.02516004 1.03828996 -2.02516004 0 P 0 
L 0.89686998 -2.02416004 1.03823002 -2.02416004 0 P 0 
L 0.8969 -2.02316004 1.03816004 -2.02316004 0 P 0 
L 0.89693996 -2.02216004 1.0381 -2.02216004 0 P 0 
L 0.89696998 -2.02116004 1.03803996 -2.02116004 0 P 0 
L 0.897 -2.02016004 1.0379 -2.02016004 0 P 0 
L 0.89703002 -2.01916004 1.03773996 -2.01916004 0 P 0 
L 0.89706004 -2.01816004 1.03751998 -2.01816004 0 P 0 
L 0.89708996 -2.01716004 1.03728002 -2.01716004 0 P 0 
L 0.89711998 -2.01616004 1.03698996 -2.01616004 0 P 0 
L 0.89713996 -2.01516004 1.03668002 -2.01516004 0 P 0 
L 0.89716998 -2.01416004 1.03631004 -2.01416004 0 P 0 
L 0.8972 -2.01316004 1.03591998 -2.01316004 0 P 0 
L 0.89721998 -2.01216004 1.03548996 -2.01216004 0 P 0 
L 0.89725 -2.01116004 1.03505 -2.01116004 0 P 0 
L 0.89726998 -2.01016004 1.03458002 -2.01016004 0 P 0 
L 0.8973 -2.00916004 1.03405 -2.00916004 0 P 0 
L 0.89733002 -2.00816004 1.03351998 -2.00816004 0 P 0 
L 0.89736004 -2.00716004 0.94676004 -2.00716004 0 P 0 
L 0.89738002 -2.00616004 0.9461 -2.00616004 0 P 0 
L 0.89741004 -2.00516004 0.94563996 -2.00516004 0 P 0 
L 0.89743996 -2.00416004 0.94563996 -2.00416004 0 P 0 
L 0.89746004 -2.00316004 0.94563996 -2.00316004 0 P 0 
L 0.89748996 -2.00216004 0.94563996 -2.00216004 0 P 0 
L 0.89751004 -2.00116004 0.94563996 -2.00116004 0 P 0 
L 0.89753996 -2.00016004 0.94563996 -2.00016004 0 P 0 
L 0.89756998 -1.99916004 0.94563996 -1.99916004 0 P 0 
L 0.8976 -1.99816004 0.94563996 -1.99816004 0 P 0 
L 0.89761998 -1.99716004 0.94563996 -1.99716004 0 P 0 
L 0.89765 -1.99616004 0.94563996 -1.99616004 0 P 0 
L 0.89768002 -1.99516004 0.94563996 -1.99516004 0 P 0 
L 0.97546998 -1.98933996 0.97236998 -1.99006004 0 P 0 
L 0.97236998 -1.99006004 0.96931998 -1.99103002 0 P 0 
L 0.96931998 -1.99103002 0.96603002 -1.99233002 0 P 0 
L 0.96603002 -1.99233002 0.96281004 -1.99383002 0 P 0 
L 0.96281004 -1.99383002 0.95976004 -1.99546998 0 P 0 
L 0.95976004 -1.99546998 0.95681004 -1.99728996 0 P 0 
L 0.95681004 -1.99728996 0.95521004 -1.99841004 0 P 0 
L 0.95521004 -1.99841004 0.95368996 -1.99963002 0 P 0 
L 0.95368996 -1.99963002 0.95223996 -2.00095 0 P 0 
L 0.95223996 -2.00095 0.94763996 -2.00546998 0 P 0 
L 0.94763996 -2.00546998 0.94763996 -1.99243996 0 P 0 
L 0.94763996 -1.99243996 0.89575 -1.99243996 0 P 0 
L 0.89575 -1.99243996 0.89505 -2.01878002 0 P 0 
L 0.89505 -2.01878002 0.89423996 -2.04316004 0 P 0 
L 0.89423996 -2.04316004 0.89321998 -2.0661 0 P 0 
L 0.89321998 -2.0661 0.89198996 -2.08728996 0 P 0 
L 0.89198996 -2.08728996 0.89055 -2.1063 0 P 0 
L 0.89055 -2.1063 0.88993996 -2.11358002 0 P 0 
L 0.88993996 -2.11358002 0.88943002 -2.11988002 0 P 0 
L 0.88943002 -2.11988002 0.88898996 -2.12533996 0 P 0 
L 0.88898996 -2.12533996 0.88896004 -2.12613002 0 P 0 
L 0.88896004 -2.12613002 0.88896998 -2.12621004 0 P 0 
L 0.88896998 -2.12621004 0.88898002 -2.12625 0 P 0 
L 0.88898002 -2.12625 0.88898996 -2.12628002 0 P 0 
L 0.88898996 -2.12628002 0.88901998 -2.12636004 0 P 0 
L 0.88901998 -2.12636004 0.88903996 -2.12638996 0 P 0 
L 0.88903996 -2.12638996 0.88906998 -2.12641998 0 P 0 
L 0.88906998 -2.12641998 0.88908996 -2.12645 0 P 0 
L 0.88908996 -2.12645 0.88911998 -2.12646998 0 P 0 
L 0.88911998 -2.12646998 0.88915 -2.1265 0 P 0 
L 0.88915 -2.1265 0.88921004 -2.12653996 0 P 0 
L 0.88921004 -2.12653996 0.88925 -2.12655 0 P 0 
L 0.88925 -2.12655 0.88928002 -2.12656004 0 P 0 
L 0.88928002 -2.12656004 0.88931998 -2.12658002 0 P 0 
L 0.88931998 -2.12658002 0.8894 -2.12658002 0 P 0 
L 0.8894 -2.12658002 0.89648002 -2.12686998 0 P 0 
L 0.89648002 -2.12686998 0.90518996 -2.1271 0 P 0 
L 0.90518996 -2.1271 0.9165 -2.12716004 0 P 0 
L 0.9165 -2.12716004 0.94403996 -2.12716004 0 P 0 
L 0.94403996 -2.12716004 0.94468996 -2.10135 0 P 0 
L 0.94468996 -2.10135 0.9461 -2.07171998 0 P 0 
L 0.9461 -2.07171998 0.94713002 -2.06233002 0 P 0 
L 0.94713002 -2.06233002 0.9489 -2.05308002 0 P 0 
L 0.9489 -2.05308002 0.94975 -2.04995 0 P 0 
L 0.94975 -2.04995 0.9508 -2.04688996 0 P 0 
L 0.9508 -2.04688996 0.95205 -2.0439 0 P 0 
L 0.95205 -2.0439 0.95351004 -2.041 0 P 0 
L 0.95351004 -2.041 0.9544 -2.03951004 0 P 0 
L 0.9544 -2.03951004 0.95541998 -2.03811004 0 P 0 
L 0.95541998 -2.03811004 0.95655 -2.03678996 0 P 0 
L 0.95655 -2.03678996 0.95778996 -2.03556998 0 P 0 
L 0.95778996 -2.03556998 0.95911998 -2.03446998 0 P 0 
L 0.95911998 -2.03446998 0.96056998 -2.03346998 0 P 0 
L 0.96056998 -2.03346998 0.96151004 -2.03291004 0 P 0 
L 0.96151004 -2.03291004 0.96248996 -2.03243002 0 P 0 
L 0.96248996 -2.03243002 0.96351004 -2.03201998 0 P 0 
L 0.96351004 -2.03201998 0.96455 -2.03168996 0 P 0 
L 0.96455 -2.03168996 0.96613002 -2.0313 0 P 0 
L 0.96613002 -2.0313 0.96773002 -2.03101998 0 P 0 
L 0.96773002 -2.03101998 0.96935 -2.03086004 0 P 0 
L 0.96935 -2.03086004 0.97095 -2.03081004 0 P 0 
L 0.97095 -2.03081004 0.97255 -2.03086998 0 P 0 
L 0.97255 -2.03086998 0.97413002 -2.03105 0 P 0 
L 0.97413002 -2.03105 0.97513002 -2.03123996 0 P 0 
L 0.97513002 -2.03123996 0.9761 -2.03151004 0 P 0 
L 0.9761 -2.03151004 0.97706004 -2.03186004 0 P 0 
L 0.97706004 -2.03186004 0.97796998 -2.0323 0 P 0 
L 0.97796998 -2.0323 0.97885 -2.0328 0 P 0 
L 0.97885 -2.0328 0.97968002 -2.03336998 0 P 0 
L 0.97968002 -2.03336998 0.98046998 -2.03398996 0 P 0 
L 0.98046998 -2.03398996 0.98121998 -2.03468002 0 P 0 
L 0.98121998 -2.03468002 0.98191004 -2.03541998 0 P 0 
L 0.98191004 -2.03541998 0.98253996 -2.0362 0 P 0 
L 0.98253996 -2.0362 0.9831 -2.03703002 0 P 0 
L 0.9831 -2.03703002 0.9836 -2.03788996 0 P 0 
L 0.9836 -2.03788996 0.98403996 -2.0388 0 P 0 
L 0.98403996 -2.0388 0.9844 -2.03973996 0 P 0 
L 0.9844 -2.03973996 0.98505 -2.04188996 0 P 0 
L 0.98505 -2.04188996 0.98553002 -2.04408002 0 P 0 
L 0.98553002 -2.04408002 0.98583002 -2.0463 0 P 0 
L 0.98583002 -2.0463 0.98653002 -2.05705 0 P 0 
L 0.98653002 -2.05705 0.9866 -2.06961004 0 P 0 
L 0.9866 -2.06961004 0.98596004 -2.08908002 0 P 0 
L 0.98596004 -2.08908002 0.98498002 -2.10858002 0 P 0 
L 0.98498002 -2.10858002 0.98388002 -2.12146998 0 P 0 
L 0.98388002 -2.12146998 0.98323002 -2.12716004 0 P 0 
L 0.98323002 -2.12716004 1.03741004 -2.12716004 0 P 0 
L 1.03741004 -2.12716004 1.03896004 -2.09103002 0 P 0 
L 1.03896004 -2.09103002 1.03956004 -2.0759 0 P 0 
L 1.03956004 -2.0759 1.04005 -2.06025 0 P 0 
L 1.04005 -2.06025 1.04038996 -2.04626004 0 P 0 
L 1.04038996 -2.04626004 1.04048002 -2.03698996 0 P 0 
L 1.04048002 -2.03698996 1.04036998 -2.02651998 0 P 0 
L 1.04036998 -2.02651998 1.04003996 -2.02096998 0 P 0 
L 1.04003996 -2.02096998 1.03975 -2.01895 0 P 0 
L 1.03975 -2.01895 1.0393 -2.01693996 0 P 0 
L 1.0393 -2.01693996 1.03868996 -2.01483996 0 P 0 
L 1.03868996 -2.01483996 1.03793996 -2.01278002 0 P 0 
L 1.03793996 -2.01278002 1.03658996 -2.00968002 0 P 0 
L 1.03658996 -2.00968002 1.03501004 -2.00668996 0 P 0 
L 1.03501004 -2.00668996 1.0332 -2.0038 0 P 0 
L 1.0332 -2.0038 1.03186998 -2.002 0 P 0 
L 1.03186998 -2.002 1.0304 -2.0003 0 P 0 
L 1.0304 -2.0003 1.0288 -1.99873002 0 P 0 
L 1.0288 -1.99873002 1.02708002 -1.99728996 0 P 0 
L 1.02708002 -1.99728996 1.02518002 -1.99593002 0 P 0 
L 1.02518002 -1.99593002 1.02318002 -1.99471998 0 P 0 
L 1.02318002 -1.99471998 1.0211 -1.99365 0 P 0 
L 1.0211 -1.99365 1.01893002 -1.99273996 0 P 0 
L 1.01893002 -1.99273996 1.01358996 -1.99098996 0 P 0 
L 1.01358996 -1.99098996 1.0081 -1.98971004 0 P 0 
L 1.0081 -1.98971004 1.00428996 -1.98908996 0 P 0 
L 1.00428996 -1.98908996 1.00043996 -1.98868002 0 P 0 
L 1.00043996 -1.98868002 0.99138002 -1.98826004 0 P 0 
L 0.99138002 -1.98826004 0.98251998 -1.98846998 0 P 0 
L 0.98251998 -1.98846998 0.97898996 -1.98878996 0 P 0 
L 0.97898996 -1.98878996 0.97546998 -1.98933996 0 P 0 
L 0.91651004 -2.12516004 0.94208996 -2.12516004 0 P 0 
L 0.8911 -2.12416004 0.94211004 -2.12416004 0 P 0 
L 0.89118002 -2.12316004 0.94213996 -2.12316004 0 P 0 
L 0.89125 -2.12216004 0.94216004 -2.12216004 0 P 0 
L 0.89133002 -2.12116004 0.94218996 -2.12116004 0 P 0 
L 0.89141004 -2.12016004 0.94221004 -2.12016004 0 P 0 
L 0.89148996 -2.11916004 0.94223996 -2.11916004 0 P 0 
L 0.89156998 -2.11816004 0.94226998 -2.11816004 0 P 0 
L 0.89166004 -2.11716004 0.94228996 -2.11716004 0 P 0 
L 0.89173996 -2.11616004 0.94231004 -2.11616004 0 P 0 
L 0.89181998 -2.11516004 0.94233996 -2.11516004 0 P 0 
L 0.8919 -2.11416004 0.94236004 -2.11416004 0 P 0 
L 0.89198002 -2.11316004 0.94238996 -2.11316004 0 P 0 
L 0.89206998 -2.11216004 0.94241998 -2.11216004 0 P 0 
L 0.89215 -2.11116004 0.94243996 -2.11116004 0 P 0 
L 0.89223002 -2.11016004 0.94246998 -2.11016004 0 P 0 
L 0.89231998 -2.10916004 0.94248996 -2.10916004 0 P 0 
L 0.8924 -2.10816004 0.94251998 -2.10816004 0 P 0 
L 0.89248002 -2.10716004 0.94255 -2.10716004 0 P 0 
L 0.89256998 -2.10616004 0.94256998 -2.10616004 0 P 0 
L 0.89263996 -2.10516004 0.94258996 -2.10516004 0 P 0 
L 0.89271004 -2.10416004 0.94261998 -2.10416004 0 P 0 
L 0.89278996 -2.10316004 0.94263996 -2.10316004 0 P 0 
L 0.89286998 -2.10216004 0.94266998 -2.10216004 0 P 0 
L 0.89293996 -2.10116004 0.9427 -2.10116004 0 P 0 
L 0.89301998 -2.10016004 0.94275 -2.10016004 0 P 0 
L 0.89308996 -2.09916004 0.94278996 -2.09916004 0 P 0 
L 0.89316998 -2.09816004 0.94283996 -2.09816004 0 P 0 
L 0.89325 -2.09716004 0.94288996 -2.09716004 0 P 0 
L 0.89331998 -2.09616004 0.94293996 -2.09616004 0 P 0 
L 0.8934 -2.09516004 0.94298002 -2.09516004 0 P 0 
L 0.89346998 -2.09416004 0.94303002 -2.09416004 0 P 0 
L 0.89355 -2.09316004 0.94308002 -2.09316004 0 P 0 
L 0.89361998 -2.09216004 0.94313002 -2.09216004 0 P 0 
L 0.8937 -2.09116004 0.94318002 -2.09116004 0 P 0 
L 0.89378002 -2.09016004 0.94321998 -2.09016004 0 P 0 
L 0.89385 -2.08916004 0.94326998 -2.08916004 0 P 0 
L 0.89393002 -2.08816004 0.94331998 -2.08816004 0 P 0 
L 0.894 -2.08716004 0.94336004 -2.08716004 0 P 0 
L 0.89406004 -2.08616004 0.94341004 -2.08616004 0 P 0 
L 0.89411998 -2.08516004 0.94346004 -2.08516004 0 P 0 
L 0.89418002 -2.08416004 0.94351004 -2.08416004 0 P 0 
L 0.91651004 -2.12516004 0.90521998 -2.1251 0 P 0 
L 0.90521998 -2.1251 0.89655 -2.12486998 0 P 0 
L 0.89655 -2.12486998 0.89106004 -2.12465 0 P 0 
L 0.89106004 -2.12465 0.89141998 -2.12003996 0 P 0 
L 0.89141998 -2.12003996 0.89193996 -2.11373996 0 P 0 
L 0.89193996 -2.11373996 0.89253996 -2.10645 0 P 0 
L 0.89253996 -2.10645 0.89398002 -2.08741998 0 P 0 
L 0.89398002 -2.08741998 0.89521998 -2.06621998 0 P 0 
L 0.89521998 -2.06621998 0.89521998 -2.06618996 0 P 0 
L 0.89521998 -2.06618996 0.89623996 -2.04323002 0 P 0 
L 0.89623996 -2.04323002 0.89703996 -2.01883002 0 P 0 
L 0.89703996 -2.01883002 0.8977 -1.99443996 0 P 0 
L 0.8977 -1.99443996 0.94563996 -1.99443996 0 P 0 
L 0.94563996 -1.99443996 0.94563996 -2.00546998 0 P 0 
L 0.94563996 -2.00546998 0.94686004 -2.00731004 0 P 0 
L 0.94686004 -2.00731004 0.94903002 -2.00688996 0 P 0 
L 0.94903002 -2.00688996 0.95361998 -2.00241004 0 P 0 
L 0.95361998 -2.00241004 0.95498996 -2.00115 0 P 0 
L 0.95498996 -2.00115 0.95641998 -2.00001004 0 P 0 
L 0.95641998 -2.00001004 0.9579 -1.99896004 0 P 0 
L 0.9579 -1.99896004 0.96076004 -1.9972 0 P 0 
L 0.96076004 -1.9972 0.9637 -1.99561998 0 P 0 
L 0.9637 -1.99561998 0.96683002 -1.99416998 0 P 0 
L 0.96683002 -1.99416998 0.96998996 -1.99291998 0 P 0 
L 0.96998996 -1.99291998 0.9729 -1.99198996 0 P 0 
L 0.9729 -1.99198996 0.97586004 -1.9913 0 P 0 
L 0.97586004 -1.9913 0.97923002 -1.99076998 0 P 0 
L 0.97923002 -1.99076998 0.98263002 -1.99046998 0 P 0 
L 0.98263002 -1.99046998 0.99136004 -1.99026004 0 P 0 
L 0.99136004 -1.99026004 1.00028996 -1.99066998 0 P 0 
L 1.00028996 -1.99066998 1.00403002 -1.99108002 0 P 0 
L 1.00403002 -1.99108002 1.00771004 -1.99166998 0 P 0 
L 1.00771004 -1.99166998 1.01305 -1.99291998 0 P 0 
L 1.01305 -1.99291998 1.01823002 -1.99461998 0 P 0 
L 1.01823002 -1.99461998 1.02026004 -1.99546998 0 P 0 
L 1.02026004 -1.99546998 1.02221004 -1.99646998 0 P 0 
L 1.02221004 -1.99646998 1.02408002 -1.9976 0 P 0 
L 1.02408002 -1.9976 1.02585 -1.99886998 0 P 0 
L 1.02585 -1.99886998 1.02746004 -2.00021004 0 P 0 
L 1.02746004 -2.00021004 1.02893996 -2.00166998 0 P 0 
L 1.02893996 -2.00166998 1.03031004 -2.00325 0 P 0 
L 1.03031004 -2.00325 1.03155 -2.00493002 0 P 0 
L 1.03155 -2.00493002 1.03326998 -2.00768002 0 P 0 
L 1.03326998 -2.00768002 1.03478002 -2.01055 0 P 0 
L 1.03478002 -2.01055 1.03608002 -2.01351998 0 P 0 
L 1.03608002 -2.01351998 1.03678996 -2.01546998 0 P 0 
L 1.03678996 -2.01546998 1.03736004 -2.01743002 0 P 0 
L 1.03736004 -2.01743002 1.03778002 -2.0193 0 P 0 
L 1.03778002 -2.0193 1.03805 -2.02116998 0 P 0 
L 1.03805 -2.02116998 1.03836998 -2.02658996 0 P 0 
L 1.03836998 -2.02658996 1.03848002 -2.03698996 0 P 0 
L 1.03848002 -2.03698996 1.03838996 -2.04623002 0 P 0 
L 1.03838996 -2.04623002 1.03805 -2.06018996 0 P 0 
L 1.03805 -2.06018996 1.03756004 -2.07583002 0 P 0 
L 1.03756004 -2.07583002 1.03696998 -2.09095 0 P 0 
L 1.03696998 -2.09095 1.03548996 -2.12516004 0 P 0 
L 1.03548996 -2.12516004 0.98546998 -2.12516004 0 P 0 
L 0.98546998 -2.12516004 0.98586998 -2.12166004 0 P 0 
L 0.98586998 -2.12166004 0.98696998 -2.10871998 0 P 0 
L 0.98696998 -2.10871998 0.98796004 -2.08916004 0 P 0 
L 0.98796004 -2.08916004 0.9886 -2.06963002 0 P 0 
L 0.9886 -2.06963002 0.98853002 -2.05698002 0 P 0 
L 0.98853002 -2.05698002 0.98781998 -2.0461 0 P 0 
L 0.98781998 -2.0461 0.9875 -2.04373002 0 P 0 
L 0.9875 -2.04373002 0.98748002 -2.04365 0 P 0 
L 0.98748002 -2.04365 0.98698996 -2.04138996 0 P 0 
L 0.98698996 -2.04138996 0.9863 -2.03908002 0 P 0 
L 0.9863 -2.03908002 0.98588002 -2.038 0 P 0 
L 0.98588002 -2.038 0.98538002 -2.03696004 0 P 0 
L 0.98538002 -2.03696004 0.9848 -2.03596004 0 P 0 
L 0.9848 -2.03596004 0.98413996 -2.03501004 0 P 0 
L 0.98413996 -2.03501004 0.98341998 -2.03411004 0 P 0 
L 0.98341998 -2.03411004 0.98336998 -2.03405 0 P 0 
L 0.98336998 -2.03405 0.98263002 -2.03326004 0 P 0 
L 0.98263002 -2.03326004 0.98176998 -2.03246998 0 P 0 
L 0.98176998 -2.03246998 0.98086998 -2.03175 0 P 0 
L 0.98086998 -2.03175 0.97991004 -2.0311 0 P 0 
L 0.97991004 -2.0311 0.9789 -2.03051998 0 P 0 
L 0.9789 -2.03051998 0.97783002 -2.03001998 0 P 0 
L 0.97783002 -2.03001998 0.97673002 -2.02961004 0 P 0 
L 0.97673002 -2.02961004 0.97663996 -2.02958002 0 P 0 
L 0.97663996 -2.02958002 0.97558996 -2.02928996 0 P 0 
L 0.97558996 -2.02928996 0.97443002 -2.02906998 0 P 0 
L 0.97443002 -2.02906998 0.9727 -2.02888002 0 P 0 
L 0.9727 -2.02888002 0.97261998 -2.02886998 0 P 0 
L 0.97261998 -2.02886998 0.97096004 -2.02881004 0 P 0 
L 0.97096004 -2.02881004 0.96921004 -2.02886004 0 P 0 
L 0.96921004 -2.02886004 0.96745 -2.02903996 0 P 0 
L 0.96745 -2.02903996 0.96571004 -2.02933996 0 P 0 
L 0.96571004 -2.02933996 0.964 -2.02976004 0 P 0 
L 0.964 -2.02976004 0.96283002 -2.03013996 0 P 0 
L 0.96283002 -2.03013996 0.96168002 -2.0306 0 P 0 
L 0.96168002 -2.0306 0.96056998 -2.03115 0 P 0 
L 0.96056998 -2.03115 0.95948996 -2.03178002 0 P 0 
L 0.95948996 -2.03178002 0.95791004 -2.03286998 0 P 0 
L 0.95791004 -2.03286998 0.95645 -2.03408996 0 P 0 
L 0.95645 -2.03408996 0.95508996 -2.03541998 0 P 0 
L 0.95508996 -2.03541998 0.95383996 -2.03686998 0 P 0 
L 0.95383996 -2.03686998 0.9538 -2.03693002 0 P 0 
L 0.9538 -2.03693002 0.95273002 -2.03841004 0 P 0 
L 0.95273002 -2.03841004 0.95175 -2.04003996 0 P 0 
L 0.95175 -2.04003996 0.95023002 -2.04306004 0 P 0 
L 0.95023002 -2.04306004 0.94896004 -2.04611004 0 P 0 
L 0.94896004 -2.04611004 0.94893002 -2.04616998 0 P 0 
L 0.94893002 -2.04616998 0.94783002 -2.04936004 0 P 0 
L 0.94783002 -2.04936004 0.94695 -2.05263002 0 P 0 
L 0.94695 -2.05263002 0.94515 -2.06203002 0 P 0 
L 0.94515 -2.06203002 0.9441 -2.07156004 0 P 0 
L 0.9441 -2.07156004 0.9427 -2.10128002 0 P 0 
L 0.9427 -2.10128002 0.94208996 -2.12516004 0 P 0 
L 0.94208996 -2.12516004 0.91651004 -2.12516004 0 P 0 
L 0.93143002 -2.21261998 1.00578996 -2.21261998 0 P 0 
L 0.94051004 -2.21161998 1.00803002 -2.21161998 0 P 0 
L 0.94941998 -2.21061998 1.01026004 -2.21061998 0 P 0 
L 0.9555 -2.20961998 1.0125 -2.20961998 0 P 0 
L 0.96158002 -2.20861998 1.01473996 -2.20861998 0 P 0 
L 0.96766004 -2.20761998 1.01696998 -2.20761998 0 P 0 
L 0.97373002 -2.20661998 1.01921004 -2.20661998 0 P 0 
L 0.97981004 -2.20561998 1.02145 -2.20561998 0 P 0 
L 0.98498996 -2.20461998 1.02368996 -2.20461998 0 P 0 
L 0.98973996 -2.20361998 1.02591998 -2.20361998 0 P 0 
L 0.99448996 -2.20261998 1.02816004 -2.20261998 0 P 0 
L 0.99923996 -2.20161998 1.0304 -2.20161998 0 P 0 
L 1.00398996 -2.20061998 1.03243996 -2.20061998 0 P 0 
L 1.00875 -2.19961998 1.0344 -2.19961998 0 P 0 
L 1.01348996 -2.19861998 1.03636998 -2.19861998 0 P 0 
L 1.0178 -2.19761998 1.03833996 -2.19761998 0 P 0 
L 1.02168996 -2.19661998 1.04031004 -2.19661998 0 P 0 
L 1.02558002 -2.19561998 1.04228002 -2.19561998 0 P 0 
L 1.02946998 -2.19461998 1.04415 -2.19461998 0 P 0 
L 1.03336004 -2.19361998 1.04596998 -2.19361998 0 P 0 
L 1.03725 -2.19261998 1.04778996 -2.19261998 0 P 0 
L 1.04113996 -2.19161998 1.0496 -2.19161998 0 P 0 
L 1.14356998 -1.98926998 1.13261004 -1.99086004 0 P 0 
L 1.13261004 -1.99086004 1.12165 -1.9934 0 P 0 
L 1.12165 -1.9934 1.11125 -1.99673002 0 P 0 
L 1.11125 -1.99673002 1.10658002 -1.99858996 0 P 0 
L 1.10658002 -1.99858996 1.10198996 -2.00071004 0 P 0 
L 1.10198996 -2.00071004 1.09653002 -2.00358996 0 P 0 
L 1.09653002 -2.00358996 1.09436998 -2.00488996 0 P 0 
L 1.09436998 -2.00488996 1.09226004 -2.00631004 0 P 0 
L 1.09226004 -2.00631004 1.09028002 -2.00781004 0 P 0 
L 1.09028002 -2.00781004 1.08836998 -2.00941998 0 P 0 
L 1.08836998 -2.00941998 1.08405 -2.0135 0 P 0 
L 1.08405 -2.0135 1.08096998 -2.01678996 0 P 0 
L 1.08096998 -2.01678996 1.07808002 -2.02026998 0 P 0 
L 1.07808002 -2.02026998 1.0754 -2.02393002 0 P 0 
L 1.0754 -2.02393002 1.07313996 -2.02748002 0 P 0 
L 1.07313996 -2.02748002 1.07116004 -2.03118996 0 P 0 
L 1.07116004 -2.03118996 1.06943996 -2.03505 0 P 0 
L 1.06943996 -2.03505 1.06795 -2.03918996 0 P 0 
L 1.06795 -2.03918996 1.06673996 -2.04343996 0 P 0 
L 1.06673996 -2.04343996 1.06583002 -2.04778002 0 P 0 
L 1.06583002 -2.04778002 1.06476998 -2.05538996 0 P 0 
L 1.06476998 -2.05538996 1.06421004 -2.06306004 0 P 0 
L 1.06421004 -2.06306004 1.06415 -2.07076004 0 P 0 
L 1.06415 -2.07076004 1.06456998 -2.0785 0 P 0 
L 1.06456998 -2.0785 1.06508996 -2.08276004 0 P 0 
L 1.06508996 -2.08276004 1.06591004 -2.08696004 0 P 0 
L 1.06591004 -2.08696004 1.06703002 -2.09108002 0 P 0 
L 1.06703002 -2.09108002 1.06833002 -2.09473002 0 P 0 
L 1.06833002 -2.09473002 1.06991998 -2.09823996 0 P 0 
L 1.06991998 -2.09823996 1.0718 -2.10161998 0 P 0 
L 1.0718 -2.10161998 1.07398002 -2.10491998 0 P 0 
L 1.07398002 -2.10491998 1.07641998 -2.10803002 0 P 0 
L 1.07641998 -2.10803002 1.07908996 -2.11095 0 P 0 
L 1.07908996 -2.11095 1.08175 -2.11345 0 P 0 
L 1.08175 -2.11345 1.08458996 -2.11573996 0 P 0 
L 1.08458996 -2.11573996 1.08758996 -2.1178 0 P 0 
L 1.08758996 -2.1178 1.09073002 -2.11963996 0 P 0 
L 1.09073002 -2.11963996 1.094 -2.12123996 0 P 0 
L 1.094 -2.12123996 1.0986 -2.12306998 0 P 0 
L 1.0986 -2.12306998 1.10331004 -2.12456004 0 P 0 
L 1.10331004 -2.12456004 1.10811004 -2.12568996 0 P 0 
L 1.10811004 -2.12568996 1.11298002 -2.12646998 0 P 0 
L 1.11298002 -2.12646998 1.1182 -2.12693002 0 P 0 
L 1.1182 -2.12693002 1.12343996 -2.12703002 0 P 0 
L 1.12343996 -2.12703002 1.12866998 -2.12676004 0 P 0 
L 1.12866998 -2.12676004 1.13388002 -2.12613002 0 P 0 
L 1.13388002 -2.12613002 1.14086004 -2.12473996 0 P 0 
L 1.14086004 -2.12473996 1.1477 -2.12273996 0 P 0 
L 1.1477 -2.12273996 1.15433996 -2.12015 0 P 0 
L 1.15433996 -2.12015 1.1545 -2.12008996 0 P 0 
L 1.1545 -2.12008996 1.15466004 -2.12003996 0 P 0 
L 1.15466004 -2.12003996 1.15483002 -2.12001004 0 P 0 
L 1.15483002 -2.12001004 1.15498996 -2.11998996 0 P 0 
L 1.15498996 -2.11998996 1.15533002 -2.11998996 0 P 0 
L 1.15533002 -2.11998996 1.15538996 -2.12 0 P 0 
L 1.15538996 -2.12 1.15545 -2.12001998 0 P 0 
L 1.15545 -2.12001998 1.15551004 -2.12003002 0 P 0 
L 1.15551004 -2.12003002 1.15556004 -2.12006004 0 P 0 
L 1.15556004 -2.12006004 1.15561004 -2.12008002 0 P 0 
L 1.15561004 -2.12008002 1.15566004 -2.12011004 0 P 0 
L 1.15566004 -2.12011004 1.15571004 -2.12015 0 P 0 
L 1.15571004 -2.12015 1.15575 -2.12018996 0 P 0 
L 1.15575 -2.12018996 1.15578996 -2.12023996 0 P 0 
L 1.15578996 -2.12023996 1.15583002 -2.12028002 0 P 0 
L 1.15583002 -2.12028002 1.15586004 -2.12033996 0 P 0 
L 1.15586004 -2.12033996 1.15588002 -2.12038996 0 P 0 
L 1.15588002 -2.12038996 1.15591004 -2.12043996 0 P 0 
L 1.15591004 -2.12043996 1.15601998 -2.12076004 0 P 0 
L 1.15601998 -2.12076004 1.1561 -2.12108002 0 P 0 
L 1.1561 -2.12108002 1.15616004 -2.12141998 0 P 0 
L 1.15616004 -2.12141998 1.15618002 -2.12175 0 P 0 
L 1.15618002 -2.12175 1.15623996 -2.12505 0 P 0 
L 1.15623996 -2.12505 1.15616004 -2.12688002 0 P 0 
L 1.15616004 -2.12688002 1.15593002 -2.12871004 0 P 0 
L 1.15593002 -2.12871004 1.15553996 -2.13051998 0 P 0 
L 1.15553996 -2.13051998 1.15516004 -2.1318 0 P 0 
L 1.15516004 -2.1318 1.1547 -2.13305 0 P 0 
L 1.1547 -2.13305 1.15415 -2.13426004 0 P 0 
L 1.15415 -2.13426004 1.15351004 -2.13545 0 P 0 
L 1.15351004 -2.13545 1.15278996 -2.1366 0 P 0 
L 1.15278996 -2.1366 1.15198002 -2.13768996 0 P 0 
L 1.15198002 -2.13768996 1.15111004 -2.13873002 0 P 0 
L 1.15111004 -2.13873002 1.15016004 -2.13971004 0 P 0 
L 1.15016004 -2.13971004 1.14876004 -2.14096004 0 P 0 
L 1.14876004 -2.14096004 1.14726004 -2.1421 0 P 0 
L 1.14726004 -2.1421 1.14566998 -2.14311004 0 P 0 
L 1.14566998 -2.14311004 1.144 -2.144 0 P 0 
L 1.144 -2.144 1.14226004 -2.14476004 0 P 0 
L 1.14226004 -2.14476004 1.14046004 -2.14536998 0 P 0 
L 1.14046004 -2.14536998 1.13863002 -2.14583002 0 P 0 
L 1.13863002 -2.14583002 1.13676004 -2.14613996 0 P 0 
L 1.13676004 -2.14613996 1.13041998 -2.14663996 0 P 0 
L 1.13041998 -2.14663996 1.12403996 -2.1466 0 P 0 
L 1.12403996 -2.1466 1.11621998 -2.14593996 0 P 0 
L 1.11621998 -2.14593996 1.10843996 -2.14471004 0 P 0 
L 1.10843996 -2.14471004 1.09946998 -2.14276998 0 P 0 
L 1.09946998 -2.14276998 1.0905 -2.14041004 0 P 0 
L 1.0905 -2.14041004 1.07963996 -2.13728996 0 P 0 
L 1.07963996 -2.13728996 1.07936004 -2.1401 0 P 0 
L 1.07936004 -2.1401 1.07931004 -2.14103996 0 P 0 
L 1.07931004 -2.14103996 1.07931998 -2.14198002 0 P 0 
L 1.07931998 -2.14198002 1.07956998 -2.14735 0 P 0 
L 1.07956998 -2.14735 1.07993996 -2.15375 0 P 0 
L 1.07993996 -2.15375 1.08045 -2.16081998 0 P 0 
L 1.08045 -2.16081998 1.08181004 -2.17873002 0 P 0 
L 1.08181004 -2.17873002 1.08996004 -2.18061004 0 P 0 
L 1.08996004 -2.18061004 1.09951004 -2.18246004 0 P 0 
L 1.09951004 -2.18246004 1.11243996 -2.18416998 0 P 0 
L 1.11243996 -2.18416998 1.1254 -2.18543002 0 P 0 
L 1.1254 -2.18543002 1.13508002 -2.18583002 0 P 0 
L 1.13508002 -2.18583002 1.14765 -2.18528996 0 P 0 
L 1.14765 -2.18528996 1.15368002 -2.18461004 0 P 0 
L 1.15368002 -2.18461004 1.15971004 -2.18363996 0 P 0 
L 1.15971004 -2.18363996 1.16521004 -2.18248002 0 P 0 
L 1.16521004 -2.18248002 1.17063996 -2.18103002 0 P 0 
L 1.17063996 -2.18103002 1.17528996 -2.17946998 0 P 0 
L 1.17528996 -2.17946998 1.17978002 -2.17753996 0 P 0 
L 1.17978002 -2.17753996 1.18216998 -2.1763 0 P 0 
L 1.18216998 -2.1763 1.18446004 -2.17488996 0 P 0 
L 1.18446004 -2.17488996 1.18663996 -2.17331004 0 P 0 
L 1.18663996 -2.17331004 1.18871004 -2.17156004 0 P 0 
L 1.18871004 -2.17156004 1.19161004 -2.16871998 0 P 0 
L 1.19161004 -2.16871998 1.19431004 -2.16568996 0 P 0 
L 1.19431004 -2.16568996 1.19678996 -2.16246998 0 P 0 
L 1.19678996 -2.16246998 1.19908996 -2.15901998 0 P 0 
L 1.19908996 -2.15901998 1.20113996 -2.15543996 0 P 0 
L 1.20113996 -2.15543996 1.20295 -2.15171004 0 P 0 
L 1.20295 -2.15171004 1.20435 -2.14815 0 P 0 
L 1.20435 -2.14815 1.20543996 -2.14448996 0 P 0 
L 1.20543996 -2.14448996 1.20621004 -2.14073996 0 P 0 
L 1.20621004 -2.14073996 1.20651998 -2.13855 0 P 0 
L 1.20651998 -2.13855 1.20671998 -2.13633996 0 P 0 
L 1.20671998 -2.13633996 1.20761998 -2.12321004 0 P 0 
L 1.20761998 -2.12321004 1.20858002 -2.10753996 0 P 0 
L 1.20858002 -2.10753996 1.20951004 -2.09021998 0 P 0 
L 1.20951004 -2.09021998 1.21048002 -2.07166004 0 P 0 
L 1.21048002 -2.07166004 1.21156004 -2.05228002 0 P 0 
L 1.21156004 -2.05228002 1.21258002 -2.03478996 0 P 0 
L 1.21258002 -2.03478996 1.21333002 -2.02286004 0 P 0 
L 1.21333002 -2.02286004 1.21393996 -2.01373996 0 P 0 
L 1.21393996 -2.01373996 1.21443996 -2.00568996 0 P 0 
L 1.21443996 -2.00568996 1.21485 -1.99883996 0 P 0 
L 1.21485 -1.99883996 1.2149 -1.99721004 0 P 0 
L 1.2149 -1.99721004 1.21488996 -1.99703996 0 P 0 
L 1.21488996 -1.99703996 1.21486998 -1.99686004 0 P 0 
L 1.21486998 -1.99686004 1.21483996 -1.99668996 0 P 0 
L 1.21483996 -1.99668996 1.21478996 -1.99653002 0 P 0 
L 1.21478996 -1.99653002 1.21473002 -1.99636998 0 P 0 
L 1.21473002 -1.99636998 1.21466004 -1.99621004 0 P 0 
L 1.21466004 -1.99621004 1.21458002 -1.99606004 0 P 0 
L 1.21458002 -1.99606004 1.21448002 -1.99591004 0 P 0 
L 1.21448002 -1.99591004 1.21433002 -1.99571998 0 P 0 
L 1.21433002 -1.99571998 1.21416998 -1.99553996 0 P 0 
L 1.21416998 -1.99553996 1.21398996 -1.99538002 0 P 0 
L 1.21398996 -1.99538002 1.21378996 -1.99523996 0 P 0 
L 1.21378996 -1.99523996 1.21358002 -1.99511004 0 P 0 
L 1.21358002 -1.99511004 1.21336004 -1.995 0 P 0 
L 1.21336004 -1.995 1.21261004 -1.99468996 0 P 0 
L 1.21261004 -1.99468996 1.21183996 -1.99443996 0 P 0 
L 1.21183996 -1.99443996 1.21105 -1.99423002 0 P 0 
L 1.21105 -1.99423002 1.20593996 -1.99318002 0 P 0 
L 1.20593996 -1.99318002 1.18996998 -1.99065 0 P 0 
L 1.18996998 -1.99065 1.17318996 -1.98908002 0 P 0 
L 1.17318996 -1.98908002 1.15718996 -1.98858002 0 P 0 
L 1.15718996 -1.98858002 1.1504 -1.98876004 0 P 0 
L 1.1504 -1.98876004 1.14356998 -1.98926998 0 P 0 
L 1.04503996 -2.19061998 1.05141998 -2.19061998 0 P 0 
L 1.04893002 -2.18961998 1.05323002 -2.18961998 0 P 0 
L 1.05263002 -2.18861998 1.05503996 -2.18861998 0 P 0 
L 1.05628996 -2.18761998 1.05676004 -2.18761998 0 P 0 
L 1.09645 -2.17983002 1.16738002 -2.17983002 0 P 0 
L 1.09126004 -2.17883002 1.17091004 -2.17883002 0 P 0 
L 1.0868 -2.17783002 1.17386998 -2.17783002 0 P 0 
L 1.08368002 -2.17683002 1.17636004 -2.17683002 0 P 0 
L 1.0836 -2.17583002 1.1787 -2.17583002 0 P 0 
L 1.08351998 -2.17483002 1.18066998 -2.17483002 0 P 0 
L 1.08345 -2.17383002 1.18236998 -2.17383002 0 P 0 
L 1.08336998 -2.17283002 1.1839 -2.17283002 0 P 0 
L 1.08328996 -2.17183002 1.18526998 -2.17183002 0 P 0 
L 1.08321998 -2.17083002 1.18646998 -2.17083002 0 P 0 
L 1.08313996 -2.16983002 1.18761998 -2.16983002 0 P 0 
L 1.08306998 -2.16883002 1.18863996 -2.16883002 0 P 0 
L 1.08298996 -2.16783002 1.18966004 -2.16783002 0 P 0 
L 1.08291998 -2.16683002 1.19061004 -2.16683002 0 P 0 
L 1.08283996 -2.16583002 1.1915 -2.16583002 0 P 0 
L 1.08276004 -2.16483002 1.19238996 -2.16483002 0 P 0 
L 1.08268996 -2.16383002 1.19321004 -2.16383002 0 P 0 
L 1.08261004 -2.16283002 1.19398002 -2.16283002 0 P 0 
L 1.08253002 -2.16183002 1.19476004 -2.16183002 0 P 0 
L 1.08246004 -2.16083002 1.19548002 -2.16083002 0 P 0 
L 1.08238002 -2.15983002 1.19613996 -2.15983002 0 P 0 
L 1.08231004 -2.15883002 1.19681004 -2.15883002 0 P 0 
L 1.08223996 -2.15783002 1.19746004 -2.15783002 0 P 0 
L 1.13506998 -2.18383002 1.12553002 -2.18343996 0 P 0 
L 1.12553002 -2.18343996 1.11266004 -2.18218002 0 P 0 
L 1.11266004 -2.18218002 1.09983002 -2.18048002 0 P 0 
L 1.09983002 -2.18048002 1.09036998 -2.17866004 0 P 0 
L 1.09036998 -2.17866004 1.0837 -2.17711004 0 P 0 
L 1.0837 -2.17711004 1.08245 -2.16066998 0 P 0 
L 1.08245 -2.16066998 1.08193996 -2.15361998 0 P 0 
L 1.08193996 -2.15361998 1.08156998 -2.14726004 0 P 0 
L 1.08156998 -2.14726004 1.08131998 -2.14191004 0 P 0 
L 1.08131998 -2.14191004 1.08131004 -2.14108996 0 P 0 
L 1.08131004 -2.14108996 1.08136004 -2.14026004 0 P 0 
L 1.08136004 -2.14026004 1.0814 -2.13986998 0 P 0 
L 1.0814 -2.13986998 1.08996004 -2.14233002 0 P 0 
L 1.08996004 -2.14233002 1.08996998 -2.14233996 0 P 0 
L 1.08996998 -2.14233996 1.08998996 -2.14233996 0 P 0 
L 1.08998996 -2.14233996 1.099 -2.14471998 0 P 0 
L 1.099 -2.14471998 1.10806998 -2.14668002 0 P 0 
L 1.10806998 -2.14668002 1.11598002 -2.14791998 0 P 0 
L 1.11598002 -2.14791998 1.12395 -2.1486 0 P 0 
L 1.12395 -2.1486 1.13048996 -2.14863996 0 P 0 
L 1.13048996 -2.14863996 1.137 -2.14811998 0 P 0 
L 1.137 -2.14811998 1.13903002 -2.14778996 0 P 0 
L 1.13903002 -2.14778996 1.14103002 -2.14728996 0 P 0 
L 1.14103002 -2.14728996 1.14298002 -2.14661998 0 P 0 
L 1.14298002 -2.14661998 1.14486998 -2.14581004 0 P 0 
L 1.14486998 -2.14581004 1.14668002 -2.14483996 0 P 0 
L 1.14668002 -2.14483996 1.1484 -2.14373996 0 P 0 
L 1.1484 -2.14373996 1.15003002 -2.1425 0 P 0 
L 1.15003002 -2.1425 1.15155 -2.14115 0 P 0 
L 1.15155 -2.14115 1.1526 -2.14006998 0 P 0 
L 1.1526 -2.14006998 1.15263996 -2.14001998 0 P 0 
L 1.15263996 -2.14001998 1.15356004 -2.13893002 0 P 0 
L 1.15356004 -2.13893002 1.15443996 -2.13771998 0 P 0 
L 1.15443996 -2.13771998 1.15523002 -2.13646004 0 P 0 
L 1.15523002 -2.13646004 1.15593996 -2.13515 0 P 0 
L 1.15593996 -2.13515 1.15655 -2.13381004 0 P 0 
L 1.15655 -2.13381004 1.15706004 -2.13243002 0 P 0 
L 1.15706004 -2.13243002 1.15748002 -2.13101004 0 P 0 
L 1.15748002 -2.13101004 1.1579 -2.12905 0 P 0 
L 1.1579 -2.12905 1.15816004 -2.12706004 0 P 0 
L 1.15816004 -2.12706004 1.15825 -2.12506998 0 P 0 
L 1.15825 -2.12506998 1.15818002 -2.12165 0 P 0 
L 1.15818002 -2.12165 1.15813996 -2.12118002 0 P 0 
L 1.15813996 -2.12118002 1.15813002 -2.1211 0 P 0 
L 1.15813002 -2.1211 1.15806004 -2.12068002 0 P 0 
L 1.15806004 -2.12068002 1.15793996 -2.12018996 0 P 0 
L 1.15793996 -2.12018996 1.15778002 -2.11973002 0 P 0 
L 1.15778002 -2.11973002 1.1577 -2.11953002 0 P 0 
L 1.1577 -2.11953002 1.15758996 -2.11933002 0 P 0 
L 1.15758996 -2.11933002 1.15746998 -2.11913996 0 P 0 
L 1.15746998 -2.11913996 1.15733002 -2.11895 0 P 0 
L 1.15733002 -2.11895 1.15716998 -2.11878002 0 P 0 
L 1.15716998 -2.11878002 1.157 -2.11863002 0 P 0 
L 1.157 -2.11863002 1.15681998 -2.11848996 0 P 0 
L 1.15681998 -2.11848996 1.15663002 -2.11836004 0 P 0 
L 1.15663002 -2.11836004 1.15641998 -2.11825 0 P 0 
L 1.15641998 -2.11825 1.15621004 -2.11816004 0 P 0 
L 1.15621004 -2.11816004 1.15598996 -2.11808996 0 P 0 
L 1.15598996 -2.11808996 1.15576998 -2.11803996 0 P 0 
L 1.15576998 -2.11803996 1.15553002 -2.118 0 P 0 
L 1.15553002 -2.118 1.15518002 -2.11798002 0 P 0 
L 1.15518002 -2.11798002 1.15483996 -2.11798996 0 P 0 
L 1.15483996 -2.11798996 1.15451004 -2.11803002 0 P 0 
L 1.15451004 -2.11803002 1.15418002 -2.1181 0 P 0 
L 1.15418002 -2.1181 1.15386004 -2.1182 0 P 0 
L 1.15386004 -2.1182 1.15361004 -2.11828996 0 P 0 
L 1.15361004 -2.11828996 1.14705 -2.12083996 0 P 0 
L 1.14705 -2.12083996 1.14038996 -2.12278996 0 P 0 
L 1.14038996 -2.12278996 1.13356004 -2.12416004 0 P 0 
L 1.13356004 -2.12416004 1.1285 -2.12476998 0 P 0 
L 1.1285 -2.12476998 1.12341004 -2.12501998 0 P 0 
L 1.12341004 -2.12501998 1.11831004 -2.12493002 0 P 0 
L 1.11831004 -2.12493002 1.11323002 -2.12448996 0 P 0 
L 1.11323002 -2.12448996 1.10848996 -2.12373002 0 P 0 
L 1.10848996 -2.12373002 1.10383996 -2.12263002 0 P 0 
L 1.10383996 -2.12263002 1.09926998 -2.12118996 0 P 0 
L 1.09926998 -2.12118996 1.09481004 -2.11941004 0 P 0 
L 1.09481004 -2.11941004 1.09168002 -2.11788002 0 P 0 
L 1.09168002 -2.11788002 1.08866004 -2.11611998 0 P 0 
L 1.08866004 -2.11611998 1.08578002 -2.11413002 0 P 0 
L 1.08578002 -2.11413002 1.08306998 -2.11193996 0 P 0 
L 1.08306998 -2.11193996 1.08051998 -2.10955 0 P 0 
L 1.08051998 -2.10955 1.07793996 -2.10673002 0 P 0 
L 1.07793996 -2.10673002 1.07561004 -2.10373996 0 P 0 
L 1.07561004 -2.10373996 1.07351004 -2.10058002 0 P 0 
L 1.07351004 -2.10058002 1.07171004 -2.09733996 0 P 0 
L 1.07171004 -2.09733996 1.07018002 -2.09396998 0 P 0 
L 1.07018002 -2.09396998 1.06893996 -2.09048002 0 P 0 
L 1.06893996 -2.09048002 1.06786004 -2.0865 0 P 0 
L 1.06786004 -2.0865 1.06706004 -2.08243996 0 P 0 
L 1.06706004 -2.08243996 1.06656004 -2.07833002 0 P 0 
L 1.06656004 -2.07833002 1.06615 -2.07071004 0 P 0 
L 1.06615 -2.07071004 1.06621004 -2.06313996 0 P 0 
L 1.06621004 -2.06313996 1.06675 -2.0556 0 P 0 
L 1.06675 -2.0556 1.0678 -2.04813002 0 P 0 
L 1.0678 -2.04813002 1.06868996 -2.04391998 0 P 0 
L 1.06868996 -2.04391998 1.06985 -2.03981004 0 P 0 
L 1.06985 -2.03981004 1.0713 -2.03578996 0 P 0 
L 1.0713 -2.03578996 1.07296004 -2.03206998 0 P 0 
L 1.07296004 -2.03206998 1.07486998 -2.02848996 0 P 0 
L 1.07486998 -2.02848996 1.07705 -2.02506004 0 P 0 
L 1.07705 -2.02506004 1.07966004 -2.0215 0 P 0 
L 1.07966004 -2.0215 1.08246998 -2.01811004 0 P 0 
L 1.08246998 -2.01811004 1.08546998 -2.01491004 0 P 0 
L 1.08546998 -2.01491004 1.0897 -2.01091004 0 P 0 
L 1.0897 -2.01091004 1.09153002 -2.00936998 0 P 0 
L 1.09153002 -2.00936998 1.09341998 -2.00793996 0 P 0 
L 1.09341998 -2.00793996 1.09545 -2.00658002 0 P 0 
L 1.09545 -2.00658002 1.09751004 -2.00533996 0 P 0 
L 1.09751004 -2.00533996 1.10288002 -2.0025 0 P 0 
L 1.10288002 -2.0025 1.10736998 -2.00043002 0 P 0 
L 1.10736998 -2.00043002 1.11193002 -1.99861004 0 P 0 
L 1.11193002 -1.99861004 1.12218002 -1.99533002 0 P 0 
L 1.12218002 -1.99533002 1.13298002 -1.99281998 0 P 0 
L 1.13298002 -1.99281998 1.14378996 -1.99126004 0 P 0 
L 1.14378996 -1.99126004 1.1505 -1.99075 0 P 0 
L 1.1505 -1.99075 1.15718002 -1.99058996 0 P 0 
L 1.15718002 -1.99058996 1.17306998 -1.99108002 0 P 0 
L 1.17306998 -1.99108002 1.18971998 -1.99263002 0 P 0 
L 1.18971998 -1.99263002 1.20558002 -1.99515 0 P 0 
L 1.20558002 -1.99515 1.21058996 -1.99618002 0 P 0 
L 1.21058996 -1.99618002 1.21126998 -1.99636004 0 P 0 
L 1.21126998 -1.99636004 1.21191998 -1.99656998 0 P 0 
L 1.21191998 -1.99656998 1.21253002 -1.99681998 0 P 0 
L 1.21253002 -1.99681998 1.21261004 -1.99686004 0 P 0 
L 1.21261004 -1.99686004 1.21266004 -1.99688996 0 P 0 
L 1.21266004 -1.99688996 1.21271998 -1.99693002 0 P 0 
L 1.21271998 -1.99693002 1.21281998 -1.99703002 0 P 0 
L 1.21281998 -1.99703002 1.21286004 -1.99708996 0 P 0 
L 1.21286004 -1.99708996 1.21288002 -1.99711004 0 P 0 
L 1.21288002 -1.99711004 1.21288002 -1.99711998 0 P 0 
L 1.21288002 -1.99711998 1.21288996 -1.99715 0 P 0 
L 1.21288996 -1.99715 1.2129 -1.99716998 0 P 0 
L 1.2129 -1.99716998 1.2129 -1.99721998 0 P 0 
L 1.2129 -1.99721998 1.21285 -1.99875 0 P 0 
L 1.21285 -1.99875 1.21243996 -2.00556998 0 P 0 
L 1.21243996 -2.00556998 1.21193996 -2.01361004 0 P 0 
L 1.21193996 -2.01361004 1.21133996 -2.02273002 0 P 0 
L 1.21133996 -2.02273002 1.21133996 -2.02273996 0 P 0 
L 1.21133996 -2.02273996 1.21058996 -2.03468002 0 P 0 
L 1.21058996 -2.03468002 1.20956004 -2.05216998 0 P 0 
L 1.20956004 -2.05216998 1.20848996 -2.07156004 0 P 0 
L 1.20848996 -2.07156004 1.20848996 -2.07156998 0 P 0 
L 1.20848996 -2.07156998 1.20751004 -2.09011004 0 P 0 
L 1.20751004 -2.09011004 1.20658996 -2.10743996 0 P 0 
L 1.20658996 -2.10743996 1.20561998 -2.12308996 0 P 0 
L 1.20561998 -2.12308996 1.20473002 -2.13618996 0 P 0 
L 1.20473002 -2.13618996 1.20453002 -2.13831998 0 P 0 
L 1.20453002 -2.13831998 1.20423996 -2.14041004 0 P 0 
L 1.20423996 -2.14041004 1.2035 -2.144 0 P 0 
L 1.2035 -2.144 1.20246004 -2.1475 0 P 0 
L 1.20246004 -2.1475 1.20111998 -2.1509 0 P 0 
L 1.20111998 -2.1509 1.19936998 -2.1545 0 P 0 
L 1.19936998 -2.1545 1.19738002 -2.15796998 0 P 0 
L 1.19738002 -2.15796998 1.19516004 -2.1613 0 P 0 
L 1.19516004 -2.1613 1.19276998 -2.16441004 0 P 0 
L 1.19276998 -2.16441004 1.19016004 -2.16733996 0 P 0 
L 1.19016004 -2.16733996 1.18736004 -2.17008002 0 P 0 
L 1.18736004 -2.17008002 1.1854 -2.17173996 0 P 0 
L 1.1854 -2.17173996 1.18335 -2.17323002 0 P 0 
L 1.18335 -2.17323002 1.18118002 -2.17456004 0 P 0 
L 1.18118002 -2.17456004 1.17893002 -2.17573002 0 P 0 
L 1.17893002 -2.17573002 1.17456998 -2.1776 0 P 0 
L 1.17456998 -2.1776 1.17006998 -2.17911998 0 P 0 
L 1.17006998 -2.17911998 1.16473996 -2.18053002 0 P 0 
L 1.16473996 -2.18053002 1.15935 -2.18166998 0 P 0 
L 1.15935 -2.18166998 1.15341998 -2.18263002 0 P 0 
L 1.15341998 -2.18263002 1.1475 -2.18328996 0 P 0 
L 1.1475 -2.18328996 1.13506998 -2.18383002 0 P 0 
L 0.90491998 -2.21461998 1.00131004 -2.21461998 0 P 0 
L 0.92235 -2.21361998 1.00355 -2.21361998 0 P 0 
L 0.76925 -1.8965 0.85586998 -1.8965 0 P 0 
L 0.76958996 -1.8955 0.85556004 -1.8955 0 P 0 
L 0.76995 -1.8945 0.85521004 -1.8945 0 P 0 
L 0.77031004 -1.8935 0.85486004 -1.8935 0 P 0 
L 0.77071004 -1.8925 0.85443996 -1.8925 0 P 0 
L 0.77115 -1.8915 0.85401004 -1.8915 0 P 0 
L 0.7716 -1.8905 0.85355 -1.8905 0 P 0 
L 0.77206004 -1.8895 0.85303002 -1.8895 0 P 0 
L 0.7726 -1.8885 0.85251004 -1.8885 0 P 0 
L 0.77313996 -1.8875 0.85198996 -1.8875 0 P 0 
L 0.77368996 -1.8865 0.85138002 -1.8865 0 P 0 
L 0.77433002 -1.8855 0.85073996 -1.8855 0 P 0 
L 0.77496004 -1.8845 0.85011004 -1.8845 0 P 0 
L 0.77561998 -1.8835 0.84943002 -1.8835 0 P 0 
L 0.77636004 -1.8825 0.84866998 -1.8825 0 P 0 
L 0.77711004 -1.8815 0.84791004 -1.8815 0 P 0 
L 0.7779 -1.8805 0.84713002 -1.8805 0 P 0 
L 0.77876998 -1.8795 0.84623002 -1.8795 0 P 0 
L 0.77963996 -1.8785 0.84533002 -1.8785 0 P 0 
L 0.7806 -1.8775 0.8444 -1.8775 0 P 0 
L 0.78161004 -1.8765 0.84335 -1.8765 0 P 0 
L 0.78265 -1.8755 0.84228996 -1.8755 0 P 0 
L 0.78381998 -1.8745 0.84108996 -1.8745 0 P 0 
L 0.78498996 -1.8735 0.83986998 -1.8735 0 P 0 
L 0.78635 -1.8725 0.83848002 -1.8725 0 P 0 
L 0.78773002 -1.8715 0.83706004 -1.8715 0 P 0 
L 0.78933002 -1.8705 0.83541998 -1.8705 0 P 0 
L 0.791 -1.8695 0.83366004 -1.8695 0 P 0 
L 0.793 -1.8685 0.83171998 -1.8685 0 P 0 
L 0.79525 -1.8675 0.82941998 -1.8675 0 P 0 
L 0.79791998 -1.8665 0.82671004 -1.8665 0 P 0 
L 0.80143996 -1.8655 0.82328996 -1.8655 0 P 0 
L 0.80705 -1.8645 0.81776004 -1.8645 0 P 0 
L 0.74543002 -1.89661998 0.75033002 -1.89661998 0 P 0 
L 0.74751004 -1.89561998 0.75058996 -1.89561998 0 P 0 
L 0.74958996 -1.89461998 0.75086004 -1.89461998 0 P 0 
L 0.76733996 -1.9125 0.85751998 -1.9125 0 P 0 
L 0.76728996 -1.9115 0.85756004 -1.9115 0 P 0 
L 0.76723996 -1.9105 0.85758996 -1.9105 0 P 0 
L 0.76721998 -1.9095 0.85763002 -1.9095 0 P 0 
L 0.76725 -1.9085 0.85761004 -1.9085 0 P 0 
L 0.76728002 -1.9075 0.85756998 -1.9075 0 P 0 
L 0.76731004 -1.9065 0.85753002 -1.9065 0 P 0 
L 0.76741998 -1.9055 0.85748996 -1.9055 0 P 0 
L 0.76753996 -1.9045 0.85738002 -1.9045 0 P 0 
L 0.76766004 -1.9035 0.85726004 -1.9035 0 P 0 
L 0.76781998 -1.9025 0.85713996 -1.9025 0 P 0 
L 0.76801998 -1.9015 0.85701004 -1.9015 0 P 0 
L 0.76821004 -1.9005 0.85683002 -1.9005 0 P 0 
L 0.76841998 -1.8995 0.85661998 -1.8995 0 P 0 
L 0.7687 -1.8985 0.85641004 -1.8985 0 P 0 
L 0.76896998 -1.8975 0.85613996 -1.8975 0 P 0 
L 0.76751004 -2.08325 0.8416 -2.08325 0 P 0 
L 0.76761998 -2.08225 0.84161998 -2.08225 0 P 0 
L 0.76773996 -2.08125 0.84166998 -2.08125 0 P 0 
L 0.76786004 -2.08025 0.84171998 -2.08025 0 P 0 
L 0.76796998 -2.07925 0.84176998 -2.07925 0 P 0 
L 0.76808002 -2.07825 0.84181004 -2.07825 0 P 0 
L 0.76818002 -2.07725 0.84186004 -2.07725 0 P 0 
L 0.76828996 -2.07625 0.8419 -2.07625 0 P 0 
L 0.76838996 -2.07525 0.84195 -2.07525 0 P 0 
L 0.76848996 -2.07425 0.842 -2.07425 0 P 0 
L 0.7686 -2.07325 0.84205 -2.07325 0 P 0 
L 0.7687 -2.07225 0.84208996 -2.07225 0 P 0 
L 0.7688 -2.07125 0.84213996 -2.07125 0 P 0 
L 0.7689 -2.07025 0.84218002 -2.07025 0 P 0 
L 0.76901004 -2.06925 0.84223002 -2.06925 0 P 0 
L 0.76911004 -2.06825 0.84228002 -2.06825 0 P 0 
L 0.76921004 -2.06725 0.84233002 -2.06725 0 P 0 
L 0.76931998 -2.06625 0.84236998 -2.06625 0 P 0 
L 0.76941998 -2.06525 0.84241998 -2.06525 0 P 0 
L 0.76948996 -2.06425 0.84246004 -2.06425 0 P 0 
L 0.76956004 -2.06325 0.84251004 -2.06325 0 P 0 
L 0.76963002 -2.06225 0.84256004 -2.06225 0 P 0 
L 0.7697 -2.06125 0.8426 -2.06125 0 P 0 
L 0.76976998 -2.06025 0.84265 -2.06025 0 P 0 
L 0.76983996 -2.05925 0.8427 -2.05925 0 P 0 
L 0.76991004 -2.05825 0.84273996 -2.05825 0 P 0 
L 0.76996998 -2.05725 0.84278996 -2.05725 0 P 0 
L 0.77001004 -2.05625 0.84283996 -2.05625 0 P 0 
L 0.77003996 -2.05525 0.84288002 -2.05525 0 P 0 
L 0.77008002 -2.05425 0.84295 -2.05425 0 P 0 
L 0.77011998 -2.05325 0.84303996 -2.05325 0 P 0 
L 0.77016004 -2.05225 0.84311998 -2.05225 0 P 0 
L 0.77018996 -2.05125 0.84321004 -2.05125 0 P 0 
L 0.77023002 -2.05025 0.8433 -2.05025 0 P 0 
L 0.77026998 -2.04925 0.84338002 -2.04925 0 P 0 
L 0.77031004 -2.04825 0.84346998 -2.04825 0 P 0 
L 0.77033996 -2.04725 0.84356004 -2.04725 0 P 0 
L 0.77038002 -2.04625 0.84363996 -2.04625 0 P 0 
L 0.77041004 -2.04525 0.84373002 -2.04525 0 P 0 
L 0.77043996 -2.04425 0.84381004 -2.04425 0 P 0 
L 0.77046004 -2.04325 0.8439 -2.04325 0 P 0 
L 0.77048002 -2.04225 0.84398996 -2.04225 0 P 0 
L 0.77051004 -2.04125 0.84406998 -2.04125 0 P 0 
L 0.77053002 -2.04025 0.84416004 -2.04025 0 P 0 
L 0.77055 -2.03925 0.84425 -2.03925 0 P 0 
L 0.77058002 -2.03825 0.84433002 -2.03825 0 P 0 
L 0.7706 -2.03725 0.84441998 -2.03725 0 P 0 
L 0.77061998 -2.03625 0.84451004 -2.03625 0 P 0 
L 0.77065 -2.03525 0.84458996 -2.03525 0 P 0 
L 0.77066998 -2.03425 0.84468002 -2.03425 0 P 0 
L 0.7707 -2.03325 0.84476998 -2.03325 0 P 0 
L 0.77071998 -2.03225 0.84485 -2.03225 0 P 0 
L 0.77073002 -2.03125 0.84493996 -2.03125 0 P 0 
L 0.77073996 -2.03025 0.84503002 -2.03025 0 P 0 
L 0.79986004 -1.8638 0.79643996 -1.86486998 0 P 0 
L 0.79643996 -1.86486998 0.79311998 -1.86621004 0 P 0 
L 0.79311998 -1.86621004 0.78991004 -1.86781004 0 P 0 
L 0.78991004 -1.86781004 0.78683996 -1.86966998 0 P 0 
L 0.78683996 -1.86966998 0.78391998 -1.87178002 0 P 0 
L 0.78391998 -1.87178002 0.78111998 -1.87416998 0 P 0 
L 0.78111998 -1.87416998 0.7785 -1.87676004 0 P 0 
L 0.7785 -1.87676004 0.77608002 -1.87953996 0 P 0 
L 0.77608002 -1.87953996 0.77386998 -1.8825 0 P 0 
L 0.77386998 -1.8825 0.77188002 -1.88561998 0 P 0 
L 0.77188002 -1.88561998 0.77013996 -1.88886004 0 P 0 
L 0.77013996 -1.88886004 0.76863996 -1.89221004 0 P 0 
L 0.76863996 -1.89221004 0.7674 -1.89566998 0 P 0 
L 0.7674 -1.89566998 0.76643002 -1.89921004 0 P 0 
L 0.76643002 -1.89921004 0.76571004 -1.90283996 0 P 0 
L 0.76571004 -1.90283996 0.76531004 -1.90636004 0 P 0 
L 0.76531004 -1.90636004 0.7652 -1.90991004 0 P 0 
L 0.7652 -1.90991004 0.76538996 -1.91345 0 P 0 
L 0.76538996 -1.91345 0.76586998 -1.91696998 0 P 0 
L 0.76586998 -1.91696998 0.76663996 -1.92046004 0 P 0 
L 0.76663996 -1.92046004 0.76803002 -1.92493996 0 P 0 
L 0.76803002 -1.92493996 0.76978002 -1.9293 0 P 0 
L 0.76978002 -1.9293 0.77106998 -1.93193996 0 P 0 
L 0.77106998 -1.93193996 0.77253002 -1.93448002 0 P 0 
L 0.77253002 -1.93448002 0.77416004 -1.93693996 0 P 0 
L 0.77416004 -1.93693996 0.77593002 -1.93923002 0 P 0 
L 0.77593002 -1.93923002 0.77783996 -1.94141004 0 P 0 
L 0.77783996 -1.94141004 0.77988996 -1.94345 0 P 0 
L 0.77988996 -1.94345 0.78216004 -1.94545 0 P 0 
L 0.78216004 -1.94545 0.78453996 -1.9473 0 P 0 
L 0.78453996 -1.9473 0.78703002 -1.94901998 0 P 0 
L 0.78703002 -1.94901998 0.79016998 -1.95088002 0 P 0 
L 0.79016998 -1.95088002 0.79343996 -1.95248996 0 P 0 
L 0.79343996 -1.95248996 0.79683002 -1.95383996 0 P 0 
L 0.79683002 -1.95383996 0.80031998 -1.95491998 0 P 0 
L 0.80031998 -1.95491998 0.80391004 -1.95573996 0 P 0 
L 0.80391004 -1.95573996 0.80751998 -1.95626004 0 P 0 
L 0.80751998 -1.95626004 0.81116004 -1.9565 0 P 0 
L 0.81116004 -1.9565 0.81481004 -1.95646004 0 P 0 
L 0.81481004 -1.95646004 0.81843996 -1.95613002 0 P 0 
L 0.81843996 -1.95613002 0.82205 -1.95551004 0 P 0 
L 0.82205 -1.95551004 0.82561998 -1.95461004 0 P 0 
L 0.82561998 -1.95461004 0.82911004 -1.95345 0 P 0 
L 0.82911004 -1.95345 0.83248996 -1.95201004 0 P 0 
L 0.83248996 -1.95201004 0.83576004 -1.95031998 0 P 0 
L 0.83576004 -1.95031998 0.83891998 -1.94836004 0 P 0 
L 0.83891998 -1.94836004 0.84191998 -1.94616998 0 P 0 
L 0.84191998 -1.94616998 0.84475 -1.94375 0 P 0 
L 0.84475 -1.94375 0.84738996 -1.94113996 0 P 0 
L 0.84738996 -1.94113996 0.84983002 -1.93833996 0 P 0 
L 0.84983002 -1.93833996 0.85206998 -1.93533996 0 P 0 
L 0.85206998 -1.93533996 0.8536 -1.93291998 0 P 0 
L 0.8536 -1.93291998 0.85496004 -1.93041004 0 P 0 
L 0.85496004 -1.93041004 0.85613996 -1.9278 0 P 0 
L 0.85613996 -1.9278 0.85711998 -1.92511004 0 P 0 
L 0.85711998 -1.92511004 0.85823002 -1.92123002 0 P 0 
L 0.85823002 -1.92123002 0.85901998 -1.91726998 0 P 0 
L 0.85901998 -1.91726998 0.85948996 -1.91323996 0 P 0 
L 0.85948996 -1.91323996 0.85963996 -1.90918002 0 P 0 
L 0.85963996 -1.90918002 0.85946998 -1.90513002 0 P 0 
L 0.85946998 -1.90513002 0.85898002 -1.9011 0 P 0 
L 0.85898002 -1.9011 0.85841998 -1.89826004 0 P 0 
L 0.85841998 -1.89826004 0.85766004 -1.89546004 0 P 0 
L 0.85766004 -1.89546004 0.85671004 -1.89273002 0 P 0 
L 0.85671004 -1.89273002 0.85556998 -1.89006004 0 P 0 
L 0.85556998 -1.89006004 0.85361998 -1.88631004 0 P 0 
L 0.85361998 -1.88631004 0.85136004 -1.88273996 0 P 0 
L 0.85136004 -1.88273996 0.84881004 -1.87938002 0 P 0 
L 0.84881004 -1.87938002 0.84596998 -1.87623002 0 P 0 
L 0.84596998 -1.87623002 0.84355 -1.87393996 0 P 0 
L 0.84355 -1.87393996 0.84096998 -1.87181998 0 P 0 
L 0.84096998 -1.87181998 0.83826004 -1.86988996 0 P 0 
L 0.83826004 -1.86988996 0.83541004 -1.86815 0 P 0 
L 0.83541004 -1.86815 0.83243996 -1.86661004 0 P 0 
L 0.83243996 -1.86661004 0.82938996 -1.86531004 0 P 0 
L 0.82938996 -1.86531004 0.82625 -1.86423002 0 P 0 
L 0.82625 -1.86423002 0.82303996 -1.86336004 0 P 0 
L 0.82303996 -1.86336004 0.81978002 -1.86273002 0 P 0 
L 0.81978002 -1.86273002 0.81646998 -1.86233002 0 P 0 
L 0.81646998 -1.86233002 0.81228996 -1.86215 0 P 0 
L 0.81228996 -1.86215 0.80811004 -1.86233996 0 P 0 
L 0.80811004 -1.86233996 0.80396004 -1.86288996 0 P 0 
L 0.80396004 -1.86288996 0.79986004 -1.8638 0 P 0 
L 0.80308996 -1.9535 0.82186004 -1.9535 0 P 0 
L 0.79926004 -1.9525 0.82563996 -1.9525 0 P 0 
L 0.79636004 -1.9515 0.82856998 -1.9515 0 P 0 
L 0.79393002 -1.9505 0.83093996 -1.9505 0 P 0 
L 0.7919 -1.9495 0.83298996 -1.9495 0 P 0 
L 0.79008002 -1.9485 0.8349 -1.9485 0 P 0 
L 0.78838996 -1.9475 0.83651004 -1.9475 0 P 0 
L 0.7869 -1.9465 0.83806998 -1.9465 0 P 0 
L 0.78548002 -1.9455 0.83943996 -1.9455 0 P 0 
L 0.7842 -1.9445 0.84078996 -1.9445 0 P 0 
L 0.78298002 -1.9435 0.84196998 -1.9435 0 P 0 
L 0.78183996 -1.9425 0.84313996 -1.9425 0 P 0 
L 0.78076998 -1.9415 0.84418996 -1.9415 0 P 0 
L 0.77976004 -1.9405 0.8452 -1.9405 0 P 0 
L 0.77883002 -1.9395 0.84616998 -1.9395 0 P 0 
L 0.77793996 -1.9385 0.84703996 -1.9385 0 P 0 
L 0.77711998 -1.9375 0.84791004 -1.9375 0 P 0 
L 0.77635 -1.9365 0.84871004 -1.9365 0 P 0 
L 0.77561004 -1.9355 0.84945 -1.9355 0 P 0 
L 0.77493996 -1.9345 0.8502 -1.9345 0 P 0 
L 0.77428002 -1.9335 0.85086998 -1.9335 0 P 0 
L 0.7737 -1.9325 0.8515 -1.9325 0 P 0 
L 0.77311998 -1.9315 0.8521 -1.9315 0 P 0 
L 0.77258996 -1.9305 0.85263996 -1.9305 0 P 0 
L 0.7721 -1.9295 0.85318002 -1.9295 0 P 0 
L 0.77161004 -1.9285 0.85363002 -1.9285 0 P 0 
L 0.77121004 -1.9275 0.85408002 -1.9275 0 P 0 
L 0.77081004 -1.9265 0.85448002 -1.9265 0 P 0 
L 0.77041004 -1.9255 0.85485 -1.9255 0 P 0 
L 0.77001004 -1.9245 0.85521998 -1.9245 0 P 0 
L 0.76968002 -1.9235 0.8555 -1.9235 0 P 0 
L 0.76936998 -1.9225 0.85578996 -1.9225 0 P 0 
L 0.76906004 -1.9215 0.85606998 -1.9215 0 P 0 
L 0.76875 -1.9205 0.85633002 -1.9205 0 P 0 
L 0.76848002 -1.9195 0.85653002 -1.9195 0 P 0 
L 0.76826004 -1.9185 0.85673002 -1.9185 0 P 0 
L 0.76803002 -1.9175 0.85693002 -1.9175 0 P 0 
L 0.76783002 -1.9165 0.85708996 -1.9165 0 P 0 
L 0.76768996 -1.9155 0.85721004 -1.9155 0 P 0 
L 0.76755 -1.9145 0.85733002 -1.9145 0 P 0 
L 0.76741998 -1.9135 0.85745 -1.9135 0 P 0 
L 0.81121004 -1.9545 0.80773002 -1.95426998 0 P 0 
L 0.80773002 -1.95426998 0.80426998 -1.95376998 0 P 0 
L 0.80426998 -1.95376998 0.80083996 -1.95298996 0 P 0 
L 0.80083996 -1.95298996 0.7975 -1.95195 0 P 0 
L 0.7975 -1.95195 0.79426004 -1.95066004 0 P 0 
L 0.79426004 -1.95066004 0.79111998 -1.94911998 0 P 0 
L 0.79111998 -1.94911998 0.78811004 -1.94733002 0 P 0 
L 0.78811004 -1.94733002 0.78573002 -1.94568996 0 P 0 
L 0.78573002 -1.94568996 0.78343996 -1.9439 0 P 0 
L 0.78343996 -1.9439 0.78126004 -1.94198996 0 P 0 
L 0.78126004 -1.94198996 0.7793 -1.94003996 0 P 0 
L 0.7793 -1.94003996 0.77746998 -1.93796004 0 P 0 
L 0.77746998 -1.93796004 0.77578996 -1.93576998 0 P 0 
L 0.77578996 -1.93576998 0.77423002 -1.93343002 0 P 0 
L 0.77423002 -1.93343002 0.77283996 -1.931 0 P 0 
L 0.77283996 -1.931 0.77161004 -1.92848996 0 P 0 
L 0.77161004 -1.92848996 0.76991998 -1.92426998 0 P 0 
L 0.76991998 -1.92426998 0.76858002 -1.91993996 0 P 0 
L 0.76858002 -1.91993996 0.76783996 -1.91661998 0 P 0 
L 0.76783996 -1.91661998 0.76738002 -1.91326998 0 P 0 
L 0.76738002 -1.91326998 0.76721004 -1.90988996 0 P 0 
L 0.76721004 -1.90988996 0.76731004 -1.90651004 0 P 0 
L 0.76731004 -1.90651004 0.7677 -1.90315 0 P 0 
L 0.7677 -1.90315 0.76838002 -1.89966998 0 P 0 
L 0.76838002 -1.89966998 0.76931004 -1.89626998 0 P 0 
L 0.76931004 -1.89626998 0.7705 -1.89296004 0 P 0 
L 0.7705 -1.89296004 0.77193996 -1.88973996 0 P 0 
L 0.77193996 -1.88973996 0.7736 -1.88663996 0 P 0 
L 0.7736 -1.88663996 0.77551004 -1.88363996 0 P 0 
L 0.77551004 -1.88363996 0.77763002 -1.8808 0 P 0 
L 0.77763002 -1.8808 0.77996004 -1.87813002 0 P 0 
L 0.77996004 -1.87813002 0.78246998 -1.87565 0 P 0 
L 0.78246998 -1.87565 0.78516004 -1.87336004 0 P 0 
L 0.78516004 -1.87336004 0.78795 -1.87133996 0 P 0 
L 0.78795 -1.87133996 0.79088002 -1.86956004 0 P 0 
L 0.79088002 -1.86956004 0.79393996 -1.86803002 0 P 0 
L 0.79393996 -1.86803002 0.79711004 -1.86675 0 P 0 
L 0.79711004 -1.86675 0.80038002 -1.86573002 0 P 0 
L 0.80038002 -1.86573002 0.80431004 -1.86486004 0 P 0 
L 0.80431004 -1.86486004 0.80828996 -1.86433996 0 P 0 
L 0.80828996 -1.86433996 0.8123 -1.86416004 0 P 0 
L 0.8123 -1.86416004 0.81631004 -1.86431998 0 P 0 
L 0.81631004 -1.86431998 0.81946998 -1.86471004 0 P 0 
L 0.81946998 -1.86471004 0.82258996 -1.86531004 0 P 0 
L 0.82258996 -1.86531004 0.82566004 -1.86613996 0 P 0 
L 0.82566004 -1.86613996 0.82866998 -1.86718002 0 P 0 
L 0.82866998 -1.86718002 0.83158996 -1.86843002 0 P 0 
L 0.83158996 -1.86843002 0.83443002 -1.86988996 0 P 0 
L 0.83443002 -1.86988996 0.83716004 -1.87156004 0 P 0 
L 0.83716004 -1.87156004 0.83976004 -1.87341004 0 P 0 
L 0.83976004 -1.87341004 0.84223002 -1.87543996 0 P 0 
L 0.84223002 -1.87543996 0.84453996 -1.87763002 0 P 0 
L 0.84453996 -1.87763002 0.84726998 -1.88065 0 P 0 
L 0.84726998 -1.88065 0.84971998 -1.88388002 0 P 0 
L 0.84971998 -1.88388002 0.85188996 -1.88731004 0 P 0 
L 0.85188996 -1.88731004 0.85376004 -1.89091004 0 P 0 
L 0.85376004 -1.89091004 0.85483996 -1.89345 0 P 0 
L 0.85483996 -1.89345 0.85575 -1.89605 0 P 0 
L 0.85575 -1.89605 0.85646998 -1.89871004 0 P 0 
L 0.85646998 -1.89871004 0.857 -1.90141004 0 P 0 
L 0.857 -1.90141004 0.85748002 -1.9053 0 P 0 
L 0.85748002 -1.9053 0.85763996 -1.90918996 0 P 0 
L 0.85763996 -1.90918996 0.8575 -1.91308002 0 P 0 
L 0.8575 -1.91308002 0.85703996 -1.91696004 0 P 0 
L 0.85703996 -1.91696004 0.85628002 -1.92076004 0 P 0 
L 0.85628002 -1.92076004 0.85521998 -1.92448996 0 P 0 
L 0.85521998 -1.92448996 0.85428002 -1.92705 0 P 0 
L 0.85428002 -1.92705 0.85316998 -1.92951998 0 P 0 
L 0.85316998 -1.92951998 0.85188002 -1.93191004 0 P 0 
L 0.85188002 -1.93191004 0.85041998 -1.9342 0 P 0 
L 0.85041998 -1.9342 0.84826998 -1.93708002 0 P 0 
L 0.84826998 -1.93708002 0.84593002 -1.93976998 0 P 0 
L 0.84593002 -1.93976998 0.8434 -1.94228002 0 P 0 
L 0.8434 -1.94228002 0.84068002 -1.9446 0 P 0 
L 0.84068002 -1.9446 0.8378 -1.9467 0 P 0 
L 0.8378 -1.9467 0.83476998 -1.94858002 0 P 0 
L 0.83476998 -1.94858002 0.83163996 -1.9502 0 P 0 
L 0.83163996 -1.9502 0.8284 -1.95158002 0 P 0 
L 0.8284 -1.95158002 0.82506004 -1.95268996 0 P 0 
L 0.82506004 -1.95268996 0.82163996 -1.95356004 0 P 0 
L 0.82163996 -1.95356004 0.81818002 -1.95413996 0 P 0 
L 0.81818002 -1.95413996 0.8147 -1.95446004 0 P 0 
L 0.8147 -1.95446004 0.81121004 -1.9545 0 P 0 
L 0.77075 -2.02925 0.84511004 -2.02925 0 P 0 
L 0.77076004 -2.02825 0.8452 -2.02825 0 P 0 
L 0.77076998 -2.02725 0.84528996 -2.02725 0 P 0 
L 0.77078002 -2.02625 0.84536998 -2.02625 0 P 0 
L 0.77078996 -2.02525 0.84548996 -2.02525 0 P 0 
L 0.7708 -2.02425 0.84561998 -2.02425 0 P 0 
L 0.77081004 -2.02325 0.84575 -2.02325 0 P 0 
L 0.77081998 -2.02225 0.84588002 -2.02225 0 P 0 
L 0.77083002 -2.02125 0.84601004 -2.02125 0 P 0 
L 0.77083996 -2.02025 0.84613996 -2.02025 0 P 0 
L 0.77085 -2.01925 0.84626004 -2.01925 0 P 0 
L 0.77085 -2.01825 0.84638996 -2.01825 0 P 0 
L 0.77085 -2.01725 0.84651998 -2.01725 0 P 0 
L 0.77086004 -2.01625 0.84663996 -2.01625 0 P 0 
L 0.77086004 -2.01525 0.84676998 -2.01525 0 P 0 
L 0.77086004 -2.01425 0.8469 -2.01425 0 P 0 
L 0.77086004 -2.01325 0.84703002 -2.01325 0 P 0 
L 0.77086004 -2.01225 0.84716004 -2.01225 0 P 0 
L 0.77086004 -2.01125 0.84728996 -2.01125 0 P 0 
L 0.77086004 -2.01025 0.84741004 -2.01025 0 P 0 
L 0.77086998 -2.00925 0.84753996 -2.00925 0 P 0 
L 0.77086998 -2.00825 0.84766998 -2.00825 0 P 0 
L 0.77086998 -2.00725 0.84778996 -2.00725 0 P 0 
L 0.77086998 -2.00625 0.84791998 -2.00625 0 P 0 
L 0.77086998 -2.00525 0.84805 -2.00525 0 P 0 
L 0.77086998 -2.00425 0.84818002 -2.00425 0 P 0 
L 0.77088002 -2.00325 0.84831004 -2.00325 0 P 0 
L 0.77088002 -2.00225 0.84843996 -2.00225 0 P 0 
L 0.77088002 -2.00125 0.84856004 -2.00125 0 P 0 
L 0.77088002 -2.00025 0.84868996 -2.00025 0 P 0 
L 0.77088002 -1.99925 0.84881998 -1.99925 0 P 0 
L 0.77088002 -1.99825 0.84896004 -1.99825 0 P 0 
L 0.77088002 -1.99725 0.84911004 -1.99725 0 P 0 
L 0.77088996 -1.99625 0.84926998 -1.99625 0 P 0 
L 0.77088996 -1.99525 0.84941998 -1.99525 0 P 0 
L 0.77088996 -1.99425 0.84956998 -1.99425 0 P 0 
L 0.77088996 -1.99325 0.84971998 -1.99325 0 P 0 
L 0.77088996 -1.99225 0.84986998 -1.99225 0 P 0 
L 0.77088996 -1.99125 0.85003002 -1.99125 0 P 0 
L 0.7709 -1.99025 0.85018002 -1.99025 0 P 0 
L 0.7709 -1.98925 0.85033002 -1.98925 0 P 0 
L 0.76885 -2.01878002 0.76871998 -2.03201998 0 P 0 
L 0.76871998 -2.03201998 0.7684 -2.04553996 0 P 0 
L 0.7684 -2.04553996 0.76796004 -2.05751004 0 P 0 
L 0.76796004 -2.05751004 0.76741004 -2.06523002 0 P 0 
L 0.76741004 -2.06523002 0.76596004 -2.07933996 0 P 0 
L 0.76596004 -2.07933996 0.7636 -2.09918002 0 P 0 
L 0.7636 -2.09918002 0.76116004 -2.119 0 P 0 
L 0.76116004 -2.119 0.76011998 -2.12526004 0 P 0 
L 0.76011998 -2.12526004 0.75948996 -2.12825 0 P 0 
L 0.75948996 -2.12825 0.84418002 -2.12825 0 P 0 
L 0.84418002 -2.12825 0.84361998 -2.10788002 0 P 0 
L 0.84361998 -2.10788002 0.8436 -2.08276004 0 P 0 
L 0.8436 -2.08276004 0.8449 -2.05491998 0 P 0 
L 0.8449 -2.05491998 0.84736004 -2.02641004 0 P 0 
L 0.84736004 -2.02641004 0.85083996 -1.99923002 0 P 0 
L 0.85083996 -1.99923002 0.85268996 -1.987 0 P 0 
L 0.85268996 -1.987 0.7689 -1.987 0 P 0 
L 0.7689 -1.987 0.76885 -2.01878002 0 P 0 
L 0.76195 -2.12625 0.84211998 -2.12625 0 P 0 
L 0.76213996 -2.12525 0.8421 -2.12525 0 P 0 
L 0.76231004 -2.12425 0.84206998 -2.12425 0 P 0 
L 0.76248002 -2.12325 0.84203996 -2.12325 0 P 0 
L 0.76263996 -2.12225 0.84201004 -2.12225 0 P 0 
L 0.76281004 -2.12125 0.84198996 -2.12125 0 P 0 
L 0.76296998 -2.12025 0.84196004 -2.12025 0 P 0 
L 0.76313996 -2.11925 0.84193002 -2.11925 0 P 0 
L 0.76326998 -2.11825 0.8419 -2.11825 0 P 0 
L 0.76338996 -2.11725 0.84188002 -2.11725 0 P 0 
L 0.76351004 -2.11625 0.84185 -2.11625 0 P 0 
L 0.76363996 -2.11525 0.84181998 -2.11525 0 P 0 
L 0.76376004 -2.11425 0.84178996 -2.11425 0 P 0 
L 0.76388002 -2.11325 0.84176998 -2.11325 0 P 0 
L 0.76401004 -2.11225 0.84173996 -2.11225 0 P 0 
L 0.76413002 -2.11125 0.84171004 -2.11125 0 P 0 
L 0.76425 -2.11025 0.84168002 -2.11025 0 P 0 
L 0.76438002 -2.10925 0.84166004 -2.10925 0 P 0 
L 0.7645 -2.10825 0.84163002 -2.10825 0 P 0 
L 0.76461998 -2.10725 0.84161998 -2.10725 0 P 0 
L 0.76475 -2.10625 0.84161998 -2.10625 0 P 0 
L 0.76486998 -2.10525 0.84161998 -2.10525 0 P 0 
L 0.76498996 -2.10425 0.84161998 -2.10425 0 P 0 
L 0.76511998 -2.10325 0.84161998 -2.10325 0 P 0 
L 0.76523996 -2.10225 0.84161998 -2.10225 0 P 0 
L 0.76536004 -2.10125 0.84161998 -2.10125 0 P 0 
L 0.76548996 -2.10025 0.84161998 -2.10025 0 P 0 
L 0.76561004 -2.09925 0.84161998 -2.09925 0 P 0 
L 0.76573002 -2.09825 0.84161004 -2.09825 0 P 0 
L 0.76583996 -2.09725 0.84161004 -2.09725 0 P 0 
L 0.76596998 -2.09625 0.84161004 -2.09625 0 P 0 
L 0.76608996 -2.09525 0.84161004 -2.09525 0 P 0 
L 0.7662 -2.09425 0.84161004 -2.09425 0 P 0 
L 0.76631998 -2.09325 0.84161004 -2.09325 0 P 0 
L 0.76643996 -2.09225 0.84161004 -2.09225 0 P 0 
L 0.76656004 -2.09125 0.84161004 -2.09125 0 P 0 
L 0.76668002 -2.09025 0.84161004 -2.09025 0 P 0 
L 0.76678996 -2.08925 0.84161004 -2.08925 0 P 0 
L 0.76691998 -2.08825 0.84161004 -2.08825 0 P 0 
L 0.76703002 -2.08725 0.84161004 -2.08725 0 P 0 
L 0.76715 -2.08625 0.8416 -2.08625 0 P 0 
L 0.76726998 -2.08525 0.8416 -2.08525 0 P 0 
L 0.76738996 -2.08425 0.8416 -2.08425 0 P 0 
L 0.76195 -2.12625 0.76208002 -2.12561998 0 P 0 
L 0.76208002 -2.12561998 0.76313996 -2.11928996 0 P 0 
L 0.76313996 -2.11928996 0.76558996 -2.09941998 0 P 0 
L 0.76558996 -2.09941998 0.76558996 -2.09941004 0 P 0 
L 0.76558996 -2.09941004 0.76793996 -2.07956004 0 P 0 
L 0.76793996 -2.07956004 0.7694 -2.0654 0 P 0 
L 0.7694 -2.0654 0.76941004 -2.06536004 0 P 0 
L 0.76941004 -2.06536004 0.76996004 -2.05761998 0 P 0 
L 0.76996004 -2.05761998 0.76996004 -2.05758996 0 P 0 
L 0.76996004 -2.05758996 0.7704 -2.0456 0 P 0 
L 0.7704 -2.0456 0.77071998 -2.03206004 0 P 0 
L 0.77071998 -2.03206004 0.77085 -2.01878002 0 P 0 
L 0.77085 -2.01878002 0.7709 -1.989 0 P 0 
L 0.7709 -1.989 0.85036004 -1.989 0 P 0 
L 0.85036004 -1.989 0.84886004 -1.99895 0 P 0 
L 0.84886004 -1.99895 0.84538002 -2.02618996 0 P 0 
L 0.84538002 -2.02618996 0.8429 -2.05478996 0 P 0 
L 0.8429 -2.05478996 0.8416 -2.08271004 0 P 0 
L 0.8416 -2.08271004 0.84161998 -2.10791004 0 P 0 
L 0.84161998 -2.10791004 0.84211998 -2.12625 0 P 0 
L 0.84211998 -2.12625 0.76195 -2.12625 0 P 0 
L 0.71628996 -1.91261998 0.74938002 -1.91261998 0 P 0 
L 0.71783002 -1.91161998 0.74933002 -1.91161998 0 P 0 
L 0.71953002 -1.91061998 0.74931004 -1.91061998 0 P 0 
L 0.72133002 -1.90961998 0.74928996 -1.90961998 0 P 0 
L 0.72313996 -1.90861998 0.74926998 -1.90861998 0 P 0 
L 0.72493996 -1.90761998 0.74928996 -1.90761998 0 P 0 
L 0.72673996 -1.90661998 0.74931998 -1.90661998 0 P 0 
L 0.72855 -1.90561998 0.74935 -1.90561998 0 P 0 
L 0.73035 -1.90461998 0.74938996 -1.90461998 0 P 0 
L 0.73215 -1.90361998 0.74946998 -1.90361998 0 P 0 
L 0.73396004 -1.90261998 0.74953996 -1.90261998 0 P 0 
L 0.73576004 -1.90161998 0.74961998 -1.90161998 0 P 0 
L 0.73756998 -1.90061998 0.74973996 -1.90061998 0 P 0 
L 0.73943002 -1.89961998 0.74986004 -1.89961998 0 P 0 
L 0.74141998 -1.89861998 0.74998996 -1.89861998 0 P 0 
L 0.74341004 -1.89761998 0.75015 -1.89761998 0 P 0 
L 0.59843002 -2.08361998 0.6754 -2.08361998 0 P 0 
L 0.59846004 -2.08261998 0.67538996 -2.08261998 0 P 0 
L 0.59848002 -2.08161998 0.67538002 -2.08161998 0 P 0 
L 0.59851004 -2.08061998 0.67538002 -2.08061998 0 P 0 
L 0.59853002 -2.07961998 0.67546004 -2.07961998 0 P 0 
L 0.59856004 -2.07861998 0.67553996 -2.07861998 0 P 0 
L 0.59861998 -2.07761998 0.67561004 -2.07761998 0 P 0 
L 0.5987 -2.07661998 0.67568996 -2.07661998 0 P 0 
L 0.59878002 -2.07561998 0.67576004 -2.07561998 0 P 0 
L 0.59885 -2.07461998 0.67583996 -2.07461998 0 P 0 
L 0.59893002 -2.07361998 0.67591998 -2.07361998 0 P 0 
L 0.59901004 -2.07261998 0.67598996 -2.07261998 0 P 0 
L 0.59908002 -2.07161998 0.67606998 -2.07161998 0 P 0 
L 0.59916004 -2.07061998 0.67613996 -2.07061998 0 P 0 
L 0.59923002 -2.06961998 0.67621004 -2.06961998 0 P 0 
L 0.59936004 -2.06861998 0.6763 -2.06861998 0 P 0 
L 0.59948996 -2.06761998 0.67645 -2.06761998 0 P 0 
L 0.59963002 -2.06661998 0.6766 -2.06661998 0 P 0 
L 0.59976998 -2.06561998 0.67676004 -2.06561998 0 P 0 
L 0.5999 -2.06461998 0.67691998 -2.06461998 0 P 0 
L 0.60003002 -2.06361998 0.67706998 -2.06361998 0 P 0 
L 0.60016998 -2.06261998 0.6773 -2.06261998 0 P 0 
L 0.60031004 -2.06161998 0.67753002 -2.06161998 0 P 0 
L 0.60051004 -2.06061998 0.67776004 -2.06061998 0 P 0 
L 0.60071004 -2.05961998 0.67798996 -2.05961998 0 P 0 
L 0.60091998 -2.05861998 0.67823002 -2.05861998 0 P 0 
L 0.60111998 -2.05761998 0.67853002 -2.05761998 0 P 0 
L 0.60133002 -2.05661998 0.67883996 -2.05661998 0 P 0 
L 0.60153996 -2.05561998 0.67913996 -2.05561998 0 P 0 
L 0.60173996 -2.05461998 0.67945 -2.05461998 0 P 0 
L 0.60195 -2.05361998 0.67975 -2.05361998 0 P 0 
L 0.60223002 -2.05261998 0.68006004 -2.05261998 0 P 0 
L 0.60251004 -2.05161998 0.68036004 -2.05161998 0 P 0 
L 0.60278996 -2.05061998 0.68066998 -2.05061998 0 P 0 
L 0.60306004 -2.04961998 0.68096998 -2.04961998 0 P 0 
L 0.60333996 -2.04861998 0.68135 -2.04861998 0 P 0 
L 0.60361998 -2.04761998 0.68173002 -2.04761998 0 P 0 
L 0.6039 -2.04661998 0.68211004 -2.04661998 0 P 0 
L 0.60418002 -2.04561998 0.68248996 -2.04561998 0 P 0 
L 0.60453002 -2.04461998 0.68288002 -2.04461998 0 P 0 
L 0.60488002 -2.04361998 0.68326004 -2.04361998 0 P 0 
L 0.60523002 -2.04261998 0.68363996 -2.04261998 0 P 0 
L 0.60556998 -2.04161998 0.68401998 -2.04161998 0 P 0 
L 0.60591998 -2.04061998 0.6844 -2.04061998 0 P 0 
L 0.60626998 -2.03961998 0.68486004 -2.03961998 0 P 0 
L 0.60661998 -2.03861998 0.68531998 -2.03861998 0 P 0 
L 0.60698996 -2.03761998 0.68578002 -2.03761998 0 P 0 
L 0.60743002 -2.03661998 0.68623996 -2.03661998 0 P 0 
L 0.60786004 -2.03561998 0.6867 -2.03561998 0 P 0 
L 0.60828996 -2.03461998 0.68716004 -2.03461998 0 P 0 
L 0.60873002 -2.03361998 0.68761998 -2.03361998 0 P 0 
L 0.60916004 -2.03261998 0.68808996 -2.03261998 0 P 0 
L 0.60958996 -2.03161998 0.68856998 -2.03161998 0 P 0 
L 0.61003002 -2.03061998 0.68911004 -2.03061998 0 P 0 
L 0.61046004 -2.02961998 0.68965 -2.02961998 0 P 0 
L 0.61088996 -2.02861998 0.69018996 -2.02861998 0 P 0 
L 0.61133002 -2.02761998 0.69073002 -2.02761998 0 P 0 
L 0.61176004 -2.02661998 0.69126998 -2.02661998 0 P 0 
L 0.6122 -2.02561998 0.69181004 -2.02561998 0 P 0 
L 0.61263002 -2.02461998 0.69235 -2.02461998 0 P 0 
L 0.61306004 -2.02361998 0.69288002 -2.02361998 0 P 0 
L 0.61348996 -2.02261998 0.69346998 -2.02261998 0 P 0 
L 0.61393002 -2.02161998 0.69408996 -2.02161998 0 P 0 
L 0.61436004 -2.02061998 0.6947 -2.02061998 0 P 0 
L 0.61478996 -2.01961998 0.69531998 -2.01961998 0 P 0 
L 0.61531004 -2.01861998 0.69593996 -2.01861998 0 P 0 
L 0.61583996 -2.01761998 0.69656004 -2.01761998 0 P 0 
L 0.61636004 -2.01661998 0.69718002 -2.01661998 0 P 0 
L 0.61688002 -2.01561998 0.69778996 -2.01561998 0 P 0 
L 0.6174 -2.01461998 0.69841998 -2.01461998 0 P 0 
L 0.61791998 -2.01361998 0.69911998 -2.01361998 0 P 0 
L 0.61843996 -2.01261998 0.69981998 -2.01261998 0 P 0 
L 0.61896004 -2.01161998 0.70051998 -2.01161998 0 P 0 
L 0.61948002 -2.01061998 0.70123002 -2.01061998 0 P 0 
L 0.62 -2.00961998 0.70193002 -2.00961998 0 P 0 
L 0.62051998 -2.00861998 0.70263002 -2.00861998 0 P 0 
L 0.62103996 -2.00761998 0.70333002 -2.00761998 0 P 0 
L 0.62163996 -2.00661998 0.70403996 -2.00661998 0 P 0 
L 0.62225 -2.00561998 0.70483002 -2.00561998 0 P 0 
L 0.62285 -2.00461998 0.70565 -2.00461998 0 P 0 
L 0.62346004 -2.00361998 0.70646004 -2.00361998 0 P 0 
L 0.62406004 -2.00261998 0.70726998 -2.00261998 0 P 0 
L 0.62466004 -2.00161998 0.70808996 -2.00161998 0 P 0 
L 0.62526998 -2.00061998 0.7089 -2.00061998 0 P 0 
L 0.62586998 -1.99961998 0.70971004 -1.99961998 0 P 0 
L 0.62648002 -1.99861998 0.71053002 -1.99861998 0 P 0 
L 0.62708002 -1.99761998 0.71133996 -1.99761998 0 P 0 
L 0.62768996 -1.99661998 0.71216004 -1.99661998 0 P 0 
L 0.62831998 -1.99561998 0.71296998 -1.99561998 0 P 0 
L 0.62901004 -1.99461998 0.71378996 -1.99461998 0 P 0 
L 0.62971004 -1.99361998 0.71466004 -1.99361998 0 P 0 
L 0.6304 -1.99261998 0.71561004 -1.99261998 0 P 0 
L 0.6311 -1.99161998 0.71656998 -1.99161998 0 P 0 
L 0.63178996 -1.99061998 0.71753002 -1.99061998 0 P 0 
L 0.63248996 -1.98961998 0.71848996 -1.98961998 0 P 0 
L 0.63318002 -1.98861998 0.71945 -1.98861998 0 P 0 
L 0.63388002 -1.98761998 0.72041004 -1.98761998 0 P 0 
L 0.63456998 -1.98661998 0.72136998 -1.98661998 0 P 0 
L 0.63526998 -1.98561998 0.72233002 -1.98561998 0 P 0 
L 0.63598002 -1.98461998 0.72328996 -1.98461998 0 P 0 
L 0.63678996 -1.98361998 0.72425 -1.98361998 0 P 0 
L 0.6376 -1.98261998 0.72521004 -1.98261998 0 P 0 
L 0.63841004 -1.98161998 0.72628002 -1.98161998 0 P 0 
L 0.63921998 -1.98061998 0.72738996 -1.98061998 0 P 0 
L 0.64003002 -1.97961998 0.7285 -1.97961998 0 P 0 
L 0.64083996 -1.97861998 0.72961004 -1.97861998 0 P 0 
L 0.64165 -1.97761998 0.73071004 -1.97761998 0 P 0 
L 0.64246004 -1.97661998 0.73181998 -1.97661998 0 P 0 
L 0.64326998 -1.97561998 0.73293002 -1.97561998 0 P 0 
L 0.64406998 -1.97461998 0.73403996 -1.97461998 0 P 0 
L 0.64488002 -1.97361998 0.73515 -1.97361998 0 P 0 
L 0.64568996 -1.97261998 0.73625 -1.97261998 0 P 0 
L 0.6465 -1.97161998 0.73736004 -1.97161998 0 P 0 
L 0.64731004 -1.97061998 0.73848002 -1.97061998 0 P 0 
L 0.64811998 -1.96961998 0.73973002 -1.96961998 0 P 0 
L 0.64893002 -1.96861998 0.74098996 -1.96861998 0 P 0 
L 0.64981004 -1.96761998 0.74225 -1.96761998 0 P 0 
L 0.65076004 -1.96661998 0.74351004 -1.96661998 0 P 0 
L 0.65171004 -1.96561998 0.74476998 -1.96561998 0 P 0 
L 0.65266998 -1.96461998 0.74603002 -1.96461998 0 P 0 
L 0.65361998 -1.96361998 0.74728996 -1.96361998 0 P 0 
L 0.65458002 -1.96261998 0.74855 -1.96261998 0 P 0 
L 0.65553002 -1.96161998 0.74981004 -1.96161998 0 P 0 
L 0.65648996 -1.96061998 0.75106004 -1.96061998 0 P 0 
L 0.65743996 -1.95961998 0.75233996 -1.95961998 0 P 0 
L 0.6584 -1.95861998 0.7537 -1.95861998 0 P 0 
L 0.65935 -1.95761998 0.75506004 -1.95761998 0 P 0 
L 0.66031004 -1.95661998 0.75641998 -1.95661998 0 P 0 
L 0.66126004 -1.95561998 0.75778996 -1.95561998 0 P 0 
L 0.66221004 -1.95461998 0.75916004 -1.95461998 0 P 0 
L 0.66316998 -1.95361998 0.76053996 -1.95361998 0 P 0 
L 0.66411998 -1.95261998 0.76193996 -1.95261998 0 P 0 
L 0.66523002 -1.95161998 0.76333996 -1.95161998 0 P 0 
L 0.66636004 -1.95061998 0.76406998 -1.95061998 0 P 0 
L 0.66746998 -1.94961998 0.76355 -1.94961998 0 P 0 
L 0.6686 -1.94861998 0.76291998 -1.94861998 0 P 0 
L 0.66971004 -1.94761998 0.76226998 -1.94761998 0 P 0 
L 0.67083996 -1.94661998 0.76161998 -1.94661998 0 P 0 
L 0.67196004 -1.94561998 0.76096998 -1.94561998 0 P 0 
L 0.67306998 -1.94461998 0.76033002 -1.94461998 0 P 0 
L 0.6742 -1.94361998 0.75968996 -1.94361998 0 P 0 
L 0.67531004 -1.94261998 0.75905 -1.94261998 0 P 0 
L 0.67643996 -1.94161998 0.75846004 -1.94161998 0 P 0 
L 0.67755 -1.94061998 0.75788996 -1.94061998 0 P 0 
L 0.67868002 -1.93961998 0.75731998 -1.93961998 0 P 0 
L 0.67978996 -1.93861998 0.75676998 -1.93861998 0 P 0 
L 0.68091998 -1.93761998 0.75626998 -1.93761998 0 P 0 
L 0.68221004 -1.93661998 0.75576998 -1.93661998 0 P 0 
L 0.68353002 -1.93561998 0.75528002 -1.93561998 0 P 0 
L 0.68483996 -1.93461998 0.75483996 -1.93461998 0 P 0 
L 0.68616004 -1.93361998 0.75441004 -1.93361998 0 P 0 
L 0.68746998 -1.93261998 0.75398002 -1.93261998 0 P 0 
L 0.68878002 -1.93161998 0.7536 -1.93161998 0 P 0 
L 0.6901 -1.93061998 0.75323996 -1.93061998 0 P 0 
L 0.69141004 -1.92961998 0.75286998 -1.92961998 0 P 0 
L 0.69271998 -1.92861998 0.75253996 -1.92861998 0 P 0 
L 0.69403002 -1.92761998 0.75223002 -1.92761998 0 P 0 
L 0.69535 -1.92661998 0.75193002 -1.92661998 0 P 0 
L 0.69666004 -1.92561998 0.75163002 -1.92561998 0 P 0 
L 0.69796998 -1.92461998 0.75138002 -1.92461998 0 P 0 
L 0.69936998 -1.92361998 0.75113996 -1.92361998 0 P 0 
L 0.70091004 -1.92261998 0.75088996 -1.92261998 0 P 0 
L 0.70243996 -1.92161998 0.75066004 -1.92161998 0 P 0 
L 0.70398002 -1.92061998 0.75046004 -1.92061998 0 P 0 
L 0.70551998 -1.91961998 0.75026004 -1.91961998 0 P 0 
L 0.70706004 -1.91861998 0.75006998 -1.91861998 0 P 0 
L 0.7086 -1.91761998 0.7499 -1.91761998 0 P 0 
L 0.71013996 -1.91661998 0.74976998 -1.91661998 0 P 0 
L 0.71166998 -1.91561998 0.74961998 -1.91561998 0 P 0 
L 0.71321004 -1.91461998 0.74951998 -1.91461998 0 P 0 
L 0.71475 -1.91361998 0.74945 -1.91361998 0 P 0 
L 0.61556998 -2.15661998 0.70655 -2.15661998 0 P 0 
L 0.61503002 -2.15561998 0.7056 -2.15561998 0 P 0 
L 0.61448996 -2.15461998 0.70465 -2.15461998 0 P 0 
L 0.61395 -2.15361998 0.7037 -2.15361998 0 P 0 
L 0.61341004 -2.15261998 0.70273996 -2.15261998 0 P 0 
L 0.61286998 -2.15161998 0.70178996 -2.15161998 0 P 0 
L 0.61233002 -2.15061998 0.70095 -2.15061998 0 P 0 
L 0.61188002 -2.14961998 0.70015 -2.14961998 0 P 0 
L 0.61143002 -2.14861998 0.69935 -2.14861998 0 P 0 
L 0.61098002 -2.14761998 0.69855 -2.14761998 0 P 0 
L 0.61053002 -2.14661998 0.69775 -2.14661998 0 P 0 
L 0.61008002 -2.14561998 0.69695 -2.14561998 0 P 0 
L 0.60963002 -2.14461998 0.69615 -2.14461998 0 P 0 
L 0.60918002 -2.14361998 0.69535 -2.14361998 0 P 0 
L 0.60873002 -2.14261998 0.69455 -2.14261998 0 P 0 
L 0.60831004 -2.14161998 0.69381998 -2.14161998 0 P 0 
L 0.60793996 -2.14061998 0.69315 -2.14061998 0 P 0 
L 0.60756998 -2.13961998 0.69248002 -2.13961998 0 P 0 
L 0.60721004 -2.13861998 0.69181004 -2.13861998 0 P 0 
L 0.60683996 -2.13761998 0.69115 -2.13761998 0 P 0 
L 0.60646998 -2.13661998 0.69048002 -2.13661998 0 P 0 
L 0.60611004 -2.13561998 0.68981004 -2.13561998 0 P 0 
L 0.60573996 -2.13461998 0.68918002 -2.13461998 0 P 0 
L 0.60538002 -2.13361998 0.68863002 -2.13361998 0 P 0 
L 0.60503996 -2.13261998 0.68808002 -2.13261998 0 P 0 
L 0.60476004 -2.13161998 0.68753002 -2.13161998 0 P 0 
L 0.60446998 -2.13061998 0.68698002 -2.13061998 0 P 0 
L 0.60418002 -2.12961998 0.68643002 -2.12961998 0 P 0 
L 0.6039 -2.12861998 0.68588002 -2.12861998 0 P 0 
L 0.60361004 -2.12761998 0.68533002 -2.12761998 0 P 0 
L 0.60331998 -2.12661998 0.68486004 -2.12661998 0 P 0 
L 0.60303002 -2.12561998 0.68441998 -2.12561998 0 P 0 
L 0.60275 -2.12461998 0.68396998 -2.12461998 0 P 0 
L 0.60246004 -2.12361998 0.68353002 -2.12361998 0 P 0 
L 0.60218002 -2.12261998 0.68308996 -2.12261998 0 P 0 
L 0.60188996 -2.12161998 0.68263996 -2.12161998 0 P 0 
L 0.60166998 -2.12061998 0.6822 -2.12061998 0 P 0 
L 0.60145 -2.11961998 0.68176004 -2.11961998 0 P 0 
L 0.60123002 -2.11861998 0.68138996 -2.11861998 0 P 0 
L 0.60101004 -2.11761998 0.68105 -2.11761998 0 P 0 
L 0.60078002 -2.11661998 0.68071004 -2.11661998 0 P 0 
L 0.6006 -2.11561998 0.68036004 -2.11561998 0 P 0 
L 0.60043002 -2.11461998 0.68001998 -2.11461998 0 P 0 
L 0.60025 -2.11361998 0.67968002 -2.11361998 0 P 0 
L 0.60008002 -2.11261998 0.67933002 -2.11261998 0 P 0 
L 0.59991004 -2.11161998 0.67898996 -2.11161998 0 P 0 
L 0.59976004 -2.11061998 0.6787 -2.11061998 0 P 0 
L 0.59963996 -2.10961998 0.67845 -2.10961998 0 P 0 
L 0.59951004 -2.10861998 0.6782 -2.10861998 0 P 0 
L 0.59938002 -2.10761998 0.67795 -2.10761998 0 P 0 
L 0.59925 -2.10661998 0.6777 -2.10661998 0 P 0 
L 0.59913002 -2.10561998 0.67746004 -2.10561998 0 P 0 
L 0.59905 -2.10461998 0.67721004 -2.10461998 0 P 0 
L 0.59896998 -2.10361998 0.67696004 -2.10361998 0 P 0 
L 0.59888002 -2.10261998 0.67671004 -2.10261998 0 P 0 
L 0.5988 -2.10161998 0.67653996 -2.10161998 0 P 0 
L 0.59871998 -2.10061998 0.67638002 -2.10061998 0 P 0 
L 0.59866998 -2.09961998 0.67621004 -2.09961998 0 P 0 
L 0.59863996 -2.09861998 0.67605 -2.09861998 0 P 0 
L 0.59861004 -2.09761998 0.67588996 -2.09761998 0 P 0 
L 0.59858996 -2.09661998 0.6758 -2.09661998 0 P 0 
L 0.59856004 -2.09561998 0.67571004 -2.09561998 0 P 0 
L 0.59853002 -2.09461998 0.67563002 -2.09461998 0 P 0 
L 0.5985 -2.09361998 0.67553996 -2.09361998 0 P 0 
L 0.59846998 -2.09261998 0.67546004 -2.09261998 0 P 0 
L 0.59843996 -2.09161998 0.67546004 -2.09161998 0 P 0 
L 0.59841998 -2.09061998 0.67545 -2.09061998 0 P 0 
L 0.59838002 -2.08961998 0.67543996 -2.08961998 0 P 0 
L 0.59836004 -2.08861998 0.67543002 -2.08861998 0 P 0 
L 0.59833002 -2.08761998 0.67543002 -2.08761998 0 P 0 
L 0.59835 -2.08661998 0.67541998 -2.08661998 0 P 0 
L 0.59836998 -2.08561998 0.67541004 -2.08561998 0 P 0 
L 0.5984 -2.08461998 0.67541004 -2.08461998 0 P 0 
L 0.80005 -2.25161998 0.85543996 -2.25161998 0 P 0 
L 0.78651998 -2.25061998 0.86596004 -2.25061998 0 P 0 
L 0.77878996 -2.24961998 0.87636004 -2.24961998 0 P 0 
L 0.77106004 -2.24861998 0.88285 -2.24861998 0 P 0 
L 0.76398996 -2.24761998 0.88933996 -2.24761998 0 P 0 
L 0.75891998 -2.24661998 0.89583996 -2.24661998 0 P 0 
L 0.73781004 -1.8982 0.71738996 -1.90951998 0 P 0 
L 0.71738996 -1.90951998 0.69766998 -1.92233996 0 P 0 
L 0.69766998 -1.92233996 0.67971004 -1.93601998 0 P 0 
L 0.67971004 -1.93601998 0.66278996 -1.95113002 0 P 0 
L 0.66278996 -1.95113002 0.64786998 -1.96675 0 P 0 
L 0.64786998 -1.96675 0.63423996 -1.98358996 0 P 0 
L 0.63423996 -1.98358996 0.62643996 -1.99483002 0 P 0 
L 0.62643996 -1.99483002 0.61933996 -2.00655 0 P 0 
L 0.61933996 -2.00655 0.61298996 -2.01873996 0 P 0 
L 0.61298996 -2.01873996 0.60503002 -2.03713002 0 P 0 
L 0.60503002 -2.03713002 0.60225 -2.04506004 0 P 0 
L 0.60225 -2.04506004 0.59998996 -2.05323002 0 P 0 
L 0.59998996 -2.05323002 0.59833996 -2.0612 0 P 0 
L 0.59833996 -2.0612 0.59725 -2.06928996 0 P 0 
L 0.59725 -2.06928996 0.59656998 -2.07833996 0 P 0 
L 0.59656998 -2.07833996 0.59633002 -2.0875 0 P 0 
L 0.59633002 -2.0875 0.59668996 -2.10036998 0 P 0 
L 0.59668996 -2.10036998 0.59715 -2.10596004 0 P 0 
L 0.59715 -2.10596004 0.59786004 -2.11151004 0 P 0 
L 0.59786004 -2.11151004 0.59878996 -2.11686998 0 P 0 
L 0.59878996 -2.11686998 0.59996998 -2.1222 0 P 0 
L 0.59996998 -2.1222 0.60326998 -2.13368996 0 P 0 
L 0.60326998 -2.13368996 0.60656998 -2.1427 0 P 0 
L 0.60656998 -2.1427 0.6105 -2.15143996 0 P 0 
L 0.6105 -2.15143996 0.61505 -2.15988002 0 P 0 
L 0.61505 -2.15988002 0.62023996 -2.16803996 0 P 0 
L 0.62023996 -2.16803996 0.62828996 -2.17873002 0 P 0 
L 0.62828996 -2.17873002 0.63718996 -2.18871004 0 P 0 
L 0.63718996 -2.18871004 0.64693002 -2.19795 0 P 0 
L 0.64693002 -2.19795 0.6582 -2.20701998 0 P 0 
L 0.6582 -2.20701998 0.67011004 -2.21518996 0 P 0 
L 0.67011004 -2.21518996 0.68261004 -2.22243002 0 P 0 
L 0.68261004 -2.22243002 0.69673996 -2.22936004 0 P 0 
L 0.69673996 -2.22936004 0.71123002 -2.23543996 0 P 0 
L 0.71123002 -2.23543996 0.72611998 -2.24066998 0 P 0 
L 0.72611998 -2.24066998 0.74536004 -2.24598996 0 P 0 
L 0.74536004 -2.24598996 0.76493002 -2.24985 0 P 0 
L 0.76493002 -2.24985 0.78671998 -2.25266998 0 P 0 
L 0.78671998 -2.25266998 0.80863002 -2.25425 0 P 0 
L 0.80863002 -2.25425 0.83146004 -2.25463002 0 P 0 
L 0.83146004 -2.25463002 0.85418002 -2.25375 0 P 0 
L 0.85418002 -2.25375 0.87641004 -2.25163996 0 P 0 
L 0.87641004 -2.25163996 0.89853002 -2.24823002 0 P 0 
L 0.89853002 -2.24823002 0.93045 -2.24101998 0 P 0 
L 0.93045 -2.24101998 0.96466004 -2.23063002 0 P 0 
L 0.96466004 -2.23063002 0.99911004 -2.2178 0 P 0 
L 0.99911004 -2.2178 1.03183002 -2.20318002 0 P 0 
L 1.03183002 -2.20318002 1.04391998 -2.19703002 0 P 0 
L 1.04391998 -2.19703002 1.05581004 -2.19048996 0 P 0 
L 1.05581004 -2.19048996 1.06676004 -2.18411998 0 P 0 
L 1.06676004 -2.18411998 1.06681004 -2.18408996 0 P 0 
L 1.06681004 -2.18408996 1.06685 -2.18405 0 P 0 
L 1.06685 -2.18405 1.0669 -2.18401004 0 P 0 
L 1.0669 -2.18401004 1.06693996 -2.18396998 0 P 0 
L 1.06693996 -2.18396998 1.06696998 -2.18391998 0 P 0 
L 1.06696998 -2.18391998 1.06701004 -2.18386998 0 P 0 
L 1.06701004 -2.18386998 1.06703002 -2.18381998 0 P 0 
L 1.06703002 -2.18381998 1.06706004 -2.18376004 0 P 0 
L 1.06706004 -2.18376004 1.06706998 -2.18371004 0 P 0 
L 1.06706998 -2.18371004 1.06708996 -2.18365 0 P 0 
L 1.06708996 -2.18365 1.06708996 -2.18358996 0 P 0 
L 1.06708996 -2.18358996 1.0671 -2.18353002 0 P 0 
L 1.0671 -2.18353002 1.0671 -2.18346998 0 P 0 
L 1.0671 -2.18346998 1.06708996 -2.18341004 0 P 0 
L 1.06708996 -2.18341004 1.06706998 -2.18336004 0 P 0 
L 1.06706998 -2.18336004 1.06706004 -2.1833 0 P 0 
L 1.06706004 -2.1833 1.06703002 -2.18323996 0 P 0 
L 1.06703002 -2.18323996 1.06701004 -2.18318996 0 P 0 
L 1.06701004 -2.18318996 1.06696998 -2.18313996 0 P 0 
L 1.06696998 -2.18313996 1.06693996 -2.18308996 0 P 0 
L 1.06693996 -2.18308996 1.06688002 -2.18303002 0 P 0 
L 1.06688002 -2.18303002 1.06678996 -2.18296998 0 P 0 
L 1.06678996 -2.18296998 1.06673002 -2.18295 0 P 0 
L 1.06673002 -2.18295 1.0667 -2.18295 0 P 0 
L 1.0667 -2.18295 1.06666004 -2.18293996 0 P 0 
L 1.06666004 -2.18293996 1.0666 -2.18293996 0 P 0 
L 1.0666 -2.18293996 1.06656998 -2.18295 0 P 0 
L 1.06656998 -2.18295 1.06653002 -2.18295 0 P 0 
L 1.06653002 -2.18295 1.06153002 -2.1842 0 P 0 
L 1.06153002 -2.1842 1.05583996 -2.18566998 0 P 0 
L 1.05583996 -2.18566998 1.04916998 -2.1875 0 P 0 
L 1.04916998 -2.1875 1.0153 -2.1962 0 P 0 
L 1.0153 -2.1962 0.9814 -2.20333996 0 P 0 
L 0.9814 -2.20333996 0.94881998 -2.2087 0 P 0 
L 0.94881998 -2.2087 0.9189 -2.21198996 0 P 0 
L 0.9189 -2.21198996 0.90113996 -2.21278996 0 P 0 
L 0.90113996 -2.21278996 0.87738002 -2.21265 0 P 0 
L 0.87738002 -2.21265 0.854 -2.21183002 0 P 0 
L 0.854 -2.21183002 0.83788996 -2.21033996 0 P 0 
L 0.83788996 -2.21033996 0.8174 -2.20693002 0 P 0 
L 0.8174 -2.20693002 0.79708996 -2.2023 0 P 0 
L 0.79708996 -2.2023 0.7769 -2.19641004 0 P 0 
L 0.7769 -2.19641004 0.76433002 -2.19183996 0 P 0 
L 0.76433002 -2.19183996 0.75208996 -2.18638002 0 P 0 
L 0.75208996 -2.18638002 0.74026998 -2.18006998 0 P 0 
L 0.74026998 -2.18006998 0.72886998 -2.17291004 0 P 0 
L 0.72886998 -2.17291004 0.71961998 -2.16603002 0 P 0 
L 0.71961998 -2.16603002 0.71098996 -2.15838996 0 P 0 
L 0.71098996 -2.15838996 0.70303002 -2.15003002 0 P 0 
L 0.70303002 -2.15003002 0.6958 -2.14098996 0 P 0 
L 0.6958 -2.14098996 0.69106998 -2.1339 0 P 0 
L 0.69106998 -2.1339 0.68696004 -2.12643002 0 P 0 
L 0.68696004 -2.12643002 0.68351004 -2.11863002 0 P 0 
L 0.68351004 -2.11863002 0.68073996 -2.11056004 0 P 0 
L 0.68073996 -2.11056004 0.67866004 -2.10218996 0 P 0 
L 0.67866004 -2.10218996 0.67788002 -2.09741998 0 P 0 
L 0.67788002 -2.09741998 0.67746004 -2.0926 0 P 0 
L 0.67746004 -2.0926 0.67738002 -2.08076004 0 P 0 
L 0.67738002 -2.08076004 0.67828002 -2.06891004 0 P 0 
L 0.67828002 -2.06891004 0.67903002 -2.06403996 0 P 0 
L 0.67903002 -2.06403996 0.68013002 -2.05923996 0 P 0 
L 0.68013002 -2.05923996 0.68288002 -2.05021998 0 P 0 
L 0.68288002 -2.05021998 0.68623996 -2.04141004 0 P 0 
L 0.68623996 -2.04141004 0.69018002 -2.03286004 0 P 0 
L 0.69018002 -2.03286004 0.69486004 -2.02418002 0 P 0 
L 0.69486004 -2.02418002 0.70003996 -2.0158 0 P 0 
L 0.70003996 -2.0158 0.70573002 -2.00768996 0 P 0 
L 0.70573002 -2.00768996 0.7158 -1.99531998 0 P 0 
L 0.7158 -1.99531998 0.72681004 -1.98385 0 P 0 
L 0.72681004 -1.98385 0.73971004 -1.9722 0 P 0 
L 0.73971004 -1.9722 0.7533 -1.9614 0 P 0 
L 0.7533 -1.9614 0.75753996 -1.95828002 0 P 0 
L 0.75753996 -1.95828002 0.76138002 -1.95548002 0 P 0 
L 0.76138002 -1.95548002 0.76463002 -1.95316004 0 P 0 
L 0.76463002 -1.95316004 0.76516004 -1.95281004 0 P 0 
L 0.76516004 -1.95281004 0.7657 -1.95248996 0 P 0 
L 0.7657 -1.95248996 0.76578002 -1.95243996 0 P 0 
L 0.76578002 -1.95243996 0.76586004 -1.95238002 0 P 0 
L 0.76586004 -1.95238002 0.76593002 -1.95231998 0 P 0 
L 0.76593002 -1.95231998 0.766 -1.95223996 0 P 0 
L 0.766 -1.95223996 0.76606004 -1.95216998 0 P 0 
L 0.76606004 -1.95216998 0.76616004 -1.95201004 0 P 0 
L 0.76616004 -1.95201004 0.7662 -1.95191998 0 P 0 
L 0.7662 -1.95191998 0.76626004 -1.95173996 0 P 0 
L 0.76626004 -1.95173996 0.76628002 -1.95163996 0 P 0 
L 0.76628002 -1.95163996 0.7663 -1.95143002 0 P 0 
L 0.7663 -1.95143002 0.7663 -1.95121004 0 P 0 
L 0.7663 -1.95121004 0.76628996 -1.951 0 P 0 
L 0.76628996 -1.951 0.76625 -1.95078996 0 P 0 
L 0.76625 -1.95078996 0.7662 -1.95058002 0 P 0 
L 0.7662 -1.95058002 0.76613002 -1.95036998 0 P 0 
L 0.76613002 -1.95036998 0.76583002 -1.94966998 0 P 0 
L 0.76583002 -1.94966998 0.76548996 -1.94896998 0 P 0 
L 0.76548996 -1.94896998 0.76508996 -1.9483 0 P 0 
L 0.76508996 -1.9483 0.76253002 -1.94436004 0 P 0 
L 0.76253002 -1.94436004 0.76056998 -1.94126998 0 P 0 
L 0.76056998 -1.94126998 0.75871998 -1.93806004 0 P 0 
L 0.75871998 -1.93806004 0.75716998 -1.93496998 0 P 0 
L 0.75716998 -1.93496998 0.7558 -1.93178002 0 P 0 
L 0.7558 -1.93178002 0.7546 -1.92853996 0 P 0 
L 0.7546 -1.92853996 0.75358996 -1.92521004 0 P 0 
L 0.75358996 -1.92521004 0.7527 -1.92161998 0 P 0 
L 0.7527 -1.92161998 0.75196998 -1.91796004 0 P 0 
L 0.75196998 -1.91796004 0.75155 -1.91496004 0 P 0 
L 0.75155 -1.91496004 0.75133002 -1.91193002 0 P 0 
L 0.75133002 -1.91193002 0.75126998 -1.9085 0 P 0 
L 0.75126998 -1.9085 0.75136004 -1.90506004 0 P 0 
L 0.75136004 -1.90506004 0.75161004 -1.90181998 0 P 0 
L 0.75161004 -1.90181998 0.752 -1.8986 0 P 0 
L 0.752 -1.8986 0.75228996 -1.89701998 0 P 0 
L 0.75228996 -1.89701998 0.75268996 -1.89546998 0 P 0 
L 0.75268996 -1.89546998 0.7532 -1.89395 0 P 0 
L 0.7532 -1.89395 0.75358996 -1.89281998 0 P 0 
L 0.75358996 -1.89281998 0.75373002 -1.89231998 0 P 0 
L 0.75373002 -1.89231998 0.75383996 -1.8918 0 P 0 
L 0.75383996 -1.8918 0.75391998 -1.89138996 0 P 0 
L 0.75391998 -1.89138996 0.75396998 -1.89098996 0 P 0 
L 0.75396998 -1.89098996 0.75396998 -1.89086004 0 P 0 
L 0.75396998 -1.89086004 0.75393996 -1.89076998 0 P 0 
L 0.75393996 -1.89076998 0.7539 -1.89071004 0 P 0 
L 0.7539 -1.89071004 0.75386004 -1.89066998 0 P 0 
L 0.75386004 -1.89066998 0.75381004 -1.89063002 0 P 0 
L 0.75381004 -1.89063002 0.75378996 -1.89061004 0 P 0 
L 0.75378996 -1.89061004 0.75373002 -1.89058996 0 P 0 
L 0.75373002 -1.89058996 0.75368002 -1.89056998 0 P 0 
L 0.75368002 -1.89056998 0.75356004 -1.89056998 0 P 0 
L 0.75356004 -1.89056998 0.75346998 -1.8906 0 P 0 
L 0.75346998 -1.8906 0.74898002 -1.8927 0 P 0 
L 0.74898002 -1.8927 0.74383002 -1.89518002 0 P 0 
L 0.74383002 -1.89518002 0.73781004 -1.8982 0 P 0 
L 0.69776998 -2.22761998 0.96701004 -2.22761998 0 P 0 
L 0.6957 -2.22661998 0.96968996 -2.22661998 0 P 0 
L 0.69366998 -2.22561998 0.97238002 -2.22561998 0 P 0 
L 0.69163002 -2.22461998 0.97506004 -2.22461998 0 P 0 
L 0.68958996 -2.22361998 0.97775 -2.22361998 0 P 0 
L 0.68756004 -2.22261998 0.98043002 -2.22261998 0 P 0 
L 0.68551998 -2.22161998 0.98311004 -2.22161998 0 P 0 
L 0.68348996 -2.22061998 0.9858 -2.22061998 0 P 0 
L 0.68176998 -2.21961998 0.98848002 -2.21961998 0 P 0 
L 0.68003996 -2.21861998 0.99116998 -2.21861998 0 P 0 
L 0.67831004 -2.21761998 0.99385 -2.21761998 0 P 0 
L 0.67658002 -2.21661998 0.99653996 -2.21661998 0 P 0 
L 0.67485 -2.21561998 0.99908002 -2.21561998 0 P 0 
L 0.67311998 -2.21461998 0.87665 -2.21461998 0 P 0 
L 0.6714 -2.21361998 0.85166004 -2.21361998 0 P 0 
L 0.6699 -2.21261998 0.84083002 -2.21261998 0 P 0 
L 0.66845 -2.21161998 0.8334 -2.21161998 0 P 0 
L 0.66698996 -2.21061998 0.8274 -2.21061998 0 P 0 
L 0.66553002 -2.20961998 0.82138996 -2.20961998 0 P 0 
L 0.66406998 -2.20861998 0.81583002 -2.20861998 0 P 0 
L 0.66261998 -2.20761998 0.81143996 -2.20761998 0 P 0 
L 0.66116004 -2.20661998 0.80706004 -2.20661998 0 P 0 
L 0.6597 -2.20561998 0.80266998 -2.20561998 0 P 0 
L 0.65841004 -2.20461998 0.79828996 -2.20461998 0 P 0 
L 0.65716998 -2.20361998 0.79448996 -2.20361998 0 P 0 
L 0.65593002 -2.20261998 0.79106004 -2.20261998 0 P 0 
L 0.65468996 -2.20161998 0.78763996 -2.20161998 0 P 0 
L 0.83143002 -2.25261998 0.80871998 -2.25225 0 P 0 
L 0.80871998 -2.25225 0.78691998 -2.25066998 0 P 0 
L 0.78691998 -2.25066998 0.76525 -2.24786998 0 P 0 
L 0.76525 -2.24786998 0.74581998 -2.24403996 0 P 0 
L 0.74581998 -2.24403996 0.72671004 -2.23876004 0 P 0 
L 0.72671004 -2.23876004 0.71196004 -2.23356998 0 P 0 
L 0.71196004 -2.23356998 0.69756998 -2.22753996 0 P 0 
L 0.69756998 -2.22753996 0.68355 -2.22066004 0 P 0 
L 0.68355 -2.22066004 0.67118002 -2.2135 0 P 0 
L 0.67118002 -2.2135 0.65938996 -2.20541004 0 P 0 
L 0.65938996 -2.20541004 0.64825 -2.19643996 0 P 0 
L 0.64825 -2.19643996 0.63861998 -2.18731998 0 P 0 
L 0.63861998 -2.18731998 0.62983002 -2.17746998 0 P 0 
L 0.62983002 -2.17746998 0.62188996 -2.1669 0 P 0 
L 0.62188996 -2.1669 0.61678002 -2.15886998 0 P 0 
L 0.61678002 -2.15886998 0.6123 -2.15056004 0 P 0 
L 0.6123 -2.15056004 0.60841998 -2.14193996 0 P 0 
L 0.60841998 -2.14193996 0.60516998 -2.13306998 0 P 0 
L 0.60516998 -2.13306998 0.60191004 -2.12171004 0 P 0 
L 0.60191004 -2.12171004 0.60075 -2.11648002 0 P 0 
L 0.60075 -2.11648002 0.59983996 -2.11121004 0 P 0 
L 0.59983996 -2.11121004 0.59913996 -2.10576004 0 P 0 
L 0.59913996 -2.10576004 0.59868996 -2.10026004 0 P 0 
L 0.59868996 -2.10026004 0.59833002 -2.0875 0 P 0 
L 0.59833002 -2.0875 0.59856998 -2.07843996 0 P 0 
L 0.59856998 -2.07843996 0.59923996 -2.0695 0 P 0 
L 0.59923996 -2.0695 0.60031998 -2.06153996 0 P 0 
L 0.60031998 -2.06153996 0.60193002 -2.05368996 0 P 0 
L 0.60193002 -2.05368996 0.60416004 -2.04566004 0 P 0 
L 0.60416004 -2.04566004 0.60688996 -2.03786004 0 P 0 
L 0.60688996 -2.03786004 0.6148 -2.01961004 0 P 0 
L 0.6148 -2.01961004 0.62108996 -2.00753002 0 P 0 
L 0.62108996 -2.00753002 0.62811998 -1.99591998 0 P 0 
L 0.62811998 -1.99591998 0.63583996 -1.98478996 0 P 0 
L 0.63583996 -1.98478996 0.64936998 -1.96808002 0 P 0 
L 0.64936998 -1.96808002 0.66418002 -1.95256998 0 P 0 
L 0.66418002 -1.95256998 0.68098002 -1.93756004 0 P 0 
L 0.68098002 -1.93756004 0.69881998 -1.92398002 0 P 0 
L 0.69881998 -1.92398002 0.71841998 -1.91123996 0 P 0 
L 0.71841998 -1.91123996 0.73875 -1.89996998 0 P 0 
L 0.73875 -1.89996998 0.74471004 -1.89696998 0 P 0 
L 0.74471004 -1.89696998 0.74983002 -1.89451004 0 P 0 
L 0.74983002 -1.89451004 0.7511 -1.89391004 0 P 0 
L 0.7511 -1.89391004 0.75076998 -1.89488996 0 P 0 
L 0.75076998 -1.89488996 0.75033996 -1.89658996 0 P 0 
L 0.75033996 -1.89658996 0.75003002 -1.8983 0 P 0 
L 0.75003002 -1.8983 0.74961998 -1.90161998 0 P 0 
L 0.74961998 -1.90161998 0.74936004 -1.90496004 0 P 0 
L 0.74936004 -1.90496004 0.74926998 -1.9085 0 P 0 
L 0.74926998 -1.9085 0.74933002 -1.91201998 0 P 0 
L 0.74933002 -1.91201998 0.74956004 -1.91516998 0 P 0 
L 0.74956004 -1.91516998 0.75 -1.91828996 0 P 0 
L 0.75 -1.91828996 0.75075 -1.92205 0 P 0 
L 0.75075 -1.92205 0.75166004 -1.92573996 0 P 0 
L 0.75166004 -1.92573996 0.7527 -1.92916998 0 P 0 
L 0.7527 -1.92916998 0.75393996 -1.93253002 0 P 0 
L 0.75393996 -1.93253002 0.75536004 -1.93581998 0 P 0 
L 0.75536004 -1.93581998 0.75696004 -1.939 0 P 0 
L 0.75696004 -1.939 0.75885 -1.94231004 0 P 0 
L 0.75885 -1.94231004 0.76083996 -1.94543996 0 P 0 
L 0.76083996 -1.94543996 0.76338996 -1.94933996 0 P 0 
L 0.76338996 -1.94933996 0.76371998 -1.94991998 0 P 0 
L 0.76371998 -1.94991998 0.76401004 -1.9505 0 P 0 
L 0.76401004 -1.9505 0.76423996 -1.95103002 0 P 0 
L 0.76423996 -1.95103002 0.76408996 -1.95111004 0 P 0 
L 0.76408996 -1.95111004 0.76348996 -1.95151004 0 P 0 
L 0.76348996 -1.95151004 0.76021004 -1.95386004 0 P 0 
L 0.76021004 -1.95386004 0.7602 -1.95386998 0 P 0 
L 0.7602 -1.95386998 0.75636998 -1.95666004 0 P 0 
L 0.75636998 -1.95666004 0.75636004 -1.95666998 0 P 0 
L 0.75636004 -1.95666998 0.75635 -1.95666998 0 P 0 
L 0.75635 -1.95666998 0.75208996 -1.95981004 0 P 0 
L 0.75208996 -1.95981004 0.73841004 -1.97066998 0 P 0 
L 0.73841004 -1.97066998 0.72541004 -1.98241004 0 P 0 
L 0.72541004 -1.98241004 0.7143 -1.994 0 P 0 
L 0.7143 -1.994 0.71425 -1.99406004 0 P 0 
L 0.71425 -1.99406004 0.70413996 -2.00648002 0 P 0 
L 0.70413996 -2.00648002 0.69836998 -2.01468996 0 P 0 
L 0.69836998 -2.01468996 0.69313002 -2.02318002 0 P 0 
L 0.69313002 -2.02318002 0.68838996 -2.03196004 0 P 0 
L 0.68838996 -2.03196004 0.68438996 -2.04063996 0 P 0 
L 0.68438996 -2.04063996 0.68098996 -2.04958002 0 P 0 
L 0.68098996 -2.04958002 0.6782 -2.05873002 0 P 0 
L 0.6782 -2.05873002 0.67706004 -2.06366004 0 P 0 
L 0.67706004 -2.06366004 0.67628996 -2.06866998 0 P 0 
L 0.67628996 -2.06866998 0.67538002 -2.08068996 0 P 0 
L 0.67538002 -2.08068996 0.67546004 -2.09268996 0 P 0 
L 0.67546004 -2.09268996 0.67588996 -2.09766998 0 P 0 
L 0.67588996 -2.09766998 0.6767 -2.10258996 0 P 0 
L 0.6767 -2.10258996 0.67881998 -2.11111998 0 P 0 
L 0.67881998 -2.11111998 0.68163996 -2.11936004 0 P 0 
L 0.68163996 -2.11936004 0.68516004 -2.12731998 0 P 0 
L 0.68516004 -2.12731998 0.68935 -2.13493996 0 P 0 
L 0.68935 -2.13493996 0.69418002 -2.14216998 0 P 0 
L 0.69418002 -2.14216998 0.70153002 -2.15135 0 P 0 
L 0.70153002 -2.15135 0.7096 -2.15983002 0 P 0 
L 0.7096 -2.15983002 0.71836004 -2.16758996 0 P 0 
L 0.71836004 -2.16758996 0.71843002 -2.16763996 0 P 0 
L 0.71843002 -2.16763996 0.72773996 -2.17456004 0 P 0 
L 0.72773996 -2.17456004 0.73926998 -2.1818 0 P 0 
L 0.73926998 -2.1818 0.75121004 -2.18818002 0 P 0 
L 0.75121004 -2.18818002 0.75128002 -2.18821004 0 P 0 
L 0.75128002 -2.18821004 0.76358002 -2.19368996 0 P 0 
L 0.76358002 -2.19368996 0.77628002 -2.19831004 0 P 0 
L 0.77628002 -2.19831004 0.79658996 -2.20423996 0 P 0 
L 0.79658996 -2.20423996 0.81701004 -2.20888996 0 P 0 
L 0.81701004 -2.20888996 0.83763996 -2.21233002 0 P 0 
L 0.83763996 -2.21233002 0.85388002 -2.21383002 0 P 0 
L 0.85388002 -2.21383002 0.87733996 -2.21465 0 P 0 
L 0.87733996 -2.21465 0.90118002 -2.21478996 0 P 0 
L 0.90118002 -2.21478996 0.91906004 -2.21398996 0 P 0 
L 0.91906004 -2.21398996 0.94908996 -2.21068002 0 P 0 
L 0.94908996 -2.21068002 0.98176998 -2.2053 0 P 0 
L 0.98176998 -2.2053 1.01575 -2.19815 0 P 0 
L 1.01575 -2.19815 1.04968002 -2.18943002 0 P 0 
L 1.04968002 -2.18943002 1.05633996 -2.18761004 0 P 0 
L 1.05633996 -2.18761004 1.05713996 -2.1874 0 P 0 
L 1.05713996 -2.1874 1.05483002 -2.18875 0 P 0 
L 1.05483002 -2.18875 1.04298996 -2.19526004 0 P 0 
L 1.04298996 -2.19526004 1.03096998 -2.20136998 0 P 0 
L 1.03096998 -2.20136998 0.99835 -2.21595 0 P 0 
L 0.99835 -2.21595 0.96401998 -2.22873996 0 P 0 
L 0.96401998 -2.22873996 0.92993996 -2.23908002 0 P 0 
L 0.92993996 -2.23908002 0.89816004 -2.24626004 0 P 0 
L 0.89816004 -2.24626004 0.87616004 -2.24965 0 P 0 
L 0.87616004 -2.24965 0.85405 -2.25176004 0 P 0 
L 0.85405 -2.25176004 0.83143002 -2.25261998 0 P 0 
L 0.65345 -2.20061998 0.78421004 -2.20061998 0 P 0 
L 0.65221004 -2.19961998 0.78078002 -2.19961998 0 P 0 
L 0.65096004 -2.19861998 0.77735 -2.19861998 0 P 0 
L 0.64971998 -2.19761998 0.77438996 -2.19761998 0 P 0 
L 0.64848002 -2.19661998 0.77163996 -2.19661998 0 P 0 
L 0.64738996 -2.19561998 0.76888996 -2.19561998 0 P 0 
L 0.64633996 -2.19461998 0.76613996 -2.19461998 0 P 0 
L 0.64528002 -2.19361998 0.76343002 -2.19361998 0 P 0 
L 0.64421998 -2.19261998 0.76118996 -2.19261998 0 P 0 
L 0.64316998 -2.19161998 0.75893996 -2.19161998 0 P 0 
L 0.64211004 -2.19061998 0.7567 -2.19061998 0 P 0 
L 0.64106004 -2.18961998 0.75446004 -2.18961998 0 P 0 
L 0.64 -2.18861998 0.75221004 -2.18861998 0 P 0 
L 0.63895 -2.18761998 0.75018002 -2.18761998 0 P 0 
L 0.63801004 -2.18661998 0.74831004 -2.18661998 0 P 0 
L 0.63711004 -2.18561998 0.74643002 -2.18561998 0 P 0 
L 0.63621998 -2.18461998 0.74456004 -2.18461998 0 P 0 
L 0.63533002 -2.18361998 0.74268002 -2.18361998 0 P 0 
L 0.63443996 -2.18261998 0.74081004 -2.18261998 0 P 0 
L 0.63353996 -2.18161998 0.73898996 -2.18161998 0 P 0 
L 0.63265 -2.18061998 0.73738996 -2.18061998 0 P 0 
L 0.63176004 -2.17961998 0.7358 -2.17961998 0 P 0 
L 0.63086998 -2.17861998 0.73421004 -2.17861998 0 P 0 
L 0.62996998 -2.17761998 0.73261998 -2.17761998 0 P 0 
L 0.6292 -2.17661998 0.73103002 -2.17661998 0 P 0 
L 0.62845 -2.17561998 0.72943996 -2.17561998 0 P 0 
L 0.6277 -2.17461998 0.72783996 -2.17461998 0 P 0 
L 0.62693996 -2.17361998 0.72648002 -2.17361998 0 P 0 
L 0.62618996 -2.17261998 0.72513996 -2.17261998 0 P 0 
L 0.62543996 -2.17161998 0.72378996 -2.17161998 0 P 0 
L 0.62468996 -2.17061998 0.72245 -2.17061998 0 P 0 
L 0.62393996 -2.16961998 0.7211 -2.16961998 0 P 0 
L 0.62318002 -2.16861998 0.71976004 -2.16861998 0 P 0 
L 0.62243996 -2.16761998 0.71841004 -2.16761998 0 P 0 
L 0.62171004 -2.16661998 0.71726998 -2.16661998 0 P 0 
L 0.62108002 -2.16561998 0.71613996 -2.16561998 0 P 0 
L 0.62043996 -2.16461998 0.71501004 -2.16461998 0 P 0 
L 0.61981004 -2.16361998 0.71388002 -2.16361998 0 P 0 
L 0.61916998 -2.16261998 0.71276004 -2.16261998 0 P 0 
L 0.61853002 -2.16161998 0.71163002 -2.16161998 0 P 0 
L 0.6179 -2.16061998 0.7105 -2.16061998 0 P 0 
L 0.61726004 -2.15961998 0.7094 -2.15961998 0 P 0 
L 0.61665 -2.15861998 0.70845 -2.15861998 0 P 0 
L 0.61611004 -2.15761998 0.7075 -2.15761998 0 P 0 
L 0.75383996 -2.24561998 0.901 -2.24561998 0 P 0 
L 0.74876998 -2.24461998 0.90541998 -2.24461998 0 P 0 
L 0.74431004 -2.24361998 0.90985 -2.24361998 0 P 0 
L 0.7407 -2.24261998 0.91426998 -2.24261998 0 P 0 
L 0.73708002 -2.24161998 0.9187 -2.24161998 0 P 0 
L 0.73346998 -2.24061998 0.92311998 -2.24061998 0 P 0 
L 0.72986004 -2.23961998 0.92753996 -2.23961998 0 P 0 
L 0.72633996 -2.23861998 0.93145 -2.23861998 0 P 0 
L 0.72348996 -2.23761998 0.93473996 -2.23761998 0 P 0 
L 0.72063996 -2.23661998 0.93803996 -2.23661998 0 P 0 
L 0.7178 -2.23561998 0.94133002 -2.23561998 0 P 0 
L 0.71495 -2.23461998 0.94461998 -2.23461998 0 P 0 
L 0.7121 -2.23361998 0.94791998 -2.23361998 0 P 0 
L 0.70968996 -2.23261998 0.95121004 -2.23261998 0 P 0 
L 0.70731004 -2.23161998 0.95451004 -2.23161998 0 P 0 
L 0.70491998 -2.23061998 0.9578 -2.23061998 0 P 0 
L 0.70253996 -2.22961998 0.9611 -2.22961998 0 P 0 
L 0.70015 -2.22861998 0.96431998 -2.22861998 0 P 0 
A 7.40433996 5.7874 7.40433996 5.7874 7.17716998 5.7874 3 P 0 N
A 7.36693002 5.7874 7.36693002 5.7874 7.17716998 5.7874 3 P 0 N
A 7.40433996 0.23621998 7.40433996 0.23621998 7.17716998 0.23621998 3 P 0 N
A 7.36693002 0.23621998 7.36693002 0.23621998 7.17716998 0.23621998 3 P 0 N
A 0.39213996 0.68898002 0.39213996 0.68898002 0.22245 0.68898002 3 P 0 N
A 0.42993002 0.68898002 0.42993002 0.68898002 0.22245 0.68898002 3 P 0 N
A 0.39213996 5.11811004 0.39213996 5.11811004 0.22245 5.11811004 3 P 0 N
A 0.42993002 5.11811004 0.42993002 5.11811004 0.22245 5.11811004 3 P 0 N
A 12.85671004 5.15748002 12.85671004 5.15748002 12.68701998 5.15748002 3 P 0 N
A 12.8945 5.15748002 12.8945 5.15748002 12.68701998 5.15748002 3 P 0 N
A 12.85671004 0.72835 12.85671004 0.72835 12.68701998 0.72835 3 P 0 N
A 12.8945 0.72835 12.8945 0.72835 12.68701998 0.72835 3 P 0 N
A 6.32558996 1.52756004 6.32558996 1.52756004 6.11811004 1.52756004 3 P 0 N
A 6.28818996 1.52756004 6.28818996 1.52756004 6.11811004 1.52756004 3 P 0 N
A 5.00275 1.50786998 5.00275 1.50786998 4.83268002 1.50786998 3 P 0 N
A 5.04016004 1.50786998 5.04016004 1.50786998 4.83268002 1.50786998 3 P 0 N
A 2.45355 1.50786998 2.45355 1.50786998 2.24606004 1.50786998 3 P 0 N
A 2.41615 1.50786998 2.41615 1.50786998 2.24606004 1.50786998 3 P 0 N
A 1.16811004 1.52756004 1.16811004 1.52756004 0.96063002 1.52756004 3 P 0 N
A 1.13071004 1.52756004 1.13071004 1.52756004 0.96063002 1.52756004 3 P 0 N
A 1.16811004 4.20473002 1.16811004 4.20473002 0.96063002 4.20473002 3 P 0 N
A 1.13071004 4.20473002 1.13071004 4.20473002 0.96063002 4.20473002 3 P 0 N
A 2.45353996 4.22441004 2.45353996 4.22441004 2.24606004 4.22441004 3 P 0 N
A 2.41615 4.22441004 2.41615 4.22441004 2.24606004 4.22441004 3 P 0 N
A 5.04016004 4.22441004 5.04016004 4.22441004 4.83268002 4.22441004 3 P 0 N
A 5.00275 4.22441004 5.00275 4.22441004 4.83268002 4.22441004 3 P 0 N
A 6.32558996 4.20473002 6.32558996 4.20473002 6.11811004 4.20473002 3 P 0 N
A 6.28818996 4.20473002 6.28818996 4.20473002 6.11811004 4.20473002 3 P 0 N
A 6.13603996 2.58268002 6.13603996 2.58268002 6.04921004 2.58268002 3 P 0 N
A 10.89553996 1.70681004 10.82152933 1.71480384 10.83661565 1.50786998 3 P 0 N
A 10.82152933 1.71480384 10.74946004 1.69616004 10.83661545 1.50786998 3 P 0 N
A 10.64413996 1.58535 10.79716073 1.30417224 10.83661998 1.50787333 3 P 0 N
A 10.79716073 1.30417224 11.0441 1.50786998 10.83661624 1.50786998 3 P 0 N
A 12.32953002 1.52756004 12.32953002 1.52756004 12.12205 1.52756004 3 P 0 N
A 12.29213002 1.52756004 12.29213002 1.52756004 12.12205 1.52756004 3 P 0 N
A 11.00668996 1.50786998 11.00668996 1.50786998 10.83661998 1.50786998 3 P 0 N
A 11.0441 1.50786998 10.99593996 1.64078002 10.83661998 1.50786988 3 P 0 N
A 8.45748996 1.50786998 8.45748996 1.50786998 8.25 1.50786998 3 P 0 N
A 8.42008996 1.50786998 8.42008996 1.50786998 8.25 1.50786998 3 P 0 N
A 7.17205 1.52756004 7.17205 1.52756004 6.96456998 1.52756004 3 P 0 N
A 7.13465 1.52756004 7.13465 1.52756004 6.96456998 1.52756004 3 P 0 N
A 7.17205 4.20473002 7.17205 4.20473002 6.96456998 4.20473002 3 P 0 N
A 7.13465 4.20473002 7.13465 4.20473002 6.96456998 4.20473002 3 P 0 N
A 8.45748002 4.22441004 8.45748002 4.22441004 8.25 4.22441004 3 P 0 N
A 8.42008996 4.22441004 8.42008996 4.22441004 8.25 4.22441004 3 P 0 N
A 11.0441 4.22441004 11.0441 4.22441004 10.83661998 4.22441004 3 P 0 N
A 11.00668996 4.22441004 11.00668996 4.22441004 10.83661998 4.22441004 3 P 0 N
A 12.32953002 4.20473002 12.32953002 4.20473002 12.12205 4.20473002 3 P 0 N
A 12.29213002 4.20473002 12.29213002 4.20473002 12.12205 4.20473002 3 P 0 N
A 12.13998002 2.58268002 12.13998002 2.58268002 12.05315 2.58268002 3 P 0 N
L 12.19961004 5.44685 12.09961004 5.44685 3 P 0 
L 12.09961004 5.44685 12.09961004 5.54685 3 P 0 
L 12.09961004 5.54685 12.19961004 5.54685 3 P 0 
L 12.19961004 5.54685 12.19961004 5.44685 3 P 0 
A 12.1996 5.71338996 12.1996 5.71338996 12.14961004 5.71338996 3 P 0 N
A 10.87678002 5.49685 10.87678002 5.49685 10.82676998 5.49685 3 P 0 N
A 10.87678002 5.71338996 10.87678002 5.71338996 10.82676998 5.71338996 3 P 0 N
L 12.15011033 5.38823002 12.15011033 5.41323002 2 P 0 ;0,1,2=0,3=0.000000
L 12.15011033 5.41323002 12.15331014 5.40823032 2 P 0 ;0,1,2=0,3=0.000000
L 12.15331014 5.38823002 12.14691053 5.38823002 2 P 0 ;0,1,2=0,3=0.000000
L 12.15961033 5.81516004 12.15961033 5.84016004 2 P 0 ;0,1,2=1,3=0.000000
L 12.15961033 5.84016004 12.16281014 5.83516033 2 P 0 ;0,1,2=1,3=0.000000
L 12.16281014 5.81516004 12.15641053 5.81516004 2 P 0 ;0,1,2=1,3=0.000000
L 12.13561033 5.84016004 12.1377437 5.83932687 2 P 0 ;0,1,2=1,3=0.000000
L 12.1377437 5.83932687 12.13934341 5.83724321 2 P 0 ;0,1,2=1,3=0.000000
L 12.13934341 5.83724321 12.14041024 5.8347437 2 P 0 ;0,1,2=1,3=0.000000
L 12.14041024 5.8347437 12.14121014 5.83140955 2 P 0 ;0,1,2=1,3=0.000000
L 12.14121014 5.83140955 12.14147677 5.82765965 2 P 0 ;0,1,2=1,3=0.000000
L 12.14147677 5.82765965 12.14121014 5.82390965 2 P 0 ;0,1,2=1,3=0.000000
L 12.14121014 5.82390965 12.14041024 5.82057628 2 P 0 ;0,1,2=1,3=0.000000
L 12.14041024 5.82057628 12.13934341 5.81807608 2 P 0 ;0,1,2=1,3=0.000000
L 12.13934341 5.81807608 12.1377437 5.81599311 2 P 0 ;0,1,2=1,3=0.000000
L 12.1377437 5.81599311 12.13561033 5.81516004 2 P 0 ;0,1,2=1,3=0.000000
L 12.13561033 5.81516004 12.13347697 5.81599311 2 P 0 ;0,1,2=1,3=0.000000
L 12.13347697 5.81599311 12.13187677 5.81807608 2 P 0 ;0,1,2=1,3=0.000000
L 12.13187677 5.81807608 12.13080994 5.82057628 2 P 0 ;0,1,2=1,3=0.000000
L 12.13080994 5.82057628 12.13001004 5.82390965 2 P 0 ;0,1,2=1,3=0.000000
L 12.13001004 5.82390965 12.12974341 5.82765965 2 P 0 ;0,1,2=1,3=0.000000
L 12.12974341 5.82765965 12.13001004 5.83140955 2 P 0 ;0,1,2=1,3=0.000000
L 12.13001004 5.83140955 12.13080994 5.8347437 2 P 0 ;0,1,2=1,3=0.000000
L 12.13080994 5.8347437 12.13187677 5.83724321 2 P 0 ;0,1,2=1,3=0.000000
L 12.13187677 5.83724321 12.13347697 5.83932687 2 P 0 ;0,1,2=1,3=0.000000
L 12.13347697 5.83932687 12.13561033 5.84016004 2 P 0 ;0,1,2=1,3=0.000000
L 10.8314937 5.39228602 10.82962687 5.39020305 2 P 0 ;0,1,2=2,3=0.000000
L 10.82962687 5.39020305 10.8274935 5.38936998 2 P 0 ;0,1,2=2,3=0.000000
L 10.8274935 5.38936998 10.82536014 5.39020305 2 P 0 ;0,1,2=2,3=0.000000
L 10.82536014 5.39020305 10.82349341 5.39270256 2 P 0 ;0,1,2=2,3=0.000000
L 10.82349341 5.39270256 10.82215994 5.39645325 2 P 0 ;0,1,2=2,3=0.000000
L 10.82215994 5.39645325 10.82162667 5.40020325 2 P 0 ;0,1,2=2,3=0.000000
L 10.82162667 5.40020325 10.82162667 5.40478632 2 P 0 ;0,1,2=2,3=0.000000
L 10.82162667 5.40478632 10.82215994 5.40853632 2 P 0 ;0,1,2=2,3=0.000000
L 10.82215994 5.40853632 10.82349341 5.41186969 2 P 0 ;0,1,2=2,3=0.000000
L 10.82349341 5.41186969 10.8250936 5.41353681 2 P 0 ;0,1,2=2,3=0.000000
L 10.8250936 5.41353681 10.82696033 5.41436998 2 P 0 ;0,1,2=2,3=0.000000
L 10.82696033 5.41436998 10.8290937 5.41353681 2 P 0 ;0,1,2=2,3=0.000000
L 10.8290937 5.41353681 10.83069341 5.41186969 2 P 0 ;0,1,2=2,3=0.000000
L 10.83069341 5.41186969 10.83176024 5.40937028 2 P 0 ;0,1,2=2,3=0.000000
L 10.83176024 5.40937028 10.8322935 5.40603612 2 P 0 ;0,1,2=2,3=0.000000
L 10.8322935 5.40603612 10.83176024 5.40312008 2 P 0 ;0,1,2=2,3=0.000000
L 10.83176024 5.40312008 10.83042677 5.40020325 2 P 0 ;0,1,2=2,3=0.000000
L 10.83042677 5.40020325 10.82882657 5.39853612 2 P 0 ;0,1,2=2,3=0.000000
L 10.82882657 5.39853612 10.82696033 5.39811959 2 P 0 ;0,1,2=2,3=0.000000
L 10.82696033 5.39811959 10.82482697 5.39895276 2 P 0 ;0,1,2=2,3=0.000000
L 10.82482697 5.39895276 10.82322677 5.40103642 2 P 0 ;0,1,2=2,3=0.000000
L 10.82322677 5.40103642 10.82162667 5.40478632 2 P 0 ;0,1,2=2,3=0.000000
L 10.83677028 5.81516004 10.83677028 5.84016004 2 P 0 ;0,1,2=3,3=0.000000
L 10.83677028 5.84016004 10.83997008 5.83516033 2 P 0 ;0,1,2=3,3=0.000000
L 10.83997008 5.81516004 10.83357047 5.81516004 2 P 0 ;0,1,2=3,3=0.000000
L 10.81277028 5.81516004 10.81090354 5.81557657 2 P 0 ;0,1,2=3,3=0.000000
L 10.81090354 5.81557657 10.80877018 5.81682628 2 P 0 ;0,1,2=3,3=0.000000
L 10.80877018 5.81682628 10.80743661 5.81890915 2 P 0 ;0,1,2=3,3=0.000000
L 10.80743661 5.81890915 10.80690335 5.82182677 2 P 0 ;0,1,2=3,3=0.000000
L 10.80690335 5.82182677 10.80743661 5.82474282 2 P 0 ;0,1,2=3,3=0.000000
L 10.80743661 5.82474282 10.80903671 5.82724301 2 P 0 ;0,1,2=3,3=0.000000
L 10.80903671 5.82724301 10.81143671 5.8284935 2 P 0 ;0,1,2=3,3=0.000000
L 10.81143671 5.8284935 10.81410335 5.8284935 2 P 0 ;0,1,2=3,3=0.000000
L 10.81410335 5.8284935 10.81570344 5.82932667 2 P 0 ;0,1,2=3,3=0.000000
L 10.81570344 5.82932667 10.81703701 5.83140955 2 P 0 ;0,1,2=3,3=0.000000
L 10.81703701 5.83140955 10.81757018 5.83432638 2 P 0 ;0,1,2=3,3=0.000000
L 10.81757018 5.83432638 10.81676988 5.83724321 2 P 0 ;0,1,2=3,3=0.000000
L 10.81676988 5.83724321 10.81490364 5.83932687 2 P 0 ;0,1,2=3,3=0.000000
L 10.81490364 5.83932687 10.81277028 5.84016004 2 P 0 ;0,1,2=3,3=0.000000
L 10.81277028 5.84016004 10.81063691 5.83932687 2 P 0 ;0,1,2=3,3=0.000000
L 10.81063691 5.83932687 10.80877018 5.83724321 2 P 0 ;0,1,2=3,3=0.000000
L 10.80877018 5.83724321 10.80796988 5.83432638 2 P 0 ;0,1,2=3,3=0.000000
L 10.80796988 5.83432638 10.80850354 5.83140955 2 P 0 ;0,1,2=3,3=0.000000
L 10.80850354 5.83140955 10.80983661 5.82932667 2 P 0 ;0,1,2=3,3=0.000000
L 10.80983661 5.82932667 10.81143671 5.8284935 2 P 0 ;0,1,2=3,3=0.000000
L 10.81143671 5.8284935 10.81410335 5.8284935 2 P 0 ;0,1,2=3,3=0.000000
L 10.81410335 5.8284935 10.81650335 5.82724301 2 P 0 ;0,1,2=3,3=0.000000
L 10.81650335 5.82724301 10.81810344 5.82474282 2 P 0 ;0,1,2=3,3=0.000000
L 10.81810344 5.82474282 10.81863671 5.82182677 2 P 0 ;0,1,2=3,3=0.000000
L 10.81863671 5.82182677 10.81810344 5.81890915 2 P 0 ;0,1,2=3,3=0.000000
L 10.81810344 5.81890915 10.81676988 5.81682628 2 P 0 ;0,1,2=3,3=0.000000
L 10.81676988 5.81682628 10.81463652 5.81557657 2 P 0 ;0,1,2=3,3=0.000000
L 10.81463652 5.81557657 10.81277028 5.81516004 2 P 0 ;0,1,2=3,3=0.000000
A 5.99825 5.4441 5.99825 5.4441 5.78346004 5.4441 3 P 0 N
A 10.42345 5.4441 10.42345 5.4441 10.20866004 5.4441 3 P 0 N
A 0.30545 5.38583002 0.30545 5.38583002 0.22255 5.38583002 3 P 0 N
A 0.30535 0.42126004 0.30535 0.42126004 0.22245 0.42126004 3 P 0 N
A 12.76991998 5.4252 12.76991998 5.4252 12.68701998 5.4252 3 P 0 N
A 12.76991004 0.46063002 12.76991004 0.46063002 12.68701004 0.46063002 3 P 0 N
A 0.13995 1.87998996 0.17616073 1.85216398 0.17322677 1.88581998 3 P 0 N
A 0.17616073 1.85216398 0.20701004 1.88583002 0.17323002 1.88581663 3 P 0 N
A 0.24661998 1.90853002 0.25948248 1.85430128 0.27165 1.88582707 3 P 0 N
A 0.25948248 1.85430128 0.30545 1.88583002 0.27165354 1.88583002 3 P 0 N
A 0.32366998 1.86716004 0.38418996 1.84646004 0.35038986 1.84646004 3 P 0 N
A 0.38418002 4.60236998 0.38418002 4.60236998 0.35038996 4.60236998 3 P 0 N
A 0.30543996 4.563 0.30543996 4.563 0.27165 4.563 3 P 0 N
A 0.20701004 4.563 0.20701004 4.563 0.17323002 4.563 3 P 0 N
A 0.12826998 4.60236998 0.12826998 4.60236998 0.09448996 4.60236998 3 P 0 N
A 0.38418996 1.68898002 0.38418996 1.68898002 0.35038996 1.68898002 3 P 0 N
A 0.38418996 1.84646004 0.37481004 1.86981998 0.35038996 1.84645118 3 P 0 N
A 0.30545 1.88583002 0.30423996 1.89478996 0.27165 1.88582697 3 P 0 N
A 0.20701004 1.88583002 0.20539065 1.89616014 0.17323002 1.88582648 3 P 0 N
A 0.20539065 1.89616014 0.20068996 1.9055 0.17323002 1.88582677 3 P 0 N
A 0.12826998 1.84646004 0.12826998 1.84646004 0.09448996 1.84646004 3 P 0 N
A 0.12826998 1.68898002 0.12826998 1.68898002 0.09448996 1.68898002 3 P 0 N
A 0.38418996 1.37401998 0.38418996 1.37401998 0.35038996 1.37401998 3 P 0 N
L 0.23786998 1.30086004 0.23786998 1.36843996 3 P 0 
L 0.23786998 1.36843996 0.30543996 1.36843996 3 P 0 
L 0.30543996 1.36843996 0.30543996 1.30086004 3 P 0 
L 0.30543996 1.30086004 0.23786998 1.30086004 3 P 0 
L 0.13943996 1.30086004 0.13943996 1.36843996 3 P 0 
L 0.13943996 1.36843996 0.20701004 1.36843996 3 P 0 
L 0.20701004 1.36843996 0.20701004 1.30086004 3 P 0 
L 0.20701004 1.30086004 0.13943996 1.30086004 3 P 0 
A 0.12826998 1.37401998 0.12826998 1.37401998 0.09448996 1.37401998 3 P 0 N
A 0.20701004 1.72835 0.20701004 1.72835 0.17323002 1.72835 3 P 0 N
A 0.30545 1.72835 0.30545 1.72835 0.27165 1.72835 3 P 0 N
L 0.08326998 4.64803297 0.10826998 4.6546997 2 P 0 ;0,1,2=4,3=90.000000
L 0.10826998 4.6546997 0.08326998 4.66136693 2 P 0 ;0,1,2=4,3=90.000000
L 0.09201959 4.65896644 0.09201959 4.65043297 2 P 0 ;0,1,2=4,3=90.000000
L 0.08326998 4.6786997 0.08368652 4.68056644 2 P 0 ;0,1,2=4,3=90.000000
L 0.08368652 4.68056644 0.08493622 4.6826998 2 P 0 ;0,1,2=4,3=90.000000
L 0.08493622 4.6826998 0.08701909 4.68403337 2 P 0 ;0,1,2=4,3=90.000000
L 0.08701909 4.68403337 0.08993671 4.68456663 2 P 0 ;0,1,2=4,3=90.000000
L 0.08993671 4.68456663 0.09285276 4.68403337 2 P 0 ;0,1,2=4,3=90.000000
L 0.09285276 4.68403337 0.09535295 4.68243327 2 P 0 ;0,1,2=4,3=90.000000
L 0.09535295 4.68243327 0.09660344 4.68003327 2 P 0 ;0,1,2=4,3=90.000000
L 0.09660344 4.68003327 0.09660344 4.67736663 2 P 0 ;0,1,2=4,3=90.000000
L 0.09660344 4.67736663 0.09743661 4.67576654 2 P 0 ;0,1,2=4,3=90.000000
L 0.09743661 4.67576654 0.09951949 4.67443297 2 P 0 ;0,1,2=4,3=90.000000
L 0.09951949 4.67443297 0.10243632 4.6738998 2 P 0 ;0,1,2=4,3=90.000000
L 0.10243632 4.6738998 0.10535315 4.6747001 2 P 0 ;0,1,2=4,3=90.000000
L 0.10535315 4.6747001 0.10743681 4.67656634 2 P 0 ;0,1,2=4,3=90.000000
L 0.10743681 4.67656634 0.10826998 4.6786997 2 P 0 ;0,1,2=4,3=90.000000
L 0.10826998 4.6786997 0.10743681 4.68083307 2 P 0 ;0,1,2=4,3=90.000000
L 0.10743681 4.68083307 0.10535315 4.6826998 2 P 0 ;0,1,2=4,3=90.000000
L 0.10535315 4.6826998 0.10243632 4.6835001 2 P 0 ;0,1,2=4,3=90.000000
L 0.10243632 4.6835001 0.09951949 4.68296644 2 P 0 ;0,1,2=4,3=90.000000
L 0.09951949 4.68296644 0.09743661 4.68163337 2 P 0 ;0,1,2=4,3=90.000000
L 0.09743661 4.68163337 0.09660344 4.68003327 2 P 0 ;0,1,2=4,3=90.000000
L 0.09660344 4.68003327 0.09660344 4.67736663 2 P 0 ;0,1,2=4,3=90.000000
L 0.09660344 4.67736663 0.09535295 4.67496663 2 P 0 ;0,1,2=4,3=90.000000
L 0.09535295 4.67496663 0.09285276 4.67336654 2 P 0 ;0,1,2=4,3=90.000000
L 0.09285276 4.67336654 0.08993671 4.67283327 2 P 0 ;0,1,2=4,3=90.000000
L 0.08993671 4.67283327 0.08701909 4.67336654 2 P 0 ;0,1,2=4,3=90.000000
L 0.08701909 4.67336654 0.08493622 4.6747001 2 P 0 ;0,1,2=4,3=90.000000
L 0.08493622 4.6747001 0.08368652 4.67683346 2 P 0 ;0,1,2=4,3=90.000000
L 0.08368652 4.67683346 0.08326998 4.6786997 2 P 0 ;0,1,2=4,3=90.000000
L 0.10410335 4.69763317 0.10660285 4.69923327 2 P 0 ;0,1,2=4,3=90.000000
L 0.10660285 4.69923327 0.10785335 4.7011 2 P 0 ;0,1,2=4,3=90.000000
L 0.10785335 4.7011 0.10826998 4.70323337 2 P 0 ;0,1,2=4,3=90.000000
L 0.10826998 4.70323337 0.10743681 4.7059 2 P 0 ;0,1,2=4,3=90.000000
L 0.10743681 4.7059 0.10535315 4.70776673 2 P 0 ;0,1,2=4,3=90.000000
L 0.10535315 4.70776673 0.10285364 4.7083 2 P 0 ;0,1,2=4,3=90.000000
L 0.10285364 4.7083 0.10035266 4.70803337 2 P 0 ;0,1,2=4,3=90.000000
L 0.10035266 4.70803337 0.09826978 4.70696644 2 P 0 ;0,1,2=4,3=90.000000
L 0.09826978 4.70696644 0.09410325 4.70163327 2 P 0 ;0,1,2=4,3=90.000000
L 0.09410325 4.70163327 0.09118642 4.69923327 2 P 0 ;0,1,2=4,3=90.000000
L 0.09118642 4.69923327 0.08701909 4.69763317 2 P 0 ;0,1,2=4,3=90.000000
L 0.08701909 4.69763317 0.08326998 4.6970999 2 P 0 ;0,1,2=4,3=90.000000
L 0.08326998 4.6970999 0.08326998 4.7083 2 P 0 ;0,1,2=4,3=90.000000
L 0.07826998 1.28007293 0.10326998 1.28673967 2 P 0 ;0,1,2=5,3=90.000000
L 0.10326998 1.28673967 0.07826998 1.29340689 2 P 0 ;0,1,2=5,3=90.000000
L 0.08701959 1.2910064 0.08701959 1.28247293 2 P 0 ;0,1,2=5,3=90.000000
L 0.09910335 1.30567313 0.10160285 1.30727323 2 P 0 ;0,1,2=5,3=90.000000
L 0.10160285 1.30727323 0.10285335 1.30913996 2 P 0 ;0,1,2=5,3=90.000000
L 0.10285335 1.30913996 0.10326998 1.31127333 2 P 0 ;0,1,2=5,3=90.000000
L 0.10326998 1.31127333 0.10243681 1.31393996 2 P 0 ;0,1,2=5,3=90.000000
L 0.10243681 1.31393996 0.10035315 1.31580669 2 P 0 ;0,1,2=5,3=90.000000
L 0.10035315 1.31580669 0.09785364 1.31633996 2 P 0 ;0,1,2=5,3=90.000000
L 0.09785364 1.31633996 0.09535266 1.31607333 2 P 0 ;0,1,2=5,3=90.000000
L 0.09535266 1.31607333 0.09326978 1.3150064 2 P 0 ;0,1,2=5,3=90.000000
L 0.09326978 1.3150064 0.08910325 1.30967323 2 P 0 ;0,1,2=5,3=90.000000
L 0.08910325 1.30967323 0.08618642 1.30727323 2 P 0 ;0,1,2=5,3=90.000000
L 0.08618642 1.30727323 0.08201909 1.30567313 2 P 0 ;0,1,2=5,3=90.000000
L 0.08201909 1.30567313 0.07826998 1.30513986 2 P 0 ;0,1,2=5,3=90.000000
L 0.07826998 1.30513986 0.07826998 1.31633996 2 P 0 ;0,1,2=5,3=90.000000
L 0.3299435 1.74238307 0.33119331 1.74345 2 P 0 ;0,1,2=6,3=90.000000
L 0.33119331 1.74345 0.33327618 1.7442498 2 P 0 ;0,1,2=6,3=90.000000
L 0.33327618 1.7442498 0.3361937 1.74478356 2 P 0 ;0,1,2=6,3=90.000000
L 0.3361937 1.74478356 0.33869321 1.7442498 2 P 0 ;0,1,2=6,3=90.000000
L 0.33869321 1.7442498 0.34035945 1.74318337 2 P 0 ;0,1,2=6,3=90.000000
L 0.34035945 1.74318337 0.34161004 1.74131663 2 P 0 ;0,1,2=6,3=90.000000
L 0.34161004 1.74131663 0.34161004 1.73411673 2 P 0 ;0,1,2=6,3=90.000000
L 0.34161004 1.73411673 0.31661004 1.73411673 2 P 0 ;0,1,2=6,3=90.000000
L 0.31661004 1.73411673 0.31661004 1.74291673 2 P 0 ;0,1,2=6,3=90.000000
L 0.31661004 1.74291673 0.31827628 1.74478356 2 P 0 ;0,1,2=6,3=90.000000
L 0.31827628 1.74478356 0.32077657 1.74585 2 P 0 ;0,1,2=6,3=90.000000
L 0.32077657 1.74585 0.32369331 1.74638317 2 P 0 ;0,1,2=6,3=90.000000
L 0.32369331 1.74638317 0.32660935 1.74585 2 P 0 ;0,1,2=6,3=90.000000
L 0.32660935 1.74585 0.32910965 1.7442498 2 P 0 ;0,1,2=6,3=90.000000
L 0.32910965 1.7442498 0.3299435 1.74238307 2 P 0 ;0,1,2=6,3=90.000000
L 0.3299435 1.74238307 0.3299435 1.73411673 2 P 0 ;0,1,2=6,3=90.000000
L 0.31661004 1.7642497 0.34161004 1.7642497 2 P 0 ;0,1,2=6,3=90.000000
L 0.34161004 1.7642497 0.33661033 1.7610499 2 P 0 ;0,1,2=6,3=90.000000
L 0.31661004 1.7610499 0.31661004 1.76744951 2 P 0 ;0,1,2=6,3=90.000000
L 0.31661004 1.7882497 0.34161004 1.7882497 2 P 0 ;0,1,2=6,3=90.000000
L 0.34161004 1.7882497 0.33661033 1.7850499 2 P 0 ;0,1,2=6,3=90.000000
L 0.31661004 1.7850499 0.31661004 1.79144951 2 P 0 ;0,1,2=6,3=90.000000
L 0.15306998 1.24070295 0.17806998 1.24736969 2 P 0 ;0,1,2=7,3=90.000000
L 0.17806998 1.24736969 0.15306998 1.25403691 2 P 0 ;0,1,2=7,3=90.000000
L 0.16181959 1.25163642 0.16181959 1.24310295 2 P 0 ;0,1,2=7,3=90.000000
L 0.15306998 1.27136969 0.17806998 1.27136969 2 P 0 ;0,1,2=7,3=90.000000
L 0.17806998 1.27136969 0.17307028 1.26816988 2 P 0 ;0,1,2=7,3=90.000000
L 0.15306998 1.26816988 0.15306998 1.27456949 2 P 0 ;0,1,2=7,3=90.000000
L 0.35357343 4.65683307 0.35482323 4.6579 2 P 0 ;0,1,2=8,3=90.000000
L 0.35482323 4.6579 0.3569061 4.6586998 2 P 0 ;0,1,2=8,3=90.000000
L 0.3569061 4.6586998 0.35982362 4.65923356 2 P 0 ;0,1,2=8,3=90.000000
L 0.35982362 4.65923356 0.36232313 4.6586998 2 P 0 ;0,1,2=8,3=90.000000
L 0.36232313 4.6586998 0.36398937 4.65763337 2 P 0 ;0,1,2=8,3=90.000000
L 0.36398937 4.65763337 0.36523996 4.65576663 2 P 0 ;0,1,2=8,3=90.000000
L 0.36523996 4.65576663 0.36523996 4.64856673 2 P 0 ;0,1,2=8,3=90.000000
L 0.36523996 4.64856673 0.34023996 4.64856673 2 P 0 ;0,1,2=8,3=90.000000
L 0.34023996 4.64856673 0.34023996 4.65736673 2 P 0 ;0,1,2=8,3=90.000000
L 0.34023996 4.65736673 0.3419062 4.65923356 2 P 0 ;0,1,2=8,3=90.000000
L 0.3419062 4.65923356 0.3444065 4.6603 2 P 0 ;0,1,2=8,3=90.000000
L 0.3444065 4.6603 0.34732323 4.66083317 2 P 0 ;0,1,2=8,3=90.000000
L 0.34732323 4.66083317 0.35023927 4.6603 2 P 0 ;0,1,2=8,3=90.000000
L 0.35023927 4.6603 0.35273957 4.6586998 2 P 0 ;0,1,2=8,3=90.000000
L 0.35273957 4.6586998 0.35357343 4.65683307 2 P 0 ;0,1,2=8,3=90.000000
L 0.35357343 4.65683307 0.35357343 4.64856673 2 P 0 ;0,1,2=8,3=90.000000
L 0.34023996 4.6786997 0.3406565 4.68056644 2 P 0 ;0,1,2=8,3=90.000000
L 0.3406565 4.68056644 0.3419062 4.6826998 2 P 0 ;0,1,2=8,3=90.000000
L 0.3419062 4.6826998 0.34398907 4.68403337 2 P 0 ;0,1,2=8,3=90.000000
L 0.34398907 4.68403337 0.34690669 4.68456663 2 P 0 ;0,1,2=8,3=90.000000
L 0.34690669 4.68456663 0.34982274 4.68403337 2 P 0 ;0,1,2=8,3=90.000000
L 0.34982274 4.68403337 0.35232293 4.68243327 2 P 0 ;0,1,2=8,3=90.000000
L 0.35232293 4.68243327 0.35357343 4.68003327 2 P 0 ;0,1,2=8,3=90.000000
L 0.35357343 4.68003327 0.35357343 4.67736663 2 P 0 ;0,1,2=8,3=90.000000
L 0.35357343 4.67736663 0.35440659 4.67576654 2 P 0 ;0,1,2=8,3=90.000000
L 0.35440659 4.67576654 0.35648947 4.67443297 2 P 0 ;0,1,2=8,3=90.000000
L 0.35648947 4.67443297 0.3594063 4.6738998 2 P 0 ;0,1,2=8,3=90.000000
L 0.3594063 4.6738998 0.36232313 4.6747001 2 P 0 ;0,1,2=8,3=90.000000
L 0.36232313 4.6747001 0.36440679 4.67656634 2 P 0 ;0,1,2=8,3=90.000000
L 0.36440679 4.67656634 0.36523996 4.6786997 2 P 0 ;0,1,2=8,3=90.000000
L 0.36523996 4.6786997 0.36440679 4.68083307 2 P 0 ;0,1,2=8,3=90.000000
L 0.36440679 4.68083307 0.36232313 4.6826998 2 P 0 ;0,1,2=8,3=90.000000
L 0.36232313 4.6826998 0.3594063 4.6835001 2 P 0 ;0,1,2=8,3=90.000000
L 0.3594063 4.6835001 0.35648947 4.68296644 2 P 0 ;0,1,2=8,3=90.000000
L 0.35648947 4.68296644 0.35440659 4.68163337 2 P 0 ;0,1,2=8,3=90.000000
L 0.35440659 4.68163337 0.35357343 4.68003327 2 P 0 ;0,1,2=8,3=90.000000
L 0.35357343 4.68003327 0.35357343 4.67736663 2 P 0 ;0,1,2=8,3=90.000000
L 0.35357343 4.67736663 0.35232293 4.67496663 2 P 0 ;0,1,2=8,3=90.000000
L 0.35232293 4.67496663 0.34982274 4.67336654 2 P 0 ;0,1,2=8,3=90.000000
L 0.34982274 4.67336654 0.34690669 4.67283327 2 P 0 ;0,1,2=8,3=90.000000
L 0.34690669 4.67283327 0.34398907 4.67336654 2 P 0 ;0,1,2=8,3=90.000000
L 0.34398907 4.67336654 0.3419062 4.6747001 2 P 0 ;0,1,2=8,3=90.000000
L 0.3419062 4.6747001 0.3406565 4.67683346 2 P 0 ;0,1,2=8,3=90.000000
L 0.3406565 4.67683346 0.34023996 4.6786997 2 P 0 ;0,1,2=8,3=90.000000
L 0.36107333 4.69763317 0.36357283 4.69923327 2 P 0 ;0,1,2=8,3=90.000000
L 0.36357283 4.69923327 0.36482333 4.7011 2 P 0 ;0,1,2=8,3=90.000000
L 0.36482333 4.7011 0.36523996 4.70323337 2 P 0 ;0,1,2=8,3=90.000000
L 0.36523996 4.70323337 0.36440679 4.7059 2 P 0 ;0,1,2=8,3=90.000000
L 0.36440679 4.7059 0.36232313 4.70776673 2 P 0 ;0,1,2=8,3=90.000000
L 0.36232313 4.70776673 0.35982362 4.7083 2 P 0 ;0,1,2=8,3=90.000000
L 0.35982362 4.7083 0.35732264 4.70803337 2 P 0 ;0,1,2=8,3=90.000000
L 0.35732264 4.70803337 0.35523976 4.70696644 2 P 0 ;0,1,2=8,3=90.000000
L 0.35523976 4.70696644 0.35107323 4.70163327 2 P 0 ;0,1,2=8,3=90.000000
L 0.35107323 4.70163327 0.3481564 4.69923327 2 P 0 ;0,1,2=8,3=90.000000
L 0.3481564 4.69923327 0.34398907 4.69763317 2 P 0 ;0,1,2=8,3=90.000000
L 0.34398907 4.69763317 0.34023996 4.6970999 2 P 0 ;0,1,2=8,3=90.000000
L 0.34023996 4.6970999 0.34023996 4.7083 2 P 0 ;0,1,2=8,3=90.000000
L 0.34357343 1.28887303 0.34482323 1.28993996 2 P 0 ;0,1,2=9,3=90.000000
L 0.34482323 1.28993996 0.3469061 1.29073976 2 P 0 ;0,1,2=9,3=90.000000
L 0.3469061 1.29073976 0.34982362 1.29127352 2 P 0 ;0,1,2=9,3=90.000000
L 0.34982362 1.29127352 0.35232313 1.29073976 2 P 0 ;0,1,2=9,3=90.000000
L 0.35232313 1.29073976 0.35398937 1.28967333 2 P 0 ;0,1,2=9,3=90.000000
L 0.35398937 1.28967333 0.35523996 1.28780659 2 P 0 ;0,1,2=9,3=90.000000
L 0.35523996 1.28780659 0.35523996 1.28060669 2 P 0 ;0,1,2=9,3=90.000000
L 0.35523996 1.28060669 0.33023996 1.28060669 2 P 0 ;0,1,2=9,3=90.000000
L 0.33023996 1.28060669 0.33023996 1.28940669 2 P 0 ;0,1,2=9,3=90.000000
L 0.33023996 1.28940669 0.3319062 1.29127352 2 P 0 ;0,1,2=9,3=90.000000
L 0.3319062 1.29127352 0.3344065 1.29233996 2 P 0 ;0,1,2=9,3=90.000000
L 0.3344065 1.29233996 0.33732323 1.29287313 2 P 0 ;0,1,2=9,3=90.000000
L 0.33732323 1.29287313 0.34023927 1.29233996 2 P 0 ;0,1,2=9,3=90.000000
L 0.34023927 1.29233996 0.34273957 1.29073976 2 P 0 ;0,1,2=9,3=90.000000
L 0.34273957 1.29073976 0.34357343 1.28887303 2 P 0 ;0,1,2=9,3=90.000000
L 0.34357343 1.28887303 0.34357343 1.28060669 2 P 0 ;0,1,2=9,3=90.000000
L 0.35107333 1.30567313 0.35357283 1.30727323 2 P 0 ;0,1,2=9,3=90.000000
L 0.35357283 1.30727323 0.35482333 1.30913996 2 P 0 ;0,1,2=9,3=90.000000
L 0.35482333 1.30913996 0.35523996 1.31127333 2 P 0 ;0,1,2=9,3=90.000000
L 0.35523996 1.31127333 0.35440679 1.31393996 2 P 0 ;0,1,2=9,3=90.000000
L 0.35440679 1.31393996 0.35232313 1.31580669 2 P 0 ;0,1,2=9,3=90.000000
L 0.35232313 1.31580669 0.34982362 1.31633996 2 P 0 ;0,1,2=9,3=90.000000
L 0.34982362 1.31633996 0.34732264 1.31607333 2 P 0 ;0,1,2=9,3=90.000000
L 0.34732264 1.31607333 0.34523976 1.3150064 2 P 0 ;0,1,2=9,3=90.000000
L 0.34523976 1.3150064 0.34107323 1.30967323 2 P 0 ;0,1,2=9,3=90.000000
L 0.34107323 1.30967323 0.3381564 1.30727323 2 P 0 ;0,1,2=9,3=90.000000
L 0.3381564 1.30727323 0.33398907 1.30567313 2 P 0 ;0,1,2=9,3=90.000000
L 0.33398907 1.30567313 0.33023996 1.30513986 2 P 0 ;0,1,2=9,3=90.000000
L 0.33023996 1.30513986 0.33023996 1.31633996 2 P 0 ;0,1,2=9,3=90.000000
L 0.26876348 1.24950305 0.27001329 1.25056998 2 P 0 ;0,1,2=10,3=90.000000
L 0.27001329 1.25056998 0.27209616 1.25136978 2 P 0 ;0,1,2=10,3=90.000000
L 0.27209616 1.25136978 0.27501368 1.25190354 2 P 0 ;0,1,2=10,3=90.000000
L 0.27501368 1.25190354 0.27751319 1.25136978 2 P 0 ;0,1,2=10,3=90.000000
L 0.27751319 1.25136978 0.27917943 1.25030335 2 P 0 ;0,1,2=10,3=90.000000
L 0.27917943 1.25030335 0.28043002 1.24843661 2 P 0 ;0,1,2=10,3=90.000000
L 0.28043002 1.24843661 0.28043002 1.24123671 2 P 0 ;0,1,2=10,3=90.000000
L 0.28043002 1.24123671 0.25543002 1.24123671 2 P 0 ;0,1,2=10,3=90.000000
L 0.25543002 1.24123671 0.25543002 1.25003671 2 P 0 ;0,1,2=10,3=90.000000
L 0.25543002 1.25003671 0.25709626 1.25190354 2 P 0 ;0,1,2=10,3=90.000000
L 0.25709626 1.25190354 0.25959656 1.25296998 2 P 0 ;0,1,2=10,3=90.000000
L 0.25959656 1.25296998 0.26251329 1.25350315 2 P 0 ;0,1,2=10,3=90.000000
L 0.26251329 1.25350315 0.26542933 1.25296998 2 P 0 ;0,1,2=10,3=90.000000
L 0.26542933 1.25296998 0.26792963 1.25136978 2 P 0 ;0,1,2=10,3=90.000000
L 0.26792963 1.25136978 0.26876348 1.24950305 2 P 0 ;0,1,2=10,3=90.000000
L 0.26876348 1.24950305 0.26876348 1.24123671 2 P 0 ;0,1,2=10,3=90.000000
L 0.25543002 1.27136969 0.28043002 1.27136969 2 P 0 ;0,1,2=10,3=90.000000
L 0.28043002 1.27136969 0.27543032 1.26816988 2 P 0 ;0,1,2=10,3=90.000000
L 0.25543002 1.26816988 0.25543002 1.27456949 2 P 0 ;0,1,2=10,3=90.000000
L 0.41656348 1.82112303 0.41781329 1.82218996 2 P 0 ;0,1,2=11,3=90.000000
L 0.41781329 1.82218996 0.41989616 1.82298976 2 P 0 ;0,1,2=11,3=90.000000
L 0.41989616 1.82298976 0.42281368 1.82352352 2 P 0 ;0,1,2=11,3=90.000000
L 0.42281368 1.82352352 0.42531319 1.82298976 2 P 0 ;0,1,2=11,3=90.000000
L 0.42531319 1.82298976 0.42697943 1.82192333 2 P 0 ;0,1,2=11,3=90.000000
L 0.42697943 1.82192333 0.42823002 1.82005659 2 P 0 ;0,1,2=11,3=90.000000
L 0.42823002 1.82005659 0.42823002 1.81285669 2 P 0 ;0,1,2=11,3=90.000000
L 0.42823002 1.81285669 0.40323002 1.81285669 2 P 0 ;0,1,2=11,3=90.000000
L 0.40323002 1.81285669 0.40323002 1.82165669 2 P 0 ;0,1,2=11,3=90.000000
L 0.40323002 1.82165669 0.40489626 1.82352352 2 P 0 ;0,1,2=11,3=90.000000
L 0.40489626 1.82352352 0.40739656 1.82458996 2 P 0 ;0,1,2=11,3=90.000000
L 0.40739656 1.82458996 0.41031329 1.82512313 2 P 0 ;0,1,2=11,3=90.000000
L 0.41031329 1.82512313 0.41322933 1.82458996 2 P 0 ;0,1,2=11,3=90.000000
L 0.41322933 1.82458996 0.41572963 1.82298976 2 P 0 ;0,1,2=11,3=90.000000
L 0.41572963 1.82298976 0.41656348 1.82112303 2 P 0 ;0,1,2=11,3=90.000000
L 0.41656348 1.82112303 0.41656348 1.81285669 2 P 0 ;0,1,2=11,3=90.000000
L 0.40323002 1.84298967 0.42823002 1.84298967 2 P 0 ;0,1,2=11,3=90.000000
L 0.42823002 1.84298967 0.42323032 1.83978986 2 P 0 ;0,1,2=11,3=90.000000
L 0.40323002 1.83978986 0.40323002 1.84618947 2 P 0 ;0,1,2=11,3=90.000000
L 0.42406339 1.86192313 0.42656289 1.86352323 2 P 0 ;0,1,2=11,3=90.000000
L 0.42656289 1.86352323 0.42781339 1.86538996 2 P 0 ;0,1,2=11,3=90.000000
L 0.42781339 1.86538996 0.42823002 1.86752333 2 P 0 ;0,1,2=11,3=90.000000
L 0.42823002 1.86752333 0.42739685 1.87018996 2 P 0 ;0,1,2=11,3=90.000000
L 0.42739685 1.87018996 0.42531319 1.87205669 2 P 0 ;0,1,2=11,3=90.000000
L 0.42531319 1.87205669 0.42281368 1.87258996 2 P 0 ;0,1,2=11,3=90.000000
L 0.42281368 1.87258996 0.4203127 1.87232333 2 P 0 ;0,1,2=11,3=90.000000
L 0.4203127 1.87232333 0.41822982 1.8712564 2 P 0 ;0,1,2=11,3=90.000000
L 0.41822982 1.8712564 0.41406329 1.86592323 2 P 0 ;0,1,2=11,3=90.000000
L 0.41406329 1.86592323 0.41114646 1.86352323 2 P 0 ;0,1,2=11,3=90.000000
L 0.41114646 1.86352323 0.40697913 1.86192313 2 P 0 ;0,1,2=11,3=90.000000
L 0.40697913 1.86192313 0.40323002 1.86138986 2 P 0 ;0,1,2=11,3=90.000000
L 0.40323002 1.86138986 0.40323002 1.87258996 2 P 0 ;0,1,2=11,3=90.000000
L 0.09795 1.72964301 0.12295 1.73630974 2 P 0 ;0,1,2=12,3=90.000000
L 0.12295 1.73630974 0.09795 1.74297697 2 P 0 ;0,1,2=12,3=90.000000
L 0.10669961 1.74057648 0.10669961 1.73204301 2 P 0 ;0,1,2=12,3=90.000000
L 0.09795 1.76030974 0.12295 1.76030974 2 P 0 ;0,1,2=12,3=90.000000
L 0.12295 1.76030974 0.1179503 1.75710994 2 P 0 ;0,1,2=12,3=90.000000
L 0.09795 1.75710994 0.09795 1.76350955 2 P 0 ;0,1,2=12,3=90.000000
L 0.09795 1.78430974 0.12295 1.78430974 2 P 0 ;0,1,2=12,3=90.000000
L 0.12295 1.78430974 0.1179503 1.78110994 2 P 0 ;0,1,2=12,3=90.000000
L 0.09795 1.78110994 0.09795 1.78750955 2 P 0 ;0,1,2=12,3=90.000000
L 0.01 1.84133297 0.035 1.8479997 2 P 0 ;0,1,2=13,3=90.000000
L 0.035 1.8479997 0.01 1.85466693 2 P 0 ;0,1,2=13,3=90.000000
L 0.01874961 1.85226644 0.01874961 1.84373297 2 P 0 ;0,1,2=13,3=90.000000
L 0.01 1.8719997 0.035 1.8719997 2 P 0 ;0,1,2=13,3=90.000000
L 0.035 1.8719997 0.0300003 1.8687999 2 P 0 ;0,1,2=13,3=90.000000
L 0.01 1.8687999 0.01 1.87519951 2 P 0 ;0,1,2=13,3=90.000000
L 0.03083337 1.89093317 0.03333287 1.89253327 2 P 0 ;0,1,2=13,3=90.000000
L 0.03333287 1.89253327 0.03458337 1.8944 2 P 0 ;0,1,2=13,3=90.000000
L 0.03458337 1.8944 0.035 1.89653337 2 P 0 ;0,1,2=13,3=90.000000
L 0.035 1.89653337 0.03416683 1.8992 2 P 0 ;0,1,2=13,3=90.000000
L 0.03416683 1.8992 0.03208317 1.90106673 2 P 0 ;0,1,2=13,3=90.000000
L 0.03208317 1.90106673 0.02958366 1.9016 2 P 0 ;0,1,2=13,3=90.000000
L 0.02958366 1.9016 0.02708268 1.90133337 2 P 0 ;0,1,2=13,3=90.000000
L 0.02708268 1.90133337 0.0249998 1.90026644 2 P 0 ;0,1,2=13,3=90.000000
L 0.0249998 1.90026644 0.02083327 1.89493327 2 P 0 ;0,1,2=13,3=90.000000
L 0.02083327 1.89493327 0.01791644 1.89253327 2 P 0 ;0,1,2=13,3=90.000000
L 0.01791644 1.89253327 0.01374911 1.89093317 2 P 0 ;0,1,2=13,3=90.000000
L 0.01374911 1.89093317 0.01 1.8903999 2 P 0 ;0,1,2=13,3=90.000000
L 0.01 1.8903999 0.01 1.9016 2 P 0 ;0,1,2=13,3=90.000000
L 0.05 1.72633297 0.075 1.7329997 2 P 0 ;0,1,2=14,3=90.000000
L 0.075 1.7329997 0.05 1.73966693 2 P 0 ;0,1,2=14,3=90.000000
L 0.05874961 1.73726644 0.05874961 1.72873297 2 P 0 ;0,1,2=14,3=90.000000
L 0.05 1.7569997 0.075 1.7569997 2 P 0 ;0,1,2=14,3=90.000000
L 0.075 1.7569997 0.0700003 1.7537999 2 P 0 ;0,1,2=14,3=90.000000
L 0.05 1.7537999 0.05 1.76019951 2 P 0 ;0,1,2=14,3=90.000000
L 0.075 1.7809997 0.07416683 1.77886634 2 P 0 ;0,1,2=14,3=90.000000
L 0.07416683 1.77886634 0.07208317 1.77726663 2 P 0 ;0,1,2=14,3=90.000000
L 0.07208317 1.77726663 0.06958366 1.7761998 2 P 0 ;0,1,2=14,3=90.000000
L 0.06958366 1.7761998 0.06624951 1.7753999 2 P 0 ;0,1,2=14,3=90.000000
L 0.06624951 1.7753999 0.06249961 1.77513327 2 P 0 ;0,1,2=14,3=90.000000
L 0.06249961 1.77513327 0.05874961 1.7753999 2 P 0 ;0,1,2=14,3=90.000000
L 0.05874961 1.7753999 0.05541624 1.7761998 2 P 0 ;0,1,2=14,3=90.000000
L 0.05541624 1.7761998 0.05291604 1.77726663 2 P 0 ;0,1,2=14,3=90.000000
L 0.05291604 1.77726663 0.05083307 1.77886634 2 P 0 ;0,1,2=14,3=90.000000
L 0.05083307 1.77886634 0.05 1.7809997 2 P 0 ;0,1,2=14,3=90.000000
L 0.05 1.7809997 0.05083307 1.78313307 2 P 0 ;0,1,2=14,3=90.000000
L 0.05083307 1.78313307 0.05291604 1.78473327 2 P 0 ;0,1,2=14,3=90.000000
L 0.05291604 1.78473327 0.05541624 1.7858001 2 P 0 ;0,1,2=14,3=90.000000
L 0.05541624 1.7858001 0.05874961 1.7866 2 P 0 ;0,1,2=14,3=90.000000
L 0.05874961 1.7866 0.06249961 1.78686663 2 P 0 ;0,1,2=14,3=90.000000
L 0.06249961 1.78686663 0.06624951 1.7866 2 P 0 ;0,1,2=14,3=90.000000
L 0.06624951 1.7866 0.06958366 1.7858001 2 P 0 ;0,1,2=14,3=90.000000
L 0.06958366 1.7858001 0.07208317 1.78473327 2 P 0 ;0,1,2=14,3=90.000000
L 0.07208317 1.78473327 0.07416683 1.78313307 2 P 0 ;0,1,2=14,3=90.000000
L 0.07416683 1.78313307 0.075 1.7809997 2 P 0 ;0,1,2=14,3=90.000000
L 0.13731998 1.77688297 0.16231998 1.7835497 2 P 0 ;0,1,2=15,3=90.000000
L 0.16231998 1.7835497 0.13731998 1.79021693 2 P 0 ;0,1,2=15,3=90.000000
L 0.14606959 1.78781644 0.14606959 1.77928297 2 P 0 ;0,1,2=15,3=90.000000
L 0.13731998 1.8075497 0.16231998 1.8075497 2 P 0 ;0,1,2=15,3=90.000000
L 0.16231998 1.8075497 0.15732028 1.8043499 2 P 0 ;0,1,2=15,3=90.000000
L 0.13731998 1.8043499 0.13731998 1.81074951 2 P 0 ;0,1,2=15,3=90.000000
L 0.14231959 1.82568327 0.13940285 1.82728297 2 P 0 ;0,1,2=15,3=90.000000
L 0.13940285 1.82728297 0.13773652 1.82941634 2 P 0 ;0,1,2=15,3=90.000000
L 0.13773652 1.82941634 0.13731998 1.83181683 2 P 0 ;0,1,2=15,3=90.000000
L 0.13731998 1.83181683 0.13773652 1.8339502 2 P 0 ;0,1,2=15,3=90.000000
L 0.13773652 1.8339502 0.13981939 1.83608356 2 P 0 ;0,1,2=15,3=90.000000
L 0.13981939 1.83608356 0.14231959 1.83741663 2 P 0 ;0,1,2=15,3=90.000000
L 0.14231959 1.83741663 0.14481988 1.83768317 2 P 0 ;0,1,2=15,3=90.000000
L 0.14481988 1.83768317 0.14773593 1.83715 2 P 0 ;0,1,2=15,3=90.000000
L 0.14773593 1.83715 0.14981959 1.83528327 2 P 0 ;0,1,2=15,3=90.000000
L 0.14981959 1.83528327 0.15065344 1.83341644 2 P 0 ;0,1,2=15,3=90.000000
L 0.15065344 1.83341644 0.15065344 1.83101654 2 P 0 ;0,1,2=15,3=90.000000
L 0.15065344 1.83341644 0.15190325 1.83501663 2 P 0 ;0,1,2=15,3=90.000000
L 0.15190325 1.83501663 0.15398612 1.8363501 2 P 0 ;0,1,2=15,3=90.000000
L 0.15398612 1.8363501 0.15648632 1.83688337 2 P 0 ;0,1,2=15,3=90.000000
L 0.15648632 1.83688337 0.15898652 1.8363501 2 P 0 ;0,1,2=15,3=90.000000
L 0.15898652 1.8363501 0.16106939 1.83501663 2 P 0 ;0,1,2=15,3=90.000000
L 0.16106939 1.83501663 0.16231998 1.83261663 2 P 0 ;0,1,2=15,3=90.000000
L 0.16231998 1.83261663 0.16190335 1.83021663 2 P 0 ;0,1,2=15,3=90.000000
L 0.16190335 1.83021663 0.16023632 1.82781663 2 P 0 ;0,1,2=15,3=90.000000
L 0.29451348 1.78962303 0.29576329 1.79068996 2 P 0 ;0,1,2=16,3=90.000000
L 0.29576329 1.79068996 0.29784616 1.79148976 2 P 0 ;0,1,2=16,3=90.000000
L 0.29784616 1.79148976 0.30076368 1.79202352 2 P 0 ;0,1,2=16,3=90.000000
L 0.30076368 1.79202352 0.30326319 1.79148976 2 P 0 ;0,1,2=16,3=90.000000
L 0.30326319 1.79148976 0.30492943 1.79042333 2 P 0 ;0,1,2=16,3=90.000000
L 0.30492943 1.79042333 0.30618002 1.78855659 2 P 0 ;0,1,2=16,3=90.000000
L 0.30618002 1.78855659 0.30618002 1.78135669 2 P 0 ;0,1,2=16,3=90.000000
L 0.30618002 1.78135669 0.28118002 1.78135669 2 P 0 ;0,1,2=16,3=90.000000
L 0.28118002 1.78135669 0.28118002 1.79015669 2 P 0 ;0,1,2=16,3=90.000000
L 0.28118002 1.79015669 0.28284626 1.79202352 2 P 0 ;0,1,2=16,3=90.000000
L 0.28284626 1.79202352 0.28534656 1.79308996 2 P 0 ;0,1,2=16,3=90.000000
L 0.28534656 1.79308996 0.28826329 1.79362313 2 P 0 ;0,1,2=16,3=90.000000
L 0.28826329 1.79362313 0.29117933 1.79308996 2 P 0 ;0,1,2=16,3=90.000000
L 0.29117933 1.79308996 0.29367963 1.79148976 2 P 0 ;0,1,2=16,3=90.000000
L 0.29367963 1.79148976 0.29451348 1.78962303 2 P 0 ;0,1,2=16,3=90.000000
L 0.29451348 1.78962303 0.29451348 1.78135669 2 P 0 ;0,1,2=16,3=90.000000
L 0.28118002 1.81148967 0.30618002 1.81148967 2 P 0 ;0,1,2=16,3=90.000000
L 0.30618002 1.81148967 0.30118032 1.80828986 2 P 0 ;0,1,2=16,3=90.000000
L 0.28118002 1.80828986 0.28118002 1.81468947 2 P 0 ;0,1,2=16,3=90.000000
L 0.28617963 1.82962323 0.28326289 1.83122293 2 P 0 ;0,1,2=16,3=90.000000
L 0.28326289 1.83122293 0.28159656 1.8333563 2 P 0 ;0,1,2=16,3=90.000000
L 0.28159656 1.8333563 0.28118002 1.83575679 2 P 0 ;0,1,2=16,3=90.000000
L 0.28118002 1.83575679 0.28159656 1.83789016 2 P 0 ;0,1,2=16,3=90.000000
L 0.28159656 1.83789016 0.28367943 1.84002352 2 P 0 ;0,1,2=16,3=90.000000
L 0.28367943 1.84002352 0.28617963 1.84135659 2 P 0 ;0,1,2=16,3=90.000000
L 0.28617963 1.84135659 0.28867992 1.84162313 2 P 0 ;0,1,2=16,3=90.000000
L 0.28867992 1.84162313 0.29159596 1.84108996 2 P 0 ;0,1,2=16,3=90.000000
L 0.29159596 1.84108996 0.29367963 1.83922323 2 P 0 ;0,1,2=16,3=90.000000
L 0.29367963 1.83922323 0.29451348 1.8373564 2 P 0 ;0,1,2=16,3=90.000000
L 0.29451348 1.8373564 0.29451348 1.8349565 2 P 0 ;0,1,2=16,3=90.000000
L 0.29451348 1.8373564 0.29576329 1.83895659 2 P 0 ;0,1,2=16,3=90.000000
L 0.29576329 1.83895659 0.29784616 1.84029006 2 P 0 ;0,1,2=16,3=90.000000
L 0.29784616 1.84029006 0.30034636 1.84082333 2 P 0 ;0,1,2=16,3=90.000000
L 0.30034636 1.84082333 0.30284656 1.84029006 2 P 0 ;0,1,2=16,3=90.000000
L 0.30284656 1.84029006 0.30492943 1.83895659 2 P 0 ;0,1,2=16,3=90.000000
L 0.30492943 1.83895659 0.30618002 1.83655659 2 P 0 ;0,1,2=16,3=90.000000
L 0.30618002 1.83655659 0.30576339 1.83415659 2 P 0 ;0,1,2=16,3=90.000000
L 0.30576339 1.83415659 0.30409636 1.83175659 2 P 0 ;0,1,2=16,3=90.000000
L 0.41656348 1.66364311 0.41781329 1.66471004 2 P 0 ;0,1,2=17,3=90.000000
L 0.41781329 1.66471004 0.41989616 1.66550984 2 P 0 ;0,1,2=17,3=90.000000
L 0.41989616 1.66550984 0.42281368 1.6660436 2 P 0 ;0,1,2=17,3=90.000000
L 0.42281368 1.6660436 0.42531319 1.66550984 2 P 0 ;0,1,2=17,3=90.000000
L 0.42531319 1.66550984 0.42697943 1.66444341 2 P 0 ;0,1,2=17,3=90.000000
L 0.42697943 1.66444341 0.42823002 1.66257667 2 P 0 ;0,1,2=17,3=90.000000
L 0.42823002 1.66257667 0.42823002 1.65537677 2 P 0 ;0,1,2=17,3=90.000000
L 0.42823002 1.65537677 0.40323002 1.65537677 2 P 0 ;0,1,2=17,3=90.000000
L 0.40323002 1.65537677 0.40323002 1.66417677 2 P 0 ;0,1,2=17,3=90.000000
L 0.40323002 1.66417677 0.40489626 1.6660436 2 P 0 ;0,1,2=17,3=90.000000
L 0.40489626 1.6660436 0.40739656 1.66711004 2 P 0 ;0,1,2=17,3=90.000000
L 0.40739656 1.66711004 0.41031329 1.66764321 2 P 0 ;0,1,2=17,3=90.000000
L 0.41031329 1.66764321 0.41322933 1.66711004 2 P 0 ;0,1,2=17,3=90.000000
L 0.41322933 1.66711004 0.41572963 1.66550984 2 P 0 ;0,1,2=17,3=90.000000
L 0.41572963 1.66550984 0.41656348 1.66364311 2 P 0 ;0,1,2=17,3=90.000000
L 0.41656348 1.66364311 0.41656348 1.65537677 2 P 0 ;0,1,2=17,3=90.000000
L 0.40323002 1.68550974 0.42823002 1.68550974 2 P 0 ;0,1,2=17,3=90.000000
L 0.42823002 1.68550974 0.42323032 1.68230994 2 P 0 ;0,1,2=17,3=90.000000
L 0.40323002 1.68230994 0.40323002 1.68870955 2 P 0 ;0,1,2=17,3=90.000000
L 0.42823002 1.70950974 0.42739685 1.70737638 2 P 0 ;0,1,2=17,3=90.000000
L 0.42739685 1.70737638 0.42531319 1.70577667 2 P 0 ;0,1,2=17,3=90.000000
L 0.42531319 1.70577667 0.42281368 1.70470984 2 P 0 ;0,1,2=17,3=90.000000
L 0.42281368 1.70470984 0.41947953 1.70390994 2 P 0 ;0,1,2=17,3=90.000000
L 0.41947953 1.70390994 0.41572963 1.70364331 2 P 0 ;0,1,2=17,3=90.000000
L 0.41572963 1.70364331 0.41197963 1.70390994 2 P 0 ;0,1,2=17,3=90.000000
L 0.41197963 1.70390994 0.40864626 1.70470984 2 P 0 ;0,1,2=17,3=90.000000
L 0.40864626 1.70470984 0.40614606 1.70577667 2 P 0 ;0,1,2=17,3=90.000000
L 0.40614606 1.70577667 0.40406309 1.70737638 2 P 0 ;0,1,2=17,3=90.000000
L 0.40406309 1.70737638 0.40323002 1.70950974 2 P 0 ;0,1,2=17,3=90.000000
L 0.40323002 1.70950974 0.40406309 1.71164311 2 P 0 ;0,1,2=17,3=90.000000
L 0.40406309 1.71164311 0.40614606 1.71324331 2 P 0 ;0,1,2=17,3=90.000000
L 0.40614606 1.71324331 0.40864626 1.71431014 2 P 0 ;0,1,2=17,3=90.000000
L 0.40864626 1.71431014 0.41197963 1.71511004 2 P 0 ;0,1,2=17,3=90.000000
L 0.41197963 1.71511004 0.41572963 1.71537667 2 P 0 ;0,1,2=17,3=90.000000
L 0.41572963 1.71537667 0.41947953 1.71511004 2 P 0 ;0,1,2=17,3=90.000000
L 0.41947953 1.71511004 0.42281368 1.71431014 2 P 0 ;0,1,2=17,3=90.000000
L 0.42281368 1.71431014 0.42531319 1.71324331 2 P 0 ;0,1,2=17,3=90.000000
L 0.42531319 1.71324331 0.42739685 1.71164311 2 P 0 ;0,1,2=17,3=90.000000
L 0.42739685 1.71164311 0.42823002 1.70950974 2 P 0 ;0,1,2=17,3=90.000000
L 0.14231998 4.60472293 0.16731998 4.61138967 2 P 0 ;0,1,2=18,3=90.000000
L 0.16731998 4.61138967 0.14231998 4.61805689 2 P 0 ;0,1,2=18,3=90.000000
L 0.15106959 4.6156564 0.15106959 4.60712293 2 P 0 ;0,1,2=18,3=90.000000
L 0.14231998 4.63538967 0.14273652 4.6372564 2 P 0 ;0,1,2=18,3=90.000000
L 0.14273652 4.6372564 0.14398622 4.63938976 2 P 0 ;0,1,2=18,3=90.000000
L 0.14398622 4.63938976 0.14606909 4.64072333 2 P 0 ;0,1,2=18,3=90.000000
L 0.14606909 4.64072333 0.14898671 4.64125659 2 P 0 ;0,1,2=18,3=90.000000
L 0.14898671 4.64125659 0.15190276 4.64072333 2 P 0 ;0,1,2=18,3=90.000000
L 0.15190276 4.64072333 0.15440295 4.63912323 2 P 0 ;0,1,2=18,3=90.000000
L 0.15440295 4.63912323 0.15565344 4.63672323 2 P 0 ;0,1,2=18,3=90.000000
L 0.15565344 4.63672323 0.15565344 4.63405659 2 P 0 ;0,1,2=18,3=90.000000
L 0.15565344 4.63405659 0.15648661 4.6324565 2 P 0 ;0,1,2=18,3=90.000000
L 0.15648661 4.6324565 0.15856949 4.63112293 2 P 0 ;0,1,2=18,3=90.000000
L 0.15856949 4.63112293 0.16148632 4.63058976 2 P 0 ;0,1,2=18,3=90.000000
L 0.16148632 4.63058976 0.16440315 4.63139006 2 P 0 ;0,1,2=18,3=90.000000
L 0.16440315 4.63139006 0.16648681 4.6332563 2 P 0 ;0,1,2=18,3=90.000000
L 0.16648681 4.6332563 0.16731998 4.63538967 2 P 0 ;0,1,2=18,3=90.000000
L 0.16731998 4.63538967 0.16648681 4.63752303 2 P 0 ;0,1,2=18,3=90.000000
L 0.16648681 4.63752303 0.16440315 4.63938976 2 P 0 ;0,1,2=18,3=90.000000
L 0.16440315 4.63938976 0.16148632 4.64019006 2 P 0 ;0,1,2=18,3=90.000000
L 0.16148632 4.64019006 0.15856949 4.6396564 2 P 0 ;0,1,2=18,3=90.000000
L 0.15856949 4.6396564 0.15648661 4.63832333 2 P 0 ;0,1,2=18,3=90.000000
L 0.15648661 4.63832333 0.15565344 4.63672323 2 P 0 ;0,1,2=18,3=90.000000
L 0.15565344 4.63672323 0.15565344 4.63405659 2 P 0 ;0,1,2=18,3=90.000000
L 0.15565344 4.63405659 0.15440295 4.63165659 2 P 0 ;0,1,2=18,3=90.000000
L 0.15440295 4.63165659 0.15190276 4.6300565 2 P 0 ;0,1,2=18,3=90.000000
L 0.15190276 4.6300565 0.14898671 4.62952323 2 P 0 ;0,1,2=18,3=90.000000
L 0.14898671 4.62952323 0.14606909 4.6300565 2 P 0 ;0,1,2=18,3=90.000000
L 0.14606909 4.6300565 0.14398622 4.63139006 2 P 0 ;0,1,2=18,3=90.000000
L 0.14398622 4.63139006 0.14273652 4.63352343 2 P 0 ;0,1,2=18,3=90.000000
L 0.14273652 4.63352343 0.14231998 4.63538967 2 P 0 ;0,1,2=18,3=90.000000
L 0.14231998 4.65938967 0.16731998 4.65938967 2 P 0 ;0,1,2=18,3=90.000000
L 0.16731998 4.65938967 0.16232028 4.65618986 2 P 0 ;0,1,2=18,3=90.000000
L 0.14231998 4.65618986 0.14231998 4.66258947 2 P 0 ;0,1,2=18,3=90.000000
L 0.29451348 4.61352303 0.29576329 4.61458996 2 P 0 ;0,1,2=19,3=90.000000
L 0.29576329 4.61458996 0.29784616 4.61538976 2 P 0 ;0,1,2=19,3=90.000000
L 0.29784616 4.61538976 0.30076368 4.61592352 2 P 0 ;0,1,2=19,3=90.000000
L 0.30076368 4.61592352 0.30326319 4.61538976 2 P 0 ;0,1,2=19,3=90.000000
L 0.30326319 4.61538976 0.30492943 4.61432333 2 P 0 ;0,1,2=19,3=90.000000
L 0.30492943 4.61432333 0.30618002 4.61245659 2 P 0 ;0,1,2=19,3=90.000000
L 0.30618002 4.61245659 0.30618002 4.60525669 2 P 0 ;0,1,2=19,3=90.000000
L 0.30618002 4.60525669 0.28118002 4.60525669 2 P 0 ;0,1,2=19,3=90.000000
L 0.28118002 4.60525669 0.28118002 4.61405669 2 P 0 ;0,1,2=19,3=90.000000
L 0.28118002 4.61405669 0.28284626 4.61592352 2 P 0 ;0,1,2=19,3=90.000000
L 0.28284626 4.61592352 0.28534656 4.61698996 2 P 0 ;0,1,2=19,3=90.000000
L 0.28534656 4.61698996 0.28826329 4.61752313 2 P 0 ;0,1,2=19,3=90.000000
L 0.28826329 4.61752313 0.29117933 4.61698996 2 P 0 ;0,1,2=19,3=90.000000
L 0.29117933 4.61698996 0.29367963 4.61538976 2 P 0 ;0,1,2=19,3=90.000000
L 0.29367963 4.61538976 0.29451348 4.61352303 2 P 0 ;0,1,2=19,3=90.000000
L 0.29451348 4.61352303 0.29451348 4.60525669 2 P 0 ;0,1,2=19,3=90.000000
L 0.28118002 4.63538967 0.28159656 4.6372564 2 P 0 ;0,1,2=19,3=90.000000
L 0.28159656 4.6372564 0.28284626 4.63938976 2 P 0 ;0,1,2=19,3=90.000000
L 0.28284626 4.63938976 0.28492913 4.64072333 2 P 0 ;0,1,2=19,3=90.000000
L 0.28492913 4.64072333 0.28784675 4.64125659 2 P 0 ;0,1,2=19,3=90.000000
L 0.28784675 4.64125659 0.2907628 4.64072333 2 P 0 ;0,1,2=19,3=90.000000
L 0.2907628 4.64072333 0.29326299 4.63912323 2 P 0 ;0,1,2=19,3=90.000000
L 0.29326299 4.63912323 0.29451348 4.63672323 2 P 0 ;0,1,2=19,3=90.000000
L 0.29451348 4.63672323 0.29451348 4.63405659 2 P 0 ;0,1,2=19,3=90.000000
L 0.29451348 4.63405659 0.29534665 4.6324565 2 P 0 ;0,1,2=19,3=90.000000
L 0.29534665 4.6324565 0.29742953 4.63112293 2 P 0 ;0,1,2=19,3=90.000000
L 0.29742953 4.63112293 0.30034636 4.63058976 2 P 0 ;0,1,2=19,3=90.000000
L 0.30034636 4.63058976 0.30326319 4.63139006 2 P 0 ;0,1,2=19,3=90.000000
L 0.30326319 4.63139006 0.30534685 4.6332563 2 P 0 ;0,1,2=19,3=90.000000
L 0.30534685 4.6332563 0.30618002 4.63538967 2 P 0 ;0,1,2=19,3=90.000000
L 0.30618002 4.63538967 0.30534685 4.63752303 2 P 0 ;0,1,2=19,3=90.000000
L 0.30534685 4.63752303 0.30326319 4.63938976 2 P 0 ;0,1,2=19,3=90.000000
L 0.30326319 4.63938976 0.30034636 4.64019006 2 P 0 ;0,1,2=19,3=90.000000
L 0.30034636 4.64019006 0.29742953 4.6396564 2 P 0 ;0,1,2=19,3=90.000000
L 0.29742953 4.6396564 0.29534665 4.63832333 2 P 0 ;0,1,2=19,3=90.000000
L 0.29534665 4.63832333 0.29451348 4.63672323 2 P 0 ;0,1,2=19,3=90.000000
L 0.29451348 4.63672323 0.29451348 4.63405659 2 P 0 ;0,1,2=19,3=90.000000
L 0.29451348 4.63405659 0.29326299 4.63165659 2 P 0 ;0,1,2=19,3=90.000000
L 0.29326299 4.63165659 0.2907628 4.6300565 2 P 0 ;0,1,2=19,3=90.000000
L 0.2907628 4.6300565 0.28784675 4.62952323 2 P 0 ;0,1,2=19,3=90.000000
L 0.28784675 4.62952323 0.28492913 4.6300565 2 P 0 ;0,1,2=19,3=90.000000
L 0.28492913 4.6300565 0.28284626 4.63139006 2 P 0 ;0,1,2=19,3=90.000000
L 0.28284626 4.63139006 0.28159656 4.63352343 2 P 0 ;0,1,2=19,3=90.000000
L 0.28159656 4.63352343 0.28118002 4.63538967 2 P 0 ;0,1,2=19,3=90.000000
L 0.28118002 4.65938967 0.30618002 4.65938967 2 P 0 ;0,1,2=19,3=90.000000
L 0.30618002 4.65938967 0.30118032 4.65618986 2 P 0 ;0,1,2=19,3=90.000000
L 0.28118002 4.65618986 0.28118002 4.66258947 2 P 0 ;0,1,2=19,3=90.000000
A 12.60541004 1.93488002 12.63289892 1.89176289 12.63778996 1.92520226 3 P 0 N
A 12.63289892 1.89176289 12.67158002 1.9252 12.6377874 1.9252 3 P 0 N
A 12.84873996 4.64173996 12.84873996 4.64173996 12.81495 4.64173996 3 P 0 N
A 12.77 4.60236998 12.77 4.60236998 12.73621004 4.60236998 3 P 0 N
A 12.67156998 4.60236998 12.67156998 4.60236998 12.63778996 4.60236998 3 P 0 N
A 12.59283002 4.64173996 12.59283002 4.64173996 12.55905 4.64173996 3 P 0 N
A 12.84873996 1.72835 12.84873996 1.72835 12.81495 1.72835 3 P 0 N
A 12.84873996 1.88583002 12.84873996 1.88583002 12.81495 1.88583002 3 P 0 N
A 12.77 1.9252 12.77 1.9252 12.73621004 1.9252 3 P 0 N
A 12.67158002 1.9252 12.65891555 1.95157539 12.63778996 1.92520344 3 P 0 N
A 12.65891555 1.95157539 12.63041004 1.95818002 12.63778661 1.9252 3 P 0 N
A 12.59283996 1.88583002 12.59283996 1.88583002 12.55905 1.88583002 3 P 0 N
A 12.59283996 1.72835 12.59283996 1.72835 12.55905 1.72835 3 P 0 N
A 12.84873996 1.41338996 12.84873996 1.41338996 12.81495 1.41338996 3 P 0 N
L 12.70243002 1.34023002 12.70243002 1.40781004 3 P 0 
L 12.70243002 1.40781004 12.77 1.40781004 3 P 0 
L 12.77 1.40781004 12.77 1.34023002 3 P 0 
L 12.77 1.34023002 12.70243002 1.34023002 3 P 0 
L 12.604 1.34023002 12.604 1.40781004 3 P 0 
L 12.604 1.40781004 12.67156998 1.40781004 3 P 0 
L 12.67156998 1.40781004 12.67156998 1.34023002 3 P 0 
L 12.67156998 1.34023002 12.604 1.34023002 3 P 0 
A 12.59283996 1.41338996 12.59283996 1.41338996 12.55905 1.41338996 3 P 0 N
A 12.67158002 1.76771998 12.67158002 1.76771998 12.63778996 1.76771998 3 P 0 N
A 12.77 1.76771998 12.77 1.76771998 12.73621004 1.76771998 3 P 0 N
L 12.54283002 4.69740295 12.56783002 4.70406969 2 P 0 ;0,1,2=4,3=90.000000
L 12.56783002 4.70406969 12.54283002 4.71073691 2 P 0 ;0,1,2=4,3=90.000000
L 12.55157963 4.70833642 12.55157963 4.69980295 2 P 0 ;0,1,2=4,3=90.000000
L 12.54283002 4.72806969 12.54324656 4.72993642 2 P 0 ;0,1,2=4,3=90.000000
L 12.54324656 4.72993642 12.54449626 4.73206978 2 P 0 ;0,1,2=4,3=90.000000
L 12.54449626 4.73206978 12.54657913 4.73340335 2 P 0 ;0,1,2=4,3=90.000000
L 12.54657913 4.73340335 12.54949675 4.73393661 2 P 0 ;0,1,2=4,3=90.000000
L 12.54949675 4.73393661 12.5524128 4.73340335 2 P 0 ;0,1,2=4,3=90.000000
L 12.5524128 4.73340335 12.55491299 4.73180325 2 P 0 ;0,1,2=4,3=90.000000
L 12.55491299 4.73180325 12.55616348 4.72940325 2 P 0 ;0,1,2=4,3=90.000000
L 12.55616348 4.72940325 12.55616348 4.72673661 2 P 0 ;0,1,2=4,3=90.000000
L 12.55616348 4.72673661 12.55699665 4.72513652 2 P 0 ;0,1,2=4,3=90.000000
L 12.55699665 4.72513652 12.55907953 4.72380295 2 P 0 ;0,1,2=4,3=90.000000
L 12.55907953 4.72380295 12.56199636 4.72326978 2 P 0 ;0,1,2=4,3=90.000000
L 12.56199636 4.72326978 12.56491319 4.72407008 2 P 0 ;0,1,2=4,3=90.000000
L 12.56491319 4.72407008 12.56699685 4.72593632 2 P 0 ;0,1,2=4,3=90.000000
L 12.56699685 4.72593632 12.56783002 4.72806969 2 P 0 ;0,1,2=4,3=90.000000
L 12.56783002 4.72806969 12.56699685 4.73020305 2 P 0 ;0,1,2=4,3=90.000000
L 12.56699685 4.73020305 12.56491319 4.73206978 2 P 0 ;0,1,2=4,3=90.000000
L 12.56491319 4.73206978 12.56199636 4.73287008 2 P 0 ;0,1,2=4,3=90.000000
L 12.56199636 4.73287008 12.55907953 4.73233642 2 P 0 ;0,1,2=4,3=90.000000
L 12.55907953 4.73233642 12.55699665 4.73100335 2 P 0 ;0,1,2=4,3=90.000000
L 12.55699665 4.73100335 12.55616348 4.72940325 2 P 0 ;0,1,2=4,3=90.000000
L 12.55616348 4.72940325 12.55616348 4.72673661 2 P 0 ;0,1,2=4,3=90.000000
L 12.55616348 4.72673661 12.55491299 4.72433661 2 P 0 ;0,1,2=4,3=90.000000
L 12.55491299 4.72433661 12.5524128 4.72273652 2 P 0 ;0,1,2=4,3=90.000000
L 12.5524128 4.72273652 12.54949675 4.72220325 2 P 0 ;0,1,2=4,3=90.000000
L 12.54949675 4.72220325 12.54657913 4.72273652 2 P 0 ;0,1,2=4,3=90.000000
L 12.54657913 4.72273652 12.54449626 4.72407008 2 P 0 ;0,1,2=4,3=90.000000
L 12.54449626 4.72407008 12.54324656 4.72620344 2 P 0 ;0,1,2=4,3=90.000000
L 12.54324656 4.72620344 12.54283002 4.72806969 2 P 0 ;0,1,2=4,3=90.000000
L 12.56366339 4.74700315 12.56616289 4.74860325 2 P 0 ;0,1,2=4,3=90.000000
L 12.56616289 4.74860325 12.56741339 4.75046998 2 P 0 ;0,1,2=4,3=90.000000
L 12.56741339 4.75046998 12.56783002 4.75260335 2 P 0 ;0,1,2=4,3=90.000000
L 12.56783002 4.75260335 12.56699685 4.75526998 2 P 0 ;0,1,2=4,3=90.000000
L 12.56699685 4.75526998 12.56491319 4.75713671 2 P 0 ;0,1,2=4,3=90.000000
L 12.56491319 4.75713671 12.56241368 4.75766998 2 P 0 ;0,1,2=4,3=90.000000
L 12.56241368 4.75766998 12.5599127 4.75740335 2 P 0 ;0,1,2=4,3=90.000000
L 12.5599127 4.75740335 12.55782982 4.75633642 2 P 0 ;0,1,2=4,3=90.000000
L 12.55782982 4.75633642 12.55366329 4.75100325 2 P 0 ;0,1,2=4,3=90.000000
L 12.55366329 4.75100325 12.55074646 4.74860325 2 P 0 ;0,1,2=4,3=90.000000
L 12.55074646 4.74860325 12.54657913 4.74700315 2 P 0 ;0,1,2=4,3=90.000000
L 12.54657913 4.74700315 12.54283002 4.74646988 2 P 0 ;0,1,2=4,3=90.000000
L 12.54283002 4.74646988 12.54283002 4.75766998 2 P 0 ;0,1,2=4,3=90.000000
L 12.54783002 1.32444301 12.57283002 1.33110974 2 P 0 ;0,1,2=5,3=90.000000
L 12.57283002 1.33110974 12.54783002 1.33777697 2 P 0 ;0,1,2=5,3=90.000000
L 12.55657963 1.33537648 12.55657963 1.32684301 2 P 0 ;0,1,2=5,3=90.000000
L 12.56866339 1.35004321 12.57116289 1.35164331 2 P 0 ;0,1,2=5,3=90.000000
L 12.57116289 1.35164331 12.57241339 1.35351004 2 P 0 ;0,1,2=5,3=90.000000
L 12.57241339 1.35351004 12.57283002 1.35564341 2 P 0 ;0,1,2=5,3=90.000000
L 12.57283002 1.35564341 12.57199685 1.35831004 2 P 0 ;0,1,2=5,3=90.000000
L 12.57199685 1.35831004 12.56991319 1.36017677 2 P 0 ;0,1,2=5,3=90.000000
L 12.56991319 1.36017677 12.56741368 1.36071004 2 P 0 ;0,1,2=5,3=90.000000
L 12.56741368 1.36071004 12.5649127 1.36044341 2 P 0 ;0,1,2=5,3=90.000000
L 12.5649127 1.36044341 12.56282982 1.35937648 2 P 0 ;0,1,2=5,3=90.000000
L 12.56282982 1.35937648 12.55866329 1.35404331 2 P 0 ;0,1,2=5,3=90.000000
L 12.55866329 1.35404331 12.55574646 1.35164331 2 P 0 ;0,1,2=5,3=90.000000
L 12.55574646 1.35164331 12.55157913 1.35004321 2 P 0 ;0,1,2=5,3=90.000000
L 12.55157913 1.35004321 12.54783002 1.34950994 2 P 0 ;0,1,2=5,3=90.000000
L 12.54783002 1.34950994 12.54783002 1.36071004 2 P 0 ;0,1,2=5,3=90.000000
L 12.79450344 1.78175305 12.79575325 1.78281998 2 P 0 ;0,1,2=6,3=90.000000
L 12.79575325 1.78281998 12.79783612 1.78361978 2 P 0 ;0,1,2=6,3=90.000000
L 12.79783612 1.78361978 12.80075364 1.78415354 2 P 0 ;0,1,2=6,3=90.000000
L 12.80075364 1.78415354 12.80325315 1.78361978 2 P 0 ;0,1,2=6,3=90.000000
L 12.80325315 1.78361978 12.80491939 1.78255335 2 P 0 ;0,1,2=6,3=90.000000
L 12.80491939 1.78255335 12.80616998 1.78068661 2 P 0 ;0,1,2=6,3=90.000000
L 12.80616998 1.78068661 12.80616998 1.77348671 2 P 0 ;0,1,2=6,3=90.000000
L 12.80616998 1.77348671 12.78116998 1.77348671 2 P 0 ;0,1,2=6,3=90.000000
L 12.78116998 1.77348671 12.78116998 1.78228671 2 P 0 ;0,1,2=6,3=90.000000
L 12.78116998 1.78228671 12.78283622 1.78415354 2 P 0 ;0,1,2=6,3=90.000000
L 12.78283622 1.78415354 12.78533652 1.78521998 2 P 0 ;0,1,2=6,3=90.000000
L 12.78533652 1.78521998 12.78825325 1.78575315 2 P 0 ;0,1,2=6,3=90.000000
L 12.78825325 1.78575315 12.79116929 1.78521998 2 P 0 ;0,1,2=6,3=90.000000
L 12.79116929 1.78521998 12.79366959 1.78361978 2 P 0 ;0,1,2=6,3=90.000000
L 12.79366959 1.78361978 12.79450344 1.78175305 2 P 0 ;0,1,2=6,3=90.000000
L 12.79450344 1.78175305 12.79450344 1.77348671 2 P 0 ;0,1,2=6,3=90.000000
L 12.78116998 1.80361969 12.80616998 1.80361969 2 P 0 ;0,1,2=6,3=90.000000
L 12.80616998 1.80361969 12.80117028 1.80041988 2 P 0 ;0,1,2=6,3=90.000000
L 12.78116998 1.80041988 12.78116998 1.80681949 2 P 0 ;0,1,2=6,3=90.000000
L 12.78116998 1.82761969 12.80616998 1.82761969 2 P 0 ;0,1,2=6,3=90.000000
L 12.80616998 1.82761969 12.80117028 1.82441988 2 P 0 ;0,1,2=6,3=90.000000
L 12.78116998 1.82441988 12.78116998 1.83081949 2 P 0 ;0,1,2=6,3=90.000000
L 12.62263002 1.28507293 12.64763002 1.29173967 2 P 0 ;0,1,2=7,3=90.000000
L 12.64763002 1.29173967 12.62263002 1.29840689 2 P 0 ;0,1,2=7,3=90.000000
L 12.63137963 1.2960064 12.63137963 1.28747293 2 P 0 ;0,1,2=7,3=90.000000
L 12.62263002 1.31573967 12.64763002 1.31573967 2 P 0 ;0,1,2=7,3=90.000000
L 12.64763002 1.31573967 12.64263032 1.31253986 2 P 0 ;0,1,2=7,3=90.000000
L 12.62263002 1.31253986 12.62263002 1.31893947 2 P 0 ;0,1,2=7,3=90.000000
L 12.81813346 4.70620305 12.81938327 4.70726998 2 P 0 ;0,1,2=8,3=90.000000
L 12.81938327 4.70726998 12.82146614 4.70806978 2 P 0 ;0,1,2=8,3=90.000000
L 12.82146614 4.70806978 12.82438366 4.70860354 2 P 0 ;0,1,2=8,3=90.000000
L 12.82438366 4.70860354 12.82688317 4.70806978 2 P 0 ;0,1,2=8,3=90.000000
L 12.82688317 4.70806978 12.82854941 4.70700335 2 P 0 ;0,1,2=8,3=90.000000
L 12.82854941 4.70700335 12.8298 4.70513661 2 P 0 ;0,1,2=8,3=90.000000
L 12.8298 4.70513661 12.8298 4.69793671 2 P 0 ;0,1,2=8,3=90.000000
L 12.8298 4.69793671 12.8048 4.69793671 2 P 0 ;0,1,2=8,3=90.000000
L 12.8048 4.69793671 12.8048 4.70673671 2 P 0 ;0,1,2=8,3=90.000000
L 12.8048 4.70673671 12.80646624 4.70860354 2 P 0 ;0,1,2=8,3=90.000000
L 12.80646624 4.70860354 12.80896654 4.70966998 2 P 0 ;0,1,2=8,3=90.000000
L 12.80896654 4.70966998 12.81188327 4.71020315 2 P 0 ;0,1,2=8,3=90.000000
L 12.81188327 4.71020315 12.81479931 4.70966998 2 P 0 ;0,1,2=8,3=90.000000
L 12.81479931 4.70966998 12.81729961 4.70806978 2 P 0 ;0,1,2=8,3=90.000000
L 12.81729961 4.70806978 12.81813346 4.70620305 2 P 0 ;0,1,2=8,3=90.000000
L 12.81813346 4.70620305 12.81813346 4.69793671 2 P 0 ;0,1,2=8,3=90.000000
L 12.8048 4.72806969 12.80521654 4.72993642 2 P 0 ;0,1,2=8,3=90.000000
L 12.80521654 4.72993642 12.80646624 4.73206978 2 P 0 ;0,1,2=8,3=90.000000
L 12.80646624 4.73206978 12.80854911 4.73340335 2 P 0 ;0,1,2=8,3=90.000000
L 12.80854911 4.73340335 12.81146673 4.73393661 2 P 0 ;0,1,2=8,3=90.000000
L 12.81146673 4.73393661 12.81438278 4.73340335 2 P 0 ;0,1,2=8,3=90.000000
L 12.81438278 4.73340335 12.81688297 4.73180325 2 P 0 ;0,1,2=8,3=90.000000
L 12.81688297 4.73180325 12.81813346 4.72940325 2 P 0 ;0,1,2=8,3=90.000000
L 12.81813346 4.72940325 12.81813346 4.72673661 2 P 0 ;0,1,2=8,3=90.000000
L 12.81813346 4.72673661 12.81896663 4.72513652 2 P 0 ;0,1,2=8,3=90.000000
L 12.81896663 4.72513652 12.82104951 4.72380295 2 P 0 ;0,1,2=8,3=90.000000
L 12.82104951 4.72380295 12.82396634 4.72326978 2 P 0 ;0,1,2=8,3=90.000000
L 12.82396634 4.72326978 12.82688317 4.72407008 2 P 0 ;0,1,2=8,3=90.000000
L 12.82688317 4.72407008 12.82896683 4.72593632 2 P 0 ;0,1,2=8,3=90.000000
L 12.82896683 4.72593632 12.8298 4.72806969 2 P 0 ;0,1,2=8,3=90.000000
L 12.8298 4.72806969 12.82896683 4.73020305 2 P 0 ;0,1,2=8,3=90.000000
L 12.82896683 4.73020305 12.82688317 4.73206978 2 P 0 ;0,1,2=8,3=90.000000
L 12.82688317 4.73206978 12.82396634 4.73287008 2 P 0 ;0,1,2=8,3=90.000000
L 12.82396634 4.73287008 12.82104951 4.73233642 2 P 0 ;0,1,2=8,3=90.000000
L 12.82104951 4.73233642 12.81896663 4.73100335 2 P 0 ;0,1,2=8,3=90.000000
L 12.81896663 4.73100335 12.81813346 4.72940325 2 P 0 ;0,1,2=8,3=90.000000
L 12.81813346 4.72940325 12.81813346 4.72673661 2 P 0 ;0,1,2=8,3=90.000000
L 12.81813346 4.72673661 12.81688297 4.72433661 2 P 0 ;0,1,2=8,3=90.000000
L 12.81688297 4.72433661 12.81438278 4.72273652 2 P 0 ;0,1,2=8,3=90.000000
L 12.81438278 4.72273652 12.81146673 4.72220325 2 P 0 ;0,1,2=8,3=90.000000
L 12.81146673 4.72220325 12.80854911 4.72273652 2 P 0 ;0,1,2=8,3=90.000000
L 12.80854911 4.72273652 12.80646624 4.72407008 2 P 0 ;0,1,2=8,3=90.000000
L 12.80646624 4.72407008 12.80521654 4.72620344 2 P 0 ;0,1,2=8,3=90.000000
L 12.80521654 4.72620344 12.8048 4.72806969 2 P 0 ;0,1,2=8,3=90.000000
L 12.82563337 4.74700315 12.82813287 4.74860325 2 P 0 ;0,1,2=8,3=90.000000
L 12.82813287 4.74860325 12.82938337 4.75046998 2 P 0 ;0,1,2=8,3=90.000000
L 12.82938337 4.75046998 12.8298 4.75260335 2 P 0 ;0,1,2=8,3=90.000000
L 12.8298 4.75260335 12.82896683 4.75526998 2 P 0 ;0,1,2=8,3=90.000000
L 12.82896683 4.75526998 12.82688317 4.75713671 2 P 0 ;0,1,2=8,3=90.000000
L 12.82688317 4.75713671 12.82438366 4.75766998 2 P 0 ;0,1,2=8,3=90.000000
L 12.82438366 4.75766998 12.82188268 4.75740335 2 P 0 ;0,1,2=8,3=90.000000
L 12.82188268 4.75740335 12.8197998 4.75633642 2 P 0 ;0,1,2=8,3=90.000000
L 12.8197998 4.75633642 12.81563327 4.75100325 2 P 0 ;0,1,2=8,3=90.000000
L 12.81563327 4.75100325 12.81271644 4.74860325 2 P 0 ;0,1,2=8,3=90.000000
L 12.81271644 4.74860325 12.80854911 4.74700315 2 P 0 ;0,1,2=8,3=90.000000
L 12.80854911 4.74700315 12.8048 4.74646988 2 P 0 ;0,1,2=8,3=90.000000
L 12.8048 4.74646988 12.8048 4.75766998 2 P 0 ;0,1,2=8,3=90.000000
L 12.81313346 1.33324311 12.81438327 1.33431004 2 P 0 ;0,1,2=9,3=90.000000
L 12.81438327 1.33431004 12.81646614 1.33510984 2 P 0 ;0,1,2=9,3=90.000000
L 12.81646614 1.33510984 12.81938366 1.3356436 2 P 0 ;0,1,2=9,3=90.000000
L 12.81938366 1.3356436 12.82188317 1.33510984 2 P 0 ;0,1,2=9,3=90.000000
L 12.82188317 1.33510984 12.82354941 1.33404341 2 P 0 ;0,1,2=9,3=90.000000
L 12.82354941 1.33404341 12.8248 1.33217667 2 P 0 ;0,1,2=9,3=90.000000
L 12.8248 1.33217667 12.8248 1.32497677 2 P 0 ;0,1,2=9,3=90.000000
L 12.8248 1.32497677 12.7998 1.32497677 2 P 0 ;0,1,2=9,3=90.000000
L 12.7998 1.32497677 12.7998 1.33377677 2 P 0 ;0,1,2=9,3=90.000000
L 12.7998 1.33377677 12.80146624 1.3356436 2 P 0 ;0,1,2=9,3=90.000000
L 12.80146624 1.3356436 12.80396654 1.33671004 2 P 0 ;0,1,2=9,3=90.000000
L 12.80396654 1.33671004 12.80688327 1.33724321 2 P 0 ;0,1,2=9,3=90.000000
L 12.80688327 1.33724321 12.80979931 1.33671004 2 P 0 ;0,1,2=9,3=90.000000
L 12.80979931 1.33671004 12.81229961 1.33510984 2 P 0 ;0,1,2=9,3=90.000000
L 12.81229961 1.33510984 12.81313346 1.33324311 2 P 0 ;0,1,2=9,3=90.000000
L 12.81313346 1.33324311 12.81313346 1.32497677 2 P 0 ;0,1,2=9,3=90.000000
L 12.82063337 1.35004321 12.82313287 1.35164331 2 P 0 ;0,1,2=9,3=90.000000
L 12.82313287 1.35164331 12.82438337 1.35351004 2 P 0 ;0,1,2=9,3=90.000000
L 12.82438337 1.35351004 12.8248 1.35564341 2 P 0 ;0,1,2=9,3=90.000000
L 12.8248 1.35564341 12.82396683 1.35831004 2 P 0 ;0,1,2=9,3=90.000000
L 12.82396683 1.35831004 12.82188317 1.36017677 2 P 0 ;0,1,2=9,3=90.000000
L 12.82188317 1.36017677 12.81938366 1.36071004 2 P 0 ;0,1,2=9,3=90.000000
L 12.81938366 1.36071004 12.81688268 1.36044341 2 P 0 ;0,1,2=9,3=90.000000
L 12.81688268 1.36044341 12.8147998 1.35937648 2 P 0 ;0,1,2=9,3=90.000000
L 12.8147998 1.35937648 12.81063327 1.35404331 2 P 0 ;0,1,2=9,3=90.000000
L 12.81063327 1.35404331 12.80771644 1.35164331 2 P 0 ;0,1,2=9,3=90.000000
L 12.80771644 1.35164331 12.80354911 1.35004321 2 P 0 ;0,1,2=9,3=90.000000
L 12.80354911 1.35004321 12.7998 1.34950994 2 P 0 ;0,1,2=9,3=90.000000
L 12.7998 1.34950994 12.7998 1.36071004 2 P 0 ;0,1,2=9,3=90.000000
L 12.73832343 1.29387303 12.73957323 1.29493996 2 P 0 ;0,1,2=10,3=90.000000
L 12.73957323 1.29493996 12.7416561 1.29573976 2 P 0 ;0,1,2=10,3=90.000000
L 12.7416561 1.29573976 12.74457362 1.29627352 2 P 0 ;0,1,2=10,3=90.000000
L 12.74457362 1.29627352 12.74707313 1.29573976 2 P 0 ;0,1,2=10,3=90.000000
L 12.74707313 1.29573976 12.74873937 1.29467333 2 P 0 ;0,1,2=10,3=90.000000
L 12.74873937 1.29467333 12.74998996 1.29280659 2 P 0 ;0,1,2=10,3=90.000000
L 12.74998996 1.29280659 12.74998996 1.28560669 2 P 0 ;0,1,2=10,3=90.000000
L 12.74998996 1.28560669 12.72498996 1.28560669 2 P 0 ;0,1,2=10,3=90.000000
L 12.72498996 1.28560669 12.72498996 1.29440669 2 P 0 ;0,1,2=10,3=90.000000
L 12.72498996 1.29440669 12.7266562 1.29627352 2 P 0 ;0,1,2=10,3=90.000000
L 12.7266562 1.29627352 12.7291565 1.29733996 2 P 0 ;0,1,2=10,3=90.000000
L 12.7291565 1.29733996 12.73207323 1.29787313 2 P 0 ;0,1,2=10,3=90.000000
L 12.73207323 1.29787313 12.73498927 1.29733996 2 P 0 ;0,1,2=10,3=90.000000
L 12.73498927 1.29733996 12.73748957 1.29573976 2 P 0 ;0,1,2=10,3=90.000000
L 12.73748957 1.29573976 12.73832343 1.29387303 2 P 0 ;0,1,2=10,3=90.000000
L 12.73832343 1.29387303 12.73832343 1.28560669 2 P 0 ;0,1,2=10,3=90.000000
L 12.72498996 1.31573967 12.74998996 1.31573967 2 P 0 ;0,1,2=10,3=90.000000
L 12.74998996 1.31573967 12.74499026 1.31253986 2 P 0 ;0,1,2=10,3=90.000000
L 12.72498996 1.31253986 12.72498996 1.31893947 2 P 0 ;0,1,2=10,3=90.000000
L 12.86612343 1.86049311 12.86737323 1.86156004 2 P 0 ;0,1,2=11,3=90.000000
L 12.86737323 1.86156004 12.8694561 1.86235984 2 P 0 ;0,1,2=11,3=90.000000
L 12.8694561 1.86235984 12.87237362 1.8628936 2 P 0 ;0,1,2=11,3=90.000000
L 12.87237362 1.8628936 12.87487313 1.86235984 2 P 0 ;0,1,2=11,3=90.000000
L 12.87487313 1.86235984 12.87653937 1.86129341 2 P 0 ;0,1,2=11,3=90.000000
L 12.87653937 1.86129341 12.87778996 1.85942667 2 P 0 ;0,1,2=11,3=90.000000
L 12.87778996 1.85942667 12.87778996 1.85222677 2 P 0 ;0,1,2=11,3=90.000000
L 12.87778996 1.85222677 12.85278996 1.85222677 2 P 0 ;0,1,2=11,3=90.000000
L 12.85278996 1.85222677 12.85278996 1.86102677 2 P 0 ;0,1,2=11,3=90.000000
L 12.85278996 1.86102677 12.8544562 1.8628936 2 P 0 ;0,1,2=11,3=90.000000
L 12.8544562 1.8628936 12.8569565 1.86396004 2 P 0 ;0,1,2=11,3=90.000000
L 12.8569565 1.86396004 12.85987323 1.86449321 2 P 0 ;0,1,2=11,3=90.000000
L 12.85987323 1.86449321 12.86278927 1.86396004 2 P 0 ;0,1,2=11,3=90.000000
L 12.86278927 1.86396004 12.86528957 1.86235984 2 P 0 ;0,1,2=11,3=90.000000
L 12.86528957 1.86235984 12.86612343 1.86049311 2 P 0 ;0,1,2=11,3=90.000000
L 12.86612343 1.86049311 12.86612343 1.85222677 2 P 0 ;0,1,2=11,3=90.000000
L 12.85278996 1.88235974 12.87778996 1.88235974 2 P 0 ;0,1,2=11,3=90.000000
L 12.87778996 1.88235974 12.87279026 1.87915994 2 P 0 ;0,1,2=11,3=90.000000
L 12.85278996 1.87915994 12.85278996 1.88555955 2 P 0 ;0,1,2=11,3=90.000000
L 12.87362333 1.90129321 12.87612283 1.90289331 2 P 0 ;0,1,2=11,3=90.000000
L 12.87612283 1.90289331 12.87737333 1.90476004 2 P 0 ;0,1,2=11,3=90.000000
L 12.87737333 1.90476004 12.87778996 1.90689341 2 P 0 ;0,1,2=11,3=90.000000
L 12.87778996 1.90689341 12.87695679 1.90956004 2 P 0 ;0,1,2=11,3=90.000000
L 12.87695679 1.90956004 12.87487313 1.91142677 2 P 0 ;0,1,2=11,3=90.000000
L 12.87487313 1.91142677 12.87237362 1.91196004 2 P 0 ;0,1,2=11,3=90.000000
L 12.87237362 1.91196004 12.86987264 1.91169341 2 P 0 ;0,1,2=11,3=90.000000
L 12.86987264 1.91169341 12.86778976 1.91062648 2 P 0 ;0,1,2=11,3=90.000000
L 12.86778976 1.91062648 12.86362323 1.90529331 2 P 0 ;0,1,2=11,3=90.000000
L 12.86362323 1.90529331 12.8607064 1.90289331 2 P 0 ;0,1,2=11,3=90.000000
L 12.8607064 1.90289331 12.85653907 1.90129321 2 P 0 ;0,1,2=11,3=90.000000
L 12.85653907 1.90129321 12.85278996 1.90075994 2 P 0 ;0,1,2=11,3=90.000000
L 12.85278996 1.90075994 12.85278996 1.91196004 2 P 0 ;0,1,2=11,3=90.000000
L 12.56751004 1.77401299 12.59251004 1.78067972 2 P 0 ;0,1,2=12,3=90.000000
L 12.59251004 1.78067972 12.56751004 1.78734695 2 P 0 ;0,1,2=12,3=90.000000
L 12.57625965 1.78494646 12.57625965 1.77641299 2 P 0 ;0,1,2=12,3=90.000000
L 12.56751004 1.80467972 12.59251004 1.80467972 2 P 0 ;0,1,2=12,3=90.000000
L 12.59251004 1.80467972 12.58751033 1.80147992 2 P 0 ;0,1,2=12,3=90.000000
L 12.56751004 1.80147992 12.56751004 1.80787953 2 P 0 ;0,1,2=12,3=90.000000
L 12.56751004 1.82867972 12.59251004 1.82867972 2 P 0 ;0,1,2=12,3=90.000000
L 12.59251004 1.82867972 12.58751033 1.82547992 2 P 0 ;0,1,2=12,3=90.000000
L 12.56751004 1.82547992 12.56751004 1.83187953 2 P 0 ;0,1,2=12,3=90.000000
L 12.48876998 1.85669301 12.51376998 1.86335974 2 P 0 ;0,1,2=13,3=90.000000
L 12.51376998 1.86335974 12.48876998 1.87002697 2 P 0 ;0,1,2=13,3=90.000000
L 12.49751959 1.86762648 12.49751959 1.85909301 2 P 0 ;0,1,2=13,3=90.000000
L 12.48876998 1.88735974 12.51376998 1.88735974 2 P 0 ;0,1,2=13,3=90.000000
L 12.51376998 1.88735974 12.50877028 1.88415994 2 P 0 ;0,1,2=13,3=90.000000
L 12.48876998 1.88415994 12.48876998 1.89055955 2 P 0 ;0,1,2=13,3=90.000000
L 12.50960335 1.90629321 12.51210285 1.90789331 2 P 0 ;0,1,2=13,3=90.000000
L 12.51210285 1.90789331 12.51335335 1.90976004 2 P 0 ;0,1,2=13,3=90.000000
L 12.51335335 1.90976004 12.51376998 1.91189341 2 P 0 ;0,1,2=13,3=90.000000
L 12.51376998 1.91189341 12.51293681 1.91456004 2 P 0 ;0,1,2=13,3=90.000000
L 12.51293681 1.91456004 12.51085315 1.91642677 2 P 0 ;0,1,2=13,3=90.000000
L 12.51085315 1.91642677 12.50835364 1.91696004 2 P 0 ;0,1,2=13,3=90.000000
L 12.50835364 1.91696004 12.50585266 1.91669341 2 P 0 ;0,1,2=13,3=90.000000
L 12.50585266 1.91669341 12.50376978 1.91562648 2 P 0 ;0,1,2=13,3=90.000000
L 12.50376978 1.91562648 12.49960325 1.91029331 2 P 0 ;0,1,2=13,3=90.000000
L 12.49960325 1.91029331 12.49668642 1.90789331 2 P 0 ;0,1,2=13,3=90.000000
L 12.49668642 1.90789331 12.49251909 1.90629321 2 P 0 ;0,1,2=13,3=90.000000
L 12.49251909 1.90629321 12.48876998 1.90575994 2 P 0 ;0,1,2=13,3=90.000000
L 12.48876998 1.90575994 12.48876998 1.91696004 2 P 0 ;0,1,2=13,3=90.000000
L 12.48876998 1.69921299 12.51376998 1.70587972 2 P 0 ;0,1,2=14,3=90.000000
L 12.51376998 1.70587972 12.48876998 1.71254695 2 P 0 ;0,1,2=14,3=90.000000
L 12.49751959 1.71014646 12.49751959 1.70161299 2 P 0 ;0,1,2=14,3=90.000000
L 12.48876998 1.72987972 12.51376998 1.72987972 2 P 0 ;0,1,2=14,3=90.000000
L 12.51376998 1.72987972 12.50877028 1.72667992 2 P 0 ;0,1,2=14,3=90.000000
L 12.48876998 1.72667992 12.48876998 1.73307953 2 P 0 ;0,1,2=14,3=90.000000
L 12.51376998 1.75387972 12.51293681 1.75174636 2 P 0 ;0,1,2=14,3=90.000000
L 12.51293681 1.75174636 12.51085315 1.75014665 2 P 0 ;0,1,2=14,3=90.000000
L 12.51085315 1.75014665 12.50835364 1.74907982 2 P 0 ;0,1,2=14,3=90.000000
L 12.50835364 1.74907982 12.50501949 1.74827992 2 P 0 ;0,1,2=14,3=90.000000
L 12.50501949 1.74827992 12.50126959 1.74801329 2 P 0 ;0,1,2=14,3=90.000000
L 12.50126959 1.74801329 12.49751959 1.74827992 2 P 0 ;0,1,2=14,3=90.000000
L 12.49751959 1.74827992 12.49418622 1.74907982 2 P 0 ;0,1,2=14,3=90.000000
L 12.49418622 1.74907982 12.49168602 1.75014665 2 P 0 ;0,1,2=14,3=90.000000
L 12.49168602 1.75014665 12.48960305 1.75174636 2 P 0 ;0,1,2=14,3=90.000000
L 12.48960305 1.75174636 12.48876998 1.75387972 2 P 0 ;0,1,2=14,3=90.000000
L 12.48876998 1.75387972 12.48960305 1.75601309 2 P 0 ;0,1,2=14,3=90.000000
L 12.48960305 1.75601309 12.49168602 1.75761329 2 P 0 ;0,1,2=14,3=90.000000
L 12.49168602 1.75761329 12.49418622 1.75868012 2 P 0 ;0,1,2=14,3=90.000000
L 12.49418622 1.75868012 12.49751959 1.75948002 2 P 0 ;0,1,2=14,3=90.000000
L 12.49751959 1.75948002 12.50126959 1.75974665 2 P 0 ;0,1,2=14,3=90.000000
L 12.50126959 1.75974665 12.50501949 1.75948002 2 P 0 ;0,1,2=14,3=90.000000
L 12.50501949 1.75948002 12.50835364 1.75868012 2 P 0 ;0,1,2=14,3=90.000000
L 12.50835364 1.75868012 12.51085315 1.75761329 2 P 0 ;0,1,2=14,3=90.000000
L 12.51085315 1.75761329 12.51293681 1.75601309 2 P 0 ;0,1,2=14,3=90.000000
L 12.51293681 1.75601309 12.51376998 1.75387972 2 P 0 ;0,1,2=14,3=90.000000
L 12.60688002 1.82125295 12.63188002 1.82791969 2 P 0 ;0,1,2=15,3=90.000000
L 12.63188002 1.82791969 12.60688002 1.83458691 2 P 0 ;0,1,2=15,3=90.000000
L 12.61562963 1.83218642 12.61562963 1.82365295 2 P 0 ;0,1,2=15,3=90.000000
L 12.60688002 1.85191969 12.63188002 1.85191969 2 P 0 ;0,1,2=15,3=90.000000
L 12.63188002 1.85191969 12.62688032 1.84871988 2 P 0 ;0,1,2=15,3=90.000000
L 12.60688002 1.84871988 12.60688002 1.85511949 2 P 0 ;0,1,2=15,3=90.000000
L 12.61187963 1.87005325 12.60896289 1.87165295 2 P 0 ;0,1,2=15,3=90.000000
L 12.60896289 1.87165295 12.60729656 1.87378632 2 P 0 ;0,1,2=15,3=90.000000
L 12.60729656 1.87378632 12.60688002 1.87618681 2 P 0 ;0,1,2=15,3=90.000000
L 12.60688002 1.87618681 12.60729656 1.87832018 2 P 0 ;0,1,2=15,3=90.000000
L 12.60729656 1.87832018 12.60937943 1.88045354 2 P 0 ;0,1,2=15,3=90.000000
L 12.60937943 1.88045354 12.61187963 1.88178661 2 P 0 ;0,1,2=15,3=90.000000
L 12.61187963 1.88178661 12.61437992 1.88205315 2 P 0 ;0,1,2=15,3=90.000000
L 12.61437992 1.88205315 12.61729596 1.88151998 2 P 0 ;0,1,2=15,3=90.000000
L 12.61729596 1.88151998 12.61937963 1.87965325 2 P 0 ;0,1,2=15,3=90.000000
L 12.61937963 1.87965325 12.62021348 1.87778642 2 P 0 ;0,1,2=15,3=90.000000
L 12.62021348 1.87778642 12.62021348 1.87538652 2 P 0 ;0,1,2=15,3=90.000000
L 12.62021348 1.87778642 12.62146329 1.87938661 2 P 0 ;0,1,2=15,3=90.000000
L 12.62146329 1.87938661 12.62354616 1.88072008 2 P 0 ;0,1,2=15,3=90.000000
L 12.62354616 1.88072008 12.62604636 1.88125335 2 P 0 ;0,1,2=15,3=90.000000
L 12.62604636 1.88125335 12.62854656 1.88072008 2 P 0 ;0,1,2=15,3=90.000000
L 12.62854656 1.88072008 12.63062943 1.87938661 2 P 0 ;0,1,2=15,3=90.000000
L 12.63062943 1.87938661 12.63188002 1.87698661 2 P 0 ;0,1,2=15,3=90.000000
L 12.63188002 1.87698661 12.63146339 1.87458661 2 P 0 ;0,1,2=15,3=90.000000
L 12.63146339 1.87458661 12.62979636 1.87218661 2 P 0 ;0,1,2=15,3=90.000000
L 12.75907343 1.82899311 12.76032323 1.83006004 2 P 0 ;0,1,2=16,3=90.000000
L 12.76032323 1.83006004 12.7624061 1.83085984 2 P 0 ;0,1,2=16,3=90.000000
L 12.7624061 1.83085984 12.76532362 1.8313936 2 P 0 ;0,1,2=16,3=90.000000
L 12.76532362 1.8313936 12.76782313 1.83085984 2 P 0 ;0,1,2=16,3=90.000000
L 12.76782313 1.83085984 12.76948937 1.82979341 2 P 0 ;0,1,2=16,3=90.000000
L 12.76948937 1.82979341 12.77073996 1.82792667 2 P 0 ;0,1,2=16,3=90.000000
L 12.77073996 1.82792667 12.77073996 1.82072677 2 P 0 ;0,1,2=16,3=90.000000
L 12.77073996 1.82072677 12.74573996 1.82072677 2 P 0 ;0,1,2=16,3=90.000000
L 12.74573996 1.82072677 12.74573996 1.82952677 2 P 0 ;0,1,2=16,3=90.000000
L 12.74573996 1.82952677 12.7474062 1.8313936 2 P 0 ;0,1,2=16,3=90.000000
L 12.7474062 1.8313936 12.7499065 1.83246004 2 P 0 ;0,1,2=16,3=90.000000
L 12.7499065 1.83246004 12.75282323 1.83299321 2 P 0 ;0,1,2=16,3=90.000000
L 12.75282323 1.83299321 12.75573927 1.83246004 2 P 0 ;0,1,2=16,3=90.000000
L 12.75573927 1.83246004 12.75823957 1.83085984 2 P 0 ;0,1,2=16,3=90.000000
L 12.75823957 1.83085984 12.75907343 1.82899311 2 P 0 ;0,1,2=16,3=90.000000
L 12.75907343 1.82899311 12.75907343 1.82072677 2 P 0 ;0,1,2=16,3=90.000000
L 12.74573996 1.85085974 12.77073996 1.85085974 2 P 0 ;0,1,2=16,3=90.000000
L 12.77073996 1.85085974 12.76574026 1.84765994 2 P 0 ;0,1,2=16,3=90.000000
L 12.74573996 1.84765994 12.74573996 1.85405955 2 P 0 ;0,1,2=16,3=90.000000
L 12.75073957 1.86899331 12.74782283 1.87059301 2 P 0 ;0,1,2=16,3=90.000000
L 12.74782283 1.87059301 12.7461565 1.87272638 2 P 0 ;0,1,2=16,3=90.000000
L 12.7461565 1.87272638 12.74573996 1.87512687 2 P 0 ;0,1,2=16,3=90.000000
L 12.74573996 1.87512687 12.7461565 1.87726024 2 P 0 ;0,1,2=16,3=90.000000
L 12.7461565 1.87726024 12.74823937 1.8793936 2 P 0 ;0,1,2=16,3=90.000000
L 12.74823937 1.8793936 12.75073957 1.88072667 2 P 0 ;0,1,2=16,3=90.000000
L 12.75073957 1.88072667 12.75323986 1.88099321 2 P 0 ;0,1,2=16,3=90.000000
L 12.75323986 1.88099321 12.75615591 1.88046004 2 P 0 ;0,1,2=16,3=90.000000
L 12.75615591 1.88046004 12.75823957 1.87859331 2 P 0 ;0,1,2=16,3=90.000000
L 12.75823957 1.87859331 12.75907343 1.87672648 2 P 0 ;0,1,2=16,3=90.000000
L 12.75907343 1.87672648 12.75907343 1.87432657 2 P 0 ;0,1,2=16,3=90.000000
L 12.75907343 1.87672648 12.76032323 1.87832667 2 P 0 ;0,1,2=16,3=90.000000
L 12.76032323 1.87832667 12.7624061 1.87966014 2 P 0 ;0,1,2=16,3=90.000000
L 12.7624061 1.87966014 12.7649063 1.88019341 2 P 0 ;0,1,2=16,3=90.000000
L 12.7649063 1.88019341 12.7674065 1.87966014 2 P 0 ;0,1,2=16,3=90.000000
L 12.7674065 1.87966014 12.76948937 1.87832667 2 P 0 ;0,1,2=16,3=90.000000
L 12.76948937 1.87832667 12.77073996 1.87592667 2 P 0 ;0,1,2=16,3=90.000000
L 12.77073996 1.87592667 12.77032333 1.87352667 2 P 0 ;0,1,2=16,3=90.000000
L 12.77032333 1.87352667 12.7686563 1.87112667 2 P 0 ;0,1,2=16,3=90.000000
L 12.86612343 1.70301309 12.86737323 1.70408002 2 P 0 ;0,1,2=17,3=90.000000
L 12.86737323 1.70408002 12.8694561 1.70487982 2 P 0 ;0,1,2=17,3=90.000000
L 12.8694561 1.70487982 12.87237362 1.70541358 2 P 0 ;0,1,2=17,3=90.000000
L 12.87237362 1.70541358 12.87487313 1.70487982 2 P 0 ;0,1,2=17,3=90.000000
L 12.87487313 1.70487982 12.87653937 1.70381339 2 P 0 ;0,1,2=17,3=90.000000
L 12.87653937 1.70381339 12.87778996 1.70194665 2 P 0 ;0,1,2=17,3=90.000000
L 12.87778996 1.70194665 12.87778996 1.69474675 2 P 0 ;0,1,2=17,3=90.000000
L 12.87778996 1.69474675 12.85278996 1.69474675 2 P 0 ;0,1,2=17,3=90.000000
L 12.85278996 1.69474675 12.85278996 1.70354675 2 P 0 ;0,1,2=17,3=90.000000
L 12.85278996 1.70354675 12.8544562 1.70541358 2 P 0 ;0,1,2=17,3=90.000000
L 12.8544562 1.70541358 12.8569565 1.70648002 2 P 0 ;0,1,2=17,3=90.000000
L 12.8569565 1.70648002 12.85987323 1.70701319 2 P 0 ;0,1,2=17,3=90.000000
L 12.85987323 1.70701319 12.86278927 1.70648002 2 P 0 ;0,1,2=17,3=90.000000
L 12.86278927 1.70648002 12.86528957 1.70487982 2 P 0 ;0,1,2=17,3=90.000000
L 12.86528957 1.70487982 12.86612343 1.70301309 2 P 0 ;0,1,2=17,3=90.000000
L 12.86612343 1.70301309 12.86612343 1.69474675 2 P 0 ;0,1,2=17,3=90.000000
L 12.85278996 1.72487972 12.87778996 1.72487972 2 P 0 ;0,1,2=17,3=90.000000
L 12.87778996 1.72487972 12.87279026 1.72167992 2 P 0 ;0,1,2=17,3=90.000000
L 12.85278996 1.72167992 12.85278996 1.72807953 2 P 0 ;0,1,2=17,3=90.000000
L 12.87778996 1.74887972 12.87695679 1.74674636 2 P 0 ;0,1,2=17,3=90.000000
L 12.87695679 1.74674636 12.87487313 1.74514665 2 P 0 ;0,1,2=17,3=90.000000
L 12.87487313 1.74514665 12.87237362 1.74407982 2 P 0 ;0,1,2=17,3=90.000000
L 12.87237362 1.74407982 12.86903947 1.74327992 2 P 0 ;0,1,2=17,3=90.000000
L 12.86903947 1.74327992 12.86528957 1.74301329 2 P 0 ;0,1,2=17,3=90.000000
L 12.86528957 1.74301329 12.86153957 1.74327992 2 P 0 ;0,1,2=17,3=90.000000
L 12.86153957 1.74327992 12.8582062 1.74407982 2 P 0 ;0,1,2=17,3=90.000000
L 12.8582062 1.74407982 12.855706 1.74514665 2 P 0 ;0,1,2=17,3=90.000000
L 12.855706 1.74514665 12.85362303 1.74674636 2 P 0 ;0,1,2=17,3=90.000000
L 12.85362303 1.74674636 12.85278996 1.74887972 2 P 0 ;0,1,2=17,3=90.000000
L 12.85278996 1.74887972 12.85362303 1.75101309 2 P 0 ;0,1,2=17,3=90.000000
L 12.85362303 1.75101309 12.855706 1.75261329 2 P 0 ;0,1,2=17,3=90.000000
L 12.855706 1.75261329 12.8582062 1.75368012 2 P 0 ;0,1,2=17,3=90.000000
L 12.8582062 1.75368012 12.86153957 1.75448002 2 P 0 ;0,1,2=17,3=90.000000
L 12.86153957 1.75448002 12.86528957 1.75474665 2 P 0 ;0,1,2=17,3=90.000000
L 12.86528957 1.75474665 12.86903947 1.75448002 2 P 0 ;0,1,2=17,3=90.000000
L 12.86903947 1.75448002 12.87237362 1.75368012 2 P 0 ;0,1,2=17,3=90.000000
L 12.87237362 1.75368012 12.87487313 1.75261329 2 P 0 ;0,1,2=17,3=90.000000
L 12.87487313 1.75261329 12.87695679 1.75101309 2 P 0 ;0,1,2=17,3=90.000000
L 12.87695679 1.75101309 12.87778996 1.74887972 2 P 0 ;0,1,2=17,3=90.000000
L 12.60188002 4.65409301 12.62688002 4.66075974 2 P 0 ;0,1,2=18,3=90.000000
L 12.62688002 4.66075974 12.60188002 4.66742697 2 P 0 ;0,1,2=18,3=90.000000
L 12.61062963 4.66502648 12.61062963 4.65649301 2 P 0 ;0,1,2=18,3=90.000000
L 12.60188002 4.68475974 12.60229656 4.68662648 2 P 0 ;0,1,2=18,3=90.000000
L 12.60229656 4.68662648 12.60354626 4.68875984 2 P 0 ;0,1,2=18,3=90.000000
L 12.60354626 4.68875984 12.60562913 4.69009341 2 P 0 ;0,1,2=18,3=90.000000
L 12.60562913 4.69009341 12.60854675 4.69062667 2 P 0 ;0,1,2=18,3=90.000000
L 12.60854675 4.69062667 12.6114628 4.69009341 2 P 0 ;0,1,2=18,3=90.000000
L 12.6114628 4.69009341 12.61396299 4.68849331 2 P 0 ;0,1,2=18,3=90.000000
L 12.61396299 4.68849331 12.61521348 4.68609331 2 P 0 ;0,1,2=18,3=90.000000
L 12.61521348 4.68609331 12.61521348 4.68342667 2 P 0 ;0,1,2=18,3=90.000000
L 12.61521348 4.68342667 12.61604665 4.68182657 2 P 0 ;0,1,2=18,3=90.000000
L 12.61604665 4.68182657 12.61812953 4.68049301 2 P 0 ;0,1,2=18,3=90.000000
L 12.61812953 4.68049301 12.62104636 4.67995984 2 P 0 ;0,1,2=18,3=90.000000
L 12.62104636 4.67995984 12.62396319 4.68076014 2 P 0 ;0,1,2=18,3=90.000000
L 12.62396319 4.68076014 12.62604685 4.68262638 2 P 0 ;0,1,2=18,3=90.000000
L 12.62604685 4.68262638 12.62688002 4.68475974 2 P 0 ;0,1,2=18,3=90.000000
L 12.62688002 4.68475974 12.62604685 4.68689311 2 P 0 ;0,1,2=18,3=90.000000
L 12.62604685 4.68689311 12.62396319 4.68875984 2 P 0 ;0,1,2=18,3=90.000000
L 12.62396319 4.68875984 12.62104636 4.68956014 2 P 0 ;0,1,2=18,3=90.000000
L 12.62104636 4.68956014 12.61812953 4.68902648 2 P 0 ;0,1,2=18,3=90.000000
L 12.61812953 4.68902648 12.61604665 4.68769341 2 P 0 ;0,1,2=18,3=90.000000
L 12.61604665 4.68769341 12.61521348 4.68609331 2 P 0 ;0,1,2=18,3=90.000000
L 12.61521348 4.68609331 12.61521348 4.68342667 2 P 0 ;0,1,2=18,3=90.000000
L 12.61521348 4.68342667 12.61396299 4.68102667 2 P 0 ;0,1,2=18,3=90.000000
L 12.61396299 4.68102667 12.6114628 4.67942657 2 P 0 ;0,1,2=18,3=90.000000
L 12.6114628 4.67942657 12.60854675 4.67889331 2 P 0 ;0,1,2=18,3=90.000000
L 12.60854675 4.67889331 12.60562913 4.67942657 2 P 0 ;0,1,2=18,3=90.000000
L 12.60562913 4.67942657 12.60354626 4.68076014 2 P 0 ;0,1,2=18,3=90.000000
L 12.60354626 4.68076014 12.60229656 4.6828935 2 P 0 ;0,1,2=18,3=90.000000
L 12.60229656 4.6828935 12.60188002 4.68475974 2 P 0 ;0,1,2=18,3=90.000000
L 12.60188002 4.70875974 12.62688002 4.70875974 2 P 0 ;0,1,2=18,3=90.000000
L 12.62688002 4.70875974 12.62188032 4.70555994 2 P 0 ;0,1,2=18,3=90.000000
L 12.60188002 4.70555994 12.60188002 4.71195955 2 P 0 ;0,1,2=18,3=90.000000
L 12.75907343 4.66289311 12.76032323 4.66396004 2 P 0 ;0,1,2=19,3=90.000000
L 12.76032323 4.66396004 12.7624061 4.66475984 2 P 0 ;0,1,2=19,3=90.000000
L 12.7624061 4.66475984 12.76532362 4.6652936 2 P 0 ;0,1,2=19,3=90.000000
L 12.76532362 4.6652936 12.76782313 4.66475984 2 P 0 ;0,1,2=19,3=90.000000
L 12.76782313 4.66475984 12.76948937 4.66369341 2 P 0 ;0,1,2=19,3=90.000000
L 12.76948937 4.66369341 12.77073996 4.66182667 2 P 0 ;0,1,2=19,3=90.000000
L 12.77073996 4.66182667 12.77073996 4.65462677 2 P 0 ;0,1,2=19,3=90.000000
L 12.77073996 4.65462677 12.74573996 4.65462677 2 P 0 ;0,1,2=19,3=90.000000
L 12.74573996 4.65462677 12.74573996 4.66342677 2 P 0 ;0,1,2=19,3=90.000000
L 12.74573996 4.66342677 12.7474062 4.6652936 2 P 0 ;0,1,2=19,3=90.000000
L 12.7474062 4.6652936 12.7499065 4.66636004 2 P 0 ;0,1,2=19,3=90.000000
L 12.7499065 4.66636004 12.75282323 4.66689321 2 P 0 ;0,1,2=19,3=90.000000
L 12.75282323 4.66689321 12.75573927 4.66636004 2 P 0 ;0,1,2=19,3=90.000000
L 12.75573927 4.66636004 12.75823957 4.66475984 2 P 0 ;0,1,2=19,3=90.000000
L 12.75823957 4.66475984 12.75907343 4.66289311 2 P 0 ;0,1,2=19,3=90.000000
L 12.75907343 4.66289311 12.75907343 4.65462677 2 P 0 ;0,1,2=19,3=90.000000
L 12.74573996 4.68475974 12.7461565 4.68662648 2 P 0 ;0,1,2=19,3=90.000000
L 12.7461565 4.68662648 12.7474062 4.68875984 2 P 0 ;0,1,2=19,3=90.000000
L 12.7474062 4.68875984 12.74948907 4.69009341 2 P 0 ;0,1,2=19,3=90.000000
L 12.74948907 4.69009341 12.75240669 4.69062667 2 P 0 ;0,1,2=19,3=90.000000
L 12.75240669 4.69062667 12.75532274 4.69009341 2 P 0 ;0,1,2=19,3=90.000000
L 12.75532274 4.69009341 12.75782293 4.68849331 2 P 0 ;0,1,2=19,3=90.000000
L 12.75782293 4.68849331 12.75907343 4.68609331 2 P 0 ;0,1,2=19,3=90.000000
L 12.75907343 4.68609331 12.75907343 4.68342667 2 P 0 ;0,1,2=19,3=90.000000
L 12.75907343 4.68342667 12.75990659 4.68182657 2 P 0 ;0,1,2=19,3=90.000000
L 12.75990659 4.68182657 12.76198947 4.68049301 2 P 0 ;0,1,2=19,3=90.000000
L 12.76198947 4.68049301 12.7649063 4.67995984 2 P 0 ;0,1,2=19,3=90.000000
L 12.7649063 4.67995984 12.76782313 4.68076014 2 P 0 ;0,1,2=19,3=90.000000
L 12.76782313 4.68076014 12.76990679 4.68262638 2 P 0 ;0,1,2=19,3=90.000000
L 12.76990679 4.68262638 12.77073996 4.68475974 2 P 0 ;0,1,2=19,3=90.000000
L 12.77073996 4.68475974 12.76990679 4.68689311 2 P 0 ;0,1,2=19,3=90.000000
L 12.76990679 4.68689311 12.76782313 4.68875984 2 P 0 ;0,1,2=19,3=90.000000
L 12.76782313 4.68875984 12.7649063 4.68956014 2 P 0 ;0,1,2=19,3=90.000000
L 12.7649063 4.68956014 12.76198947 4.68902648 2 P 0 ;0,1,2=19,3=90.000000
L 12.76198947 4.68902648 12.75990659 4.68769341 2 P 0 ;0,1,2=19,3=90.000000
L 12.75990659 4.68769341 12.75907343 4.68609331 2 P 0 ;0,1,2=19,3=90.000000
L 12.75907343 4.68609331 12.75907343 4.68342667 2 P 0 ;0,1,2=19,3=90.000000
L 12.75907343 4.68342667 12.75782293 4.68102667 2 P 0 ;0,1,2=19,3=90.000000
L 12.75782293 4.68102667 12.75532274 4.67942657 2 P 0 ;0,1,2=19,3=90.000000
L 12.75532274 4.67942657 12.75240669 4.67889331 2 P 0 ;0,1,2=19,3=90.000000
L 12.75240669 4.67889331 12.74948907 4.67942657 2 P 0 ;0,1,2=19,3=90.000000
L 12.74948907 4.67942657 12.7474062 4.68076014 2 P 0 ;0,1,2=19,3=90.000000
L 12.7474062 4.68076014 12.7461565 4.6828935 2 P 0 ;0,1,2=19,3=90.000000
L 12.7461565 4.6828935 12.74573996 4.68475974 2 P 0 ;0,1,2=19,3=90.000000
L 12.74573996 4.70875974 12.77073996 4.70875974 2 P 0 ;0,1,2=19,3=90.000000
L 12.77073996 4.70875974 12.76574026 4.70555994 2 P 0 ;0,1,2=19,3=90.000000
L 12.74573996 4.70555994 12.74573996 4.71195955 2 P 0 ;0,1,2=19,3=90.000000
L 0.0349 -2.3038 0.0349 -1.0038 4 P 0 
L 0.0349 -1.0038 4.5349 -1.0038 4 P 0 
L 4.5349 -1.0038 4.5349 -2.3038 4 P 0 
L 4.5349 -2.3038 0.0349 -2.3038 4 P 0 
L 0.0349 -1.6038 4.5349 -1.6038 4 P 0 
L 0.0349 -1.8038 4.5349 -1.8038 4 P 0 
L 2.4349 -2.1038 4.0349 -2.1038 4 P 0 
L 2.4349 -2.3038 2.4349 -1.8038 4 P 0 
L 3.2349 -2.1038 3.2349 -1.8038 4 P 0 
L 4.0349 -2.3038 4.0349 -1.8038 4 P 0 
L 0.0723999 -1.6844687 0.07906663 -1.69030079 2 P 0 ;0,2=20,3=0.000000
L 0.07906663 -1.69030079 0.08656654 -1.6938 2 P 0 ;0,2=20,3=0.000000
L 0.08656654 -1.6938 0.09323337 -1.6938 2 P 0 ;0,2=20,3=0.000000
L 0.09323337 -1.6938 0.0999001 -1.69030079 2 P 0 ;0,2=20,3=0.000000
L 0.0999001 -1.69030079 0.10490059 -1.6844687 2 P 0 ;0,2=20,3=0.000000
L 0.10490059 -1.6844687 0.1074 -1.67629951 2 P 0 ;0,2=20,3=0.000000
L 0.1074 -1.67629951 0.10573376 -1.66813455 2 P 0 ;0,2=20,3=0.000000
L 0.10573376 -1.66813455 0.10156644 -1.66113396 2 P 0 ;0,2=20,3=0.000000
L 0.10156644 -1.66113396 0.09406654 -1.65646614 2 P 0 ;0,2=20,3=0.000000
L 0.09406654 -1.65646614 0.08406713 -1.65413327 2 P 0 ;0,2=20,3=0.000000
L 0.08406713 -1.65413327 0.07823346 -1.64946762 2 P 0 ;0,2=20,3=0.000000
L 0.07823346 -1.64946762 0.07573248 -1.64130059 2 P 0 ;0,2=20,3=0.000000
L 0.07573248 -1.64130059 0.0774003 -1.63313356 2 P 0 ;0,2=20,3=0.000000
L 0.0774003 -1.63313356 0.08156614 -1.62730148 2 P 0 ;0,2=20,3=0.000000
L 0.08156614 -1.62730148 0.0873997 -1.6238 2 P 0 ;0,2=20,3=0.000000
L 0.0873997 -1.6238 0.09323337 -1.6238 2 P 0 ;0,2=20,3=0.000000
L 0.09323337 -1.6238 0.09906693 -1.62613287 2 P 0 ;0,2=20,3=0.000000
L 0.09906693 -1.62613287 0.10406742 -1.63196713 2 P 0 ;0,2=20,3=0.000000
L 0.1383999 -1.6938 0.1383999 -1.6238 2 P 0 ;0,2=20,3=0.000000
L 0.1734 -1.6238 0.1734 -1.6938 2 P 0 ;0,2=20,3=0.000000
L 0.1734 -1.65880108 0.1383999 -1.65880108 2 P 0 ;0,2=20,3=0.000000
L 0.23856683 -1.6938 0.20523307 -1.6938 2 P 0 ;0,2=20,3=0.000000
L 0.20523307 -1.6938 0.20523307 -1.6238 2 P 0 ;0,2=20,3=0.000000
L 0.20523307 -1.6238 0.23856683 -1.6238 2 P 0 ;0,2=20,3=0.000000
L 0.22523337 -1.65763258 0.20523307 -1.65763258 2 P 0 ;0,2=20,3=0.000000
L 0.30456683 -1.6938 0.27123307 -1.6938 2 P 0 ;0,2=20,3=0.000000
L 0.27123307 -1.6938 0.27123307 -1.6238 2 P 0 ;0,2=20,3=0.000000
L 0.27123307 -1.6238 0.30456683 -1.6238 2 P 0 ;0,2=20,3=0.000000
L 0.29123337 -1.65763258 0.27123307 -1.65763258 2 P 0 ;0,2=20,3=0.000000
L 0.35389921 -1.6238 0.35389921 -1.6938 2 P 0 ;0,2=20,3=0.000000
L 0.33473356 -1.6238 0.37306634 -1.6238 2 P 0 ;0,2=20,3=0.000000
L 0.09489921 -1.7188 0.09489921 -1.7888 2 P 0 ;0,2=21,3=0.000000
L 0.07573356 -1.7188 0.11406634 -1.7188 2 P 0 ;0,2=21,3=0.000000
L 0.1508998 -1.7188 0.17089862 -1.7188 2 P 0 ;0,2=21,3=0.000000
L 0.16089921 -1.7188 0.16089921 -1.7888 2 P 0 ;0,2=21,3=0.000000
L 0.1508998 -1.7888 0.17089862 -1.7888 2 P 0 ;0,2=21,3=0.000000
L 0.22689921 -1.7188 0.22689921 -1.7888 2 P 0 ;0,2=21,3=0.000000
L 0.20773356 -1.7188 0.24606634 -1.7188 2 P 0 ;0,2=21,3=0.000000
L 0.27623307 -1.7188 0.27623307 -1.7888 2 P 0 ;0,2=21,3=0.000000
L 0.27623307 -1.7888 0.30956683 -1.7888 2 P 0 ;0,2=21,3=0.000000
L 0.37556683 -1.7888 0.34223307 -1.7888 2 P 0 ;0,2=21,3=0.000000
L 0.34223307 -1.7888 0.34223307 -1.7188 2 P 0 ;0,2=21,3=0.000000
L 0.34223307 -1.7188 0.37556683 -1.7188 2 P 0 ;0,2=21,3=0.000000
L 0.36223337 -1.75263258 0.34223307 -1.75263258 2 P 0 ;0,2=21,3=0.000000
L 2.5438999 -1.96813563 2.5519 -1.97480089 2 P 0 ;0,2=22,3=0.000000
L 2.5519 -1.97480089 2.5608999 -1.9788 2 P 0 ;0,2=22,3=0.000000
L 2.5608999 -1.9788 2.5689 -1.9788 2 P 0 ;0,2=22,3=0.000000
L 2.5689 -1.9788 2.5769001 -1.97480089 2 P 0 ;0,2=22,3=0.000000
L 2.5769001 -1.97480089 2.58290069 -1.96813563 2 P 0 ;0,2=22,3=0.000000
L 2.58290069 -1.96813563 2.5859 -1.95879941 2 P 0 ;0,2=22,3=0.000000
L 2.5859 -1.95879941 2.58390049 -1.94946811 2 P 0 ;0,2=22,3=0.000000
L 2.58390049 -1.94946811 2.5788997 -1.94146732 2 P 0 ;0,2=22,3=0.000000
L 2.5788997 -1.94146732 2.5698998 -1.93613278 2 P 0 ;0,2=22,3=0.000000
L 2.5698998 -1.93613278 2.55790049 -1.93346663 2 P 0 ;0,2=22,3=0.000000
L 2.55790049 -1.93346663 2.5509002 -1.92813445 2 P 0 ;0,2=22,3=0.000000
L 2.5509002 -1.92813445 2.54789902 -1.91880069 2 P 0 ;0,2=22,3=0.000000
L 2.54789902 -1.91880069 2.54990039 -1.90946683 2 P 0 ;0,2=22,3=0.000000
L 2.54990039 -1.90946683 2.55489931 -1.90280167 2 P 0 ;0,2=22,3=0.000000
L 2.55489931 -1.90280167 2.5618997 -1.8988 2 P 0 ;0,2=22,3=0.000000
L 2.5618997 -1.8988 2.5689 -1.8988 2 P 0 ;0,2=22,3=0.000000
L 2.5689 -1.8988 2.57590039 -1.90146614 2 P 0 ;0,2=22,3=0.000000
L 2.57590039 -1.90146614 2.58190089 -1.90813386 2 P 0 ;0,2=22,3=0.000000
L 2.6648998 -1.90546772 2.65889931 -1.90146614 2 P 0 ;0,2=22,3=0.000000
L 2.65889931 -1.90146614 2.65190079 -1.8988 2 P 0 ;0,2=22,3=0.000000
L 2.65190079 -1.8988 2.64390069 -1.8988 2 P 0 ;0,2=22,3=0.000000
L 2.64390069 -1.8988 2.63489892 -1.90280167 2 P 0 ;0,2=22,3=0.000000
L 2.63489892 -1.90280167 2.62790039 -1.90946683 2 P 0 ;0,2=22,3=0.000000
L 2.62790039 -1.90946683 2.62289961 -1.91746762 2 P 0 ;0,2=22,3=0.000000
L 2.62289961 -1.91746762 2.61889862 -1.93080049 2 P 0 ;0,2=22,3=0.000000
L 2.61889862 -1.93080049 2.61789892 -1.94280039 2 P 0 ;0,2=22,3=0.000000
L 2.61789892 -1.94280039 2.6199003 -1.9548003 2 P 0 ;0,2=22,3=0.000000
L 2.6199003 -1.9548003 2.62289961 -1.96280098 2 P 0 ;0,2=22,3=0.000000
L 2.62289961 -1.96280098 2.6289002 -1.97080177 2 P 0 ;0,2=22,3=0.000000
L 2.6289002 -1.97080177 2.63590049 -1.97613396 2 P 0 ;0,2=22,3=0.000000
L 2.63590049 -1.97613396 2.64289902 -1.9788 2 P 0 ;0,2=22,3=0.000000
L 2.64289902 -1.9788 2.64989941 -1.9788 2 P 0 ;0,2=22,3=0.000000
L 2.64989941 -1.9788 2.6568997 -1.97613396 2 P 0 ;0,2=22,3=0.000000
L 2.6568997 -1.97613396 2.6629003 -1.97213484 2 P 0 ;0,2=22,3=0.000000
L 2.6629003 -1.97213484 2.66790098 -1.96680266 2 P 0 ;0,2=22,3=0.000000
L 2.69589892 -1.9788 2.72089902 -1.8988 2 P 0 ;0,2=22,3=0.000000
L 2.72089902 -1.8988 2.74590098 -1.9788 2 P 0 ;0,2=22,3=0.000000
L 2.73689931 -1.95080118 2.70489882 -1.95080118 2 P 0 ;0,2=22,3=0.000000
L 2.77889961 -1.8988 2.77889961 -1.9788 2 P 0 ;0,2=22,3=0.000000
L 2.77889961 -1.9788 2.8189003 -1.9788 2 P 0 ;0,2=22,3=0.000000
L 2.8969003 -1.9788 2.85689961 -1.9788 2 P 0 ;0,2=22,3=0.000000
L 2.85689961 -1.9788 2.85689961 -1.8988 2 P 0 ;0,2=22,3=0.000000
L 2.85689961 -1.8988 2.8969003 -1.8988 2 P 0 ;0,2=22,3=0.000000
L 2.8809 -1.93746575 2.85689961 -1.93746575 2 P 0 ;0,2=22,3=0.000000
L 3.03289902 -1.9788 3.03289902 -1.8988 2 P 0 ;0,2=22,3=0.000000
L 3.03289902 -1.8988 3.0208998 -1.91479911 2 P 0 ;0,2=22,3=0.000000
L 3.0208998 -1.9788 3.04489833 -1.9788 2 P 0 ;0,2=22,3=0.000000
L 3.11089902 -1.98146604 3.10889951 -1.98013297 2 P 0 ;0,2=22,3=0.000000
L 3.10889951 -1.98013297 3.10889951 -1.97746703 2 P 0 ;0,2=22,3=0.000000
L 3.10889951 -1.97746703 3.11089902 -1.97613396 2 P 0 ;0,2=22,3=0.000000
L 3.11089902 -1.97613396 3.11290039 -1.97746703 2 P 0 ;0,2=22,3=0.000000
L 3.11290039 -1.97746703 3.11290039 -1.98013297 2 P 0 ;0,2=22,3=0.000000
L 3.11290039 -1.98013297 3.11089902 -1.98146604 2 P 0 ;0,2=22,3=0.000000
L 3.11089902 -1.945469 3.10889951 -1.94413346 2 P 0 ;0,2=22,3=0.000000
L 3.10889951 -1.94413346 3.10889951 -1.94146732 2 P 0 ;0,2=22,3=0.000000
L 3.10889951 -1.94146732 3.11089902 -1.94013435 2 P 0 ;0,2=22,3=0.000000
L 3.11089902 -1.94013435 3.11290039 -1.94146732 2 P 0 ;0,2=22,3=0.000000
L 3.11290039 -1.94146732 3.11290039 -1.94413346 2 P 0 ;0,2=22,3=0.000000
L 3.11290039 -1.94413346 3.11089902 -1.945469 2 P 0 ;0,2=22,3=0.000000
L 3.18889902 -1.9788 3.18889902 -1.8988 2 P 0 ;0,2=22,3=0.000000
L 3.18889902 -1.8988 3.1768998 -1.91479911 2 P 0 ;0,2=22,3=0.000000
L 3.1768998 -1.9788 3.20089833 -1.9788 2 P 0 ;0,2=22,3=0.000000
L 2.5138999 -2.23313563 2.5219 -2.23980089 2 P 0 ;0,2=20,3=0.000000
L 2.5219 -2.23980089 2.5308999 -2.2438 2 P 0 ;0,2=20,3=0.000000
L 2.5308999 -2.2438 2.5389 -2.2438 2 P 0 ;0,2=20,3=0.000000
L 2.5389 -2.2438 2.5469001 -2.23980089 2 P 0 ;0,2=20,3=0.000000
L 2.5469001 -2.23980089 2.55290069 -2.23313563 2 P 0 ;0,2=20,3=0.000000
L 2.55290069 -2.23313563 2.5559 -2.22379941 2 P 0 ;0,2=20,3=0.000000
L 2.5559 -2.22379941 2.55390049 -2.21446811 2 P 0 ;0,2=20,3=0.000000
L 2.55390049 -2.21446811 2.5488997 -2.20646732 2 P 0 ;0,2=20,3=0.000000
L 2.5488997 -2.20646732 2.5398998 -2.20113278 2 P 0 ;0,2=20,3=0.000000
L 2.5398998 -2.20113278 2.52790049 -2.19846663 2 P 0 ;0,2=20,3=0.000000
L 2.52790049 -2.19846663 2.5209002 -2.19313445 2 P 0 ;0,2=20,3=0.000000
L 2.5209002 -2.19313445 2.51789902 -2.18380069 2 P 0 ;0,2=20,3=0.000000
L 2.51789902 -2.18380069 2.51990039 -2.17446683 2 P 0 ;0,2=20,3=0.000000
L 2.51990039 -2.17446683 2.52489931 -2.16780167 2 P 0 ;0,2=20,3=0.000000
L 2.52489931 -2.16780167 2.5318997 -2.1638 2 P 0 ;0,2=20,3=0.000000
L 2.5318997 -2.1638 2.5389 -2.1638 2 P 0 ;0,2=20,3=0.000000
L 2.5389 -2.1638 2.54590039 -2.16646614 2 P 0 ;0,2=20,3=0.000000
L 2.54590039 -2.16646614 2.55190089 -2.17313386 2 P 0 ;0,2=20,3=0.000000
L 2.5918999 -2.2438 2.5918999 -2.1638 2 P 0 ;0,2=20,3=0.000000
L 2.6339 -2.1638 2.6339 -2.2438 2 P 0 ;0,2=20,3=0.000000
L 2.6339 -2.20380128 2.5918999 -2.20380128 2 P 0 ;0,2=20,3=0.000000
L 2.7109003 -2.2438 2.67089961 -2.2438 2 P 0 ;0,2=20,3=0.000000
L 2.67089961 -2.2438 2.67089961 -2.1638 2 P 0 ;0,2=20,3=0.000000
L 2.67089961 -2.1638 2.7109003 -2.1638 2 P 0 ;0,2=20,3=0.000000
L 2.6949 -2.20246575 2.67089961 -2.20246575 2 P 0 ;0,2=20,3=0.000000
L 2.7889003 -2.2438 2.74889961 -2.2438 2 P 0 ;0,2=20,3=0.000000
L 2.74889961 -2.2438 2.74889961 -2.1638 2 P 0 ;0,2=20,3=0.000000
L 2.74889961 -2.1638 2.7889003 -2.1638 2 P 0 ;0,2=20,3=0.000000
L 2.7729 -2.20246575 2.74889961 -2.20246575 2 P 0 ;0,2=20,3=0.000000
L 2.84689902 -2.1638 2.84689902 -2.2438 2 P 0 ;0,2=20,3=0.000000
L 2.8239003 -2.1638 2.86989961 -2.1638 2 P 0 ;0,2=20,3=0.000000
L 3.29489961 -1.9238 3.29489961 -2.0038 2 P 0 ;0,2=23,3=0.000000
L 3.29489961 -2.0038 3.3349003 -2.0038 2 P 0 ;0,2=23,3=0.000000
L 3.36789892 -2.0038 3.39289902 -1.9238 2 P 0 ;0,2=23,3=0.000000
L 3.39289902 -1.9238 3.41790098 -2.0038 2 P 0 ;0,2=23,3=0.000000
L 3.40889931 -1.97580118 3.37689882 -1.97580118 2 P 0 ;0,2=23,3=0.000000
L 3.47089902 -2.0038 3.47089902 -1.96780039 2 P 0 ;0,2=23,3=0.000000
L 3.47089902 -1.96780039 3.45089961 -1.9238 2 P 0 ;0,2=23,3=0.000000
L 3.4909003 -1.9238 3.47089902 -1.96780039 2 P 0 ;0,2=23,3=0.000000
L 3.5689003 -2.0038 3.52889961 -2.0038 2 P 0 ;0,2=23,3=0.000000
L 3.52889961 -2.0038 3.52889961 -1.9238 2 P 0 ;0,2=23,3=0.000000
L 3.52889961 -1.9238 3.5689003 -1.9238 2 P 0 ;0,2=23,3=0.000000
L 3.5529 -1.96246575 3.52889961 -1.96246575 2 P 0 ;0,2=23,3=0.000000
L 3.60689961 -2.0038 3.60689961 -1.9238 2 P 0 ;0,2=23,3=0.000000
L 3.60689961 -1.9238 3.6318998 -1.9238 2 P 0 ;0,2=23,3=0.000000
L 3.6318998 -1.9238 3.6398999 -1.92780167 2 P 0 ;0,2=23,3=0.000000
L 3.6398999 -1.92780167 3.64490069 -1.93313386 2 P 0 ;0,2=23,3=0.000000
L 3.64490069 -1.93313386 3.6469003 -1.94380069 2 P 0 ;0,2=23,3=0.000000
L 3.6469003 -1.94380069 3.64490069 -1.95446752 2 P 0 ;0,2=23,3=0.000000
L 3.64490069 -1.95446752 3.6389001 -1.96113278 2 P 0 ;0,2=23,3=0.000000
L 3.6389001 -1.96113278 3.6318998 -1.96513435 2 P 0 ;0,2=23,3=0.000000
L 3.6318998 -1.96513435 3.60689961 -1.96513435 2 P 0 ;0,2=23,3=0.000000
L 3.6318998 -1.96513435 3.6469003 -2.0038 2 P 0 ;0,2=23,3=0.000000
L 3.33989902 -2.2538 3.33189892 -2.25246703 2 P 0 ;0,2=24,3=0.000000
L 3.33189892 -2.25246703 3.32490039 -2.24713484 2 P 0 ;0,2=24,3=0.000000
L 3.32490039 -2.24713484 3.3188999 -2.23913406 2 P 0 ;0,2=24,3=0.000000
L 3.3188999 -2.23913406 3.31489892 -2.2298003 2 P 0 ;0,2=24,3=0.000000
L 3.31489892 -2.2298003 3.31289931 -2.21913346 2 P 0 ;0,2=24,3=0.000000
L 3.31289931 -2.21913346 3.31289931 -2.20846663 2 P 0 ;0,2=24,3=0.000000
L 3.31289931 -2.20846663 3.31489892 -2.1977998 2 P 0 ;0,2=24,3=0.000000
L 3.31489892 -2.1977998 3.3188999 -2.18846604 2 P 0 ;0,2=24,3=0.000000
L 3.3188999 -2.18846604 3.32490039 -2.18046772 2 P 0 ;0,2=24,3=0.000000
L 3.32490039 -2.18046772 3.33189892 -2.17513307 2 P 0 ;0,2=24,3=0.000000
L 3.33189892 -2.17513307 3.33989902 -2.1738 2 P 0 ;0,2=24,3=0.000000
L 3.33989902 -2.1738 3.34789911 -2.17513307 2 P 0 ;0,2=24,3=0.000000
L 3.34789911 -2.17513307 3.35489951 -2.18046772 2 P 0 ;0,2=24,3=0.000000
L 3.35489951 -2.18046772 3.3609 -2.18846604 2 P 0 ;0,2=24,3=0.000000
L 3.3609 -2.18846604 3.36490098 -2.1977998 2 P 0 ;0,2=24,3=0.000000
L 3.36490098 -2.1977998 3.36690059 -2.20846663 2 P 0 ;0,2=24,3=0.000000
L 3.36690059 -2.20846663 3.36690059 -2.21913346 2 P 0 ;0,2=24,3=0.000000
L 3.36690059 -2.21913346 3.36490098 -2.2298003 2 P 0 ;0,2=24,3=0.000000
L 3.36490098 -2.2298003 3.3609 -2.23913406 2 P 0 ;0,2=24,3=0.000000
L 3.3609 -2.23913406 3.35489951 -2.24713484 2 P 0 ;0,2=24,3=0.000000
L 3.35489951 -2.24713484 3.34789911 -2.25246703 2 P 0 ;0,2=24,3=0.000000
L 3.34789911 -2.25246703 3.33989902 -2.2538 2 P 0 ;0,2=24,3=0.000000
L 3.39889941 -2.2538 3.39889941 -2.1738 2 P 0 ;0,2=24,3=0.000000
L 3.39889941 -2.1738 3.43690049 -2.1738 2 P 0 ;0,2=24,3=0.000000
L 3.4228998 -2.21246575 3.39889941 -2.21246575 2 P 0 ;0,2=24,3=0.000000
L 0.16489872 -1.0538 0.16489872 -1.1538 2 P 0 ;0,2=21,3=0.000000
L 0.13423376 -1.0538 0.19556614 -1.0538 2 P 0 ;0,2=21,3=0.000000
L 0.2588997 -1.0538 0.29089774 -1.0538 2 P 0 ;0,2=21,3=0.000000
L 0.27489872 -1.0538 0.27489872 -1.1538 2 P 0 ;0,2=21,3=0.000000
L 0.2588997 -1.1538 0.29089774 -1.1538 2 P 0 ;0,2=21,3=0.000000
L 0.38489872 -1.0538 0.38489872 -1.1538 2 P 0 ;0,2=21,3=0.000000
L 0.35423376 -1.0538 0.41556614 -1.0538 2 P 0 ;0,2=21,3=0.000000
L 0.46823287 -1.0538 0.46823287 -1.1538 2 P 0 ;0,2=21,3=0.000000
L 0.46823287 -1.1538 0.52156703 -1.1538 2 P 0 ;0,2=21,3=0.000000
L 0.63156703 -1.1538 0.57823287 -1.1538 2 P 0 ;0,2=21,3=0.000000
L 0.57823287 -1.1538 0.57823287 -1.0538 2 P 0 ;0,2=21,3=0.000000
L 0.57823287 -1.0538 0.63156703 -1.0538 2 P 0 ;0,2=21,3=0.000000
L 0.61023337 -1.10213219 0.57823287 -1.10213219 2 P 0 ;0,2=21,3=0.000000
L 4.18989892 -1.9538 4.21489902 -1.8738 2 P 0 ;0,2=25,3=0.000000
L 4.21489902 -1.8738 4.23990098 -1.9538 2 P 0 ;0,2=25,3=0.000000
L 4.23089931 -1.92580118 4.19889882 -1.92580118 2 P 0 ;0,2=25,3=0.000000
L 4.27289961 -1.9538 4.27289961 -1.8738 2 P 0 ;0,2=25,3=0.000000
L 4.27289961 -1.8738 4.2978998 -1.8738 2 P 0 ;0,2=25,3=0.000000
L 4.2978998 -1.8738 4.3058999 -1.87780167 2 P 0 ;0,2=25,3=0.000000
L 4.3058999 -1.87780167 4.31090069 -1.88313386 2 P 0 ;0,2=25,3=0.000000
L 4.31090069 -1.88313386 4.3129003 -1.89380069 2 P 0 ;0,2=25,3=0.000000
L 4.3129003 -1.89380069 4.31090069 -1.90446752 2 P 0 ;0,2=25,3=0.000000
L 4.31090069 -1.90446752 4.3049001 -1.91113278 2 P 0 ;0,2=25,3=0.000000
L 4.3049001 -1.91113278 4.2978998 -1.91513435 2 P 0 ;0,2=25,3=0.000000
L 4.2978998 -1.91513435 4.27289961 -1.91513435 2 P 0 ;0,2=25,3=0.000000
L 4.2978998 -1.91513435 4.3129003 -1.9538 2 P 0 ;0,2=25,3=0.000000
L 4.37089902 -1.8738 4.37089902 -1.9538 2 P 0 ;0,2=25,3=0.000000
L 4.3479003 -1.8738 4.39389961 -1.8738 2 P 0 ;0,2=25,3=0.000000
L 2.1744002 -1.74180266 2.16506663 -1.74930098 2 P 0 ;0,1,2=26,3=0.000000
L 2.16506663 -1.74930098 2.15456683 -1.7538 2 P 0 ;0,1,2=26,3=0.000000
L 2.15456683 -1.7538 2.14523327 -1.7538 2 P 0 ;0,1,2=26,3=0.000000
L 2.14523327 -1.7538 2.1358998 -1.74930098 2 P 0 ;0,1,2=26,3=0.000000
L 2.1358998 -1.74930098 2.12889921 -1.74180266 2 P 0 ;0,1,2=26,3=0.000000
L 2.12889921 -1.74180266 2.1253999 -1.73129941 2 P 0 ;0,1,2=26,3=0.000000
L 2.1253999 -1.73129941 2.12773278 -1.72080157 2 P 0 ;0,1,2=26,3=0.000000
L 2.12773278 -1.72080157 2.13356703 -1.71180079 2 P 0 ;0,1,2=26,3=0.000000
L 2.13356703 -1.71180079 2.14406693 -1.70579931 2 P 0 ;0,1,2=26,3=0.000000
L 2.14406693 -1.70579931 2.15806604 -1.7028 2 P 0 ;0,1,2=26,3=0.000000
L 2.15806604 -1.7028 2.16623307 -1.69680128 2 P 0 ;0,1,2=26,3=0.000000
L 2.16623307 -1.69680128 2.16973445 -1.68630069 2 P 0 ;0,1,2=26,3=0.000000
L 2.16973445 -1.68630069 2.16739951 -1.6758002 2 P 0 ;0,1,2=26,3=0.000000
L 2.16739951 -1.6758002 2.16156742 -1.66830187 2 P 0 ;0,1,2=26,3=0.000000
L 2.16156742 -1.66830187 2.15340039 -1.6638 2 P 0 ;0,1,2=26,3=0.000000
L 2.15340039 -1.6638 2.14523327 -1.6638 2 P 0 ;0,1,2=26,3=0.000000
L 2.14523327 -1.6638 2.13706624 -1.66679941 2 P 0 ;0,1,2=26,3=0.000000
L 2.13706624 -1.66679941 2.13006565 -1.67430059 2 P 0 ;0,1,2=26,3=0.000000
L 2.0739003 -1.6638 2.04590197 -1.6638 2 P 0 ;0,1,2=26,3=0.000000
L 2.05990108 -1.6638 2.05990108 -1.7538 2 P 0 ;0,1,2=26,3=0.000000
L 2.0739003 -1.7538 2.04590197 -1.7538 2 P 0 ;0,1,2=26,3=0.000000
L 1.99323376 -1.6638 1.99323376 -1.7538 2 P 0 ;0,1,2=26,3=0.000000
L 1.99323376 -1.7538 1.94656634 -1.7538 2 P 0 ;0,1,2=26,3=0.000000
L 1.90556654 -1.7538 1.90556654 -1.6638 2 P 0 ;0,1,2=26,3=0.000000
L 1.86123415 -1.6638 1.90556654 -1.71930197 2 P 0 ;0,1,2=26,3=0.000000
L 1.85423356 -1.7538 1.88573317 -1.69380187 2 P 0 ;0,1,2=26,3=0.000000
L 1.7244002 -1.74180266 1.71506663 -1.74930098 2 P 0 ;0,1,2=26,3=0.000000
L 1.71506663 -1.74930098 1.70456683 -1.7538 2 P 0 ;0,1,2=26,3=0.000000
L 1.70456683 -1.7538 1.69523327 -1.7538 2 P 0 ;0,1,2=26,3=0.000000
L 1.69523327 -1.7538 1.6858998 -1.74930098 2 P 0 ;0,1,2=26,3=0.000000
L 1.6858998 -1.74930098 1.67889921 -1.74180266 2 P 0 ;0,1,2=26,3=0.000000
L 1.67889921 -1.74180266 1.6753999 -1.73129941 2 P 0 ;0,1,2=26,3=0.000000
L 1.6753999 -1.73129941 1.67773278 -1.72080157 2 P 0 ;0,1,2=26,3=0.000000
L 1.67773278 -1.72080157 1.68356703 -1.71180079 2 P 0 ;0,1,2=26,3=0.000000
L 1.68356703 -1.71180079 1.69406693 -1.70579931 2 P 0 ;0,1,2=26,3=0.000000
L 1.69406693 -1.70579931 1.70806604 -1.7028 2 P 0 ;0,1,2=26,3=0.000000
L 1.70806604 -1.7028 1.71623307 -1.69680128 2 P 0 ;0,1,2=26,3=0.000000
L 1.71623307 -1.69680128 1.71973445 -1.68630069 2 P 0 ;0,1,2=26,3=0.000000
L 1.71973445 -1.68630069 1.71739951 -1.6758002 2 P 0 ;0,1,2=26,3=0.000000
L 1.71739951 -1.6758002 1.71156742 -1.66830187 2 P 0 ;0,1,2=26,3=0.000000
L 1.71156742 -1.66830187 1.70340039 -1.6638 2 P 0 ;0,1,2=26,3=0.000000
L 1.70340039 -1.6638 1.69523327 -1.6638 2 P 0 ;0,1,2=26,3=0.000000
L 1.69523327 -1.6638 1.68706624 -1.66679941 2 P 0 ;0,1,2=26,3=0.000000
L 1.68706624 -1.66679941 1.68006565 -1.67430059 2 P 0 ;0,1,2=26,3=0.000000
L 1.58423356 -1.67130118 1.59123415 -1.66679941 2 P 0 ;0,1,2=26,3=0.000000
L 1.59123415 -1.66679941 1.59939911 -1.6638 2 P 0 ;0,1,2=26,3=0.000000
L 1.59939911 -1.6638 1.60873258 -1.6638 2 P 0 ;0,1,2=26,3=0.000000
L 1.60873258 -1.6638 1.61923455 -1.66830187 2 P 0 ;0,1,2=26,3=0.000000
L 1.61923455 -1.66830187 1.62739951 -1.6758002 2 P 0 ;0,1,2=26,3=0.000000
L 1.62739951 -1.6758002 1.63323376 -1.68480108 2 P 0 ;0,1,2=26,3=0.000000
L 1.63323376 -1.68480108 1.63790157 -1.69980059 2 P 0 ;0,1,2=26,3=0.000000
L 1.63790157 -1.69980059 1.63906791 -1.71330049 2 P 0 ;0,1,2=26,3=0.000000
L 1.63906791 -1.71330049 1.63673297 -1.7268003 2 P 0 ;0,1,2=26,3=0.000000
L 1.63673297 -1.7268003 1.63323376 -1.73580118 2 P 0 ;0,1,2=26,3=0.000000
L 1.63323376 -1.73580118 1.62623307 -1.74480197 2 P 0 ;0,1,2=26,3=0.000000
L 1.62623307 -1.74480197 1.61806604 -1.75080069 2 P 0 ;0,1,2=26,3=0.000000
L 1.61806604 -1.75080069 1.60990108 -1.7538 2 P 0 ;0,1,2=26,3=0.000000
L 1.60990108 -1.7538 1.60173406 -1.7538 2 P 0 ;0,1,2=26,3=0.000000
L 1.60173406 -1.7538 1.59356703 -1.75080069 2 P 0 ;0,1,2=26,3=0.000000
L 1.59356703 -1.75080069 1.58656634 -1.74630167 2 P 0 ;0,1,2=26,3=0.000000
L 1.58656634 -1.74630167 1.58073219 -1.74030295 2 P 0 ;0,1,2=26,3=0.000000
L 1.54323376 -1.7538 1.54323376 -1.6638 2 P 0 ;0,1,2=26,3=0.000000
L 1.54323376 -1.6638 1.51406693 -1.6638 2 P 0 ;0,1,2=26,3=0.000000
L 1.51406693 -1.6638 1.50473346 -1.66830187 2 P 0 ;0,1,2=26,3=0.000000
L 1.50473346 -1.66830187 1.49889921 -1.67430059 2 P 0 ;0,1,2=26,3=0.000000
L 1.49889921 -1.67430059 1.49656634 -1.68630069 2 P 0 ;0,1,2=26,3=0.000000
L 1.49656634 -1.68630069 1.49889921 -1.69830089 2 P 0 ;0,1,2=26,3=0.000000
L 1.49889921 -1.69830089 1.5058998 -1.70579931 2 P 0 ;0,1,2=26,3=0.000000
L 1.5058998 -1.70579931 1.51406693 -1.71030108 2 P 0 ;0,1,2=26,3=0.000000
L 1.51406693 -1.71030108 1.54323376 -1.71030108 2 P 0 ;0,1,2=26,3=0.000000
L 1.51406693 -1.71030108 1.49656634 -1.7538 2 P 0 ;0,1,2=26,3=0.000000
L 1.40656634 -1.7538 1.45323376 -1.7538 2 P 0 ;0,1,2=26,3=0.000000
L 1.45323376 -1.7538 1.45323376 -1.6638 2 P 0 ;0,1,2=26,3=0.000000
L 1.45323376 -1.6638 1.40656634 -1.6638 2 P 0 ;0,1,2=26,3=0.000000
L 1.42523327 -1.70729902 1.45323376 -1.70729902 2 P 0 ;0,1,2=26,3=0.000000
L 1.31656634 -1.7538 1.36323376 -1.7538 2 P 0 ;0,1,2=26,3=0.000000
L 1.36323376 -1.7538 1.36323376 -1.6638 2 P 0 ;0,1,2=26,3=0.000000
L 1.36323376 -1.6638 1.31656634 -1.6638 2 P 0 ;0,1,2=26,3=0.000000
L 1.33523327 -1.70729902 1.36323376 -1.70729902 2 P 0 ;0,1,2=26,3=0.000000
L 1.27673297 -1.7538 1.27673297 -1.6638 2 P 0 ;0,1,2=26,3=0.000000
L 1.27673297 -1.6638 1.22306713 -1.7538 2 P 0 ;0,1,2=26,3=0.000000
L 1.22306713 -1.7538 1.22306713 -1.6638 2 P 0 ;0,1,2=26,3=0.000000
L 1.07573317 -1.78379902 1.08739951 -1.76879951 2 P 0 ;0,1,2=26,3=0.000000
L 1.08739951 -1.76879951 1.09323376 -1.7538 2 P 0 ;0,1,2=26,3=0.000000
L 1.09323376 -1.7538 1.09323376 -1.69380187 2 P 0 ;0,1,2=26,3=0.000000
L 1.09323376 -1.69380187 1.08739951 -1.67879961 2 P 0 ;0,1,2=26,3=0.000000
L 1.08739951 -1.67879961 1.07573317 -1.6638 2 P 0 ;0,1,2=26,3=0.000000
L 0.88056762 -1.70579931 0.8758998 -1.7013003 2 P 0 ;0,1,2=26,3=0.000000
L 0.8758998 -1.7013003 0.87240059 -1.69380187 2 P 0 ;0,1,2=26,3=0.000000
L 0.87240059 -1.69380187 0.87006565 -1.68329862 2 P 0 ;0,1,2=26,3=0.000000
L 0.87006565 -1.68329862 0.87240059 -1.67430059 2 P 0 ;0,1,2=26,3=0.000000
L 0.87240059 -1.67430059 0.87706624 -1.66830187 2 P 0 ;0,1,2=26,3=0.000000
L 0.87706624 -1.66830187 0.88523327 -1.6638 2 P 0 ;0,1,2=26,3=0.000000
L 0.88523327 -1.6638 0.91673297 -1.6638 2 P 0 ;0,1,2=26,3=0.000000
L 0.91673297 -1.6638 0.91673297 -1.7538 2 P 0 ;0,1,2=26,3=0.000000
L 0.91673297 -1.7538 0.87823268 -1.7538 2 P 0 ;0,1,2=26,3=0.000000
L 0.87823268 -1.7538 0.87006565 -1.74780138 2 P 0 ;0,1,2=26,3=0.000000
L 0.87006565 -1.74780138 0.8653999 -1.73880049 2 P 0 ;0,1,2=26,3=0.000000
L 0.8653999 -1.73880049 0.86306713 -1.7283 2 P 0 ;0,1,2=26,3=0.000000
L 0.86306713 -1.7283 0.8653999 -1.71780226 2 P 0 ;0,1,2=26,3=0.000000
L 0.8653999 -1.71780226 0.87240059 -1.70880138 2 P 0 ;0,1,2=26,3=0.000000
L 0.87240059 -1.70880138 0.88056762 -1.70579931 2 P 0 ;0,1,2=26,3=0.000000
L 0.88056762 -1.70579931 0.91673297 -1.70579931 2 P 0 ;0,1,2=26,3=0.000000
L 0.79990108 -1.7538 0.80923455 -1.75230039 2 P 0 ;0,1,2=26,3=0.000000
L 0.80923455 -1.75230039 0.81739951 -1.74630167 2 P 0 ;0,1,2=26,3=0.000000
L 0.81739951 -1.74630167 0.8244002 -1.73730079 2 P 0 ;0,1,2=26,3=0.000000
L 0.8244002 -1.73730079 0.82906791 -1.7268003 2 P 0 ;0,1,2=26,3=0.000000
L 0.82906791 -1.7268003 0.83140079 -1.7148001 2 P 0 ;0,1,2=26,3=0.000000
L 0.83140079 -1.7148001 0.83140079 -1.7028 2 P 0 ;0,1,2=26,3=0.000000
L 0.83140079 -1.7028 0.82906791 -1.6907998 2 P 0 ;0,1,2=26,3=0.000000
L 0.82906791 -1.6907998 0.8244002 -1.68029931 2 P 0 ;0,1,2=26,3=0.000000
L 0.8244002 -1.68029931 0.81739951 -1.67130118 2 P 0 ;0,1,2=26,3=0.000000
L 0.81739951 -1.67130118 0.80923455 -1.6652997 2 P 0 ;0,1,2=26,3=0.000000
L 0.80923455 -1.6652997 0.79990108 -1.6638 2 P 0 ;0,1,2=26,3=0.000000
L 0.79990108 -1.6638 0.79056762 -1.6652997 2 P 0 ;0,1,2=26,3=0.000000
L 0.79056762 -1.6652997 0.78240059 -1.67130118 2 P 0 ;0,1,2=26,3=0.000000
L 0.78240059 -1.67130118 0.7753999 -1.68029931 2 P 0 ;0,1,2=26,3=0.000000
L 0.7753999 -1.68029931 0.77073219 -1.6907998 2 P 0 ;0,1,2=26,3=0.000000
L 0.77073219 -1.6907998 0.76839931 -1.7028 2 P 0 ;0,1,2=26,3=0.000000
L 0.76839931 -1.7028 0.76839931 -1.7148001 2 P 0 ;0,1,2=26,3=0.000000
L 0.76839931 -1.7148001 0.77073219 -1.7268003 2 P 0 ;0,1,2=26,3=0.000000
L 0.77073219 -1.7268003 0.7753999 -1.73730079 2 P 0 ;0,1,2=26,3=0.000000
L 0.7753999 -1.73730079 0.78240059 -1.74630167 2 P 0 ;0,1,2=26,3=0.000000
L 0.78240059 -1.74630167 0.79056762 -1.75230039 2 P 0 ;0,1,2=26,3=0.000000
L 0.79056762 -1.75230039 0.79990108 -1.7538 2 P 0 ;0,1,2=26,3=0.000000
L 0.70990108 -1.6638 0.70990108 -1.7538 2 P 0 ;0,1,2=26,3=0.000000
L 0.73673297 -1.6638 0.68306713 -1.6638 2 P 0 ;0,1,2=26,3=0.000000
L 0.52406693 -1.78379902 0.51240059 -1.76879951 2 P 0 ;0,1,2=26,3=0.000000
L 0.51240059 -1.76879951 0.50656634 -1.7538 2 P 0 ;0,1,2=26,3=0.000000
L 0.50656634 -1.7538 0.50656634 -1.69380187 2 P 0 ;0,1,2=26,3=0.000000
L 0.50656634 -1.69380187 0.51240059 -1.67879961 2 P 0 ;0,1,2=26,3=0.000000
L 0.51240059 -1.67879961 0.52406693 -1.6638 2 P 0 ;0,1,2=26,3=0.000000
L 3.72973337 -1.97380098 3.76006654 -1.97380098 2 P 0 ;0,2=27,3=0.000000
L 3.06989892 -2.2538 3.06989892 -2.1638 2 P 0 ;0,2=0,3=0.000000
L 3.06989892 -2.1638 3.0558997 -2.18179892 2 P 0 ;0,2=0,3=0.000000
L 3.0558997 -2.2538 3.08389803 -2.2538 2 P 0 ;0,2=0,3=0.000000
L 3.64489892 -2.2538 3.64489892 -2.1638 2 P 0 ;0,2=0,3=0.000000
L 3.64489892 -2.1638 3.6308997 -2.18179892 2 P 0 ;0,2=0,3=0.000000
L 3.6308997 -2.2538 3.65889803 -2.2538 2 P 0 ;0,2=0,3=0.000000
L 0.59099833 -1.36499882 0.5990003 -1.35750039 2 P 0 ;0,2=28,3=0.000000
L 0.5990003 -1.35750039 0.60499902 -1.34500315 2 P 0 ;0,2=28,3=0.000000
L 0.60499902 -1.34500315 0.60900187 -1.32749764 2 P 0 ;0,2=28,3=0.000000
L 0.60900187 -1.32749764 0.60499902 -1.31250089 2 P 0 ;0,2=28,3=0.000000
L 0.60499902 -1.31250089 0.59700079 -1.30250305 2 P 0 ;0,2=28,3=0.000000
L 0.59700079 -1.30250305 0.5830001 -1.295 2 P 0 ;0,2=28,3=0.000000
L 0.5830001 -1.295 0.52900059 -1.295 2 P 0 ;0,2=28,3=0.000000
L 0.52900059 -1.295 0.52900059 -1.445 2 P 0 ;0,2=28,3=0.000000
L 0.52900059 -1.445 0.59500118 -1.445 2 P 0 ;0,2=28,3=0.000000
L 0.59500118 -1.445 0.60900187 -1.43500217 2 P 0 ;0,2=28,3=0.000000
L 0.60900187 -1.43500217 0.6170001 -1.42000079 2 P 0 ;0,2=28,3=0.000000
L 0.6170001 -1.42000079 0.62099931 -1.4025 2 P 0 ;0,2=28,3=0.000000
L 0.62099931 -1.4025 0.6170001 -1.38500374 2 P 0 ;0,2=28,3=0.000000
L 0.6170001 -1.38500374 0.60499902 -1.37000236 2 P 0 ;0,2=28,3=0.000000
L 0.60499902 -1.37000236 0.59099833 -1.36499882 2 P 0 ;0,2=28,3=0.000000
L 0.59099833 -1.36499882 0.52900059 -1.36499882 2 P 0 ;0,2=28,3=0.000000
L 0.77100138 -1.445 0.77100138 -1.34500315 2 P 0 ;0,2=28,3=0.000000
L 0.77100138 -1.36249941 0.76299951 -1.35250148 2 P 0 ;0,2=28,3=0.000000
L 0.76299951 -1.35250148 0.75099833 -1.34750256 2 P 0 ;0,2=28,3=0.000000
L 0.75099833 -1.34750256 0.73700138 -1.34500315 2 P 0 ;0,2=28,3=0.000000
L 0.73700138 -1.34500315 0.72300069 -1.35000207 2 P 0 ;0,2=28,3=0.000000
L 0.72300069 -1.35000207 0.71099961 -1.3599999 2 P 0 ;0,2=28,3=0.000000
L 0.71099961 -1.3599999 0.70299764 -1.37500128 2 P 0 ;0,2=28,3=0.000000
L 0.70299764 -1.37500128 0.69899852 -1.39500157 2 P 0 ;0,2=28,3=0.000000
L 0.69899852 -1.39500157 0.70299764 -1.41500187 2 P 0 ;0,2=28,3=0.000000
L 0.70299764 -1.41500187 0.71099961 -1.43000325 2 P 0 ;0,2=28,3=0.000000
L 0.71099961 -1.43000325 0.72300069 -1.44000108 2 P 0 ;0,2=28,3=0.000000
L 0.72300069 -1.44000108 0.73700138 -1.445 2 P 0 ;0,2=28,3=0.000000
L 0.73700138 -1.445 0.75099833 -1.44250059 2 P 0 ;0,2=28,3=0.000000
L 0.75099833 -1.44250059 0.76299951 -1.43500217 2 P 0 ;0,2=28,3=0.000000
L 0.76299951 -1.43500217 0.77100138 -1.42500433 2 P 0 ;0,2=28,3=0.000000
L 0.86700039 -1.445 0.86700039 -1.34500315 2 P 0 ;0,2=28,3=0.000000
L 0.86700039 -1.36499882 0.87699833 -1.35500098 2 P 0 ;0,2=28,3=0.000000
L 0.87699833 -1.35500098 0.8869998 -1.34750256 2 P 0 ;0,2=28,3=0.000000
L 0.8869998 -1.34750256 0.90100049 -1.34500315 2 P 0 ;0,2=28,3=0.000000
L 0.90100049 -1.34500315 0.91099833 -1.34750256 2 P 0 ;0,2=28,3=0.000000
L 0.91099833 -1.34750256 0.92299951 -1.35500098 2 P 0 ;0,2=28,3=0.000000
L 1.02700039 -1.445 1.02700039 -1.34500315 2 P 0 ;0,2=28,3=0.000000
L 1.02700039 -1.36499882 1.03699833 -1.35500098 2 P 0 ;0,2=28,3=0.000000
L 1.03699833 -1.35500098 1.0469998 -1.34750256 2 P 0 ;0,2=28,3=0.000000
L 1.0469998 -1.34750256 1.06100049 -1.34500315 2 P 0 ;0,2=28,3=0.000000
L 1.06100049 -1.34500315 1.07099833 -1.34750256 2 P 0 ;0,2=28,3=0.000000
L 1.07099833 -1.34750256 1.08299951 -1.35500098 2 P 0 ;0,2=28,3=0.000000
L 1.18500089 -1.37750069 1.24900187 -1.37750069 2 P 0 ;0,2=28,3=0.000000
L 1.24900187 -1.37750069 1.24299951 -1.3599999 2 P 0 ;0,2=28,3=0.000000
L 1.24299951 -1.3599999 1.23300157 -1.35000207 2 P 0 ;0,2=28,3=0.000000
L 1.23300157 -1.35000207 1.21900089 -1.34500315 2 P 0 ;0,2=28,3=0.000000
L 1.21900089 -1.34500315 1.2050003 -1.34750256 2 P 0 ;0,2=28,3=0.000000
L 1.2050003 -1.34750256 1.19299911 -1.35500098 2 P 0 ;0,2=28,3=0.000000
L 1.19299911 -1.35500098 1.18500089 -1.37250177 2 P 0 ;0,2=28,3=0.000000
L 1.18500089 -1.37250177 1.18099803 -1.38750315 2 P 0 ;0,2=28,3=0.000000
L 1.18099803 -1.38750315 1.18099803 -1.4025 2 P 0 ;0,2=28,3=0.000000
L 1.18099803 -1.4025 1.18500089 -1.41750138 2 P 0 ;0,2=28,3=0.000000
L 1.18500089 -1.41750138 1.19499872 -1.43250276 2 P 0 ;0,2=28,3=0.000000
L 1.19499872 -1.43250276 1.2069998 -1.44250059 2 P 0 ;0,2=28,3=0.000000
L 1.2069998 -1.44250059 1.22100049 -1.445 2 P 0 ;0,2=28,3=0.000000
L 1.22100049 -1.445 1.23500118 -1.44000108 2 P 0 ;0,2=28,3=0.000000
L 1.23500118 -1.44000108 1.24900187 -1.42500433 2 P 0 ;0,2=28,3=0.000000
L 1.37499813 -1.445 1.37499813 -1.295 2 P 0 ;0,2=28,3=0.000000
L 1.50500089 -1.37750069 1.56900187 -1.37750069 2 P 0 ;0,2=28,3=0.000000
L 1.56900187 -1.37750069 1.56299951 -1.3599999 2 P 0 ;0,2=28,3=0.000000
L 1.56299951 -1.3599999 1.55300157 -1.35000207 2 P 0 ;0,2=28,3=0.000000
L 1.55300157 -1.35000207 1.53900089 -1.34500315 2 P 0 ;0,2=28,3=0.000000
L 1.53900089 -1.34500315 1.5250003 -1.34750256 2 P 0 ;0,2=28,3=0.000000
L 1.5250003 -1.34750256 1.51299911 -1.35500098 2 P 0 ;0,2=28,3=0.000000
L 1.51299911 -1.35500098 1.50500089 -1.37250177 2 P 0 ;0,2=28,3=0.000000
L 1.50500089 -1.37250177 1.50099803 -1.38750315 2 P 0 ;0,2=28,3=0.000000
L 1.50099803 -1.38750315 1.50099803 -1.4025 2 P 0 ;0,2=28,3=0.000000
L 1.50099803 -1.4025 1.50500089 -1.41750138 2 P 0 ;0,2=28,3=0.000000
L 1.50500089 -1.41750138 1.51499872 -1.43250276 2 P 0 ;0,2=28,3=0.000000
L 1.51499872 -1.43250276 1.5269998 -1.44250059 2 P 0 ;0,2=28,3=0.000000
L 1.5269998 -1.44250059 1.54100049 -1.445 2 P 0 ;0,2=28,3=0.000000
L 1.54100049 -1.445 1.55500118 -1.44000108 2 P 0 ;0,2=28,3=0.000000
L 1.55500118 -1.44000108 1.56900187 -1.42500433 2 P 0 ;0,2=28,3=0.000000
L 1.6529998 -1.48999951 1.66500089 -1.49499843 2 P 0 ;0,2=28,3=0.000000
L 1.66500089 -1.49499843 1.68100108 -1.48999951 2 P 0 ;0,2=28,3=0.000000
L 1.68100108 -1.48999951 1.69099902 -1.48000167 2 P 0 ;0,2=28,3=0.000000
L 1.69099902 -1.48000167 1.69900089 -1.4674997 2 P 0 ;0,2=28,3=0.000000
L 1.69900089 -1.4674997 1.71099833 -1.42750374 2 P 0 ;0,2=28,3=0.000000
L 1.71099833 -1.42750374 1.7370001 -1.34500315 2 P 0 ;0,2=28,3=0.000000
L 1.67299911 -1.34500315 1.71099833 -1.42750374 2 P 0 ;0,2=28,3=0.000000
L 1.82500089 -1.37750069 1.88900187 -1.37750069 2 P 0 ;0,2=28,3=0.000000
L 1.88900187 -1.37750069 1.88299951 -1.3599999 2 P 0 ;0,2=28,3=0.000000
L 1.88299951 -1.3599999 1.87300157 -1.35000207 2 P 0 ;0,2=28,3=0.000000
L 1.87300157 -1.35000207 1.85900089 -1.34500315 2 P 0 ;0,2=28,3=0.000000
L 1.85900089 -1.34500315 1.8450003 -1.34750256 2 P 0 ;0,2=28,3=0.000000
L 1.8450003 -1.34750256 1.83299911 -1.35500098 2 P 0 ;0,2=28,3=0.000000
L 1.83299911 -1.35500098 1.82500089 -1.37250177 2 P 0 ;0,2=28,3=0.000000
L 1.82500089 -1.37250177 1.82099803 -1.38750315 2 P 0 ;0,2=28,3=0.000000
L 1.82099803 -1.38750315 1.82099803 -1.4025 2 P 0 ;0,2=28,3=0.000000
L 1.82099803 -1.4025 1.82500089 -1.41750138 2 P 0 ;0,2=28,3=0.000000
L 1.82500089 -1.41750138 1.83499872 -1.43250276 2 P 0 ;0,2=28,3=0.000000
L 1.83499872 -1.43250276 1.8469998 -1.44250059 2 P 0 ;0,2=28,3=0.000000
L 1.8469998 -1.44250059 1.86100049 -1.445 2 P 0 ;0,2=28,3=0.000000
L 1.86100049 -1.445 1.87500118 -1.44000108 2 P 0 ;0,2=28,3=0.000000
L 1.87500118 -1.44000108 1.88900187 -1.42500433 2 P 0 ;0,2=28,3=0.000000
L 2.18699921 -1.37000236 2.22700167 -1.37000236 2 P 0 ;0,2=28,3=0.000000
L 2.22700167 -1.37000236 2.22700167 -1.41500187 2 P 0 ;0,2=28,3=0.000000
L 2.22700167 -1.41500187 2.21500059 -1.43000325 2 P 0 ;0,2=28,3=0.000000
L 2.21500059 -1.43000325 2.2009999 -1.44000108 2 P 0 ;0,2=28,3=0.000000
L 2.2009999 -1.44000108 2.18100049 -1.445 2 P 0 ;0,2=28,3=0.000000
L 2.18100049 -1.445 2.16100108 -1.44000108 2 P 0 ;0,2=28,3=0.000000
L 2.16100108 -1.44000108 2.14700039 -1.43000325 2 P 0 ;0,2=28,3=0.000000
L 2.14700039 -1.43000325 2.13499931 -1.41500187 2 P 0 ;0,2=28,3=0.000000
L 2.13499931 -1.41500187 2.12699734 -1.39750108 2 P 0 ;0,2=28,3=0.000000
L 2.12699734 -1.39750108 2.12299823 -1.37750069 2 P 0 ;0,2=28,3=0.000000
L 2.12299823 -1.37750069 2.12299823 -1.3599999 2 P 0 ;0,2=28,3=0.000000
L 2.12299823 -1.3599999 2.12699734 -1.34500315 2 P 0 ;0,2=28,3=0.000000
L 2.12699734 -1.34500315 2.13499931 -1.32749764 2 P 0 ;0,2=28,3=0.000000
L 2.13499931 -1.32749764 2.14700039 -1.31250089 2 P 0 ;0,2=28,3=0.000000
L 2.14700039 -1.31250089 2.15899783 -1.30250305 2 P 0 ;0,2=28,3=0.000000
L 2.15899783 -1.30250305 2.17499813 -1.295 2 P 0 ;0,2=28,3=0.000000
L 2.17499813 -1.295 2.18899882 -1.295 2 P 0 ;0,2=28,3=0.000000
L 2.18899882 -1.295 2.20499902 -1.29999902 2 P 0 ;0,2=28,3=0.000000
L 2.20499902 -1.29999902 2.2170001 -1.31000138 2 P 0 ;0,2=28,3=0.000000
L 2.29699892 -1.31999931 2.309 -1.30500246 2 P 0 ;0,2=28,3=0.000000
L 2.309 -1.30500246 2.32300069 -1.29749951 2 P 0 ;0,2=28,3=0.000000
L 2.32300069 -1.29749951 2.33900089 -1.295 2 P 0 ;0,2=28,3=0.000000
L 2.33900089 -1.295 2.3590003 -1.29999902 2 P 0 ;0,2=28,3=0.000000
L 2.3590003 -1.29999902 2.37300098 -1.31250089 2 P 0 ;0,2=28,3=0.000000
L 2.37300098 -1.31250089 2.3770001 -1.32749764 2 P 0 ;0,2=28,3=0.000000
L 2.3770001 -1.32749764 2.37500059 -1.34250364 2 P 0 ;0,2=28,3=0.000000
L 2.37500059 -1.34250364 2.36699862 -1.35500098 2 P 0 ;0,2=28,3=0.000000
L 2.36699862 -1.35500098 2.3269998 -1.3800002 2 P 0 ;0,2=28,3=0.000000
L 2.3269998 -1.3800002 2.309 -1.39750108 2 P 0 ;0,2=28,3=0.000000
L 2.309 -1.39750108 2.29699892 -1.42250482 2 P 0 ;0,2=28,3=0.000000
L 2.29699892 -1.42250482 2.2929998 -1.445 2 P 0 ;0,2=28,3=0.000000
L 2.2929998 -1.445 2.3770001 -1.445 2 P 0 ;0,2=28,3=0.000000
L 2.6129998 -1.42500433 2.629 -1.43750167 2 P 0 ;0,2=28,3=0.000000
L 2.629 -1.43750167 2.6469998 -1.445 2 P 0 ;0,2=28,3=0.000000
L 2.6469998 -1.445 2.6630001 -1.445 2 P 0 ;0,2=28,3=0.000000
L 2.6630001 -1.445 2.6790003 -1.43750167 2 P 0 ;0,2=28,3=0.000000
L 2.6790003 -1.43750167 2.69100138 -1.42500433 2 P 0 ;0,2=28,3=0.000000
L 2.69100138 -1.42500433 2.6970001 -1.40749892 2 P 0 ;0,2=28,3=0.000000
L 2.6970001 -1.40749892 2.69300098 -1.39000266 2 P 0 ;0,2=28,3=0.000000
L 2.69300098 -1.39000266 2.68299951 -1.37500128 2 P 0 ;0,2=28,3=0.000000
L 2.68299951 -1.37500128 2.66499961 -1.36499882 2 P 0 ;0,2=28,3=0.000000
L 2.66499961 -1.36499882 2.64100108 -1.3599999 2 P 0 ;0,2=28,3=0.000000
L 2.64100108 -1.3599999 2.62700039 -1.35000207 2 P 0 ;0,2=28,3=0.000000
L 2.62700039 -1.35000207 2.62099803 -1.33250118 2 P 0 ;0,2=28,3=0.000000
L 2.62099803 -1.33250118 2.62500089 -1.31500039 2 P 0 ;0,2=28,3=0.000000
L 2.62500089 -1.31500039 2.63499872 -1.30250305 2 P 0 ;0,2=28,3=0.000000
L 2.63499872 -1.30250305 2.64899941 -1.295 2 P 0 ;0,2=28,3=0.000000
L 2.64899941 -1.295 2.6630001 -1.295 2 P 0 ;0,2=28,3=0.000000
L 2.6630001 -1.295 2.67700079 -1.29999902 2 P 0 ;0,2=28,3=0.000000
L 2.67700079 -1.29999902 2.68900187 -1.31250089 2 P 0 ;0,2=28,3=0.000000
L 2.7729998 -1.445 2.8570001 -1.295 2 P 0 ;0,2=28,3=0.000000
L 2.7729998 -1.295 2.8570001 -1.445 2 P 0 ;0,2=28,3=0.000000
L 2.92299823 -1.445 2.92299823 -1.295 2 P 0 ;0,2=28,3=0.000000
L 2.92299823 -1.295 2.97499813 -1.42000079 2 P 0 ;0,2=28,3=0.000000
L 2.97499813 -1.42000079 3.02700167 -1.295 2 P 0 ;0,2=28,3=0.000000
L 3.02700167 -1.295 3.02700167 -1.445 2 P 0 ;0,2=28,3=0.000000
L 3.09699892 -1.31999931 3.109 -1.30500246 2 P 0 ;0,2=28,3=0.000000
L 3.109 -1.30500246 3.12300069 -1.29749951 2 P 0 ;0,2=28,3=0.000000
L 3.12300069 -1.29749951 3.13900089 -1.295 2 P 0 ;0,2=28,3=0.000000
L 3.13900089 -1.295 3.1590003 -1.29999902 2 P 0 ;0,2=28,3=0.000000
L 3.1590003 -1.29999902 3.17300098 -1.31250089 2 P 0 ;0,2=28,3=0.000000
L 3.17300098 -1.31250089 3.1770001 -1.32749764 2 P 0 ;0,2=28,3=0.000000
L 3.1770001 -1.32749764 3.17500059 -1.34250364 2 P 0 ;0,2=28,3=0.000000
L 3.17500059 -1.34250364 3.16699862 -1.35500098 2 P 0 ;0,2=28,3=0.000000
L 3.16699862 -1.35500098 3.1269998 -1.3800002 2 P 0 ;0,2=28,3=0.000000
L 3.1269998 -1.3800002 3.109 -1.39750108 2 P 0 ;0,2=28,3=0.000000
L 3.109 -1.39750108 3.09699892 -1.42250482 2 P 0 ;0,2=28,3=0.000000
L 3.09699892 -1.42250482 3.0929998 -1.445 2 P 0 ;0,2=28,3=0.000000
L 3.0929998 -1.445 3.1770001 -1.445 2 P 0 ;0,2=28,3=0.000000
L 3.269 -1.39500157 3.3209999 -1.39500157 2 P 0 ;0,2=28,3=0.000000
L 3.41499931 -1.445 3.41499931 -1.295 2 P 0 ;0,2=28,3=0.000000
L 3.41499931 -1.295 3.46499961 -1.295 2 P 0 ;0,2=28,3=0.000000
L 3.46499961 -1.295 3.4809999 -1.30250305 2 P 0 ;0,2=28,3=0.000000
L 3.4809999 -1.30250305 3.49100138 -1.31250089 2 P 0 ;0,2=28,3=0.000000
L 3.49100138 -1.31250089 3.49500059 -1.33250118 2 P 0 ;0,2=28,3=0.000000
L 3.49500059 -1.33250118 3.49100138 -1.35250148 2 P 0 ;0,2=28,3=0.000000
L 3.49100138 -1.35250148 3.4790003 -1.36499882 2 P 0 ;0,2=28,3=0.000000
L 3.4790003 -1.36499882 3.46499961 -1.37250177 2 P 0 ;0,2=28,3=0.000000
L 3.46499961 -1.37250177 3.41499931 -1.37250177 2 P 0 ;0,2=28,3=0.000000
L 3.46499961 -1.37250177 3.49500059 -1.445 2 P 0 ;0,2=28,3=0.000000
L 3.61499813 -1.34500315 3.61499813 -1.445 2 P 0 ;0,2=28,3=0.000000
L 3.61499813 -1.30500246 3.61099902 -1.30250305 2 P 0 ;0,2=28,3=0.000000
L 3.61099902 -1.30250305 3.61099902 -1.29749951 2 P 0 ;0,2=28,3=0.000000
L 3.61099902 -1.29749951 3.61499813 -1.295 2 P 0 ;0,2=28,3=0.000000
L 3.61499813 -1.295 3.61900089 -1.29749951 2 P 0 ;0,2=28,3=0.000000
L 3.61900089 -1.29749951 3.61900089 -1.30250305 2 P 0 ;0,2=28,3=0.000000
L 3.61900089 -1.30250305 3.61499813 -1.30500246 2 P 0 ;0,2=28,3=0.000000
L 3.74500089 -1.42750374 3.75499872 -1.43750167 2 P 0 ;0,2=28,3=0.000000
L 3.75499872 -1.43750167 3.76899941 -1.445 2 P 0 ;0,2=28,3=0.000000
L 3.76899941 -1.445 3.78100049 -1.445 2 P 0 ;0,2=28,3=0.000000
L 3.78100049 -1.445 3.79300157 -1.44000108 2 P 0 ;0,2=28,3=0.000000
L 3.79300157 -1.44000108 3.8009999 -1.43250276 2 P 0 ;0,2=28,3=0.000000
L 3.8009999 -1.43250276 3.80499902 -1.42250482 2 P 0 ;0,2=28,3=0.000000
L 3.80499902 -1.42250482 3.80299951 -1.40749892 2 P 0 ;0,2=28,3=0.000000
L 3.80299951 -1.40749892 3.79500118 -1.40000049 2 P 0 ;0,2=28,3=0.000000
L 3.79500118 -1.40000049 3.75899783 -1.38500374 2 P 0 ;0,2=28,3=0.000000
L 3.75899783 -1.38500374 3.75099961 -1.36749833 2 P 0 ;0,2=28,3=0.000000
L 3.75099961 -1.36749833 3.75499872 -1.35500098 2 P 0 ;0,2=28,3=0.000000
L 3.75499872 -1.35500098 3.76300069 -1.34750256 2 P 0 ;0,2=28,3=0.000000
L 3.76300069 -1.34750256 3.77499813 -1.34500315 2 P 0 ;0,2=28,3=0.000000
L 3.77499813 -1.34500315 3.78699921 -1.34750256 2 P 0 ;0,2=28,3=0.000000
L 3.78699921 -1.34750256 3.7990003 -1.35500098 2 P 0 ;0,2=28,3=0.000000
L 3.90500089 -1.37750069 3.96900187 -1.37750069 2 P 0 ;0,2=28,3=0.000000
L 3.96900187 -1.37750069 3.96299951 -1.3599999 2 P 0 ;0,2=28,3=0.000000
L 3.96299951 -1.3599999 3.95300157 -1.35000207 2 P 0 ;0,2=28,3=0.000000
L 3.95300157 -1.35000207 3.93900089 -1.34500315 2 P 0 ;0,2=28,3=0.000000
L 3.93900089 -1.34500315 3.9250003 -1.34750256 2 P 0 ;0,2=28,3=0.000000
L 3.9250003 -1.34750256 3.91299911 -1.35500098 2 P 0 ;0,2=28,3=0.000000
L 3.91299911 -1.35500098 3.90500089 -1.37250177 2 P 0 ;0,2=28,3=0.000000
L 3.90500089 -1.37250177 3.90099803 -1.38750315 2 P 0 ;0,2=28,3=0.000000
L 3.90099803 -1.38750315 3.90099803 -1.4025 2 P 0 ;0,2=28,3=0.000000
L 3.90099803 -1.4025 3.90500089 -1.41750138 2 P 0 ;0,2=28,3=0.000000
L 3.90500089 -1.41750138 3.91499872 -1.43250276 2 P 0 ;0,2=28,3=0.000000
L 3.91499872 -1.43250276 3.9269998 -1.44250059 2 P 0 ;0,2=28,3=0.000000
L 3.9269998 -1.44250059 3.94100049 -1.445 2 P 0 ;0,2=28,3=0.000000
L 3.94100049 -1.445 3.95500118 -1.44000108 2 P 0 ;0,2=28,3=0.000000
L 3.95500118 -1.44000108 3.96900187 -1.42500433 2 P 0 ;0,2=28,3=0.000000
L 4.06700039 -1.445 4.06700039 -1.34500315 2 P 0 ;0,2=28,3=0.000000
L 4.06700039 -1.36499882 4.07699833 -1.35500098 2 P 0 ;0,2=28,3=0.000000
L 4.07699833 -1.35500098 4.0869998 -1.34750256 2 P 0 ;0,2=28,3=0.000000
L 4.0869998 -1.34750256 4.10100049 -1.34500315 2 P 0 ;0,2=28,3=0.000000
L 4.10100049 -1.34500315 4.11099833 -1.34750256 2 P 0 ;0,2=28,3=0.000000
L 4.11099833 -1.34750256 4.12299951 -1.35500098 2 P 0 ;0,2=28,3=0.000000
L 4.16964783 -2.2038 4.21839813 -2.0478 2 P 0 ;0,2=7,3=0.000000
L 4.21839813 -2.0478 4.26715207 -2.2038 2 P 0 ;0,2=7,3=0.000000
L 4.24959862 -2.14920217 4.18719774 -2.14920217 2 P 0 ;0,2=7,3=0.000000
L 4.37939813 -2.2038 4.37939813 -2.0478 2 P 0 ;0,2=7,3=0.000000
L 4.37939813 -2.0478 4.35599961 -2.07899813 2 P 0 ;0,2=7,3=0.000000
L 4.35599961 -2.2038 4.40279675 -2.2038 2 P 0 ;0,2=7,3=0.000000
L 2.0009002 -0.9538 2.0009002 -0.8038 2 P 0 ;0,2=29,3=0.000000
L 2.0009002 -0.8038 2.04089902 -0.8038 2 P 0 ;0,2=29,3=0.000000
L 2.04089902 -0.8038 2.05689921 -0.81130305 2 P 0 ;0,2=29,3=0.000000
L 2.05689921 -0.81130305 2.0689003 -0.82130089 2 P 0 ;0,2=29,3=0.000000
L 2.0689003 -0.82130089 2.07890187 -0.83629764 2 P 0 ;0,2=29,3=0.000000
L 2.07890187 -0.83629764 2.0869001 -0.85380315 2 P 0 ;0,2=29,3=0.000000
L 2.0869001 -0.85380315 2.0888997 -0.87880236 2 P 0 ;0,2=29,3=0.000000
L 2.0888997 -0.87880236 2.0869001 -0.90380157 2 P 0 ;0,2=29,3=0.000000
L 2.0869001 -0.90380157 2.07890187 -0.92130246 2 P 0 ;0,2=29,3=0.000000
L 2.07890187 -0.92130246 2.0689003 -0.93630374 2 P 0 ;0,2=29,3=0.000000
L 2.0689003 -0.93630374 2.05689921 -0.94630167 2 P 0 ;0,2=29,3=0.000000
L 2.05689921 -0.94630167 2.04089902 -0.9538 2 P 0 ;0,2=29,3=0.000000
L 2.04089902 -0.9538 2.0009002 -0.9538 2 P 0 ;0,2=29,3=0.000000
L 2.15489783 -0.9538 2.20489813 -0.8038 2 P 0 ;0,2=29,3=0.000000
L 2.20489813 -0.8038 2.25490207 -0.9538 2 P 0 ;0,2=29,3=0.000000
L 2.23689862 -0.90130207 2.17289764 -0.90130207 2 P 0 ;0,2=29,3=0.000000
L 2.36489813 -0.8038 2.36489813 -0.9538 2 P 0 ;0,2=29,3=0.000000
L 2.31890059 -0.8038 2.41089931 -0.8038 2 P 0 ;0,2=29,3=0.000000
L 2.56490059 -0.9538 2.48489931 -0.9538 2 P 0 ;0,2=29,3=0.000000
L 2.48489931 -0.9538 2.48489931 -0.8038 2 P 0 ;0,2=29,3=0.000000
L 2.48489931 -0.8038 2.56490059 -0.8038 2 P 0 ;0,2=29,3=0.000000
L 2.5329001 -0.87629833 2.48489931 -0.87629833 2 P 0 ;0,2=29,3=0.000000
L 2.84489813 -0.9538 2.82889783 -0.95130059 2 P 0 ;0,2=29,3=0.000000
L 2.82889783 -0.95130059 2.81490089 -0.94130276 2 P 0 ;0,2=29,3=0.000000
L 2.81490089 -0.94130276 2.8028998 -0.92630138 2 P 0 ;0,2=29,3=0.000000
L 2.8028998 -0.92630138 2.79489783 -0.90880049 2 P 0 ;0,2=29,3=0.000000
L 2.79489783 -0.90880049 2.79089862 -0.8888002 2 P 0 ;0,2=29,3=0.000000
L 2.79089862 -0.8888002 2.79089862 -0.8687999 2 P 0 ;0,2=29,3=0.000000
L 2.79089862 -0.8687999 2.79489783 -0.84879961 2 P 0 ;0,2=29,3=0.000000
L 2.79489783 -0.84879961 2.8028998 -0.83129872 2 P 0 ;0,2=29,3=0.000000
L 2.8028998 -0.83129872 2.81490089 -0.81630197 2 P 0 ;0,2=29,3=0.000000
L 2.81490089 -0.81630197 2.82889783 -0.80629951 2 P 0 ;0,2=29,3=0.000000
L 2.82889783 -0.80629951 2.84489813 -0.8038 2 P 0 ;0,2=29,3=0.000000
L 2.84489813 -0.8038 2.86089833 -0.80629951 2 P 0 ;0,2=29,3=0.000000
L 2.86089833 -0.80629951 2.87489902 -0.81630197 2 P 0 ;0,2=29,3=0.000000
L 2.87489902 -0.81630197 2.8869001 -0.83129872 2 P 0 ;0,2=29,3=0.000000
L 2.8869001 -0.83129872 2.89490207 -0.84879961 2 P 0 ;0,2=29,3=0.000000
L 2.89490207 -0.84879961 2.89890128 -0.8687999 2 P 0 ;0,2=29,3=0.000000
L 2.89890128 -0.8687999 2.89890128 -0.8888002 2 P 0 ;0,2=29,3=0.000000
L 2.89890128 -0.8888002 2.89490207 -0.90880049 2 P 0 ;0,2=29,3=0.000000
L 2.89490207 -0.90880049 2.8869001 -0.92630138 2 P 0 ;0,2=29,3=0.000000
L 2.8869001 -0.92630138 2.87489902 -0.94130276 2 P 0 ;0,2=29,3=0.000000
L 2.87489902 -0.94130276 2.86089833 -0.95130059 2 P 0 ;0,2=29,3=0.000000
L 2.86089833 -0.95130059 2.84489813 -0.9538 2 P 0 ;0,2=29,3=0.000000
L 3.0488997 -0.81630197 3.03689862 -0.80879902 2 P 0 ;0,2=29,3=0.000000
L 3.03689862 -0.80879902 3.02290157 -0.8038 2 P 0 ;0,2=29,3=0.000000
L 3.02290157 -0.8038 3.00690138 -0.8038 2 P 0 ;0,2=29,3=0.000000
L 3.00690138 -0.8038 2.98889783 -0.81130305 2 P 0 ;0,2=29,3=0.000000
L 2.98889783 -0.81130305 2.97490089 -0.82380039 2 P 0 ;0,2=29,3=0.000000
L 2.97490089 -0.82380039 2.96489931 -0.83880177 2 P 0 ;0,2=29,3=0.000000
L 2.96489931 -0.83880177 2.95689734 -0.86380098 2 P 0 ;0,2=29,3=0.000000
L 2.95689734 -0.86380098 2.95489783 -0.88630069 2 P 0 ;0,2=29,3=0.000000
L 2.95489783 -0.88630069 2.95890059 -0.90880049 2 P 0 ;0,2=29,3=0.000000
L 2.95890059 -0.90880049 2.96489931 -0.92380187 2 P 0 ;0,2=29,3=0.000000
L 2.96489931 -0.92380187 2.97690039 -0.93880325 2 P 0 ;0,2=29,3=0.000000
L 2.97690039 -0.93880325 2.99090108 -0.94880108 2 P 0 ;0,2=29,3=0.000000
L 2.99090108 -0.94880108 3.00489813 -0.9538 2 P 0 ;0,2=29,3=0.000000
L 3.00489813 -0.9538 3.01889882 -0.9538 2 P 0 ;0,2=29,3=0.000000
L 3.01889882 -0.9538 3.03289951 -0.94880108 2 P 0 ;0,2=29,3=0.000000
L 3.03289951 -0.94880108 3.04490059 -0.94130276 2 P 0 ;0,2=29,3=0.000000
L 3.04490059 -0.94130276 3.05490207 -0.93130482 2 P 0 ;0,2=29,3=0.000000
L 3.16489813 -0.8038 3.16489813 -0.9538 2 P 0 ;0,2=29,3=0.000000
L 3.11890059 -0.8038 3.21089931 -0.8038 2 P 0 ;0,2=29,3=0.000000
L 3.28889852 -0.95879892 3.36090138 -0.8038 2 P 0 ;0,2=29,3=0.000000
L 3.44689892 -0.82879931 3.4589 -0.81380246 2 P 0 ;0,2=29,3=0.000000
L 3.4589 -0.81380246 3.47290069 -0.80629951 2 P 0 ;0,2=29,3=0.000000
L 3.47290069 -0.80629951 3.48890089 -0.8038 2 P 0 ;0,2=29,3=0.000000
L 3.48890089 -0.8038 3.5089003 -0.80879902 2 P 0 ;0,2=29,3=0.000000
L 3.5089003 -0.80879902 3.52290098 -0.82130089 2 P 0 ;0,2=29,3=0.000000
L 3.52290098 -0.82130089 3.5269001 -0.83629764 2 P 0 ;0,2=29,3=0.000000
L 3.5269001 -0.83629764 3.52490059 -0.85130364 2 P 0 ;0,2=29,3=0.000000
L 3.52490059 -0.85130364 3.51689862 -0.86380098 2 P 0 ;0,2=29,3=0.000000
L 3.51689862 -0.86380098 3.4768998 -0.8888002 2 P 0 ;0,2=29,3=0.000000
L 3.4768998 -0.8888002 3.4589 -0.90630108 2 P 0 ;0,2=29,3=0.000000
L 3.4589 -0.90630108 3.44689892 -0.93130482 2 P 0 ;0,2=29,3=0.000000
L 3.44689892 -0.93130482 3.4428998 -0.9538 2 P 0 ;0,2=29,3=0.000000
L 3.4428998 -0.9538 3.5269001 -0.9538 2 P 0 ;0,2=29,3=0.000000
L 3.64089902 -0.9538 3.64489813 -0.92130246 2 P 0 ;0,2=29,3=0.000000
L 3.64489813 -0.92130246 3.65090049 -0.89380374 2 P 0 ;0,2=29,3=0.000000
L 3.65090049 -0.89380374 3.65889882 -0.8687999 2 P 0 ;0,2=29,3=0.000000
L 3.65889882 -0.8687999 3.6689003 -0.84130118 2 P 0 ;0,2=29,3=0.000000
L 3.6689003 -0.84130118 3.68490059 -0.8038 2 P 0 ;0,2=29,3=0.000000
L 3.68490059 -0.8038 3.60489931 -0.8038 2 P 0 ;0,2=29,3=0.000000
L 3.76889852 -0.95879892 3.84090138 -0.8038 2 P 0 ;0,2=29,3=0.000000
L 3.92689892 -0.82879931 3.9389 -0.81380246 2 P 0 ;0,2=29,3=0.000000
L 3.9389 -0.81380246 3.95290069 -0.80629951 2 P 0 ;0,2=29,3=0.000000
L 3.95290069 -0.80629951 3.96890089 -0.8038 2 P 0 ;0,2=29,3=0.000000
L 3.96890089 -0.8038 3.9889003 -0.80879902 2 P 0 ;0,2=29,3=0.000000
L 3.9889003 -0.80879902 4.00290098 -0.82130089 2 P 0 ;0,2=29,3=0.000000
L 4.00290098 -0.82130089 4.0069001 -0.83629764 2 P 0 ;0,2=29,3=0.000000
L 4.0069001 -0.83629764 4.00490059 -0.85130364 2 P 0 ;0,2=29,3=0.000000
L 4.00490059 -0.85130364 3.99689862 -0.86380098 2 P 0 ;0,2=29,3=0.000000
L 3.99689862 -0.86380098 3.9568998 -0.8888002 2 P 0 ;0,2=29,3=0.000000
L 3.9568998 -0.8888002 3.9389 -0.90630108 2 P 0 ;0,2=29,3=0.000000
L 3.9389 -0.90630108 3.92689892 -0.93130482 2 P 0 ;0,2=29,3=0.000000
L 3.92689892 -0.93130482 3.9228998 -0.9538 2 P 0 ;0,2=29,3=0.000000
L 3.9228998 -0.9538 4.0069001 -0.9538 2 P 0 ;0,2=29,3=0.000000
L 4.12489813 -0.8038 4.10889783 -0.80879902 2 P 0 ;0,2=29,3=0.000000
L 4.10889783 -0.80879902 4.09690039 -0.82130089 2 P 0 ;0,2=29,3=0.000000
L 4.09690039 -0.82130089 4.08889852 -0.83629764 2 P 0 ;0,2=29,3=0.000000
L 4.08889852 -0.83629764 4.0828998 -0.85630256 2 P 0 ;0,2=29,3=0.000000
L 4.0828998 -0.85630256 4.0809002 -0.87880236 2 P 0 ;0,2=29,3=0.000000
L 4.0809002 -0.87880236 4.0828998 -0.90130207 2 P 0 ;0,2=29,3=0.000000
L 4.0828998 -0.90130207 4.08889852 -0.92130246 2 P 0 ;0,2=29,3=0.000000
L 4.08889852 -0.92130246 4.09690039 -0.93630374 2 P 0 ;0,2=29,3=0.000000
L 4.09690039 -0.93630374 4.10889783 -0.94880108 2 P 0 ;0,2=29,3=0.000000
L 4.10889783 -0.94880108 4.12489813 -0.9538 2 P 0 ;0,2=29,3=0.000000
L 4.12489813 -0.9538 4.14089833 -0.94880108 2 P 0 ;0,2=29,3=0.000000
L 4.14089833 -0.94880108 4.15289951 -0.93630374 2 P 0 ;0,2=29,3=0.000000
L 4.15289951 -0.93630374 4.16090138 -0.92130246 2 P 0 ;0,2=29,3=0.000000
L 4.16090138 -0.92130246 4.1669001 -0.90130207 2 P 0 ;0,2=29,3=0.000000
L 4.1669001 -0.90130207 4.1688997 -0.87880236 2 P 0 ;0,2=29,3=0.000000
L 4.1688997 -0.87880236 4.1669001 -0.85630256 2 P 0 ;0,2=29,3=0.000000
L 4.1669001 -0.85630256 4.16090138 -0.83629764 2 P 0 ;0,2=29,3=0.000000
L 4.16090138 -0.83629764 4.15289951 -0.82130089 2 P 0 ;0,2=29,3=0.000000
L 4.15289951 -0.82130089 4.14089833 -0.80879902 2 P 0 ;0,2=29,3=0.000000
L 4.14089833 -0.80879902 4.12489813 -0.8038 2 P 0 ;0,2=29,3=0.000000
L 4.28489813 -0.9538 4.28489813 -0.8038 2 P 0 ;0,2=29,3=0.000000
L 4.28489813 -0.8038 4.26089961 -0.83379823 2 P 0 ;0,2=29,3=0.000000
L 4.26089961 -0.9538 4.30889665 -0.9538 2 P 0 ;0,2=29,3=0.000000
L 4.44089902 -0.9538 4.44489813 -0.92130246 2 P 0 ;0,2=29,3=0.000000
L 4.44489813 -0.92130246 4.45090049 -0.89380374 2 P 0 ;0,2=29,3=0.000000
L 4.45090049 -0.89380374 4.45889882 -0.8687999 2 P 0 ;0,2=29,3=0.000000
L 4.45889882 -0.8687999 4.4689003 -0.84130118 2 P 0 ;0,2=29,3=0.000000
L 4.4689003 -0.84130118 4.48490059 -0.8038 2 P 0 ;0,2=29,3=0.000000
L 4.48490059 -0.8038 4.40489931 -0.8038 2 P 0 ;0,2=29,3=0.000000
L 0.53206683 -0.415 0.53206683 -0.39 2 P 0 ;0,1,2=30,3=0.000000
L 0.53206683 -0.39 0.52193327 -0.39 2 P 0 ;0,1,2=30,3=0.000000
L 0.52566673 -0.40208307 0.53206683 -0.40208307 2 P 0 ;0,1,2=30,3=0.000000
L 0.50886673 -0.415 0.50886673 -0.39 2 P 0 ;0,1,2=30,3=0.000000
L 0.50886673 -0.39 0.50353346 -0.39 2 P 0 ;0,1,2=30,3=0.000000
L 0.50353346 -0.39 0.5014001 -0.39125059 2 P 0 ;0,1,2=30,3=0.000000
L 0.5014001 -0.39125059 0.4998 -0.39291683 2 P 0 ;0,1,2=30,3=0.000000
L 0.4998 -0.39291683 0.49846644 -0.39541634 2 P 0 ;0,1,2=30,3=0.000000
L 0.49846644 -0.39541634 0.4974 -0.39833386 2 P 0 ;0,1,2=30,3=0.000000
L 0.4974 -0.39833386 0.49713337 -0.40250039 2 P 0 ;0,1,2=30,3=0.000000
L 0.49713337 -0.40250039 0.4974 -0.40666693 2 P 0 ;0,1,2=30,3=0.000000
L 0.4974 -0.40666693 0.49846644 -0.40958376 2 P 0 ;0,1,2=30,3=0.000000
L 0.49846644 -0.40958376 0.4998 -0.41208396 2 P 0 ;0,1,2=30,3=0.000000
L 0.4998 -0.41208396 0.5014001 -0.4137503 2 P 0 ;0,1,2=30,3=0.000000
L 0.5014001 -0.4137503 0.50353346 -0.415 2 P 0 ;0,1,2=30,3=0.000000
L 0.50353346 -0.415 0.50886673 -0.415 2 P 0 ;0,1,2=30,3=0.000000
L 0.48486673 -0.41000039 0.48326703 -0.41291713 2 P 0 ;0,1,2=30,3=0.000000
L 0.48326703 -0.41291713 0.48113366 -0.41458346 2 P 0 ;0,1,2=30,3=0.000000
L 0.48113366 -0.41458346 0.47873317 -0.415 2 P 0 ;0,1,2=30,3=0.000000
L 0.47873317 -0.415 0.4765998 -0.41458346 2 P 0 ;0,1,2=30,3=0.000000
L 0.4765998 -0.41458346 0.47446644 -0.41250059 2 P 0 ;0,1,2=30,3=0.000000
L 0.47446644 -0.41250059 0.47313337 -0.41000039 2 P 0 ;0,1,2=30,3=0.000000
L 0.47313337 -0.41000039 0.47286683 -0.4075001 2 P 0 ;0,1,2=30,3=0.000000
L 0.47286683 -0.4075001 0.4734 -0.40458406 2 P 0 ;0,1,2=30,3=0.000000
L 0.4734 -0.40458406 0.47526673 -0.40250039 2 P 0 ;0,1,2=30,3=0.000000
L 0.47526673 -0.40250039 0.47713356 -0.40166654 2 P 0 ;0,1,2=30,3=0.000000
L 0.47713356 -0.40166654 0.47953346 -0.40166654 2 P 0 ;0,1,2=30,3=0.000000
L 0.47713356 -0.40166654 0.47553337 -0.40041673 2 P 0 ;0,1,2=30,3=0.000000
L 0.47553337 -0.40041673 0.4741999 -0.39833386 2 P 0 ;0,1,2=30,3=0.000000
L 0.4741999 -0.39833386 0.47366663 -0.39583366 2 P 0 ;0,1,2=30,3=0.000000
L 0.47366663 -0.39583366 0.4741999 -0.39333346 2 P 0 ;0,1,2=30,3=0.000000
L 0.4741999 -0.39333346 0.47553337 -0.39125059 2 P 0 ;0,1,2=30,3=0.000000
L 0.47553337 -0.39125059 0.47793337 -0.39 2 P 0 ;0,1,2=30,3=0.000000
L 0.47793337 -0.39 0.48033337 -0.39041663 2 P 0 ;0,1,2=30,3=0.000000
L 0.48033337 -0.39041663 0.48273337 -0.39208366 2 P 0 ;0,1,2=30,3=0.000000
L 12.45206683 -0.19 12.45206683 -0.165 2 P 0 ;0,1,2=31,3=0.000000
L 12.45206683 -0.165 12.44193327 -0.165 2 P 0 ;0,1,2=31,3=0.000000
L 12.44566673 -0.17708307 12.45206683 -0.17708307 2 P 0 ;0,1,2=31,3=0.000000
L 12.42886673 -0.19 12.42886673 -0.165 2 P 0 ;0,1,2=31,3=0.000000
L 12.42886673 -0.165 12.42353346 -0.165 2 P 0 ;0,1,2=31,3=0.000000
L 12.42353346 -0.165 12.4214001 -0.16625059 2 P 0 ;0,1,2=31,3=0.000000
L 12.4214001 -0.16625059 12.4198 -0.16791683 2 P 0 ;0,1,2=31,3=0.000000
L 12.4198 -0.16791683 12.41846644 -0.17041634 2 P 0 ;0,1,2=31,3=0.000000
L 12.41846644 -0.17041634 12.4174 -0.17333386 2 P 0 ;0,1,2=31,3=0.000000
L 12.4174 -0.17333386 12.41713337 -0.17750039 2 P 0 ;0,1,2=31,3=0.000000
L 12.41713337 -0.17750039 12.4174 -0.18166693 2 P 0 ;0,1,2=31,3=0.000000
L 12.4174 -0.18166693 12.41846644 -0.18458376 2 P 0 ;0,1,2=31,3=0.000000
L 12.41846644 -0.18458376 12.4198 -0.18708396 2 P 0 ;0,1,2=31,3=0.000000
L 12.4198 -0.18708396 12.4214001 -0.1887503 2 P 0 ;0,1,2=31,3=0.000000
L 12.4214001 -0.1887503 12.42353346 -0.19 2 P 0 ;0,1,2=31,3=0.000000
L 12.42353346 -0.19 12.42886673 -0.19 2 P 0 ;0,1,2=31,3=0.000000
L 12.3990003 -0.19 12.3990003 -0.165 2 P 0 ;0,1,2=31,3=0.000000
L 12.3990003 -0.165 12.4022001 -0.1699997 2 P 0 ;0,1,2=31,3=0.000000
L 12.4022001 -0.19 12.39580049 -0.19 2 P 0 ;0,1,2=31,3=0.000000
L 0.52706683 6.41 0.52706683 6.435 2 P 0 ;0,1,2=32,3=0.000000
L 0.52706683 6.435 0.51693327 6.435 2 P 0 ;0,1,2=32,3=0.000000
L 0.52066673 6.42291693 0.52706683 6.42291693 2 P 0 ;0,1,2=32,3=0.000000
L 0.50386673 6.41 0.50386673 6.435 2 P 0 ;0,1,2=32,3=0.000000
L 0.50386673 6.435 0.49853346 6.435 2 P 0 ;0,1,2=32,3=0.000000
L 0.49853346 6.435 0.4964001 6.43374941 2 P 0 ;0,1,2=32,3=0.000000
L 0.4964001 6.43374941 0.4948 6.43208317 2 P 0 ;0,1,2=32,3=0.000000
L 0.4948 6.43208317 0.49346644 6.42958366 2 P 0 ;0,1,2=32,3=0.000000
L 0.49346644 6.42958366 0.4924 6.42666614 2 P 0 ;0,1,2=32,3=0.000000
L 0.4924 6.42666614 0.49213337 6.42249961 2 P 0 ;0,1,2=32,3=0.000000
L 0.49213337 6.42249961 0.4924 6.41833307 2 P 0 ;0,1,2=32,3=0.000000
L 0.4924 6.41833307 0.49346644 6.41541624 2 P 0 ;0,1,2=32,3=0.000000
L 0.49346644 6.41541624 0.4948 6.41291604 2 P 0 ;0,1,2=32,3=0.000000
L 0.4948 6.41291604 0.4964001 6.4112497 2 P 0 ;0,1,2=32,3=0.000000
L 0.4964001 6.4112497 0.49853346 6.41 2 P 0 ;0,1,2=32,3=0.000000
L 0.49853346 6.41 0.50386673 6.41 2 P 0 ;0,1,2=32,3=0.000000
L 0.4740003 6.41 0.4740003 6.435 2 P 0 ;0,1,2=32,3=0.000000
L 0.4740003 6.435 0.4772001 6.4300003 2 P 0 ;0,1,2=32,3=0.000000
L 0.4772001 6.41 0.47080049 6.41 2 P 0 ;0,1,2=32,3=0.000000
L 0.4500003 6.435 0.45213366 6.43416683 2 P 0 ;0,1,2=32,3=0.000000
L 0.45213366 6.43416683 0.45373337 6.43208317 2 P 0 ;0,1,2=32,3=0.000000
L 0.45373337 6.43208317 0.4548002 6.42958366 2 P 0 ;0,1,2=32,3=0.000000
L 0.4548002 6.42958366 0.4556001 6.42624951 2 P 0 ;0,1,2=32,3=0.000000
L 0.4556001 6.42624951 0.45586673 6.42249961 2 P 0 ;0,1,2=32,3=0.000000
L 0.45586673 6.42249961 0.4556001 6.41874961 2 P 0 ;0,1,2=32,3=0.000000
L 0.4556001 6.41874961 0.4548002 6.41541624 2 P 0 ;0,1,2=32,3=0.000000
L 0.4548002 6.41541624 0.45373337 6.41291604 2 P 0 ;0,1,2=32,3=0.000000
L 0.45373337 6.41291604 0.45213366 6.41083307 2 P 0 ;0,1,2=32,3=0.000000
L 0.45213366 6.41083307 0.4500003 6.41 2 P 0 ;0,1,2=32,3=0.000000
L 0.4500003 6.41 0.44786693 6.41083307 2 P 0 ;0,1,2=32,3=0.000000
L 0.44786693 6.41083307 0.44626673 6.41291604 2 P 0 ;0,1,2=32,3=0.000000
L 0.44626673 6.41291604 0.4451999 6.41541624 2 P 0 ;0,1,2=32,3=0.000000
L 0.4451999 6.41541624 0.4444 6.41874961 2 P 0 ;0,1,2=32,3=0.000000
L 0.4444 6.41874961 0.44413337 6.42249961 2 P 0 ;0,1,2=32,3=0.000000
L 0.44413337 6.42249961 0.4444 6.42624951 2 P 0 ;0,1,2=32,3=0.000000
L 0.4444 6.42624951 0.4451999 6.42958366 2 P 0 ;0,1,2=32,3=0.000000
L 0.4451999 6.42958366 0.44626673 6.43208317 2 P 0 ;0,1,2=32,3=0.000000
L 0.44626673 6.43208317 0.44786693 6.43416683 2 P 0 ;0,1,2=32,3=0.000000
L 0.44786693 6.43416683 0.4500003 6.435 2 P 0 ;0,1,2=32,3=0.000000
L 12.45706683 6.415 12.45706683 6.44 2 P 0 ;0,1,2=33,3=0.000000
L 12.45706683 6.44 12.44693327 6.44 2 P 0 ;0,1,2=33,3=0.000000
L 12.45066673 6.42791693 12.45706683 6.42791693 2 P 0 ;0,1,2=33,3=0.000000
L 12.43386673 6.415 12.43386673 6.44 2 P 0 ;0,1,2=33,3=0.000000
L 12.43386673 6.44 12.42853346 6.44 2 P 0 ;0,1,2=33,3=0.000000
L 12.42853346 6.44 12.4264001 6.43874941 2 P 0 ;0,1,2=33,3=0.000000
L 12.4264001 6.43874941 12.4248 6.43708317 2 P 0 ;0,1,2=33,3=0.000000
L 12.4248 6.43708317 12.42346644 6.43458366 2 P 0 ;0,1,2=33,3=0.000000
L 12.42346644 6.43458366 12.4224 6.43166614 2 P 0 ;0,1,2=33,3=0.000000
L 12.4224 6.43166614 12.42213337 6.42749961 2 P 0 ;0,1,2=33,3=0.000000
L 12.42213337 6.42749961 12.4224 6.42333307 2 P 0 ;0,1,2=33,3=0.000000
L 12.4224 6.42333307 12.42346644 6.42041624 2 P 0 ;0,1,2=33,3=0.000000
L 12.42346644 6.42041624 12.4248 6.41791604 2 P 0 ;0,1,2=33,3=0.000000
L 12.4248 6.41791604 12.4264001 6.4162497 2 P 0 ;0,1,2=33,3=0.000000
L 12.4264001 6.4162497 12.42853346 6.415 2 P 0 ;0,1,2=33,3=0.000000
L 12.42853346 6.415 12.43386673 6.415 2 P 0 ;0,1,2=33,3=0.000000
L 12.4040003 6.415 12.4040003 6.44 2 P 0 ;0,1,2=33,3=0.000000
L 12.4040003 6.44 12.4072001 6.4350003 2 P 0 ;0,1,2=33,3=0.000000
L 12.4072001 6.415 12.40080049 6.415 2 P 0 ;0,1,2=33,3=0.000000
L 12.38506683 6.43583337 12.38346673 6.43833287 2 P 0 ;0,1,2=33,3=0.000000
L 12.38346673 6.43833287 12.3816 6.43958337 2 P 0 ;0,1,2=33,3=0.000000
L 12.3816 6.43958337 12.37946663 6.44 2 P 0 ;0,1,2=33,3=0.000000
L 12.37946663 6.44 12.3768 6.43916683 2 P 0 ;0,1,2=33,3=0.000000
L 12.3768 6.43916683 12.37493327 6.43708317 2 P 0 ;0,1,2=33,3=0.000000
L 12.37493327 6.43708317 12.3744 6.43458366 2 P 0 ;0,1,2=33,3=0.000000
L 12.3744 6.43458366 12.37466663 6.43208268 2 P 0 ;0,1,2=33,3=0.000000
L 12.37466663 6.43208268 12.37573356 6.4299998 2 P 0 ;0,1,2=33,3=0.000000
L 12.37573356 6.4299998 12.38106673 6.42583327 2 P 0 ;0,1,2=33,3=0.000000
L 12.38106673 6.42583327 12.38346673 6.42291644 2 P 0 ;0,1,2=33,3=0.000000
L 12.38346673 6.42291644 12.38506683 6.41874911 2 P 0 ;0,1,2=33,3=0.000000
L 12.38506683 6.41874911 12.3856001 6.415 2 P 0 ;0,1,2=33,3=0.000000
L 12.3856001 6.415 12.3744 6.415 2 P 0 ;0,1,2=33,3=0.000000
L 0.60566683 5.2537 0.60566683 5.2787 2 P 0 ;0,1,2=34,3=0.000000
L 0.60566683 5.2787 0.59553327 5.2787 2 P 0 ;0,1,2=34,3=0.000000
L 0.59926673 5.26661693 0.60566683 5.26661693 2 P 0 ;0,1,2=34,3=0.000000
L 0.58246673 5.2537 0.58246673 5.2787 2 P 0 ;0,1,2=34,3=0.000000
L 0.58246673 5.2787 0.57713346 5.2787 2 P 0 ;0,1,2=34,3=0.000000
L 0.57713346 5.2787 0.5750001 5.27744941 2 P 0 ;0,1,2=34,3=0.000000
L 0.5750001 5.27744941 0.5734 5.27578317 2 P 0 ;0,1,2=34,3=0.000000
L 0.5734 5.27578317 0.57206644 5.27328366 2 P 0 ;0,1,2=34,3=0.000000
L 0.57206644 5.27328366 0.571 5.27036614 2 P 0 ;0,1,2=34,3=0.000000
L 0.571 5.27036614 0.57073337 5.26619961 2 P 0 ;0,1,2=34,3=0.000000
L 0.57073337 5.26619961 0.571 5.26203307 2 P 0 ;0,1,2=34,3=0.000000
L 0.571 5.26203307 0.57206644 5.25911624 2 P 0 ;0,1,2=34,3=0.000000
L 0.57206644 5.25911624 0.5734 5.25661604 2 P 0 ;0,1,2=34,3=0.000000
L 0.5734 5.25661604 0.5750001 5.2549497 2 P 0 ;0,1,2=34,3=0.000000
L 0.5750001 5.2549497 0.57713346 5.2537 2 P 0 ;0,1,2=34,3=0.000000
L 0.57713346 5.2537 0.58246673 5.2537 2 P 0 ;0,1,2=34,3=0.000000
L 0.5494 5.2537 0.5494 5.2787 2 P 0 ;0,1,2=34,3=0.000000
L 0.5494 5.2787 0.55926703 5.26078327 2 P 0 ;0,1,2=34,3=0.000000
L 0.55926703 5.26078327 0.54593307 5.26078327 2 P 0 ;0,1,2=34,3=0.000000
L 0.95816683 0.1654 0.95816683 0.1904 2 P 0 ;0,1,2=35,3=0.000000
L 0.95816683 0.1904 0.94803327 0.1904 2 P 0 ;0,1,2=35,3=0.000000
L 0.95176673 0.17831693 0.95816683 0.17831693 2 P 0 ;0,1,2=35,3=0.000000
L 0.93496673 0.1654 0.93496673 0.1904 2 P 0 ;0,1,2=35,3=0.000000
L 0.93496673 0.1904 0.92963346 0.1904 2 P 0 ;0,1,2=35,3=0.000000
L 0.92963346 0.1904 0.9275001 0.18914941 2 P 0 ;0,1,2=35,3=0.000000
L 0.9275001 0.18914941 0.9259 0.18748317 2 P 0 ;0,1,2=35,3=0.000000
L 0.9259 0.18748317 0.92456644 0.18498366 2 P 0 ;0,1,2=35,3=0.000000
L 0.92456644 0.18498366 0.9235 0.18206614 2 P 0 ;0,1,2=35,3=0.000000
L 0.9235 0.18206614 0.92323337 0.17789961 2 P 0 ;0,1,2=35,3=0.000000
L 0.92323337 0.17789961 0.9235 0.17373307 2 P 0 ;0,1,2=35,3=0.000000
L 0.9235 0.17373307 0.92456644 0.17081624 2 P 0 ;0,1,2=35,3=0.000000
L 0.92456644 0.17081624 0.9259 0.16831604 2 P 0 ;0,1,2=35,3=0.000000
L 0.9259 0.16831604 0.9275001 0.1666497 2 P 0 ;0,1,2=35,3=0.000000
L 0.9275001 0.1666497 0.92963346 0.1654 2 P 0 ;0,1,2=35,3=0.000000
L 0.92963346 0.1654 0.93496673 0.1654 2 P 0 ;0,1,2=35,3=0.000000
L 0.91096673 0.16914911 0.90936703 0.16706624 2 P 0 ;0,1,2=35,3=0.000000
L 0.90936703 0.16706624 0.9075003 0.16581654 2 P 0 ;0,1,2=35,3=0.000000
L 0.9075003 0.16581654 0.9051003 0.1654 2 P 0 ;0,1,2=35,3=0.000000
L 0.9051003 0.1654 0.9026998 0.16623307 2 P 0 ;0,1,2=35,3=0.000000
L 0.9026998 0.16623307 0.90083356 0.16789941 2 P 0 ;0,1,2=35,3=0.000000
L 0.90083356 0.16789941 0.8995 0.17081624 2 P 0 ;0,1,2=35,3=0.000000
L 0.8995 0.17081624 0.89923337 0.17414961 2 P 0 ;0,1,2=35,3=0.000000
L 0.89923337 0.17414961 0.89976663 0.17748297 2 P 0 ;0,1,2=35,3=0.000000
L 0.89976663 0.17748297 0.9011002 0.17956663 2 P 0 ;0,1,2=35,3=0.000000
L 0.9011002 0.17956663 0.90296693 0.18123297 2 P 0 ;0,1,2=35,3=0.000000
L 0.90296693 0.18123297 0.90483317 0.18164951 2 P 0 ;0,1,2=35,3=0.000000
L 0.90483317 0.18164951 0.9067 0.18123297 2 P 0 ;0,1,2=35,3=0.000000
L 0.9067 0.18123297 0.9090999 0.17956663 2 P 0 ;0,1,2=35,3=0.000000
L 0.9090999 0.17956663 0.9083001 0.1904 2 P 0 ;0,1,2=35,3=0.000000
L 0.9083001 0.1904 0.9011002 0.1904 2 P 0 ;0,1,2=35,3=0.000000
L 12.02706683 0.185 12.02706683 0.21 2 P 0 ;0,1,2=36,3=0.000000
L 12.02706683 0.21 12.01693327 0.21 2 P 0 ;0,1,2=36,3=0.000000
L 12.02066673 0.19791693 12.02706683 0.19791693 2 P 0 ;0,1,2=36,3=0.000000
L 12.00386673 0.185 12.00386673 0.21 2 P 0 ;0,1,2=36,3=0.000000
L 12.00386673 0.21 11.99853346 0.21 2 P 0 ;0,1,2=36,3=0.000000
L 11.99853346 0.21 11.9964001 0.20874941 2 P 0 ;0,1,2=36,3=0.000000
L 11.9964001 0.20874941 11.9948 0.20708317 2 P 0 ;0,1,2=36,3=0.000000
L 11.9948 0.20708317 11.99346644 0.20458366 2 P 0 ;0,1,2=36,3=0.000000
L 11.99346644 0.20458366 11.9924 0.20166614 2 P 0 ;0,1,2=36,3=0.000000
L 11.9924 0.20166614 11.99213337 0.19749961 2 P 0 ;0,1,2=36,3=0.000000
L 11.99213337 0.19749961 11.9924 0.19333307 2 P 0 ;0,1,2=36,3=0.000000
L 11.9924 0.19333307 11.99346644 0.19041624 2 P 0 ;0,1,2=36,3=0.000000
L 11.99346644 0.19041624 11.9948 0.18791604 2 P 0 ;0,1,2=36,3=0.000000
L 11.9948 0.18791604 11.9964001 0.1862497 2 P 0 ;0,1,2=36,3=0.000000
L 11.9964001 0.1862497 11.99853346 0.185 2 P 0 ;0,1,2=36,3=0.000000
L 11.99853346 0.185 12.00386673 0.185 2 P 0 ;0,1,2=36,3=0.000000
L 11.97906683 0.19541594 11.9772001 0.19833346 2 P 0 ;0,1,2=36,3=0.000000
L 11.9772001 0.19833346 11.9756 0.1999998 2 P 0 ;0,1,2=36,3=0.000000
L 11.9756 0.1999998 11.97346663 0.20083297 2 P 0 ;0,1,2=36,3=0.000000
L 11.97346663 0.20083297 11.9715998 0.1999998 2 P 0 ;0,1,2=36,3=0.000000
L 11.9715998 0.1999998 11.97026673 0.19833346 2 P 0 ;0,1,2=36,3=0.000000
L 11.97026673 0.19833346 11.9691999 0.19583327 2 P 0 ;0,1,2=36,3=0.000000
L 11.9691999 0.19583327 11.96893327 0.19291644 2 P 0 ;0,1,2=36,3=0.000000
L 11.96893327 0.19291644 11.9691999 0.19041624 2 P 0 ;0,1,2=36,3=0.000000
L 11.9691999 0.19041624 11.97026673 0.18791604 2 P 0 ;0,1,2=36,3=0.000000
L 11.97026673 0.18791604 11.97186693 0.18583307 2 P 0 ;0,1,2=36,3=0.000000
L 11.97186693 0.18583307 11.97373317 0.185 2 P 0 ;0,1,2=36,3=0.000000
L 11.97373317 0.185 11.97586654 0.18583307 2 P 0 ;0,1,2=36,3=0.000000
L 11.97586654 0.18583307 11.97773337 0.18833258 2 P 0 ;0,1,2=36,3=0.000000
L 11.97773337 0.18833258 11.9788002 0.19208327 2 P 0 ;0,1,2=36,3=0.000000
L 11.9788002 0.19208327 11.97906683 0.1962498 2 P 0 ;0,1,2=36,3=0.000000
L 11.97906683 0.1962498 11.97853366 0.20166614 2 P 0 ;0,1,2=36,3=0.000000
L 11.97853366 0.20166614 11.97773337 0.20458366 2 P 0 ;0,1,2=36,3=0.000000
L 11.97773337 0.20458366 11.9764003 0.2074997 2 P 0 ;0,1,2=36,3=0.000000
L 11.9764003 0.2074997 11.97453346 0.20958337 2 P 0 ;0,1,2=36,3=0.000000
L 11.97453346 0.20958337 11.97266673 0.21 2 P 0 ;0,1,2=36,3=0.000000
L 11.97266673 0.21 11.9708 0.20916683 2 P 0 ;0,1,2=36,3=0.000000
L 11.9708 0.20916683 11.96946644 0.20708317 2 P 0 ;0,1,2=36,3=0.000000
L 9.10566998 4.525 9.12141004 4.525 3 P 0 
L 9.06 4.45266654 9.085 4.45266654 2 P 0 ;0,1,2=37,3=90.000000
L 9.085 4.45266654 9.085 4.45933327 2 P 0 ;0,1,2=37,3=90.000000
L 9.085 4.45933327 9.08374941 4.46146663 2 P 0 ;0,1,2=37,3=90.000000
L 9.08374941 4.46146663 9.08208317 4.4628001 2 P 0 ;0,1,2=37,3=90.000000
L 9.08208317 4.4628001 9.0787498 4.46333337 2 P 0 ;0,1,2=37,3=90.000000
L 9.0787498 4.46333337 9.07541634 4.4628001 2 P 0 ;0,1,2=37,3=90.000000
L 9.07541634 4.4628001 9.07333346 4.4612 2 P 0 ;0,1,2=37,3=90.000000
L 9.07333346 4.4612 9.07208297 4.45933327 2 P 0 ;0,1,2=37,3=90.000000
L 9.07208297 4.45933327 9.07208297 4.45266654 2 P 0 ;0,1,2=37,3=90.000000
L 9.07208297 4.45933327 9.06 4.46333337 2 P 0 ;0,1,2=37,3=90.000000
L 9.06 4.4819997 9.085 4.4819997 2 P 0 ;0,1,2=37,3=90.000000
L 9.085 4.4819997 9.0800003 4.4787999 2 P 0 ;0,1,2=37,3=90.000000
L 9.06 4.4787999 9.06 4.48519951 2 P 0 ;0,1,2=37,3=90.000000
L 9.06374911 4.50013327 9.06166624 4.50173297 2 P 0 ;0,1,2=37,3=90.000000
L 9.06166624 4.50173297 9.06041654 4.5035997 2 P 0 ;0,1,2=37,3=90.000000
L 9.06041654 4.5035997 9.06 4.5059997 2 P 0 ;0,1,2=37,3=90.000000
L 9.06 4.5059997 9.06083307 4.5084002 2 P 0 ;0,1,2=37,3=90.000000
L 9.06083307 4.5084002 9.06249941 4.51026644 2 P 0 ;0,1,2=37,3=90.000000
L 9.06249941 4.51026644 9.06541624 4.5116 2 P 0 ;0,1,2=37,3=90.000000
L 9.06541624 4.5116 9.06874961 4.51186663 2 P 0 ;0,1,2=37,3=90.000000
L 9.06874961 4.51186663 9.07208297 4.51133337 2 P 0 ;0,1,2=37,3=90.000000
L 9.07208297 4.51133337 9.07416663 4.5099998 2 P 0 ;0,1,2=37,3=90.000000
L 9.07416663 4.5099998 9.07583297 4.50813307 2 P 0 ;0,1,2=37,3=90.000000
L 9.07583297 4.50813307 9.07624951 4.50626683 2 P 0 ;0,1,2=37,3=90.000000
L 9.07624951 4.50626683 9.07583297 4.5044 2 P 0 ;0,1,2=37,3=90.000000
L 9.07583297 4.5044 9.07416663 4.5020001 2 P 0 ;0,1,2=37,3=90.000000
L 9.07416663 4.5020001 9.085 4.5027999 2 P 0 ;0,1,2=37,3=90.000000
L 9.085 4.5027999 9.085 4.5099998 2 P 0 ;0,1,2=37,3=90.000000
L 9.07041594 4.52493317 9.07333346 4.5267999 2 P 0 ;0,1,2=37,3=90.000000
L 9.07333346 4.5267999 9.0749998 4.5284 2 P 0 ;0,1,2=37,3=90.000000
L 9.0749998 4.5284 9.07583297 4.53053337 2 P 0 ;0,1,2=37,3=90.000000
L 9.07583297 4.53053337 9.0749998 4.5324002 2 P 0 ;0,1,2=37,3=90.000000
L 9.0749998 4.5324002 9.07333346 4.53373327 2 P 0 ;0,1,2=37,3=90.000000
L 9.07333346 4.53373327 9.07083327 4.5348001 2 P 0 ;0,1,2=37,3=90.000000
L 9.07083327 4.5348001 9.06791644 4.53506673 2 P 0 ;0,1,2=37,3=90.000000
L 9.06791644 4.53506673 9.06541624 4.5348001 2 P 0 ;0,1,2=37,3=90.000000
L 9.06541624 4.5348001 9.06291604 4.53373327 2 P 0 ;0,1,2=37,3=90.000000
L 9.06291604 4.53373327 9.06083307 4.53213307 2 P 0 ;0,1,2=37,3=90.000000
L 9.06083307 4.53213307 9.06 4.53026683 2 P 0 ;0,1,2=37,3=90.000000
L 9.06 4.53026683 9.06083307 4.52813346 2 P 0 ;0,1,2=37,3=90.000000
L 9.06083307 4.52813346 9.06333258 4.52626663 2 P 0 ;0,1,2=37,3=90.000000
L 9.06333258 4.52626663 9.06708327 4.5251998 2 P 0 ;0,1,2=37,3=90.000000
L 9.06708327 4.5251998 9.0712498 4.52493317 2 P 0 ;0,1,2=37,3=90.000000
L 9.0712498 4.52493317 9.07666614 4.52546634 2 P 0 ;0,1,2=37,3=90.000000
L 9.07666614 4.52546634 9.07958366 4.52626663 2 P 0 ;0,1,2=37,3=90.000000
L 9.07958366 4.52626663 9.0824997 4.5275997 2 P 0 ;0,1,2=37,3=90.000000
L 9.0824997 4.5275997 9.08458337 4.52946654 2 P 0 ;0,1,2=37,3=90.000000
L 9.08458337 4.52946654 9.085 4.53133327 2 P 0 ;0,1,2=37,3=90.000000
L 9.085 4.53133327 9.08416683 4.5332 2 P 0 ;0,1,2=37,3=90.000000
L 9.08416683 4.5332 9.08208317 4.53453356 2 P 0 ;0,1,2=37,3=90.000000
L 9.08083337 4.54893317 9.08333287 4.55053327 2 P 0 ;0,1,2=37,3=90.000000
L 9.08333287 4.55053327 9.08458337 4.5524 2 P 0 ;0,1,2=37,3=90.000000
L 9.08458337 4.5524 9.085 4.55453337 2 P 0 ;0,1,2=37,3=90.000000
L 9.085 4.55453337 9.08416683 4.5572 2 P 0 ;0,1,2=37,3=90.000000
L 9.08416683 4.5572 9.08208317 4.55906673 2 P 0 ;0,1,2=37,3=90.000000
L 9.08208317 4.55906673 9.07958366 4.5596 2 P 0 ;0,1,2=37,3=90.000000
L 9.07958366 4.5596 9.07708268 4.55933337 2 P 0 ;0,1,2=37,3=90.000000
L 9.07708268 4.55933337 9.0749998 4.55826644 2 P 0 ;0,1,2=37,3=90.000000
L 9.0749998 4.55826644 9.07083327 4.55293327 2 P 0 ;0,1,2=37,3=90.000000
L 9.07083327 4.55293327 9.06791644 4.55053327 2 P 0 ;0,1,2=37,3=90.000000
L 9.06791644 4.55053327 9.06374911 4.54893317 2 P 0 ;0,1,2=37,3=90.000000
L 9.06374911 4.54893317 9.06 4.5483999 2 P 0 ;0,1,2=37,3=90.000000
L 9.06 4.5483999 9.06 4.5596 2 P 0 ;0,1,2=37,3=90.000000
L 9.15566998 4.525 9.17141004 4.525 3 P 0 
L 9.195 4.45266654 9.22 4.45266654 2 P 0 ;0,1,2=38,3=90.000000
L 9.22 4.45266654 9.22 4.45933327 2 P 0 ;0,1,2=38,3=90.000000
L 9.22 4.45933327 9.21874941 4.46146663 2 P 0 ;0,1,2=38,3=90.000000
L 9.21874941 4.46146663 9.21708317 4.4628001 2 P 0 ;0,1,2=38,3=90.000000
L 9.21708317 4.4628001 9.2137498 4.46333337 2 P 0 ;0,1,2=38,3=90.000000
L 9.2137498 4.46333337 9.21041634 4.4628001 2 P 0 ;0,1,2=38,3=90.000000
L 9.21041634 4.4628001 9.20833346 4.4612 2 P 0 ;0,1,2=38,3=90.000000
L 9.20833346 4.4612 9.20708297 4.45933327 2 P 0 ;0,1,2=38,3=90.000000
L 9.20708297 4.45933327 9.20708297 4.45266654 2 P 0 ;0,1,2=38,3=90.000000
L 9.20708297 4.45933327 9.195 4.46333337 2 P 0 ;0,1,2=38,3=90.000000
L 9.195 4.4819997 9.22 4.4819997 2 P 0 ;0,1,2=38,3=90.000000
L 9.22 4.4819997 9.2150003 4.4787999 2 P 0 ;0,1,2=38,3=90.000000
L 9.195 4.4787999 9.195 4.48519951 2 P 0 ;0,1,2=38,3=90.000000
L 9.19874911 4.50013327 9.19666624 4.50173297 2 P 0 ;0,1,2=38,3=90.000000
L 9.19666624 4.50173297 9.19541654 4.5035997 2 P 0 ;0,1,2=38,3=90.000000
L 9.19541654 4.5035997 9.195 4.5059997 2 P 0 ;0,1,2=38,3=90.000000
L 9.195 4.5059997 9.19583307 4.5084002 2 P 0 ;0,1,2=38,3=90.000000
L 9.19583307 4.5084002 9.19749941 4.51026644 2 P 0 ;0,1,2=38,3=90.000000
L 9.19749941 4.51026644 9.20041624 4.5116 2 P 0 ;0,1,2=38,3=90.000000
L 9.20041624 4.5116 9.20374961 4.51186663 2 P 0 ;0,1,2=38,3=90.000000
L 9.20374961 4.51186663 9.20708297 4.51133337 2 P 0 ;0,1,2=38,3=90.000000
L 9.20708297 4.51133337 9.20916663 4.5099998 2 P 0 ;0,1,2=38,3=90.000000
L 9.20916663 4.5099998 9.21083297 4.50813307 2 P 0 ;0,1,2=38,3=90.000000
L 9.21083297 4.50813307 9.21124951 4.50626683 2 P 0 ;0,1,2=38,3=90.000000
L 9.21124951 4.50626683 9.21083297 4.5044 2 P 0 ;0,1,2=38,3=90.000000
L 9.21083297 4.5044 9.20916663 4.5020001 2 P 0 ;0,1,2=38,3=90.000000
L 9.20916663 4.5020001 9.22 4.5027999 2 P 0 ;0,1,2=38,3=90.000000
L 9.22 4.5027999 9.22 4.5099998 2 P 0 ;0,1,2=38,3=90.000000
L 9.20541594 4.52493317 9.20833346 4.5267999 2 P 0 ;0,1,2=38,3=90.000000
L 9.20833346 4.5267999 9.2099998 4.5284 2 P 0 ;0,1,2=38,3=90.000000
L 9.2099998 4.5284 9.21083297 4.53053337 2 P 0 ;0,1,2=38,3=90.000000
L 9.21083297 4.53053337 9.2099998 4.5324002 2 P 0 ;0,1,2=38,3=90.000000
L 9.2099998 4.5324002 9.20833346 4.53373327 2 P 0 ;0,1,2=38,3=90.000000
L 9.20833346 4.53373327 9.20583327 4.5348001 2 P 0 ;0,1,2=38,3=90.000000
L 9.20583327 4.5348001 9.20291644 4.53506673 2 P 0 ;0,1,2=38,3=90.000000
L 9.20291644 4.53506673 9.20041624 4.5348001 2 P 0 ;0,1,2=38,3=90.000000
L 9.20041624 4.5348001 9.19791604 4.53373327 2 P 0 ;0,1,2=38,3=90.000000
L 9.19791604 4.53373327 9.19583307 4.53213307 2 P 0 ;0,1,2=38,3=90.000000
L 9.19583307 4.53213307 9.195 4.53026683 2 P 0 ;0,1,2=38,3=90.000000
L 9.195 4.53026683 9.19583307 4.52813346 2 P 0 ;0,1,2=38,3=90.000000
L 9.19583307 4.52813346 9.19833258 4.52626663 2 P 0 ;0,1,2=38,3=90.000000
L 9.19833258 4.52626663 9.20208327 4.5251998 2 P 0 ;0,1,2=38,3=90.000000
L 9.20208327 4.5251998 9.2062498 4.52493317 2 P 0 ;0,1,2=38,3=90.000000
L 9.2062498 4.52493317 9.21166614 4.52546634 2 P 0 ;0,1,2=38,3=90.000000
L 9.21166614 4.52546634 9.21458366 4.52626663 2 P 0 ;0,1,2=38,3=90.000000
L 9.21458366 4.52626663 9.2174997 4.5275997 2 P 0 ;0,1,2=38,3=90.000000
L 9.2174997 4.5275997 9.21958337 4.52946654 2 P 0 ;0,1,2=38,3=90.000000
L 9.21958337 4.52946654 9.22 4.53133327 2 P 0 ;0,1,2=38,3=90.000000
L 9.22 4.53133327 9.21916683 4.5332 2 P 0 ;0,1,2=38,3=90.000000
L 9.21916683 4.5332 9.21708317 4.53453356 2 P 0 ;0,1,2=38,3=90.000000
L 9.195 4.5539997 9.22 4.5539997 2 P 0 ;0,1,2=38,3=90.000000
L 9.22 4.5539997 9.2150003 4.5507999 2 P 0 ;0,1,2=38,3=90.000000
L 9.195 4.5507999 9.195 4.55719951 2 P 0 ;0,1,2=38,3=90.000000
L 3.10213002 4.525 3.11786998 4.525 3 P 0 
L 3.055 4.45266654 3.08 4.45266654 2 P 0 ;0,1,2=39,3=90.000000
L 3.08 4.45266654 3.08 4.45933327 2 P 0 ;0,1,2=39,3=90.000000
L 3.08 4.45933327 3.07874941 4.46146663 2 P 0 ;0,1,2=39,3=90.000000
L 3.07874941 4.46146663 3.07708317 4.4628001 2 P 0 ;0,1,2=39,3=90.000000
L 3.07708317 4.4628001 3.0737498 4.46333337 2 P 0 ;0,1,2=39,3=90.000000
L 3.0737498 4.46333337 3.07041634 4.4628001 2 P 0 ;0,1,2=39,3=90.000000
L 3.07041634 4.4628001 3.06833346 4.4612 2 P 0 ;0,1,2=39,3=90.000000
L 3.06833346 4.4612 3.06708297 4.45933327 2 P 0 ;0,1,2=39,3=90.000000
L 3.06708297 4.45933327 3.06708297 4.45266654 2 P 0 ;0,1,2=39,3=90.000000
L 3.06708297 4.45933327 3.055 4.46333337 2 P 0 ;0,1,2=39,3=90.000000
L 3.055 4.4819997 3.08 4.4819997 2 P 0 ;0,1,2=39,3=90.000000
L 3.08 4.4819997 3.0750003 4.4787999 2 P 0 ;0,1,2=39,3=90.000000
L 3.055 4.4787999 3.055 4.48519951 2 P 0 ;0,1,2=39,3=90.000000
L 3.05874911 4.50013327 3.05666624 4.50173297 2 P 0 ;0,1,2=39,3=90.000000
L 3.05666624 4.50173297 3.05541654 4.5035997 2 P 0 ;0,1,2=39,3=90.000000
L 3.05541654 4.5035997 3.055 4.5059997 2 P 0 ;0,1,2=39,3=90.000000
L 3.055 4.5059997 3.05583307 4.5084002 2 P 0 ;0,1,2=39,3=90.000000
L 3.05583307 4.5084002 3.05749941 4.51026644 2 P 0 ;0,1,2=39,3=90.000000
L 3.05749941 4.51026644 3.06041624 4.5116 2 P 0 ;0,1,2=39,3=90.000000
L 3.06041624 4.5116 3.06374961 4.51186663 2 P 0 ;0,1,2=39,3=90.000000
L 3.06374961 4.51186663 3.06708297 4.51133337 2 P 0 ;0,1,2=39,3=90.000000
L 3.06708297 4.51133337 3.06916663 4.5099998 2 P 0 ;0,1,2=39,3=90.000000
L 3.06916663 4.5099998 3.07083297 4.50813307 2 P 0 ;0,1,2=39,3=90.000000
L 3.07083297 4.50813307 3.07124951 4.50626683 2 P 0 ;0,1,2=39,3=90.000000
L 3.07124951 4.50626683 3.07083297 4.5044 2 P 0 ;0,1,2=39,3=90.000000
L 3.07083297 4.5044 3.06916663 4.5020001 2 P 0 ;0,1,2=39,3=90.000000
L 3.06916663 4.5020001 3.08 4.5027999 2 P 0 ;0,1,2=39,3=90.000000
L 3.08 4.5027999 3.08 4.5099998 2 P 0 ;0,1,2=39,3=90.000000
L 3.06541594 4.52493317 3.06833346 4.5267999 2 P 0 ;0,1,2=39,3=90.000000
L 3.06833346 4.5267999 3.0699998 4.5284 2 P 0 ;0,1,2=39,3=90.000000
L 3.0699998 4.5284 3.07083297 4.53053337 2 P 0 ;0,1,2=39,3=90.000000
L 3.07083297 4.53053337 3.0699998 4.5324002 2 P 0 ;0,1,2=39,3=90.000000
L 3.0699998 4.5324002 3.06833346 4.53373327 2 P 0 ;0,1,2=39,3=90.000000
L 3.06833346 4.53373327 3.06583327 4.5348001 2 P 0 ;0,1,2=39,3=90.000000
L 3.06583327 4.5348001 3.06291644 4.53506673 2 P 0 ;0,1,2=39,3=90.000000
L 3.06291644 4.53506673 3.06041624 4.5348001 2 P 0 ;0,1,2=39,3=90.000000
L 3.06041624 4.5348001 3.05791604 4.53373327 2 P 0 ;0,1,2=39,3=90.000000
L 3.05791604 4.53373327 3.05583307 4.53213307 2 P 0 ;0,1,2=39,3=90.000000
L 3.05583307 4.53213307 3.055 4.53026683 2 P 0 ;0,1,2=39,3=90.000000
L 3.055 4.53026683 3.05583307 4.52813346 2 P 0 ;0,1,2=39,3=90.000000
L 3.05583307 4.52813346 3.05833258 4.52626663 2 P 0 ;0,1,2=39,3=90.000000
L 3.05833258 4.52626663 3.06208327 4.5251998 2 P 0 ;0,1,2=39,3=90.000000
L 3.06208327 4.5251998 3.0662498 4.52493317 2 P 0 ;0,1,2=39,3=90.000000
L 3.0662498 4.52493317 3.07166614 4.52546634 2 P 0 ;0,1,2=39,3=90.000000
L 3.07166614 4.52546634 3.07458366 4.52626663 2 P 0 ;0,1,2=39,3=90.000000
L 3.07458366 4.52626663 3.0774997 4.5275997 2 P 0 ;0,1,2=39,3=90.000000
L 3.0774997 4.5275997 3.07958337 4.52946654 2 P 0 ;0,1,2=39,3=90.000000
L 3.07958337 4.52946654 3.08 4.53133327 2 P 0 ;0,1,2=39,3=90.000000
L 3.08 4.53133327 3.07916683 4.5332 2 P 0 ;0,1,2=39,3=90.000000
L 3.07916683 4.5332 3.07708317 4.53453356 2 P 0 ;0,1,2=39,3=90.000000
L 3.08 4.5539997 3.07916683 4.55186634 2 P 0 ;0,1,2=39,3=90.000000
L 3.07916683 4.55186634 3.07708317 4.55026663 2 P 0 ;0,1,2=39,3=90.000000
L 3.07708317 4.55026663 3.07458366 4.5491998 2 P 0 ;0,1,2=39,3=90.000000
L 3.07458366 4.5491998 3.07124951 4.5483999 2 P 0 ;0,1,2=39,3=90.000000
L 3.07124951 4.5483999 3.06749961 4.54813327 2 P 0 ;0,1,2=39,3=90.000000
L 3.06749961 4.54813327 3.06374961 4.5483999 2 P 0 ;0,1,2=39,3=90.000000
L 3.06374961 4.5483999 3.06041624 4.5491998 2 P 0 ;0,1,2=39,3=90.000000
L 3.06041624 4.5491998 3.05791604 4.55026663 2 P 0 ;0,1,2=39,3=90.000000
L 3.05791604 4.55026663 3.05583307 4.55186634 2 P 0 ;0,1,2=39,3=90.000000
L 3.05583307 4.55186634 3.055 4.5539997 2 P 0 ;0,1,2=39,3=90.000000
L 3.055 4.5539997 3.05583307 4.55613307 2 P 0 ;0,1,2=39,3=90.000000
L 3.05583307 4.55613307 3.05791604 4.55773327 2 P 0 ;0,1,2=39,3=90.000000
L 3.05791604 4.55773327 3.06041624 4.5588001 2 P 0 ;0,1,2=39,3=90.000000
L 3.06041624 4.5588001 3.06374961 4.5596 2 P 0 ;0,1,2=39,3=90.000000
L 3.06374961 4.5596 3.06749961 4.55986663 2 P 0 ;0,1,2=39,3=90.000000
L 3.06749961 4.55986663 3.07124951 4.5596 2 P 0 ;0,1,2=39,3=90.000000
L 3.07124951 4.5596 3.07458366 4.5588001 2 P 0 ;0,1,2=39,3=90.000000
L 3.07458366 4.5588001 3.07708317 4.55773327 2 P 0 ;0,1,2=39,3=90.000000
L 3.07708317 4.55773327 3.07916683 4.55613307 2 P 0 ;0,1,2=39,3=90.000000
L 3.07916683 4.55613307 3.08 4.5539997 2 P 0 ;0,1,2=39,3=90.000000
L 3.15213002 4.525 3.16786998 4.525 3 P 0 
L 3.19 4.45266654 3.215 4.45266654 2 P 0 ;0,1,2=40,3=90.000000
L 3.215 4.45266654 3.215 4.45933327 2 P 0 ;0,1,2=40,3=90.000000
L 3.215 4.45933327 3.21374941 4.46146663 2 P 0 ;0,1,2=40,3=90.000000
L 3.21374941 4.46146663 3.21208317 4.4628001 2 P 0 ;0,1,2=40,3=90.000000
L 3.21208317 4.4628001 3.2087498 4.46333337 2 P 0 ;0,1,2=40,3=90.000000
L 3.2087498 4.46333337 3.20541634 4.4628001 2 P 0 ;0,1,2=40,3=90.000000
L 3.20541634 4.4628001 3.20333346 4.4612 2 P 0 ;0,1,2=40,3=90.000000
L 3.20333346 4.4612 3.20208297 4.45933327 2 P 0 ;0,1,2=40,3=90.000000
L 3.20208297 4.45933327 3.20208297 4.45266654 2 P 0 ;0,1,2=40,3=90.000000
L 3.20208297 4.45933327 3.19 4.46333337 2 P 0 ;0,1,2=40,3=90.000000
L 3.19 4.4819997 3.215 4.4819997 2 P 0 ;0,1,2=40,3=90.000000
L 3.215 4.4819997 3.2100003 4.4787999 2 P 0 ;0,1,2=40,3=90.000000
L 3.19 4.4787999 3.19 4.48519951 2 P 0 ;0,1,2=40,3=90.000000
L 3.19374911 4.50013327 3.19166624 4.50173297 2 P 0 ;0,1,2=40,3=90.000000
L 3.19166624 4.50173297 3.19041654 4.5035997 2 P 0 ;0,1,2=40,3=90.000000
L 3.19041654 4.5035997 3.19 4.5059997 2 P 0 ;0,1,2=40,3=90.000000
L 3.19 4.5059997 3.19083307 4.5084002 2 P 0 ;0,1,2=40,3=90.000000
L 3.19083307 4.5084002 3.19249941 4.51026644 2 P 0 ;0,1,2=40,3=90.000000
L 3.19249941 4.51026644 3.19541624 4.5116 2 P 0 ;0,1,2=40,3=90.000000
L 3.19541624 4.5116 3.19874961 4.51186663 2 P 0 ;0,1,2=40,3=90.000000
L 3.19874961 4.51186663 3.20208297 4.51133337 2 P 0 ;0,1,2=40,3=90.000000
L 3.20208297 4.51133337 3.20416663 4.5099998 2 P 0 ;0,1,2=40,3=90.000000
L 3.20416663 4.5099998 3.20583297 4.50813307 2 P 0 ;0,1,2=40,3=90.000000
L 3.20583297 4.50813307 3.20624951 4.50626683 2 P 0 ;0,1,2=40,3=90.000000
L 3.20624951 4.50626683 3.20583297 4.5044 2 P 0 ;0,1,2=40,3=90.000000
L 3.20583297 4.5044 3.20416663 4.5020001 2 P 0 ;0,1,2=40,3=90.000000
L 3.20416663 4.5020001 3.215 4.5027999 2 P 0 ;0,1,2=40,3=90.000000
L 3.215 4.5027999 3.215 4.5099998 2 P 0 ;0,1,2=40,3=90.000000
L 3.19374911 4.52413327 3.19166624 4.52573297 2 P 0 ;0,1,2=40,3=90.000000
L 3.19166624 4.52573297 3.19041654 4.5275997 2 P 0 ;0,1,2=40,3=90.000000
L 3.19041654 4.5275997 3.19 4.5299997 2 P 0 ;0,1,2=40,3=90.000000
L 3.19 4.5299997 3.19083307 4.5324002 2 P 0 ;0,1,2=40,3=90.000000
L 3.19083307 4.5324002 3.19249941 4.53426644 2 P 0 ;0,1,2=40,3=90.000000
L 3.19249941 4.53426644 3.19541624 4.5356 2 P 0 ;0,1,2=40,3=90.000000
L 3.19541624 4.5356 3.19874961 4.53586663 2 P 0 ;0,1,2=40,3=90.000000
L 3.19874961 4.53586663 3.20208297 4.53533337 2 P 0 ;0,1,2=40,3=90.000000
L 3.20208297 4.53533337 3.20416663 4.5339998 2 P 0 ;0,1,2=40,3=90.000000
L 3.20416663 4.5339998 3.20583297 4.53213307 2 P 0 ;0,1,2=40,3=90.000000
L 3.20583297 4.53213307 3.20624951 4.53026683 2 P 0 ;0,1,2=40,3=90.000000
L 3.20624951 4.53026683 3.20583297 4.5284 2 P 0 ;0,1,2=40,3=90.000000
L 3.20583297 4.5284 3.20416663 4.5260001 2 P 0 ;0,1,2=40,3=90.000000
L 3.20416663 4.5260001 3.215 4.5267999 2 P 0 ;0,1,2=40,3=90.000000
L 3.215 4.5267999 3.215 4.5339998 2 P 0 ;0,1,2=40,3=90.000000
L 3.19291604 4.54946634 3.19083307 4.55133317 2 P 0 ;0,1,2=40,3=90.000000
L 3.19083307 4.55133317 3.19 4.55346654 2 P 0 ;0,1,2=40,3=90.000000
L 3.19 4.55346654 3.19083307 4.5555999 2 P 0 ;0,1,2=40,3=90.000000
L 3.19083307 4.5555999 3.19333258 4.55746663 2 P 0 ;0,1,2=40,3=90.000000
L 3.19333258 4.55746663 3.19708327 4.5588001 2 P 0 ;0,1,2=40,3=90.000000
L 3.19708327 4.5588001 3.20083327 4.55933337 2 P 0 ;0,1,2=40,3=90.000000
L 3.20083327 4.55933337 3.20541634 4.55933337 2 P 0 ;0,1,2=40,3=90.000000
L 3.20541634 4.55933337 3.20916634 4.5588001 2 P 0 ;0,1,2=40,3=90.000000
L 3.20916634 4.5588001 3.2124997 4.55746663 2 P 0 ;0,1,2=40,3=90.000000
L 3.2124997 4.55746663 3.21416683 4.55586644 2 P 0 ;0,1,2=40,3=90.000000
L 3.21416683 4.55586644 3.215 4.5539997 2 P 0 ;0,1,2=40,3=90.000000
L 3.215 4.5539997 3.21416683 4.55186634 2 P 0 ;0,1,2=40,3=90.000000
L 3.21416683 4.55186634 3.2124997 4.55026663 2 P 0 ;0,1,2=40,3=90.000000
L 3.2124997 4.55026663 3.2100003 4.5491998 2 P 0 ;0,1,2=40,3=90.000000
L 3.2100003 4.5491998 3.20666614 4.54866654 2 P 0 ;0,1,2=40,3=90.000000
L 3.20666614 4.54866654 3.2037501 4.5491998 2 P 0 ;0,1,2=40,3=90.000000
L 3.2037501 4.5491998 3.20083327 4.55053327 2 P 0 ;0,1,2=40,3=90.000000
L 3.20083327 4.55053327 3.19916614 4.55213346 2 P 0 ;0,1,2=40,3=90.000000
L 3.19916614 4.55213346 3.19874961 4.5539997 2 P 0 ;0,1,2=40,3=90.000000
L 3.19874961 4.5539997 3.19958278 4.55613307 2 P 0 ;0,1,2=40,3=90.000000
L 3.19958278 4.55613307 3.20166644 4.55773327 2 P 0 ;0,1,2=40,3=90.000000
L 3.20166644 4.55773327 3.20541634 4.55933337 2 P 0 ;0,1,2=40,3=90.000000
L 1.84 3.60213002 1.84 3.61786998 3 P 0 
L 1.7872935 3.59583002 1.7872935 3.62083002 2 P 0 ;0,1,2=41,3=0.000000
L 1.7872935 3.62083002 1.78062677 3.62083002 2 P 0 ;0,1,2=41,3=0.000000
L 1.78062677 3.62083002 1.77849341 3.61957943 2 P 0 ;0,1,2=41,3=0.000000
L 1.77849341 3.61957943 1.77715994 3.61791319 2 P 0 ;0,1,2=41,3=0.000000
L 1.77715994 3.61791319 1.77662667 3.61457982 2 P 0 ;0,1,2=41,3=0.000000
L 1.77662667 3.61457982 1.77715994 3.61124636 2 P 0 ;0,1,2=41,3=0.000000
L 1.77715994 3.61124636 1.77876004 3.60916348 2 P 0 ;0,1,2=41,3=0.000000
L 1.77876004 3.60916348 1.78062677 3.60791299 2 P 0 ;0,1,2=41,3=0.000000
L 1.78062677 3.60791299 1.7872935 3.60791299 2 P 0 ;0,1,2=41,3=0.000000
L 1.78062677 3.60791299 1.77662667 3.59583002 2 P 0 ;0,1,2=41,3=0.000000
L 1.75796033 3.59583002 1.75796033 3.62083002 2 P 0 ;0,1,2=41,3=0.000000
L 1.75796033 3.62083002 1.76116014 3.61583032 2 P 0 ;0,1,2=41,3=0.000000
L 1.76116014 3.59583002 1.75476053 3.59583002 2 P 0 ;0,1,2=41,3=0.000000
L 1.73902687 3.60624596 1.73716014 3.60916348 2 P 0 ;0,1,2=41,3=0.000000
L 1.73716014 3.60916348 1.73556004 3.61082982 2 P 0 ;0,1,2=41,3=0.000000
L 1.73556004 3.61082982 1.73342667 3.61166299 2 P 0 ;0,1,2=41,3=0.000000
L 1.73342667 3.61166299 1.73155984 3.61082982 2 P 0 ;0,1,2=41,3=0.000000
L 1.73155984 3.61082982 1.73022677 3.60916348 2 P 0 ;0,1,2=41,3=0.000000
L 1.73022677 3.60916348 1.72915994 3.60666329 2 P 0 ;0,1,2=41,3=0.000000
L 1.72915994 3.60666329 1.72889331 3.60374646 2 P 0 ;0,1,2=41,3=0.000000
L 1.72889331 3.60374646 1.72915994 3.60124626 2 P 0 ;0,1,2=41,3=0.000000
L 1.72915994 3.60124626 1.73022677 3.59874606 2 P 0 ;0,1,2=41,3=0.000000
L 1.73022677 3.59874606 1.73182697 3.59666309 2 P 0 ;0,1,2=41,3=0.000000
L 1.73182697 3.59666309 1.73369321 3.59583002 2 P 0 ;0,1,2=41,3=0.000000
L 1.73369321 3.59583002 1.73582657 3.59666309 2 P 0 ;0,1,2=41,3=0.000000
L 1.73582657 3.59666309 1.73769341 3.5991626 2 P 0 ;0,1,2=41,3=0.000000
L 1.73769341 3.5991626 1.73876024 3.60291329 2 P 0 ;0,1,2=41,3=0.000000
L 1.73876024 3.60291329 1.73902687 3.60707982 2 P 0 ;0,1,2=41,3=0.000000
L 1.73902687 3.60707982 1.7384937 3.61249616 2 P 0 ;0,1,2=41,3=0.000000
L 1.7384937 3.61249616 1.73769341 3.61541368 2 P 0 ;0,1,2=41,3=0.000000
L 1.73769341 3.61541368 1.73636033 3.61832972 2 P 0 ;0,1,2=41,3=0.000000
L 1.73636033 3.61832972 1.7344935 3.62041339 2 P 0 ;0,1,2=41,3=0.000000
L 1.7344935 3.62041339 1.73262677 3.62083002 2 P 0 ;0,1,2=41,3=0.000000
L 1.73262677 3.62083002 1.73076004 3.61999685 2 P 0 ;0,1,2=41,3=0.000000
L 1.73076004 3.61999685 1.72942648 3.61791319 2 P 0 ;0,1,2=41,3=0.000000
L 1.70996033 3.59583002 1.70996033 3.62083002 2 P 0 ;0,1,2=41,3=0.000000
L 1.70996033 3.62083002 1.71316014 3.61583032 2 P 0 ;0,1,2=41,3=0.000000
L 1.71316014 3.59583002 1.70676053 3.59583002 2 P 0 ;0,1,2=41,3=0.000000
L 1.68596033 3.59583002 1.68596033 3.62083002 2 P 0 ;0,1,2=41,3=0.000000
L 1.68596033 3.62083002 1.68916014 3.61583032 2 P 0 ;0,1,2=41,3=0.000000
L 1.68916014 3.59583002 1.68276053 3.59583002 2 P 0 ;0,1,2=41,3=0.000000
L 7.84393996 3.60213002 7.84393996 3.61786998 3 P 0 
L 7.78623346 3.59583002 7.78623346 3.62083002 2 P 0 ;0,1,2=42,3=0.000000
L 7.78623346 3.62083002 7.77956673 3.62083002 2 P 0 ;0,1,2=42,3=0.000000
L 7.77956673 3.62083002 7.77743337 3.61957943 2 P 0 ;0,1,2=42,3=0.000000
L 7.77743337 3.61957943 7.7760999 3.61791319 2 P 0 ;0,1,2=42,3=0.000000
L 7.7760999 3.61791319 7.77556663 3.61457982 2 P 0 ;0,1,2=42,3=0.000000
L 7.77556663 3.61457982 7.7760999 3.61124636 2 P 0 ;0,1,2=42,3=0.000000
L 7.7760999 3.61124636 7.7777 3.60916348 2 P 0 ;0,1,2=42,3=0.000000
L 7.7777 3.60916348 7.77956673 3.60791299 2 P 0 ;0,1,2=42,3=0.000000
L 7.77956673 3.60791299 7.78623346 3.60791299 2 P 0 ;0,1,2=42,3=0.000000
L 7.77956673 3.60791299 7.77556663 3.59583002 2 P 0 ;0,1,2=42,3=0.000000
L 7.7569003 3.59583002 7.7569003 3.62083002 2 P 0 ;0,1,2=42,3=0.000000
L 7.7569003 3.62083002 7.7601001 3.61583032 2 P 0 ;0,1,2=42,3=0.000000
L 7.7601001 3.59583002 7.75370049 3.59583002 2 P 0 ;0,1,2=42,3=0.000000
L 7.73796683 3.60624596 7.7361001 3.60916348 2 P 0 ;0,1,2=42,3=0.000000
L 7.7361001 3.60916348 7.7345 3.61082982 2 P 0 ;0,1,2=42,3=0.000000
L 7.7345 3.61082982 7.73236663 3.61166299 2 P 0 ;0,1,2=42,3=0.000000
L 7.73236663 3.61166299 7.7304998 3.61082982 2 P 0 ;0,1,2=42,3=0.000000
L 7.7304998 3.61082982 7.72916673 3.60916348 2 P 0 ;0,1,2=42,3=0.000000
L 7.72916673 3.60916348 7.7280999 3.60666329 2 P 0 ;0,1,2=42,3=0.000000
L 7.7280999 3.60666329 7.72783327 3.60374646 2 P 0 ;0,1,2=42,3=0.000000
L 7.72783327 3.60374646 7.7280999 3.60124626 2 P 0 ;0,1,2=42,3=0.000000
L 7.7280999 3.60124626 7.72916673 3.59874606 2 P 0 ;0,1,2=42,3=0.000000
L 7.72916673 3.59874606 7.73076693 3.59666309 2 P 0 ;0,1,2=42,3=0.000000
L 7.73076693 3.59666309 7.73263317 3.59583002 2 P 0 ;0,1,2=42,3=0.000000
L 7.73263317 3.59583002 7.73476654 3.59666309 2 P 0 ;0,1,2=42,3=0.000000
L 7.73476654 3.59666309 7.73663337 3.5991626 2 P 0 ;0,1,2=42,3=0.000000
L 7.73663337 3.5991626 7.7377002 3.60291329 2 P 0 ;0,1,2=42,3=0.000000
L 7.7377002 3.60291329 7.73796683 3.60707982 2 P 0 ;0,1,2=42,3=0.000000
L 7.73796683 3.60707982 7.73743366 3.61249616 2 P 0 ;0,1,2=42,3=0.000000
L 7.73743366 3.61249616 7.73663337 3.61541368 2 P 0 ;0,1,2=42,3=0.000000
L 7.73663337 3.61541368 7.7353003 3.61832972 2 P 0 ;0,1,2=42,3=0.000000
L 7.7353003 3.61832972 7.73343346 3.62041339 2 P 0 ;0,1,2=42,3=0.000000
L 7.73343346 3.62041339 7.73156673 3.62083002 2 P 0 ;0,1,2=42,3=0.000000
L 7.73156673 3.62083002 7.7297 3.61999685 2 P 0 ;0,1,2=42,3=0.000000
L 7.7297 3.61999685 7.72836644 3.61791319 2 P 0 ;0,1,2=42,3=0.000000
L 7.7089003 3.59583002 7.7089003 3.62083002 2 P 0 ;0,1,2=42,3=0.000000
L 7.7089003 3.62083002 7.7121001 3.61583032 2 P 0 ;0,1,2=42,3=0.000000
L 7.7121001 3.59583002 7.70570049 3.59583002 2 P 0 ;0,1,2=42,3=0.000000
L 7.6849003 3.62083002 7.68703366 3.61999685 2 P 0 ;0,1,2=42,3=0.000000
L 7.68703366 3.61999685 7.68863337 3.61791319 2 P 0 ;0,1,2=42,3=0.000000
L 7.68863337 3.61791319 7.6897002 3.61541368 2 P 0 ;0,1,2=42,3=0.000000
L 7.6897002 3.61541368 7.6905001 3.61207953 2 P 0 ;0,1,2=42,3=0.000000
L 7.6905001 3.61207953 7.69076673 3.60832963 2 P 0 ;0,1,2=42,3=0.000000
L 7.69076673 3.60832963 7.6905001 3.60457963 2 P 0 ;0,1,2=42,3=0.000000
L 7.6905001 3.60457963 7.6897002 3.60124626 2 P 0 ;0,1,2=42,3=0.000000
L 7.6897002 3.60124626 7.68863337 3.59874606 2 P 0 ;0,1,2=42,3=0.000000
L 7.68863337 3.59874606 7.68703366 3.59666309 2 P 0 ;0,1,2=42,3=0.000000
L 7.68703366 3.59666309 7.6849003 3.59583002 2 P 0 ;0,1,2=42,3=0.000000
L 7.6849003 3.59583002 7.68276693 3.59666309 2 P 0 ;0,1,2=42,3=0.000000
L 7.68276693 3.59666309 7.68116673 3.59874606 2 P 0 ;0,1,2=42,3=0.000000
L 7.68116673 3.59874606 7.6800999 3.60124626 2 P 0 ;0,1,2=42,3=0.000000
L 7.6800999 3.60124626 7.6793 3.60457963 2 P 0 ;0,1,2=42,3=0.000000
L 7.6793 3.60457963 7.67903337 3.60832963 2 P 0 ;0,1,2=42,3=0.000000
L 7.67903337 3.60832963 7.6793 3.61207953 2 P 0 ;0,1,2=42,3=0.000000
L 7.6793 3.61207953 7.6800999 3.61541368 2 P 0 ;0,1,2=42,3=0.000000
L 7.6800999 3.61541368 7.68116673 3.61791319 2 P 0 ;0,1,2=42,3=0.000000
L 7.68116673 3.61791319 7.68276693 3.61999685 2 P 0 ;0,1,2=42,3=0.000000
L 7.68276693 3.61999685 7.6849003 3.62083002 2 P 0 ;0,1,2=42,3=0.000000
L 1.81713002 4.545 1.83286998 4.545 3 P 0 
L 1.775 4.51266654 1.8 4.51266654 2 P 0 ;0,1,2=43,3=90.000000
L 1.8 4.51266654 1.8 4.51933327 2 P 0 ;0,1,2=43,3=90.000000
L 1.8 4.51933327 1.79874941 4.52146663 2 P 0 ;0,1,2=43,3=90.000000
L 1.79874941 4.52146663 1.79708317 4.5228001 2 P 0 ;0,1,2=43,3=90.000000
L 1.79708317 4.5228001 1.7937498 4.52333337 2 P 0 ;0,1,2=43,3=90.000000
L 1.7937498 4.52333337 1.79041634 4.5228001 2 P 0 ;0,1,2=43,3=90.000000
L 1.79041634 4.5228001 1.78833346 4.5212 2 P 0 ;0,1,2=43,3=90.000000
L 1.78833346 4.5212 1.78708297 4.51933327 2 P 0 ;0,1,2=43,3=90.000000
L 1.78708297 4.51933327 1.78708297 4.51266654 2 P 0 ;0,1,2=43,3=90.000000
L 1.78708297 4.51933327 1.775 4.52333337 2 P 0 ;0,1,2=43,3=90.000000
L 1.775 4.5419997 1.8 4.5419997 2 P 0 ;0,1,2=43,3=90.000000
L 1.8 4.5419997 1.7950003 4.5387999 2 P 0 ;0,1,2=43,3=90.000000
L 1.775 4.5387999 1.775 4.54519951 2 P 0 ;0,1,2=43,3=90.000000
L 1.78541594 4.56093317 1.78833346 4.5627999 2 P 0 ;0,1,2=43,3=90.000000
L 1.78833346 4.5627999 1.7899998 4.5644 2 P 0 ;0,1,2=43,3=90.000000
L 1.7899998 4.5644 1.79083297 4.56653337 2 P 0 ;0,1,2=43,3=90.000000
L 1.79083297 4.56653337 1.7899998 4.5684002 2 P 0 ;0,1,2=43,3=90.000000
L 1.7899998 4.5684002 1.78833346 4.56973327 2 P 0 ;0,1,2=43,3=90.000000
L 1.78833346 4.56973327 1.78583327 4.5708001 2 P 0 ;0,1,2=43,3=90.000000
L 1.78583327 4.5708001 1.78291644 4.57106673 2 P 0 ;0,1,2=43,3=90.000000
L 1.78291644 4.57106673 1.78041624 4.5708001 2 P 0 ;0,1,2=43,3=90.000000
L 1.78041624 4.5708001 1.77791604 4.56973327 2 P 0 ;0,1,2=43,3=90.000000
L 1.77791604 4.56973327 1.77583307 4.56813307 2 P 0 ;0,1,2=43,3=90.000000
L 1.77583307 4.56813307 1.775 4.56626683 2 P 0 ;0,1,2=43,3=90.000000
L 1.775 4.56626683 1.77583307 4.56413346 2 P 0 ;0,1,2=43,3=90.000000
L 1.77583307 4.56413346 1.77833258 4.56226663 2 P 0 ;0,1,2=43,3=90.000000
L 1.77833258 4.56226663 1.78208327 4.5611998 2 P 0 ;0,1,2=43,3=90.000000
L 1.78208327 4.5611998 1.7862498 4.56093317 2 P 0 ;0,1,2=43,3=90.000000
L 1.7862498 4.56093317 1.79166614 4.56146634 2 P 0 ;0,1,2=43,3=90.000000
L 1.79166614 4.56146634 1.79458366 4.56226663 2 P 0 ;0,1,2=43,3=90.000000
L 1.79458366 4.56226663 1.7974997 4.5635997 2 P 0 ;0,1,2=43,3=90.000000
L 1.7974997 4.5635997 1.79958337 4.56546654 2 P 0 ;0,1,2=43,3=90.000000
L 1.79958337 4.56546654 1.8 4.56733327 2 P 0 ;0,1,2=43,3=90.000000
L 1.8 4.56733327 1.79916683 4.5692 2 P 0 ;0,1,2=43,3=90.000000
L 1.79916683 4.5692 1.79708317 4.57053356 2 P 0 ;0,1,2=43,3=90.000000
L 1.79583337 4.58493317 1.79833287 4.58653327 2 P 0 ;0,1,2=43,3=90.000000
L 1.79833287 4.58653327 1.79958337 4.5884 2 P 0 ;0,1,2=43,3=90.000000
L 1.79958337 4.5884 1.8 4.59053337 2 P 0 ;0,1,2=43,3=90.000000
L 1.8 4.59053337 1.79916683 4.5932 2 P 0 ;0,1,2=43,3=90.000000
L 1.79916683 4.5932 1.79708317 4.59506673 2 P 0 ;0,1,2=43,3=90.000000
L 1.79708317 4.59506673 1.79458366 4.5956 2 P 0 ;0,1,2=43,3=90.000000
L 1.79458366 4.5956 1.79208268 4.59533337 2 P 0 ;0,1,2=43,3=90.000000
L 1.79208268 4.59533337 1.7899998 4.59426644 2 P 0 ;0,1,2=43,3=90.000000
L 1.7899998 4.59426644 1.78583327 4.58893327 2 P 0 ;0,1,2=43,3=90.000000
L 1.78583327 4.58893327 1.78291644 4.58653327 2 P 0 ;0,1,2=43,3=90.000000
L 1.78291644 4.58653327 1.77874911 4.58493317 2 P 0 ;0,1,2=43,3=90.000000
L 1.77874911 4.58493317 1.775 4.5843999 2 P 0 ;0,1,2=43,3=90.000000
L 1.775 4.5843999 1.775 4.5956 2 P 0 ;0,1,2=43,3=90.000000
L 1.775 4.6139997 1.77541654 4.61586644 2 P 0 ;0,1,2=43,3=90.000000
L 1.77541654 4.61586644 1.77666624 4.6179998 2 P 0 ;0,1,2=43,3=90.000000
L 1.77666624 4.6179998 1.77874911 4.61933337 2 P 0 ;0,1,2=43,3=90.000000
L 1.77874911 4.61933337 1.78166673 4.61986663 2 P 0 ;0,1,2=43,3=90.000000
L 1.78166673 4.61986663 1.78458278 4.61933337 2 P 0 ;0,1,2=43,3=90.000000
L 1.78458278 4.61933337 1.78708297 4.61773327 2 P 0 ;0,1,2=43,3=90.000000
L 1.78708297 4.61773327 1.78833346 4.61533327 2 P 0 ;0,1,2=43,3=90.000000
L 1.78833346 4.61533327 1.78833346 4.61266663 2 P 0 ;0,1,2=43,3=90.000000
L 1.78833346 4.61266663 1.78916663 4.61106654 2 P 0 ;0,1,2=43,3=90.000000
L 1.78916663 4.61106654 1.79124951 4.60973297 2 P 0 ;0,1,2=43,3=90.000000
L 1.79124951 4.60973297 1.79416634 4.6091998 2 P 0 ;0,1,2=43,3=90.000000
L 1.79416634 4.6091998 1.79708317 4.6100001 2 P 0 ;0,1,2=43,3=90.000000
L 1.79708317 4.6100001 1.79916683 4.61186634 2 P 0 ;0,1,2=43,3=90.000000
L 1.79916683 4.61186634 1.8 4.6139997 2 P 0 ;0,1,2=43,3=90.000000
L 1.8 4.6139997 1.79916683 4.61613307 2 P 0 ;0,1,2=43,3=90.000000
L 1.79916683 4.61613307 1.79708317 4.6179998 2 P 0 ;0,1,2=43,3=90.000000
L 1.79708317 4.6179998 1.79416634 4.6188001 2 P 0 ;0,1,2=43,3=90.000000
L 1.79416634 4.6188001 1.79124951 4.61826644 2 P 0 ;0,1,2=43,3=90.000000
L 1.79124951 4.61826644 1.78916663 4.61693337 2 P 0 ;0,1,2=43,3=90.000000
L 1.78916663 4.61693337 1.78833346 4.61533327 2 P 0 ;0,1,2=43,3=90.000000
L 1.78833346 4.61533327 1.78833346 4.61266663 2 P 0 ;0,1,2=43,3=90.000000
L 1.78833346 4.61266663 1.78708297 4.61026663 2 P 0 ;0,1,2=43,3=90.000000
L 1.78708297 4.61026663 1.78458278 4.60866654 2 P 0 ;0,1,2=43,3=90.000000
L 1.78458278 4.60866654 1.78166673 4.60813327 2 P 0 ;0,1,2=43,3=90.000000
L 1.78166673 4.60813327 1.77874911 4.60866654 2 P 0 ;0,1,2=43,3=90.000000
L 1.77874911 4.60866654 1.77666624 4.6100001 2 P 0 ;0,1,2=43,3=90.000000
L 1.77666624 4.6100001 1.77541654 4.61213346 2 P 0 ;0,1,2=43,3=90.000000
L 1.77541654 4.61213346 1.775 4.6139997 2 P 0 ;0,1,2=43,3=90.000000
L 7.87566998 4.545 7.89141004 4.545 3 P 0 
L 7.92 4.49266654 7.945 4.49266654 2 P 0 ;0,1,2=44,3=90.000000
L 7.945 4.49266654 7.945 4.49933327 2 P 0 ;0,1,2=44,3=90.000000
L 7.945 4.49933327 7.94374941 4.50146663 2 P 0 ;0,1,2=44,3=90.000000
L 7.94374941 4.50146663 7.94208317 4.5028001 2 P 0 ;0,1,2=44,3=90.000000
L 7.94208317 4.5028001 7.9387498 4.50333337 2 P 0 ;0,1,2=44,3=90.000000
L 7.9387498 4.50333337 7.93541634 4.5028001 2 P 0 ;0,1,2=44,3=90.000000
L 7.93541634 4.5028001 7.93333346 4.5012 2 P 0 ;0,1,2=44,3=90.000000
L 7.93333346 4.5012 7.93208297 4.49933327 2 P 0 ;0,1,2=44,3=90.000000
L 7.93208297 4.49933327 7.93208297 4.49266654 2 P 0 ;0,1,2=44,3=90.000000
L 7.93208297 4.49933327 7.92 4.50333337 2 P 0 ;0,1,2=44,3=90.000000
L 7.92 4.5219997 7.945 4.5219997 2 P 0 ;0,1,2=44,3=90.000000
L 7.945 4.5219997 7.9400003 4.5187999 2 P 0 ;0,1,2=44,3=90.000000
L 7.92 4.5187999 7.92 4.52519951 2 P 0 ;0,1,2=44,3=90.000000
L 7.93041594 4.54093317 7.93333346 4.5427999 2 P 0 ;0,1,2=44,3=90.000000
L 7.93333346 4.5427999 7.9349998 4.5444 2 P 0 ;0,1,2=44,3=90.000000
L 7.9349998 4.5444 7.93583297 4.54653337 2 P 0 ;0,1,2=44,3=90.000000
L 7.93583297 4.54653337 7.9349998 4.5484002 2 P 0 ;0,1,2=44,3=90.000000
L 7.9349998 4.5484002 7.93333346 4.54973327 2 P 0 ;0,1,2=44,3=90.000000
L 7.93333346 4.54973327 7.93083327 4.5508001 2 P 0 ;0,1,2=44,3=90.000000
L 7.93083327 4.5508001 7.92791644 4.55106673 2 P 0 ;0,1,2=44,3=90.000000
L 7.92791644 4.55106673 7.92541624 4.5508001 2 P 0 ;0,1,2=44,3=90.000000
L 7.92541624 4.5508001 7.92291604 4.54973327 2 P 0 ;0,1,2=44,3=90.000000
L 7.92291604 4.54973327 7.92083307 4.54813307 2 P 0 ;0,1,2=44,3=90.000000
L 7.92083307 4.54813307 7.92 4.54626683 2 P 0 ;0,1,2=44,3=90.000000
L 7.92 4.54626683 7.92083307 4.54413346 2 P 0 ;0,1,2=44,3=90.000000
L 7.92083307 4.54413346 7.92333258 4.54226663 2 P 0 ;0,1,2=44,3=90.000000
L 7.92333258 4.54226663 7.92708327 4.5411998 2 P 0 ;0,1,2=44,3=90.000000
L 7.92708327 4.5411998 7.9312498 4.54093317 2 P 0 ;0,1,2=44,3=90.000000
L 7.9312498 4.54093317 7.93666614 4.54146634 2 P 0 ;0,1,2=44,3=90.000000
L 7.93666614 4.54146634 7.93958366 4.54226663 2 P 0 ;0,1,2=44,3=90.000000
L 7.93958366 4.54226663 7.9424997 4.5435997 2 P 0 ;0,1,2=44,3=90.000000
L 7.9424997 4.5435997 7.94458337 4.54546654 2 P 0 ;0,1,2=44,3=90.000000
L 7.94458337 4.54546654 7.945 4.54733327 2 P 0 ;0,1,2=44,3=90.000000
L 7.945 4.54733327 7.94416683 4.5492 2 P 0 ;0,1,2=44,3=90.000000
L 7.94416683 4.5492 7.94208317 4.55053356 2 P 0 ;0,1,2=44,3=90.000000
L 7.92499961 4.56413327 7.92208287 4.56573297 2 P 0 ;0,1,2=44,3=90.000000
L 7.92208287 4.56573297 7.92041654 4.56786634 2 P 0 ;0,1,2=44,3=90.000000
L 7.92041654 4.56786634 7.92 4.57026683 2 P 0 ;0,1,2=44,3=90.000000
L 7.92 4.57026683 7.92041654 4.5724002 2 P 0 ;0,1,2=44,3=90.000000
L 7.92041654 4.5724002 7.92249941 4.57453356 2 P 0 ;0,1,2=44,3=90.000000
L 7.92249941 4.57453356 7.92499961 4.57586663 2 P 0 ;0,1,2=44,3=90.000000
L 7.92499961 4.57586663 7.9274999 4.57613317 2 P 0 ;0,1,2=44,3=90.000000
L 7.9274999 4.57613317 7.93041594 4.5756 2 P 0 ;0,1,2=44,3=90.000000
L 7.93041594 4.5756 7.93249961 4.57373327 2 P 0 ;0,1,2=44,3=90.000000
L 7.93249961 4.57373327 7.93333346 4.57186644 2 P 0 ;0,1,2=44,3=90.000000
L 7.93333346 4.57186644 7.93333346 4.56946654 2 P 0 ;0,1,2=44,3=90.000000
L 7.93333346 4.57186644 7.93458327 4.57346663 2 P 0 ;0,1,2=44,3=90.000000
L 7.93458327 4.57346663 7.93666614 4.5748001 2 P 0 ;0,1,2=44,3=90.000000
L 7.93666614 4.5748001 7.93916634 4.57533337 2 P 0 ;0,1,2=44,3=90.000000
L 7.93916634 4.57533337 7.94166654 4.5748001 2 P 0 ;0,1,2=44,3=90.000000
L 7.94166654 4.5748001 7.94374941 4.57346663 2 P 0 ;0,1,2=44,3=90.000000
L 7.94374941 4.57346663 7.945 4.57106663 2 P 0 ;0,1,2=44,3=90.000000
L 7.945 4.57106663 7.94458337 4.56866663 2 P 0 ;0,1,2=44,3=90.000000
L 7.94458337 4.56866663 7.94291634 4.56626663 2 P 0 ;0,1,2=44,3=90.000000
L 7.92 4.5939997 7.945 4.5939997 2 P 0 ;0,1,2=44,3=90.000000
L 7.945 4.5939997 7.9400003 4.5907999 2 P 0 ;0,1,2=44,3=90.000000
L 7.92 4.5907999 7.92 4.59719951 2 P 0 ;0,1,2=44,3=90.000000
L 1.87213002 4.545 1.88786998 4.545 3 P 0 
L 1.91 4.48266654 1.935 4.48266654 2 P 0 ;0,1,2=45,3=90.000000
L 1.935 4.48266654 1.935 4.48933327 2 P 0 ;0,1,2=45,3=90.000000
L 1.935 4.48933327 1.93374941 4.49146663 2 P 0 ;0,1,2=45,3=90.000000
L 1.93374941 4.49146663 1.93208317 4.4928001 2 P 0 ;0,1,2=45,3=90.000000
L 1.93208317 4.4928001 1.9287498 4.49333337 2 P 0 ;0,1,2=45,3=90.000000
L 1.9287498 4.49333337 1.92541634 4.4928001 2 P 0 ;0,1,2=45,3=90.000000
L 1.92541634 4.4928001 1.92333346 4.4912 2 P 0 ;0,1,2=45,3=90.000000
L 1.92333346 4.4912 1.92208297 4.48933327 2 P 0 ;0,1,2=45,3=90.000000
L 1.92208297 4.48933327 1.92208297 4.48266654 2 P 0 ;0,1,2=45,3=90.000000
L 1.92208297 4.48933327 1.91 4.49333337 2 P 0 ;0,1,2=45,3=90.000000
L 1.91 4.5119997 1.935 4.5119997 2 P 0 ;0,1,2=45,3=90.000000
L 1.935 4.5119997 1.9300003 4.5087999 2 P 0 ;0,1,2=45,3=90.000000
L 1.91 4.5087999 1.91 4.51519951 2 P 0 ;0,1,2=45,3=90.000000
L 1.92041594 4.53093317 1.92333346 4.5327999 2 P 0 ;0,1,2=45,3=90.000000
L 1.92333346 4.5327999 1.9249998 4.5344 2 P 0 ;0,1,2=45,3=90.000000
L 1.9249998 4.5344 1.92583297 4.53653337 2 P 0 ;0,1,2=45,3=90.000000
L 1.92583297 4.53653337 1.9249998 4.5384002 2 P 0 ;0,1,2=45,3=90.000000
L 1.9249998 4.5384002 1.92333346 4.53973327 2 P 0 ;0,1,2=45,3=90.000000
L 1.92333346 4.53973327 1.92083327 4.5408001 2 P 0 ;0,1,2=45,3=90.000000
L 1.92083327 4.5408001 1.91791644 4.54106673 2 P 0 ;0,1,2=45,3=90.000000
L 1.91791644 4.54106673 1.91541624 4.5408001 2 P 0 ;0,1,2=45,3=90.000000
L 1.91541624 4.5408001 1.91291604 4.53973327 2 P 0 ;0,1,2=45,3=90.000000
L 1.91291604 4.53973327 1.91083307 4.53813307 2 P 0 ;0,1,2=45,3=90.000000
L 1.91083307 4.53813307 1.91 4.53626683 2 P 0 ;0,1,2=45,3=90.000000
L 1.91 4.53626683 1.91083307 4.53413346 2 P 0 ;0,1,2=45,3=90.000000
L 1.91083307 4.53413346 1.91333258 4.53226663 2 P 0 ;0,1,2=45,3=90.000000
L 1.91333258 4.53226663 1.91708327 4.5311998 2 P 0 ;0,1,2=45,3=90.000000
L 1.91708327 4.5311998 1.9212498 4.53093317 2 P 0 ;0,1,2=45,3=90.000000
L 1.9212498 4.53093317 1.92666614 4.53146634 2 P 0 ;0,1,2=45,3=90.000000
L 1.92666614 4.53146634 1.92958366 4.53226663 2 P 0 ;0,1,2=45,3=90.000000
L 1.92958366 4.53226663 1.9324997 4.5335997 2 P 0 ;0,1,2=45,3=90.000000
L 1.9324997 4.5335997 1.93458337 4.53546654 2 P 0 ;0,1,2=45,3=90.000000
L 1.93458337 4.53546654 1.935 4.53733327 2 P 0 ;0,1,2=45,3=90.000000
L 1.935 4.53733327 1.93416683 4.5392 2 P 0 ;0,1,2=45,3=90.000000
L 1.93416683 4.5392 1.93208317 4.54053356 2 P 0 ;0,1,2=45,3=90.000000
L 1.93083337 4.55493317 1.93333287 4.55653327 2 P 0 ;0,1,2=45,3=90.000000
L 1.93333287 4.55653327 1.93458337 4.5584 2 P 0 ;0,1,2=45,3=90.000000
L 1.93458337 4.5584 1.935 4.56053337 2 P 0 ;0,1,2=45,3=90.000000
L 1.935 4.56053337 1.93416683 4.5632 2 P 0 ;0,1,2=45,3=90.000000
L 1.93416683 4.5632 1.93208317 4.56506673 2 P 0 ;0,1,2=45,3=90.000000
L 1.93208317 4.56506673 1.92958366 4.5656 2 P 0 ;0,1,2=45,3=90.000000
L 1.92958366 4.5656 1.92708268 4.56533337 2 P 0 ;0,1,2=45,3=90.000000
L 1.92708268 4.56533337 1.9249998 4.56426644 2 P 0 ;0,1,2=45,3=90.000000
L 1.9249998 4.56426644 1.92083327 4.55893327 2 P 0 ;0,1,2=45,3=90.000000
L 1.92083327 4.55893327 1.91791644 4.55653327 2 P 0 ;0,1,2=45,3=90.000000
L 1.91791644 4.55653327 1.91374911 4.55493317 2 P 0 ;0,1,2=45,3=90.000000
L 1.91374911 4.55493317 1.91 4.5543999 2 P 0 ;0,1,2=45,3=90.000000
L 1.91 4.5543999 1.91 4.5656 2 P 0 ;0,1,2=45,3=90.000000
L 1.91291604 4.57946634 1.91083307 4.58133317 2 P 0 ;0,1,2=45,3=90.000000
L 1.91083307 4.58133317 1.91 4.58346654 2 P 0 ;0,1,2=45,3=90.000000
L 1.91 4.58346654 1.91083307 4.5855999 2 P 0 ;0,1,2=45,3=90.000000
L 1.91083307 4.5855999 1.91333258 4.58746663 2 P 0 ;0,1,2=45,3=90.000000
L 1.91333258 4.58746663 1.91708327 4.5888001 2 P 0 ;0,1,2=45,3=90.000000
L 1.91708327 4.5888001 1.92083327 4.58933337 2 P 0 ;0,1,2=45,3=90.000000
L 1.92083327 4.58933337 1.92541634 4.58933337 2 P 0 ;0,1,2=45,3=90.000000
L 1.92541634 4.58933337 1.92916634 4.5888001 2 P 0 ;0,1,2=45,3=90.000000
L 1.92916634 4.5888001 1.9324997 4.58746663 2 P 0 ;0,1,2=45,3=90.000000
L 1.9324997 4.58746663 1.93416683 4.58586644 2 P 0 ;0,1,2=45,3=90.000000
L 1.93416683 4.58586644 1.935 4.5839997 2 P 0 ;0,1,2=45,3=90.000000
L 1.935 4.5839997 1.93416683 4.58186634 2 P 0 ;0,1,2=45,3=90.000000
L 1.93416683 4.58186634 1.9324997 4.58026663 2 P 0 ;0,1,2=45,3=90.000000
L 1.9324997 4.58026663 1.9300003 4.5791998 2 P 0 ;0,1,2=45,3=90.000000
L 1.9300003 4.5791998 1.92666614 4.57866654 2 P 0 ;0,1,2=45,3=90.000000
L 1.92666614 4.57866654 1.9237501 4.5791998 2 P 0 ;0,1,2=45,3=90.000000
L 1.9237501 4.5791998 1.92083327 4.58053327 2 P 0 ;0,1,2=45,3=90.000000
L 1.92083327 4.58053327 1.91916614 4.58213346 2 P 0 ;0,1,2=45,3=90.000000
L 1.91916614 4.58213346 1.91874961 4.5839997 2 P 0 ;0,1,2=45,3=90.000000
L 1.91874961 4.5839997 1.91958278 4.58613307 2 P 0 ;0,1,2=45,3=90.000000
L 1.91958278 4.58613307 1.92166644 4.58773327 2 P 0 ;0,1,2=45,3=90.000000
L 1.92166644 4.58773327 1.92541634 4.58933337 2 P 0 ;0,1,2=45,3=90.000000
L 7.82066998 4.545 7.83641004 4.545 3 P 0 
L 7.77 4.48766654 7.795 4.48766654 2 P 0 ;0,1,2=46,3=90.000000
L 7.795 4.48766654 7.795 4.49433327 2 P 0 ;0,1,2=46,3=90.000000
L 7.795 4.49433327 7.79374941 4.49646663 2 P 0 ;0,1,2=46,3=90.000000
L 7.79374941 4.49646663 7.79208317 4.4978001 2 P 0 ;0,1,2=46,3=90.000000
L 7.79208317 4.4978001 7.7887498 4.49833337 2 P 0 ;0,1,2=46,3=90.000000
L 7.7887498 4.49833337 7.78541634 4.4978001 2 P 0 ;0,1,2=46,3=90.000000
L 7.78541634 4.4978001 7.78333346 4.4962 2 P 0 ;0,1,2=46,3=90.000000
L 7.78333346 4.4962 7.78208297 4.49433327 2 P 0 ;0,1,2=46,3=90.000000
L 7.78208297 4.49433327 7.78208297 4.48766654 2 P 0 ;0,1,2=46,3=90.000000
L 7.78208297 4.49433327 7.77 4.49833337 2 P 0 ;0,1,2=46,3=90.000000
L 7.77 4.5169997 7.795 4.5169997 2 P 0 ;0,1,2=46,3=90.000000
L 7.795 4.5169997 7.7900003 4.5137999 2 P 0 ;0,1,2=46,3=90.000000
L 7.77 4.5137999 7.77 4.52019951 2 P 0 ;0,1,2=46,3=90.000000
L 7.78041594 4.53593317 7.78333346 4.5377999 2 P 0 ;0,1,2=46,3=90.000000
L 7.78333346 4.5377999 7.7849998 4.5394 2 P 0 ;0,1,2=46,3=90.000000
L 7.7849998 4.5394 7.78583297 4.54153337 2 P 0 ;0,1,2=46,3=90.000000
L 7.78583297 4.54153337 7.7849998 4.5434002 2 P 0 ;0,1,2=46,3=90.000000
L 7.7849998 4.5434002 7.78333346 4.54473327 2 P 0 ;0,1,2=46,3=90.000000
L 7.78333346 4.54473327 7.78083327 4.5458001 2 P 0 ;0,1,2=46,3=90.000000
L 7.78083327 4.5458001 7.77791644 4.54606673 2 P 0 ;0,1,2=46,3=90.000000
L 7.77791644 4.54606673 7.77541624 4.5458001 2 P 0 ;0,1,2=46,3=90.000000
L 7.77541624 4.5458001 7.77291604 4.54473327 2 P 0 ;0,1,2=46,3=90.000000
L 7.77291604 4.54473327 7.77083307 4.54313307 2 P 0 ;0,1,2=46,3=90.000000
L 7.77083307 4.54313307 7.77 4.54126683 2 P 0 ;0,1,2=46,3=90.000000
L 7.77 4.54126683 7.77083307 4.53913346 2 P 0 ;0,1,2=46,3=90.000000
L 7.77083307 4.53913346 7.77333258 4.53726663 2 P 0 ;0,1,2=46,3=90.000000
L 7.77333258 4.53726663 7.77708327 4.5361998 2 P 0 ;0,1,2=46,3=90.000000
L 7.77708327 4.5361998 7.7812498 4.53593317 2 P 0 ;0,1,2=46,3=90.000000
L 7.7812498 4.53593317 7.78666614 4.53646634 2 P 0 ;0,1,2=46,3=90.000000
L 7.78666614 4.53646634 7.78958366 4.53726663 2 P 0 ;0,1,2=46,3=90.000000
L 7.78958366 4.53726663 7.7924997 4.5385997 2 P 0 ;0,1,2=46,3=90.000000
L 7.7924997 4.5385997 7.79458337 4.54046654 2 P 0 ;0,1,2=46,3=90.000000
L 7.79458337 4.54046654 7.795 4.54233327 2 P 0 ;0,1,2=46,3=90.000000
L 7.795 4.54233327 7.79416683 4.5442 2 P 0 ;0,1,2=46,3=90.000000
L 7.79416683 4.5442 7.79208317 4.54553356 2 P 0 ;0,1,2=46,3=90.000000
L 7.77499961 4.55913327 7.77208287 4.56073297 2 P 0 ;0,1,2=46,3=90.000000
L 7.77208287 4.56073297 7.77041654 4.56286634 2 P 0 ;0,1,2=46,3=90.000000
L 7.77041654 4.56286634 7.77 4.56526683 2 P 0 ;0,1,2=46,3=90.000000
L 7.77 4.56526683 7.77041654 4.5674002 2 P 0 ;0,1,2=46,3=90.000000
L 7.77041654 4.5674002 7.77249941 4.56953356 2 P 0 ;0,1,2=46,3=90.000000
L 7.77249941 4.56953356 7.77499961 4.57086663 2 P 0 ;0,1,2=46,3=90.000000
L 7.77499961 4.57086663 7.7774999 4.57113317 2 P 0 ;0,1,2=46,3=90.000000
L 7.7774999 4.57113317 7.78041594 4.5706 2 P 0 ;0,1,2=46,3=90.000000
L 7.78041594 4.5706 7.78249961 4.56873327 2 P 0 ;0,1,2=46,3=90.000000
L 7.78249961 4.56873327 7.78333346 4.56686644 2 P 0 ;0,1,2=46,3=90.000000
L 7.78333346 4.56686644 7.78333346 4.56446654 2 P 0 ;0,1,2=46,3=90.000000
L 7.78333346 4.56686644 7.78458327 4.56846663 2 P 0 ;0,1,2=46,3=90.000000
L 7.78458327 4.56846663 7.78666614 4.5698001 2 P 0 ;0,1,2=46,3=90.000000
L 7.78666614 4.5698001 7.78916634 4.57033337 2 P 0 ;0,1,2=46,3=90.000000
L 7.78916634 4.57033337 7.79166654 4.5698001 2 P 0 ;0,1,2=46,3=90.000000
L 7.79166654 4.5698001 7.79374941 4.56846663 2 P 0 ;0,1,2=46,3=90.000000
L 7.79374941 4.56846663 7.795 4.56606663 2 P 0 ;0,1,2=46,3=90.000000
L 7.795 4.56606663 7.79458337 4.56366663 2 P 0 ;0,1,2=46,3=90.000000
L 7.79458337 4.56366663 7.79291634 4.56126663 2 P 0 ;0,1,2=46,3=90.000000
L 7.795 4.5889997 7.79416683 4.58686634 2 P 0 ;0,1,2=46,3=90.000000
L 7.79416683 4.58686634 7.79208317 4.58526663 2 P 0 ;0,1,2=46,3=90.000000
L 7.79208317 4.58526663 7.78958366 4.5841998 2 P 0 ;0,1,2=46,3=90.000000
L 7.78958366 4.5841998 7.78624951 4.5833999 2 P 0 ;0,1,2=46,3=90.000000
L 7.78624951 4.5833999 7.78249961 4.58313327 2 P 0 ;0,1,2=46,3=90.000000
L 7.78249961 4.58313327 7.77874961 4.5833999 2 P 0 ;0,1,2=46,3=90.000000
L 7.77874961 4.5833999 7.77541624 4.5841998 2 P 0 ;0,1,2=46,3=90.000000
L 7.77541624 4.5841998 7.77291604 4.58526663 2 P 0 ;0,1,2=46,3=90.000000
L 7.77291604 4.58526663 7.77083307 4.58686634 2 P 0 ;0,1,2=46,3=90.000000
L 7.77083307 4.58686634 7.77 4.5889997 2 P 0 ;0,1,2=46,3=90.000000
L 7.77 4.5889997 7.77083307 4.59113307 2 P 0 ;0,1,2=46,3=90.000000
L 7.77083307 4.59113307 7.77291604 4.59273327 2 P 0 ;0,1,2=46,3=90.000000
L 7.77291604 4.59273327 7.77541624 4.5938001 2 P 0 ;0,1,2=46,3=90.000000
L 7.77541624 4.5938001 7.77874961 4.5946 2 P 0 ;0,1,2=46,3=90.000000
L 7.77874961 4.5946 7.78249961 4.59486663 2 P 0 ;0,1,2=46,3=90.000000
L 7.78249961 4.59486663 7.78624951 4.5946 2 P 0 ;0,1,2=46,3=90.000000
L 7.78624951 4.5946 7.78958366 4.5938001 2 P 0 ;0,1,2=46,3=90.000000
L 7.78958366 4.5938001 7.79208317 4.59273327 2 P 0 ;0,1,2=46,3=90.000000
L 7.79208317 4.59273327 7.79416683 4.59113307 2 P 0 ;0,1,2=46,3=90.000000
L 7.79416683 4.59113307 7.795 4.5889997 2 P 0 ;0,1,2=46,3=90.000000
L 10.116 2.92013002 10.116 2.93586998 3 P 0 
L 10.28733346 2.915 10.28733346 2.94 2 P 0 ;0,1,2=47,3=0.000000
L 10.28733346 2.94 10.28066673 2.94 2 P 0 ;0,1,2=47,3=0.000000
L 10.28066673 2.94 10.27853337 2.93874941 2 P 0 ;0,1,2=47,3=0.000000
L 10.27853337 2.93874941 10.2771999 2.93708317 2 P 0 ;0,1,2=47,3=0.000000
L 10.2771999 2.93708317 10.27666663 2.9337498 2 P 0 ;0,1,2=47,3=0.000000
L 10.27666663 2.9337498 10.2771999 2.93041634 2 P 0 ;0,1,2=47,3=0.000000
L 10.2771999 2.93041634 10.2788 2.92833346 2 P 0 ;0,1,2=47,3=0.000000
L 10.2788 2.92833346 10.28066673 2.92708297 2 P 0 ;0,1,2=47,3=0.000000
L 10.28066673 2.92708297 10.28733346 2.92708297 2 P 0 ;0,1,2=47,3=0.000000
L 10.28066673 2.92708297 10.27666663 2.915 2 P 0 ;0,1,2=47,3=0.000000
L 10.2580003 2.915 10.2580003 2.94 2 P 0 ;0,1,2=47,3=0.000000
L 10.2580003 2.94 10.2612001 2.9350003 2 P 0 ;0,1,2=47,3=0.000000
L 10.2612001 2.915 10.25480049 2.915 2 P 0 ;0,1,2=47,3=0.000000
L 10.23986673 2.91874911 10.23826703 2.91666624 2 P 0 ;0,1,2=47,3=0.000000
L 10.23826703 2.91666624 10.2364003 2.91541654 2 P 0 ;0,1,2=47,3=0.000000
L 10.2364003 2.91541654 10.2340003 2.915 2 P 0 ;0,1,2=47,3=0.000000
L 10.2340003 2.915 10.2315998 2.91583307 2 P 0 ;0,1,2=47,3=0.000000
L 10.2315998 2.91583307 10.22973356 2.91749941 2 P 0 ;0,1,2=47,3=0.000000
L 10.22973356 2.91749941 10.2284 2.92041624 2 P 0 ;0,1,2=47,3=0.000000
L 10.2284 2.92041624 10.22813337 2.92374961 2 P 0 ;0,1,2=47,3=0.000000
L 10.22813337 2.92374961 10.22866663 2.92708297 2 P 0 ;0,1,2=47,3=0.000000
L 10.22866663 2.92708297 10.2300002 2.92916663 2 P 0 ;0,1,2=47,3=0.000000
L 10.2300002 2.92916663 10.23186693 2.93083297 2 P 0 ;0,1,2=47,3=0.000000
L 10.23186693 2.93083297 10.23373317 2.93124951 2 P 0 ;0,1,2=47,3=0.000000
L 10.23373317 2.93124951 10.2356 2.93083297 2 P 0 ;0,1,2=47,3=0.000000
L 10.2356 2.93083297 10.2379999 2.92916663 2 P 0 ;0,1,2=47,3=0.000000
L 10.2379999 2.92916663 10.2372001 2.94 2 P 0 ;0,1,2=47,3=0.000000
L 10.2372001 2.94 10.2300002 2.94 2 P 0 ;0,1,2=47,3=0.000000
L 10.21453366 2.91791604 10.21266683 2.91583307 2 P 0 ;0,1,2=47,3=0.000000
L 10.21266683 2.91583307 10.21053346 2.915 2 P 0 ;0,1,2=47,3=0.000000
L 10.21053346 2.915 10.2084001 2.91583307 2 P 0 ;0,1,2=47,3=0.000000
L 10.2084001 2.91583307 10.20653337 2.91833258 2 P 0 ;0,1,2=47,3=0.000000
L 10.20653337 2.91833258 10.2051999 2.92208327 2 P 0 ;0,1,2=47,3=0.000000
L 10.2051999 2.92208327 10.20466663 2.92583327 2 P 0 ;0,1,2=47,3=0.000000
L 10.20466663 2.92583327 10.20466663 2.93041634 2 P 0 ;0,1,2=47,3=0.000000
L 10.20466663 2.93041634 10.2051999 2.93416634 2 P 0 ;0,1,2=47,3=0.000000
L 10.2051999 2.93416634 10.20653337 2.9374997 2 P 0 ;0,1,2=47,3=0.000000
L 10.20653337 2.9374997 10.20813356 2.93916683 2 P 0 ;0,1,2=47,3=0.000000
L 10.20813356 2.93916683 10.2100003 2.94 2 P 0 ;0,1,2=47,3=0.000000
L 10.2100003 2.94 10.21213366 2.93916683 2 P 0 ;0,1,2=47,3=0.000000
L 10.21213366 2.93916683 10.21373337 2.9374997 2 P 0 ;0,1,2=47,3=0.000000
L 10.21373337 2.9374997 10.2148002 2.9350003 2 P 0 ;0,1,2=47,3=0.000000
L 10.2148002 2.9350003 10.21533346 2.93166614 2 P 0 ;0,1,2=47,3=0.000000
L 10.21533346 2.93166614 10.2148002 2.9287501 2 P 0 ;0,1,2=47,3=0.000000
L 10.2148002 2.9287501 10.21346673 2.92583327 2 P 0 ;0,1,2=47,3=0.000000
L 10.21346673 2.92583327 10.21186654 2.92416614 2 P 0 ;0,1,2=47,3=0.000000
L 10.21186654 2.92416614 10.2100003 2.92374961 2 P 0 ;0,1,2=47,3=0.000000
L 10.2100003 2.92374961 10.20786693 2.92458278 2 P 0 ;0,1,2=47,3=0.000000
L 10.20786693 2.92458278 10.20626673 2.92666644 2 P 0 ;0,1,2=47,3=0.000000
L 10.20626673 2.92666644 10.20466663 2.93041634 2 P 0 ;0,1,2=47,3=0.000000
L 10.19186673 2.91874911 10.19026703 2.91666624 2 P 0 ;0,1,2=47,3=0.000000
L 10.19026703 2.91666624 10.1884003 2.91541654 2 P 0 ;0,1,2=47,3=0.000000
L 10.1884003 2.91541654 10.1860003 2.915 2 P 0 ;0,1,2=47,3=0.000000
L 10.1860003 2.915 10.1835998 2.91583307 2 P 0 ;0,1,2=47,3=0.000000
L 10.1835998 2.91583307 10.18173356 2.91749941 2 P 0 ;0,1,2=47,3=0.000000
L 10.18173356 2.91749941 10.1804 2.92041624 2 P 0 ;0,1,2=47,3=0.000000
L 10.1804 2.92041624 10.18013337 2.92374961 2 P 0 ;0,1,2=47,3=0.000000
L 10.18013337 2.92374961 10.18066663 2.92708297 2 P 0 ;0,1,2=47,3=0.000000
L 10.18066663 2.92708297 10.1820002 2.92916663 2 P 0 ;0,1,2=47,3=0.000000
L 10.1820002 2.92916663 10.18386693 2.93083297 2 P 0 ;0,1,2=47,3=0.000000
L 10.18386693 2.93083297 10.18573317 2.93124951 2 P 0 ;0,1,2=47,3=0.000000
L 10.18573317 2.93124951 10.1876 2.93083297 2 P 0 ;0,1,2=47,3=0.000000
L 10.1876 2.93083297 10.1899999 2.92916663 2 P 0 ;0,1,2=47,3=0.000000
L 10.1899999 2.92916663 10.1892001 2.94 2 P 0 ;0,1,2=47,3=0.000000
L 10.1892001 2.94 10.1820002 2.94 2 P 0 ;0,1,2=47,3=0.000000
L 4.074 2.69213002 4.074 2.70786998 3 P 0 
L 4.25733346 2.69 4.25733346 2.715 2 P 0 ;0,1,2=48,3=0.000000
L 4.25733346 2.715 4.25066673 2.715 2 P 0 ;0,1,2=48,3=0.000000
L 4.25066673 2.715 4.24853337 2.71374941 2 P 0 ;0,1,2=48,3=0.000000
L 4.24853337 2.71374941 4.2471999 2.71208317 2 P 0 ;0,1,2=48,3=0.000000
L 4.2471999 2.71208317 4.24666663 2.7087498 2 P 0 ;0,1,2=48,3=0.000000
L 4.24666663 2.7087498 4.2471999 2.70541634 2 P 0 ;0,1,2=48,3=0.000000
L 4.2471999 2.70541634 4.2488 2.70333346 2 P 0 ;0,1,2=48,3=0.000000
L 4.2488 2.70333346 4.25066673 2.70208297 2 P 0 ;0,1,2=48,3=0.000000
L 4.25066673 2.70208297 4.25733346 2.70208297 2 P 0 ;0,1,2=48,3=0.000000
L 4.25066673 2.70208297 4.24666663 2.69 2 P 0 ;0,1,2=48,3=0.000000
L 4.2280003 2.69 4.2280003 2.715 2 P 0 ;0,1,2=48,3=0.000000
L 4.2280003 2.715 4.2312001 2.7100003 2 P 0 ;0,1,2=48,3=0.000000
L 4.2312001 2.69 4.22480049 2.69 2 P 0 ;0,1,2=48,3=0.000000
L 4.20986673 2.69374911 4.20826703 2.69166624 2 P 0 ;0,1,2=48,3=0.000000
L 4.20826703 2.69166624 4.2064003 2.69041654 2 P 0 ;0,1,2=48,3=0.000000
L 4.2064003 2.69041654 4.2040003 2.69 2 P 0 ;0,1,2=48,3=0.000000
L 4.2040003 2.69 4.2015998 2.69083307 2 P 0 ;0,1,2=48,3=0.000000
L 4.2015998 2.69083307 4.19973356 2.69249941 2 P 0 ;0,1,2=48,3=0.000000
L 4.19973356 2.69249941 4.1984 2.69541624 2 P 0 ;0,1,2=48,3=0.000000
L 4.1984 2.69541624 4.19813337 2.69874961 2 P 0 ;0,1,2=48,3=0.000000
L 4.19813337 2.69874961 4.19866663 2.70208297 2 P 0 ;0,1,2=48,3=0.000000
L 4.19866663 2.70208297 4.2000002 2.70416663 2 P 0 ;0,1,2=48,3=0.000000
L 4.2000002 2.70416663 4.20186693 2.70583297 2 P 0 ;0,1,2=48,3=0.000000
L 4.20186693 2.70583297 4.20373317 2.70624951 2 P 0 ;0,1,2=48,3=0.000000
L 4.20373317 2.70624951 4.2056 2.70583297 2 P 0 ;0,1,2=48,3=0.000000
L 4.2056 2.70583297 4.2079999 2.70416663 2 P 0 ;0,1,2=48,3=0.000000
L 4.2079999 2.70416663 4.2072001 2.715 2 P 0 ;0,1,2=48,3=0.000000
L 4.2072001 2.715 4.2000002 2.715 2 P 0 ;0,1,2=48,3=0.000000
L 4.18453366 2.69291604 4.18266683 2.69083307 2 P 0 ;0,1,2=48,3=0.000000
L 4.18266683 2.69083307 4.18053346 2.69 2 P 0 ;0,1,2=48,3=0.000000
L 4.18053346 2.69 4.1784001 2.69083307 2 P 0 ;0,1,2=48,3=0.000000
L 4.1784001 2.69083307 4.17653337 2.69333258 2 P 0 ;0,1,2=48,3=0.000000
L 4.17653337 2.69333258 4.1751999 2.69708327 2 P 0 ;0,1,2=48,3=0.000000
L 4.1751999 2.69708327 4.17466663 2.70083327 2 P 0 ;0,1,2=48,3=0.000000
L 4.17466663 2.70083327 4.17466663 2.70541634 2 P 0 ;0,1,2=48,3=0.000000
L 4.17466663 2.70541634 4.1751999 2.70916634 2 P 0 ;0,1,2=48,3=0.000000
L 4.1751999 2.70916634 4.17653337 2.7124997 2 P 0 ;0,1,2=48,3=0.000000
L 4.17653337 2.7124997 4.17813356 2.71416683 2 P 0 ;0,1,2=48,3=0.000000
L 4.17813356 2.71416683 4.1800003 2.715 2 P 0 ;0,1,2=48,3=0.000000
L 4.1800003 2.715 4.18213366 2.71416683 2 P 0 ;0,1,2=48,3=0.000000
L 4.18213366 2.71416683 4.18373337 2.7124997 2 P 0 ;0,1,2=48,3=0.000000
L 4.18373337 2.7124997 4.1848002 2.7100003 2 P 0 ;0,1,2=48,3=0.000000
L 4.1848002 2.7100003 4.18533346 2.70666614 2 P 0 ;0,1,2=48,3=0.000000
L 4.18533346 2.70666614 4.1848002 2.7037501 2 P 0 ;0,1,2=48,3=0.000000
L 4.1848002 2.7037501 4.18346673 2.70083327 2 P 0 ;0,1,2=48,3=0.000000
L 4.18346673 2.70083327 4.18186654 2.69916614 2 P 0 ;0,1,2=48,3=0.000000
L 4.18186654 2.69916614 4.1800003 2.69874961 2 P 0 ;0,1,2=48,3=0.000000
L 4.1800003 2.69874961 4.17786693 2.69958278 2 P 0 ;0,1,2=48,3=0.000000
L 4.17786693 2.69958278 4.17626673 2.70166644 2 P 0 ;0,1,2=48,3=0.000000
L 4.17626673 2.70166644 4.17466663 2.70541634 2 P 0 ;0,1,2=48,3=0.000000
L 4.1528 2.69 4.1528 2.715 2 P 0 ;0,1,2=48,3=0.000000
L 4.1528 2.715 4.16266703 2.69708327 2 P 0 ;0,1,2=48,3=0.000000
L 4.16266703 2.69708327 4.14933307 2.69708327 2 P 0 ;0,1,2=48,3=0.000000
L 5.9 3.06213002 5.9 3.07786998 3 P 0 
L 6.05733346 3.055 6.05733346 3.08 2 P 0 ;0,1,2=49,3=0.000000
L 6.05733346 3.08 6.05066673 3.08 2 P 0 ;0,1,2=49,3=0.000000
L 6.05066673 3.08 6.04853337 3.07874941 2 P 0 ;0,1,2=49,3=0.000000
L 6.04853337 3.07874941 6.0471999 3.07708317 2 P 0 ;0,1,2=49,3=0.000000
L 6.0471999 3.07708317 6.04666663 3.0737498 2 P 0 ;0,1,2=49,3=0.000000
L 6.04666663 3.0737498 6.0471999 3.07041634 2 P 0 ;0,1,2=49,3=0.000000
L 6.0471999 3.07041634 6.0488 3.06833346 2 P 0 ;0,1,2=49,3=0.000000
L 6.0488 3.06833346 6.05066673 3.06708297 2 P 0 ;0,1,2=49,3=0.000000
L 6.05066673 3.06708297 6.05733346 3.06708297 2 P 0 ;0,1,2=49,3=0.000000
L 6.05066673 3.06708297 6.04666663 3.055 2 P 0 ;0,1,2=49,3=0.000000
L 6.0280003 3.055 6.0280003 3.08 2 P 0 ;0,1,2=49,3=0.000000
L 6.0280003 3.08 6.0312001 3.0750003 2 P 0 ;0,1,2=49,3=0.000000
L 6.0312001 3.055 6.02480049 3.055 2 P 0 ;0,1,2=49,3=0.000000
L 6.00906683 3.06541594 6.0072001 3.06833346 2 P 0 ;0,1,2=49,3=0.000000
L 6.0072001 3.06833346 6.0056 3.0699998 2 P 0 ;0,1,2=49,3=0.000000
L 6.0056 3.0699998 6.00346663 3.07083297 2 P 0 ;0,1,2=49,3=0.000000
L 6.00346663 3.07083297 6.0015998 3.0699998 2 P 0 ;0,1,2=49,3=0.000000
L 6.0015998 3.0699998 6.00026673 3.06833346 2 P 0 ;0,1,2=49,3=0.000000
L 6.00026673 3.06833346 5.9991999 3.06583327 2 P 0 ;0,1,2=49,3=0.000000
L 5.9991999 3.06583327 5.99893327 3.06291644 2 P 0 ;0,1,2=49,3=0.000000
L 5.99893327 3.06291644 5.9991999 3.06041624 2 P 0 ;0,1,2=49,3=0.000000
L 5.9991999 3.06041624 6.00026673 3.05791604 2 P 0 ;0,1,2=49,3=0.000000
L 6.00026673 3.05791604 6.00186693 3.05583307 2 P 0 ;0,1,2=49,3=0.000000
L 6.00186693 3.05583307 6.00373317 3.055 2 P 0 ;0,1,2=49,3=0.000000
L 6.00373317 3.055 6.00586654 3.05583307 2 P 0 ;0,1,2=49,3=0.000000
L 6.00586654 3.05583307 6.00773337 3.05833258 2 P 0 ;0,1,2=49,3=0.000000
L 6.00773337 3.05833258 6.0088002 3.06208327 2 P 0 ;0,1,2=49,3=0.000000
L 6.0088002 3.06208327 6.00906683 3.0662498 2 P 0 ;0,1,2=49,3=0.000000
L 6.00906683 3.0662498 6.00853366 3.07166614 2 P 0 ;0,1,2=49,3=0.000000
L 6.00853366 3.07166614 6.00773337 3.07458366 2 P 0 ;0,1,2=49,3=0.000000
L 6.00773337 3.07458366 6.0064003 3.0774997 2 P 0 ;0,1,2=49,3=0.000000
L 6.0064003 3.0774997 6.00453346 3.07958337 2 P 0 ;0,1,2=49,3=0.000000
L 6.00453346 3.07958337 6.00266673 3.08 2 P 0 ;0,1,2=49,3=0.000000
L 6.00266673 3.08 6.0008 3.07916683 2 P 0 ;0,1,2=49,3=0.000000
L 6.0008 3.07916683 5.99946644 3.07708317 2 P 0 ;0,1,2=49,3=0.000000
L 5.9800003 3.08 5.98213366 3.07916683 2 P 0 ;0,1,2=49,3=0.000000
L 5.98213366 3.07916683 5.98373337 3.07708317 2 P 0 ;0,1,2=49,3=0.000000
L 5.98373337 3.07708317 5.9848002 3.07458366 2 P 0 ;0,1,2=49,3=0.000000
L 5.9848002 3.07458366 5.9856001 3.07124951 2 P 0 ;0,1,2=49,3=0.000000
L 5.9856001 3.07124951 5.98586673 3.06749961 2 P 0 ;0,1,2=49,3=0.000000
L 5.98586673 3.06749961 5.9856001 3.06374961 2 P 0 ;0,1,2=49,3=0.000000
L 5.9856001 3.06374961 5.9848002 3.06041624 2 P 0 ;0,1,2=49,3=0.000000
L 5.9848002 3.06041624 5.98373337 3.05791604 2 P 0 ;0,1,2=49,3=0.000000
L 5.98373337 3.05791604 5.98213366 3.05583307 2 P 0 ;0,1,2=49,3=0.000000
L 5.98213366 3.05583307 5.9800003 3.055 2 P 0 ;0,1,2=49,3=0.000000
L 5.9800003 3.055 5.97786693 3.05583307 2 P 0 ;0,1,2=49,3=0.000000
L 5.97786693 3.05583307 5.97626673 3.05791604 2 P 0 ;0,1,2=49,3=0.000000
L 5.97626673 3.05791604 5.9751999 3.06041624 2 P 0 ;0,1,2=49,3=0.000000
L 5.9751999 3.06041624 5.9744 3.06374961 2 P 0 ;0,1,2=49,3=0.000000
L 5.9744 3.06374961 5.97413337 3.06749961 2 P 0 ;0,1,2=49,3=0.000000
L 5.97413337 3.06749961 5.9744 3.07124951 2 P 0 ;0,1,2=49,3=0.000000
L 5.9744 3.07124951 5.9751999 3.07458366 2 P 0 ;0,1,2=49,3=0.000000
L 5.9751999 3.07458366 5.97626673 3.07708317 2 P 0 ;0,1,2=49,3=0.000000
L 5.97626673 3.07708317 5.97786693 3.07916683 2 P 0 ;0,1,2=49,3=0.000000
L 5.97786693 3.07916683 5.9800003 3.08 2 P 0 ;0,1,2=49,3=0.000000
L 5.9560003 3.08 5.95813366 3.07916683 2 P 0 ;0,1,2=49,3=0.000000
L 5.95813366 3.07916683 5.95973337 3.07708317 2 P 0 ;0,1,2=49,3=0.000000
L 5.95973337 3.07708317 5.9608002 3.07458366 2 P 0 ;0,1,2=49,3=0.000000
L 5.9608002 3.07458366 5.9616001 3.07124951 2 P 0 ;0,1,2=49,3=0.000000
L 5.9616001 3.07124951 5.96186673 3.06749961 2 P 0 ;0,1,2=49,3=0.000000
L 5.96186673 3.06749961 5.9616001 3.06374961 2 P 0 ;0,1,2=49,3=0.000000
L 5.9616001 3.06374961 5.9608002 3.06041624 2 P 0 ;0,1,2=49,3=0.000000
L 5.9608002 3.06041624 5.95973337 3.05791604 2 P 0 ;0,1,2=49,3=0.000000
L 5.95973337 3.05791604 5.95813366 3.05583307 2 P 0 ;0,1,2=49,3=0.000000
L 5.95813366 3.05583307 5.9560003 3.055 2 P 0 ;0,1,2=49,3=0.000000
L 5.9560003 3.055 5.95386693 3.05583307 2 P 0 ;0,1,2=49,3=0.000000
L 5.95386693 3.05583307 5.95226673 3.05791604 2 P 0 ;0,1,2=49,3=0.000000
L 5.95226673 3.05791604 5.9511999 3.06041624 2 P 0 ;0,1,2=49,3=0.000000
L 5.9511999 3.06041624 5.9504 3.06374961 2 P 0 ;0,1,2=49,3=0.000000
L 5.9504 3.06374961 5.95013337 3.06749961 2 P 0 ;0,1,2=49,3=0.000000
L 5.95013337 3.06749961 5.9504 3.07124951 2 P 0 ;0,1,2=49,3=0.000000
L 5.9504 3.07124951 5.9511999 3.07458366 2 P 0 ;0,1,2=49,3=0.000000
L 5.9511999 3.07458366 5.95226673 3.07708317 2 P 0 ;0,1,2=49,3=0.000000
L 5.95226673 3.07708317 5.95386693 3.07916683 2 P 0 ;0,1,2=49,3=0.000000
L 5.95386693 3.07916683 5.9560003 3.08 2 P 0 ;0,1,2=49,3=0.000000
L 12.34786004 1.3231 12.33211998 1.3231 3 P 0 
L 12.33 1.16266654 12.355 1.16266654 2 P 0 ;0,1,2=50,3=90.000000
L 12.355 1.16266654 12.355 1.16933327 2 P 0 ;0,1,2=50,3=90.000000
L 12.355 1.16933327 12.35374941 1.17146663 2 P 0 ;0,1,2=50,3=90.000000
L 12.35374941 1.17146663 12.35208317 1.1728001 2 P 0 ;0,1,2=50,3=90.000000
L 12.35208317 1.1728001 12.3487498 1.17333337 2 P 0 ;0,1,2=50,3=90.000000
L 12.3487498 1.17333337 12.34541634 1.1728001 2 P 0 ;0,1,2=50,3=90.000000
L 12.34541634 1.1728001 12.34333346 1.1712 2 P 0 ;0,1,2=50,3=90.000000
L 12.34333346 1.1712 12.34208297 1.16933327 2 P 0 ;0,1,2=50,3=90.000000
L 12.34208297 1.16933327 12.34208297 1.16266654 2 P 0 ;0,1,2=50,3=90.000000
L 12.34208297 1.16933327 12.33 1.17333337 2 P 0 ;0,1,2=50,3=90.000000
L 12.33 1.1919997 12.355 1.1919997 2 P 0 ;0,1,2=50,3=90.000000
L 12.355 1.1919997 12.3500003 1.1887999 2 P 0 ;0,1,2=50,3=90.000000
L 12.33 1.1887999 12.33 1.19519951 2 P 0 ;0,1,2=50,3=90.000000
L 12.33374911 1.21013327 12.33166624 1.21173297 2 P 0 ;0,1,2=50,3=90.000000
L 12.33166624 1.21173297 12.33041654 1.2135997 2 P 0 ;0,1,2=50,3=90.000000
L 12.33041654 1.2135997 12.33 1.2159997 2 P 0 ;0,1,2=50,3=90.000000
L 12.33 1.2159997 12.33083307 1.2184002 2 P 0 ;0,1,2=50,3=90.000000
L 12.33083307 1.2184002 12.33249941 1.22026644 2 P 0 ;0,1,2=50,3=90.000000
L 12.33249941 1.22026644 12.33541624 1.2216 2 P 0 ;0,1,2=50,3=90.000000
L 12.33541624 1.2216 12.33874961 1.22186663 2 P 0 ;0,1,2=50,3=90.000000
L 12.33874961 1.22186663 12.34208297 1.22133337 2 P 0 ;0,1,2=50,3=90.000000
L 12.34208297 1.22133337 12.34416663 1.2199998 2 P 0 ;0,1,2=50,3=90.000000
L 12.34416663 1.2199998 12.34583297 1.21813307 2 P 0 ;0,1,2=50,3=90.000000
L 12.34583297 1.21813307 12.34624951 1.21626683 2 P 0 ;0,1,2=50,3=90.000000
L 12.34624951 1.21626683 12.34583297 1.2144 2 P 0 ;0,1,2=50,3=90.000000
L 12.34583297 1.2144 12.34416663 1.2120001 2 P 0 ;0,1,2=50,3=90.000000
L 12.34416663 1.2120001 12.355 1.2127999 2 P 0 ;0,1,2=50,3=90.000000
L 12.355 1.2127999 12.355 1.2199998 2 P 0 ;0,1,2=50,3=90.000000
L 12.33291604 1.23546634 12.33083307 1.23733317 2 P 0 ;0,1,2=50,3=90.000000
L 12.33083307 1.23733317 12.33 1.23946654 2 P 0 ;0,1,2=50,3=90.000000
L 12.33 1.23946654 12.33083307 1.2415999 2 P 0 ;0,1,2=50,3=90.000000
L 12.33083307 1.2415999 12.33333258 1.24346663 2 P 0 ;0,1,2=50,3=90.000000
L 12.33333258 1.24346663 12.33708327 1.2448001 2 P 0 ;0,1,2=50,3=90.000000
L 12.33708327 1.2448001 12.34083327 1.24533337 2 P 0 ;0,1,2=50,3=90.000000
L 12.34083327 1.24533337 12.34541634 1.24533337 2 P 0 ;0,1,2=50,3=90.000000
L 12.34541634 1.24533337 12.34916634 1.2448001 2 P 0 ;0,1,2=50,3=90.000000
L 12.34916634 1.2448001 12.3524997 1.24346663 2 P 0 ;0,1,2=50,3=90.000000
L 12.3524997 1.24346663 12.35416683 1.24186644 2 P 0 ;0,1,2=50,3=90.000000
L 12.35416683 1.24186644 12.355 1.2399997 2 P 0 ;0,1,2=50,3=90.000000
L 12.355 1.2399997 12.35416683 1.23786634 2 P 0 ;0,1,2=50,3=90.000000
L 12.35416683 1.23786634 12.3524997 1.23626663 2 P 0 ;0,1,2=50,3=90.000000
L 12.3524997 1.23626663 12.3500003 1.2351998 2 P 0 ;0,1,2=50,3=90.000000
L 12.3500003 1.2351998 12.34666614 1.23466654 2 P 0 ;0,1,2=50,3=90.000000
L 12.34666614 1.23466654 12.3437501 1.2351998 2 P 0 ;0,1,2=50,3=90.000000
L 12.3437501 1.2351998 12.34083327 1.23653327 2 P 0 ;0,1,2=50,3=90.000000
L 12.34083327 1.23653327 12.33916614 1.23813346 2 P 0 ;0,1,2=50,3=90.000000
L 12.33916614 1.23813346 12.33874961 1.2399997 2 P 0 ;0,1,2=50,3=90.000000
L 12.33874961 1.2399997 12.33958278 1.24213307 2 P 0 ;0,1,2=50,3=90.000000
L 12.33958278 1.24213307 12.34166644 1.24373327 2 P 0 ;0,1,2=50,3=90.000000
L 12.34166644 1.24373327 12.34541634 1.24533337 2 P 0 ;0,1,2=50,3=90.000000
L 12.33499961 1.25813327 12.33208287 1.25973297 2 P 0 ;0,1,2=50,3=90.000000
L 12.33208287 1.25973297 12.33041654 1.26186634 2 P 0 ;0,1,2=50,3=90.000000
L 12.33041654 1.26186634 12.33 1.26426683 2 P 0 ;0,1,2=50,3=90.000000
L 12.33 1.26426683 12.33041654 1.2664002 2 P 0 ;0,1,2=50,3=90.000000
L 12.33041654 1.2664002 12.33249941 1.26853356 2 P 0 ;0,1,2=50,3=90.000000
L 12.33249941 1.26853356 12.33499961 1.26986663 2 P 0 ;0,1,2=50,3=90.000000
L 12.33499961 1.26986663 12.3374999 1.27013317 2 P 0 ;0,1,2=50,3=90.000000
L 12.3374999 1.27013317 12.34041594 1.2696 2 P 0 ;0,1,2=50,3=90.000000
L 12.34041594 1.2696 12.34249961 1.26773327 2 P 0 ;0,1,2=50,3=90.000000
L 12.34249961 1.26773327 12.34333346 1.26586644 2 P 0 ;0,1,2=50,3=90.000000
L 12.34333346 1.26586644 12.34333346 1.26346654 2 P 0 ;0,1,2=50,3=90.000000
L 12.34333346 1.26586644 12.34458327 1.26746663 2 P 0 ;0,1,2=50,3=90.000000
L 12.34458327 1.26746663 12.34666614 1.2688001 2 P 0 ;0,1,2=50,3=90.000000
L 12.34666614 1.2688001 12.34916634 1.26933337 2 P 0 ;0,1,2=50,3=90.000000
L 12.34916634 1.26933337 12.35166654 1.2688001 2 P 0 ;0,1,2=50,3=90.000000
L 12.35166654 1.2688001 12.35374941 1.26746663 2 P 0 ;0,1,2=50,3=90.000000
L 12.35374941 1.26746663 12.355 1.26506663 2 P 0 ;0,1,2=50,3=90.000000
L 12.355 1.26506663 12.35458337 1.26266663 2 P 0 ;0,1,2=50,3=90.000000
L 12.35458337 1.26266663 12.35291634 1.26026663 2 P 0 ;0,1,2=50,3=90.000000
L 0.59998996 1.33023002 0.59998996 1.34596998 3 P 0 
L 0.67733346 1.36 0.67733346 1.385 2 P 0 ;0,1,2=51,3=0.000000
L 0.67733346 1.385 0.67066673 1.385 2 P 0 ;0,1,2=51,3=0.000000
L 0.67066673 1.385 0.66853337 1.38374941 2 P 0 ;0,1,2=51,3=0.000000
L 0.66853337 1.38374941 0.6671999 1.38208317 2 P 0 ;0,1,2=51,3=0.000000
L 0.6671999 1.38208317 0.66666663 1.3787498 2 P 0 ;0,1,2=51,3=0.000000
L 0.66666663 1.3787498 0.6671999 1.37541634 2 P 0 ;0,1,2=51,3=0.000000
L 0.6671999 1.37541634 0.6688 1.37333346 2 P 0 ;0,1,2=51,3=0.000000
L 0.6688 1.37333346 0.67066673 1.37208297 2 P 0 ;0,1,2=51,3=0.000000
L 0.67066673 1.37208297 0.67733346 1.37208297 2 P 0 ;0,1,2=51,3=0.000000
L 0.67066673 1.37208297 0.66666663 1.36 2 P 0 ;0,1,2=51,3=0.000000
L 0.6480003 1.36 0.6480003 1.385 2 P 0 ;0,1,2=51,3=0.000000
L 0.6480003 1.385 0.6512001 1.3800003 2 P 0 ;0,1,2=51,3=0.000000
L 0.6512001 1.36 0.64480049 1.36 2 P 0 ;0,1,2=51,3=0.000000
L 0.62986673 1.36374911 0.62826703 1.36166624 2 P 0 ;0,1,2=51,3=0.000000
L 0.62826703 1.36166624 0.6264003 1.36041654 2 P 0 ;0,1,2=51,3=0.000000
L 0.6264003 1.36041654 0.6240003 1.36 2 P 0 ;0,1,2=51,3=0.000000
L 0.6240003 1.36 0.6215998 1.36083307 2 P 0 ;0,1,2=51,3=0.000000
L 0.6215998 1.36083307 0.61973356 1.36249941 2 P 0 ;0,1,2=51,3=0.000000
L 0.61973356 1.36249941 0.6184 1.36541624 2 P 0 ;0,1,2=51,3=0.000000
L 0.6184 1.36541624 0.61813337 1.36874961 2 P 0 ;0,1,2=51,3=0.000000
L 0.61813337 1.36874961 0.61866663 1.37208297 2 P 0 ;0,1,2=51,3=0.000000
L 0.61866663 1.37208297 0.6200002 1.37416663 2 P 0 ;0,1,2=51,3=0.000000
L 0.6200002 1.37416663 0.62186693 1.37583297 2 P 0 ;0,1,2=51,3=0.000000
L 0.62186693 1.37583297 0.62373317 1.37624951 2 P 0 ;0,1,2=51,3=0.000000
L 0.62373317 1.37624951 0.6256 1.37583297 2 P 0 ;0,1,2=51,3=0.000000
L 0.6256 1.37583297 0.6279999 1.37416663 2 P 0 ;0,1,2=51,3=0.000000
L 0.6279999 1.37416663 0.6272001 1.385 2 P 0 ;0,1,2=51,3=0.000000
L 0.6272001 1.385 0.6200002 1.385 2 P 0 ;0,1,2=51,3=0.000000
L 0.60453366 1.36291604 0.60266683 1.36083307 2 P 0 ;0,1,2=51,3=0.000000
L 0.60266683 1.36083307 0.60053346 1.36 2 P 0 ;0,1,2=51,3=0.000000
L 0.60053346 1.36 0.5984001 1.36083307 2 P 0 ;0,1,2=51,3=0.000000
L 0.5984001 1.36083307 0.59653337 1.36333258 2 P 0 ;0,1,2=51,3=0.000000
L 0.59653337 1.36333258 0.5951999 1.36708327 2 P 0 ;0,1,2=51,3=0.000000
L 0.5951999 1.36708327 0.59466663 1.37083327 2 P 0 ;0,1,2=51,3=0.000000
L 0.59466663 1.37083327 0.59466663 1.37541634 2 P 0 ;0,1,2=51,3=0.000000
L 0.59466663 1.37541634 0.5951999 1.37916634 2 P 0 ;0,1,2=51,3=0.000000
L 0.5951999 1.37916634 0.59653337 1.3824997 2 P 0 ;0,1,2=51,3=0.000000
L 0.59653337 1.3824997 0.59813356 1.38416683 2 P 0 ;0,1,2=51,3=0.000000
L 0.59813356 1.38416683 0.6000003 1.385 2 P 0 ;0,1,2=51,3=0.000000
L 0.6000003 1.385 0.60213366 1.38416683 2 P 0 ;0,1,2=51,3=0.000000
L 0.60213366 1.38416683 0.60373337 1.3824997 2 P 0 ;0,1,2=51,3=0.000000
L 0.60373337 1.3824997 0.6048002 1.3800003 2 P 0 ;0,1,2=51,3=0.000000
L 0.6048002 1.3800003 0.60533346 1.37666614 2 P 0 ;0,1,2=51,3=0.000000
L 0.60533346 1.37666614 0.6048002 1.3737501 2 P 0 ;0,1,2=51,3=0.000000
L 0.6048002 1.3737501 0.60346673 1.37083327 2 P 0 ;0,1,2=51,3=0.000000
L 0.60346673 1.37083327 0.60186654 1.36916614 2 P 0 ;0,1,2=51,3=0.000000
L 0.60186654 1.36916614 0.6000003 1.36874961 2 P 0 ;0,1,2=51,3=0.000000
L 0.6000003 1.36874961 0.59786693 1.36958278 2 P 0 ;0,1,2=51,3=0.000000
L 0.59786693 1.36958278 0.59626673 1.37166644 2 P 0 ;0,1,2=51,3=0.000000
L 0.59626673 1.37166644 0.59466663 1.37541634 2 P 0 ;0,1,2=51,3=0.000000
L 0.58106683 1.38083337 0.57946673 1.38333287 2 P 0 ;0,1,2=51,3=0.000000
L 0.57946673 1.38333287 0.5776 1.38458337 2 P 0 ;0,1,2=51,3=0.000000
L 0.5776 1.38458337 0.57546663 1.385 2 P 0 ;0,1,2=51,3=0.000000
L 0.57546663 1.385 0.5728 1.38416683 2 P 0 ;0,1,2=51,3=0.000000
L 0.5728 1.38416683 0.57093327 1.38208317 2 P 0 ;0,1,2=51,3=0.000000
L 0.57093327 1.38208317 0.5704 1.37958366 2 P 0 ;0,1,2=51,3=0.000000
L 0.5704 1.37958366 0.57066663 1.37708268 2 P 0 ;0,1,2=51,3=0.000000
L 0.57066663 1.37708268 0.57173356 1.3749998 2 P 0 ;0,1,2=51,3=0.000000
L 0.57173356 1.3749998 0.57706673 1.37083327 2 P 0 ;0,1,2=51,3=0.000000
L 0.57706673 1.37083327 0.57946673 1.36791644 2 P 0 ;0,1,2=51,3=0.000000
L 0.57946673 1.36791644 0.58106683 1.36374911 2 P 0 ;0,1,2=51,3=0.000000
L 0.58106683 1.36374911 0.5816001 1.36 2 P 0 ;0,1,2=51,3=0.000000
L 0.5816001 1.36 0.5704 1.36 2 P 0 ;0,1,2=51,3=0.000000
L 6.44118996 5.05491998 6.44118996 5.03918002 3 P 0 
L 6.45333346 5.125 6.45333346 5.15 2 P 0 ;0,1,2=52,3=0.000000
L 6.45333346 5.15 6.44693337 5.15 2 P 0 ;0,1,2=52,3=0.000000
L 6.44693337 5.15 6.4448 5.14874941 2 P 0 ;0,1,2=52,3=0.000000
L 6.4448 5.14874941 6.4431999 5.14583337 2 P 0 ;0,1,2=52,3=0.000000
L 6.4431999 5.14583337 6.44266663 5.1425 2 P 0 ;0,1,2=52,3=0.000000
L 6.44266663 5.1425 6.4431999 5.13916663 2 P 0 ;0,1,2=52,3=0.000000
L 6.4431999 5.13916663 6.44453337 5.13666644 2 P 0 ;0,1,2=52,3=0.000000
L 6.44453337 5.13666644 6.44693337 5.13541594 2 P 0 ;0,1,2=52,3=0.000000
L 6.44693337 5.13541594 6.45333346 5.13541594 2 P 0 ;0,1,2=52,3=0.000000
L 6.4296001 5.12833258 6.42746673 5.1262497 2 P 0 ;0,1,2=52,3=0.000000
L 6.42746673 5.1262497 6.42506673 5.125 2 P 0 ;0,1,2=52,3=0.000000
L 6.42506673 5.125 6.42293337 5.125 2 P 0 ;0,1,2=52,3=0.000000
L 6.42293337 5.125 6.4208 5.1262497 2 P 0 ;0,1,2=52,3=0.000000
L 6.4208 5.1262497 6.4191999 5.12833258 2 P 0 ;0,1,2=52,3=0.000000
L 6.4191999 5.12833258 6.4184 5.1312501 2 P 0 ;0,1,2=52,3=0.000000
L 6.4184 5.1312501 6.41893327 5.13416614 2 P 0 ;0,1,2=52,3=0.000000
L 6.41893327 5.13416614 6.42026673 5.13666644 2 P 0 ;0,1,2=52,3=0.000000
L 6.42026673 5.13666644 6.42266673 5.13833346 2 P 0 ;0,1,2=52,3=0.000000
L 6.42266673 5.13833346 6.42586654 5.13916663 2 P 0 ;0,1,2=52,3=0.000000
L 6.42586654 5.13916663 6.42773337 5.14083297 2 P 0 ;0,1,2=52,3=0.000000
L 6.42773337 5.14083297 6.42853366 5.1437498 2 P 0 ;0,1,2=52,3=0.000000
L 6.42853366 5.1437498 6.4279999 5.14666654 2 P 0 ;0,1,2=52,3=0.000000
L 6.4279999 5.14666654 6.42666683 5.14874941 2 P 0 ;0,1,2=52,3=0.000000
L 6.42666683 5.14874941 6.4248001 5.15 2 P 0 ;0,1,2=52,3=0.000000
L 6.4248001 5.15 6.42293337 5.15 2 P 0 ;0,1,2=52,3=0.000000
L 6.42293337 5.15 6.42106663 5.14916683 2 P 0 ;0,1,2=52,3=0.000000
L 6.42106663 5.14916683 6.41946644 5.14708317 2 P 0 ;0,1,2=52,3=0.000000
L 6.4000003 5.15 6.4000003 5.125 2 P 0 ;0,1,2=52,3=0.000000
L 6.40613327 5.15 6.39386683 5.15 2 P 0 ;0,1,2=52,3=0.000000
L 6.38133346 5.125 6.38133346 5.15 2 P 0 ;0,1,2=52,3=0.000000
L 6.38133346 5.15 6.37466673 5.15 2 P 0 ;0,1,2=52,3=0.000000
L 6.37466673 5.15 6.37253337 5.14874941 2 P 0 ;0,1,2=52,3=0.000000
L 6.37253337 5.14874941 6.3711999 5.14708317 2 P 0 ;0,1,2=52,3=0.000000
L 6.3711999 5.14708317 6.37066663 5.1437498 2 P 0 ;0,1,2=52,3=0.000000
L 6.37066663 5.1437498 6.3711999 5.14041634 2 P 0 ;0,1,2=52,3=0.000000
L 6.3711999 5.14041634 6.3728 5.13833346 2 P 0 ;0,1,2=52,3=0.000000
L 6.3728 5.13833346 6.37466673 5.13708297 2 P 0 ;0,1,2=52,3=0.000000
L 6.37466673 5.13708297 6.38133346 5.13708297 2 P 0 ;0,1,2=52,3=0.000000
L 6.37466673 5.13708297 6.37066663 5.125 2 P 0 ;0,1,2=52,3=0.000000
L 6.3520003 5.125 6.35013356 5.12541654 2 P 0 ;0,1,2=52,3=0.000000
L 6.35013356 5.12541654 6.3480002 5.12666624 2 P 0 ;0,1,2=52,3=0.000000
L 6.3480002 5.12666624 6.34666663 5.12874911 2 P 0 ;0,1,2=52,3=0.000000
L 6.34666663 5.12874911 6.34613337 5.13166673 2 P 0 ;0,1,2=52,3=0.000000
L 6.34613337 5.13166673 6.34666663 5.13458278 2 P 0 ;0,1,2=52,3=0.000000
L 6.34666663 5.13458278 6.34826673 5.13708297 2 P 0 ;0,1,2=52,3=0.000000
L 6.34826673 5.13708297 6.35066673 5.13833346 2 P 0 ;0,1,2=52,3=0.000000
L 6.35066673 5.13833346 6.35333337 5.13833346 2 P 0 ;0,1,2=52,3=0.000000
L 6.35333337 5.13833346 6.35493346 5.13916663 2 P 0 ;0,1,2=52,3=0.000000
L 6.35493346 5.13916663 6.35626703 5.14124951 2 P 0 ;0,1,2=52,3=0.000000
L 6.35626703 5.14124951 6.3568002 5.14416634 2 P 0 ;0,1,2=52,3=0.000000
L 6.3568002 5.14416634 6.3559999 5.14708317 2 P 0 ;0,1,2=52,3=0.000000
L 6.3559999 5.14708317 6.35413366 5.14916683 2 P 0 ;0,1,2=52,3=0.000000
L 6.35413366 5.14916683 6.3520003 5.15 2 P 0 ;0,1,2=52,3=0.000000
L 6.3520003 5.15 6.34986693 5.14916683 2 P 0 ;0,1,2=52,3=0.000000
L 6.34986693 5.14916683 6.3480002 5.14708317 2 P 0 ;0,1,2=52,3=0.000000
L 6.3480002 5.14708317 6.3471999 5.14416634 2 P 0 ;0,1,2=52,3=0.000000
L 6.3471999 5.14416634 6.34773356 5.14124951 2 P 0 ;0,1,2=52,3=0.000000
L 6.34773356 5.14124951 6.34906663 5.13916663 2 P 0 ;0,1,2=52,3=0.000000
L 6.34906663 5.13916663 6.35066673 5.13833346 2 P 0 ;0,1,2=52,3=0.000000
L 6.35066673 5.13833346 6.35333337 5.13833346 2 P 0 ;0,1,2=52,3=0.000000
L 6.35333337 5.13833346 6.35573337 5.13708297 2 P 0 ;0,1,2=52,3=0.000000
L 6.35573337 5.13708297 6.35733346 5.13458278 2 P 0 ;0,1,2=52,3=0.000000
L 6.35733346 5.13458278 6.35786673 5.13166673 2 P 0 ;0,1,2=52,3=0.000000
L 6.35786673 5.13166673 6.35733346 5.12874911 2 P 0 ;0,1,2=52,3=0.000000
L 6.35733346 5.12874911 6.3559999 5.12666624 2 P 0 ;0,1,2=52,3=0.000000
L 6.3559999 5.12666624 6.35386654 5.12541654 2 P 0 ;0,1,2=52,3=0.000000
L 6.35386654 5.12541654 6.3520003 5.125 2 P 0 ;0,1,2=52,3=0.000000
L 6.44118996 4.98918002 6.44118996 5.00491998 3 P 0 
L 6.44833346 5.085 6.44833346 5.11 2 P 0 ;0,1,2=53,3=0.000000
L 6.44833346 5.11 6.44193337 5.11 2 P 0 ;0,1,2=53,3=0.000000
L 6.44193337 5.11 6.4398 5.10874941 2 P 0 ;0,1,2=53,3=0.000000
L 6.4398 5.10874941 6.4381999 5.10583337 2 P 0 ;0,1,2=53,3=0.000000
L 6.4381999 5.10583337 6.43766663 5.1025 2 P 0 ;0,1,2=53,3=0.000000
L 6.43766663 5.1025 6.4381999 5.09916663 2 P 0 ;0,1,2=53,3=0.000000
L 6.4381999 5.09916663 6.43953337 5.09666644 2 P 0 ;0,1,2=53,3=0.000000
L 6.43953337 5.09666644 6.44193337 5.09541594 2 P 0 ;0,1,2=53,3=0.000000
L 6.44193337 5.09541594 6.44833346 5.09541594 2 P 0 ;0,1,2=53,3=0.000000
L 6.4246001 5.08833258 6.42246673 5.0862497 2 P 0 ;0,1,2=53,3=0.000000
L 6.42246673 5.0862497 6.42006673 5.085 2 P 0 ;0,1,2=53,3=0.000000
L 6.42006673 5.085 6.41793337 5.085 2 P 0 ;0,1,2=53,3=0.000000
L 6.41793337 5.085 6.4158 5.0862497 2 P 0 ;0,1,2=53,3=0.000000
L 6.4158 5.0862497 6.4141999 5.08833258 2 P 0 ;0,1,2=53,3=0.000000
L 6.4141999 5.08833258 6.4134 5.0912501 2 P 0 ;0,1,2=53,3=0.000000
L 6.4134 5.0912501 6.41393327 5.09416614 2 P 0 ;0,1,2=53,3=0.000000
L 6.41393327 5.09416614 6.41526673 5.09666644 2 P 0 ;0,1,2=53,3=0.000000
L 6.41526673 5.09666644 6.41766673 5.09833346 2 P 0 ;0,1,2=53,3=0.000000
L 6.41766673 5.09833346 6.42086654 5.09916663 2 P 0 ;0,1,2=53,3=0.000000
L 6.42086654 5.09916663 6.42273337 5.10083297 2 P 0 ;0,1,2=53,3=0.000000
L 6.42273337 5.10083297 6.42353366 5.1037498 2 P 0 ;0,1,2=53,3=0.000000
L 6.42353366 5.1037498 6.4229999 5.10666654 2 P 0 ;0,1,2=53,3=0.000000
L 6.4229999 5.10666654 6.42166683 5.10874941 2 P 0 ;0,1,2=53,3=0.000000
L 6.42166683 5.10874941 6.4198001 5.11 2 P 0 ;0,1,2=53,3=0.000000
L 6.4198001 5.11 6.41793337 5.11 2 P 0 ;0,1,2=53,3=0.000000
L 6.41793337 5.11 6.41606663 5.10916683 2 P 0 ;0,1,2=53,3=0.000000
L 6.41606663 5.10916683 6.41446644 5.10708317 2 P 0 ;0,1,2=53,3=0.000000
L 6.3950003 5.11 6.3950003 5.085 2 P 0 ;0,1,2=53,3=0.000000
L 6.40113327 5.11 6.38886683 5.11 2 P 0 ;0,1,2=53,3=0.000000
L 6.37633346 5.085 6.37633346 5.11 2 P 0 ;0,1,2=53,3=0.000000
L 6.37633346 5.11 6.36966673 5.11 2 P 0 ;0,1,2=53,3=0.000000
L 6.36966673 5.11 6.36753337 5.10874941 2 P 0 ;0,1,2=53,3=0.000000
L 6.36753337 5.10874941 6.3661999 5.10708317 2 P 0 ;0,1,2=53,3=0.000000
L 6.3661999 5.10708317 6.36566663 5.1037498 2 P 0 ;0,1,2=53,3=0.000000
L 6.36566663 5.1037498 6.3661999 5.10041634 2 P 0 ;0,1,2=53,3=0.000000
L 6.3661999 5.10041634 6.3678 5.09833346 2 P 0 ;0,1,2=53,3=0.000000
L 6.3678 5.09833346 6.36966673 5.09708297 2 P 0 ;0,1,2=53,3=0.000000
L 6.36966673 5.09708297 6.37633346 5.09708297 2 P 0 ;0,1,2=53,3=0.000000
L 6.36966673 5.09708297 6.36566663 5.085 2 P 0 ;0,1,2=53,3=0.000000
L 6.3470003 5.085 6.3470003 5.11 2 P 0 ;0,1,2=53,3=0.000000
L 6.3470003 5.11 6.3502001 5.1050003 2 P 0 ;0,1,2=53,3=0.000000
L 6.3502001 5.085 6.34380049 5.085 2 P 0 ;0,1,2=53,3=0.000000
L 6.36648996 4.98918002 6.36648996 5.00491998 3 P 0 
L 6.31533346 5.085 6.31533346 5.11 2 P 0 ;0,1,2=54,3=0.000000
L 6.31533346 5.11 6.30893337 5.11 2 P 0 ;0,1,2=54,3=0.000000
L 6.30893337 5.11 6.3068 5.10874941 2 P 0 ;0,1,2=54,3=0.000000
L 6.3068 5.10874941 6.3051999 5.10583337 2 P 0 ;0,1,2=54,3=0.000000
L 6.3051999 5.10583337 6.30466663 5.1025 2 P 0 ;0,1,2=54,3=0.000000
L 6.30466663 5.1025 6.3051999 5.09916663 2 P 0 ;0,1,2=54,3=0.000000
L 6.3051999 5.09916663 6.30653337 5.09666644 2 P 0 ;0,1,2=54,3=0.000000
L 6.30653337 5.09666644 6.30893337 5.09541594 2 P 0 ;0,1,2=54,3=0.000000
L 6.30893337 5.09541594 6.31533346 5.09541594 2 P 0 ;0,1,2=54,3=0.000000
L 6.2916001 5.08833258 6.28946673 5.0862497 2 P 0 ;0,1,2=54,3=0.000000
L 6.28946673 5.0862497 6.28706673 5.085 2 P 0 ;0,1,2=54,3=0.000000
L 6.28706673 5.085 6.28493337 5.085 2 P 0 ;0,1,2=54,3=0.000000
L 6.28493337 5.085 6.2828 5.0862497 2 P 0 ;0,1,2=54,3=0.000000
L 6.2828 5.0862497 6.2811999 5.08833258 2 P 0 ;0,1,2=54,3=0.000000
L 6.2811999 5.08833258 6.2804 5.0912501 2 P 0 ;0,1,2=54,3=0.000000
L 6.2804 5.0912501 6.28093327 5.09416614 2 P 0 ;0,1,2=54,3=0.000000
L 6.28093327 5.09416614 6.28226673 5.09666644 2 P 0 ;0,1,2=54,3=0.000000
L 6.28226673 5.09666644 6.28466673 5.09833346 2 P 0 ;0,1,2=54,3=0.000000
L 6.28466673 5.09833346 6.28786654 5.09916663 2 P 0 ;0,1,2=54,3=0.000000
L 6.28786654 5.09916663 6.28973337 5.10083297 2 P 0 ;0,1,2=54,3=0.000000
L 6.28973337 5.10083297 6.29053366 5.1037498 2 P 0 ;0,1,2=54,3=0.000000
L 6.29053366 5.1037498 6.2899999 5.10666654 2 P 0 ;0,1,2=54,3=0.000000
L 6.2899999 5.10666654 6.28866683 5.10874941 2 P 0 ;0,1,2=54,3=0.000000
L 6.28866683 5.10874941 6.2868001 5.11 2 P 0 ;0,1,2=54,3=0.000000
L 6.2868001 5.11 6.28493337 5.11 2 P 0 ;0,1,2=54,3=0.000000
L 6.28493337 5.11 6.28306663 5.10916683 2 P 0 ;0,1,2=54,3=0.000000
L 6.28306663 5.10916683 6.28146644 5.10708317 2 P 0 ;0,1,2=54,3=0.000000
L 6.2620003 5.11 6.2620003 5.085 2 P 0 ;0,1,2=54,3=0.000000
L 6.26813327 5.11 6.25586683 5.11 2 P 0 ;0,1,2=54,3=0.000000
L 6.24333346 5.085 6.24333346 5.11 2 P 0 ;0,1,2=54,3=0.000000
L 6.24333346 5.11 6.23666673 5.11 2 P 0 ;0,1,2=54,3=0.000000
L 6.23666673 5.11 6.23453337 5.10874941 2 P 0 ;0,1,2=54,3=0.000000
L 6.23453337 5.10874941 6.2331999 5.10708317 2 P 0 ;0,1,2=54,3=0.000000
L 6.2331999 5.10708317 6.23266663 5.1037498 2 P 0 ;0,1,2=54,3=0.000000
L 6.23266663 5.1037498 6.2331999 5.10041634 2 P 0 ;0,1,2=54,3=0.000000
L 6.2331999 5.10041634 6.2348 5.09833346 2 P 0 ;0,1,2=54,3=0.000000
L 6.2348 5.09833346 6.23666673 5.09708297 2 P 0 ;0,1,2=54,3=0.000000
L 6.23666673 5.09708297 6.24333346 5.09708297 2 P 0 ;0,1,2=54,3=0.000000
L 6.23666673 5.09708297 6.23266663 5.085 2 P 0 ;0,1,2=54,3=0.000000
L 6.21986673 5.08999961 6.21826703 5.08708287 2 P 0 ;0,1,2=54,3=0.000000
L 6.21826703 5.08708287 6.21613366 5.08541654 2 P 0 ;0,1,2=54,3=0.000000
L 6.21613366 5.08541654 6.21373317 5.085 2 P 0 ;0,1,2=54,3=0.000000
L 6.21373317 5.085 6.2115998 5.08541654 2 P 0 ;0,1,2=54,3=0.000000
L 6.2115998 5.08541654 6.20946644 5.08749941 2 P 0 ;0,1,2=54,3=0.000000
L 6.20946644 5.08749941 6.20813337 5.08999961 2 P 0 ;0,1,2=54,3=0.000000
L 6.20813337 5.08999961 6.20786683 5.0924999 2 P 0 ;0,1,2=54,3=0.000000
L 6.20786683 5.0924999 6.2084 5.09541594 2 P 0 ;0,1,2=54,3=0.000000
L 6.2084 5.09541594 6.21026673 5.09749961 2 P 0 ;0,1,2=54,3=0.000000
L 6.21026673 5.09749961 6.21213356 5.09833346 2 P 0 ;0,1,2=54,3=0.000000
L 6.21213356 5.09833346 6.21453346 5.09833346 2 P 0 ;0,1,2=54,3=0.000000
L 6.21213356 5.09833346 6.21053337 5.09958327 2 P 0 ;0,1,2=54,3=0.000000
L 6.21053337 5.09958327 6.2091999 5.10166614 2 P 0 ;0,1,2=54,3=0.000000
L 6.2091999 5.10166614 6.20866663 5.10416634 2 P 0 ;0,1,2=54,3=0.000000
L 6.20866663 5.10416634 6.2091999 5.10666654 2 P 0 ;0,1,2=54,3=0.000000
L 6.2091999 5.10666654 6.21053337 5.10874941 2 P 0 ;0,1,2=54,3=0.000000
L 6.21053337 5.10874941 6.21293337 5.11 2 P 0 ;0,1,2=54,3=0.000000
L 6.21293337 5.11 6.21533337 5.10958337 2 P 0 ;0,1,2=54,3=0.000000
L 6.21533337 5.10958337 6.21773337 5.10791634 2 P 0 ;0,1,2=54,3=0.000000
L 6.19506683 5.09541594 6.1932001 5.09833346 2 P 0 ;0,1,2=54,3=0.000000
L 6.1932001 5.09833346 6.1916 5.0999998 2 P 0 ;0,1,2=54,3=0.000000
L 6.1916 5.0999998 6.18946663 5.10083297 2 P 0 ;0,1,2=54,3=0.000000
L 6.18946663 5.10083297 6.1875998 5.0999998 2 P 0 ;0,1,2=54,3=0.000000
L 6.1875998 5.0999998 6.18626673 5.09833346 2 P 0 ;0,1,2=54,3=0.000000
L 6.18626673 5.09833346 6.1851999 5.09583327 2 P 0 ;0,1,2=54,3=0.000000
L 6.1851999 5.09583327 6.18493327 5.09291644 2 P 0 ;0,1,2=54,3=0.000000
L 6.18493327 5.09291644 6.1851999 5.09041624 2 P 0 ;0,1,2=54,3=0.000000
L 6.1851999 5.09041624 6.18626673 5.08791604 2 P 0 ;0,1,2=54,3=0.000000
L 6.18626673 5.08791604 6.18786693 5.08583307 2 P 0 ;0,1,2=54,3=0.000000
L 6.18786693 5.08583307 6.18973317 5.085 2 P 0 ;0,1,2=54,3=0.000000
L 6.18973317 5.085 6.19186654 5.08583307 2 P 0 ;0,1,2=54,3=0.000000
L 6.19186654 5.08583307 6.19373337 5.08833258 2 P 0 ;0,1,2=54,3=0.000000
L 6.19373337 5.08833258 6.1948002 5.09208327 2 P 0 ;0,1,2=54,3=0.000000
L 6.1948002 5.09208327 6.19506683 5.0962498 2 P 0 ;0,1,2=54,3=0.000000
L 6.19506683 5.0962498 6.19453366 5.10166614 2 P 0 ;0,1,2=54,3=0.000000
L 6.19453366 5.10166614 6.19373337 5.10458366 2 P 0 ;0,1,2=54,3=0.000000
L 6.19373337 5.10458366 6.1924003 5.1074997 2 P 0 ;0,1,2=54,3=0.000000
L 6.1924003 5.1074997 6.19053346 5.10958337 2 P 0 ;0,1,2=54,3=0.000000
L 6.19053346 5.10958337 6.18866673 5.11 2 P 0 ;0,1,2=54,3=0.000000
L 6.18866673 5.11 6.1868 5.10916683 2 P 0 ;0,1,2=54,3=0.000000
L 6.1868 5.10916683 6.18546644 5.10708317 2 P 0 ;0,1,2=54,3=0.000000
L 6.59118996 4.98918002 6.59118996 5.00491998 3 P 0 
L 6.64033346 5.125 6.64033346 5.15 2 P 0 ;0,1,2=55,3=0.000000
L 6.64033346 5.15 6.63393337 5.15 2 P 0 ;0,1,2=55,3=0.000000
L 6.63393337 5.15 6.6318 5.14874941 2 P 0 ;0,1,2=55,3=0.000000
L 6.6318 5.14874941 6.6301999 5.14583337 2 P 0 ;0,1,2=55,3=0.000000
L 6.6301999 5.14583337 6.62966663 5.1425 2 P 0 ;0,1,2=55,3=0.000000
L 6.62966663 5.1425 6.6301999 5.13916663 2 P 0 ;0,1,2=55,3=0.000000
L 6.6301999 5.13916663 6.63153337 5.13666644 2 P 0 ;0,1,2=55,3=0.000000
L 6.63153337 5.13666644 6.63393337 5.13541594 2 P 0 ;0,1,2=55,3=0.000000
L 6.63393337 5.13541594 6.64033346 5.13541594 2 P 0 ;0,1,2=55,3=0.000000
L 6.6166001 5.12833258 6.61446673 5.1262497 2 P 0 ;0,1,2=55,3=0.000000
L 6.61446673 5.1262497 6.61206673 5.125 2 P 0 ;0,1,2=55,3=0.000000
L 6.61206673 5.125 6.60993337 5.125 2 P 0 ;0,1,2=55,3=0.000000
L 6.60993337 5.125 6.6078 5.1262497 2 P 0 ;0,1,2=55,3=0.000000
L 6.6078 5.1262497 6.6061999 5.12833258 2 P 0 ;0,1,2=55,3=0.000000
L 6.6061999 5.12833258 6.6054 5.1312501 2 P 0 ;0,1,2=55,3=0.000000
L 6.6054 5.1312501 6.60593327 5.13416614 2 P 0 ;0,1,2=55,3=0.000000
L 6.60593327 5.13416614 6.60726673 5.13666644 2 P 0 ;0,1,2=55,3=0.000000
L 6.60726673 5.13666644 6.60966673 5.13833346 2 P 0 ;0,1,2=55,3=0.000000
L 6.60966673 5.13833346 6.61286654 5.13916663 2 P 0 ;0,1,2=55,3=0.000000
L 6.61286654 5.13916663 6.61473337 5.14083297 2 P 0 ;0,1,2=55,3=0.000000
L 6.61473337 5.14083297 6.61553366 5.1437498 2 P 0 ;0,1,2=55,3=0.000000
L 6.61553366 5.1437498 6.6149999 5.14666654 2 P 0 ;0,1,2=55,3=0.000000
L 6.6149999 5.14666654 6.61366683 5.14874941 2 P 0 ;0,1,2=55,3=0.000000
L 6.61366683 5.14874941 6.6118001 5.15 2 P 0 ;0,1,2=55,3=0.000000
L 6.6118001 5.15 6.60993337 5.15 2 P 0 ;0,1,2=55,3=0.000000
L 6.60993337 5.15 6.60806663 5.14916683 2 P 0 ;0,1,2=55,3=0.000000
L 6.60806663 5.14916683 6.60646644 5.14708317 2 P 0 ;0,1,2=55,3=0.000000
L 6.5870003 5.15 6.5870003 5.125 2 P 0 ;0,1,2=55,3=0.000000
L 6.59313327 5.15 6.58086683 5.15 2 P 0 ;0,1,2=55,3=0.000000
L 6.56833346 5.125 6.56833346 5.15 2 P 0 ;0,1,2=55,3=0.000000
L 6.56833346 5.15 6.56166673 5.15 2 P 0 ;0,1,2=55,3=0.000000
L 6.56166673 5.15 6.55953337 5.14874941 2 P 0 ;0,1,2=55,3=0.000000
L 6.55953337 5.14874941 6.5581999 5.14708317 2 P 0 ;0,1,2=55,3=0.000000
L 6.5581999 5.14708317 6.55766663 5.1437498 2 P 0 ;0,1,2=55,3=0.000000
L 6.55766663 5.1437498 6.5581999 5.14041634 2 P 0 ;0,1,2=55,3=0.000000
L 6.5581999 5.14041634 6.5598 5.13833346 2 P 0 ;0,1,2=55,3=0.000000
L 6.5598 5.13833346 6.56166673 5.13708297 2 P 0 ;0,1,2=55,3=0.000000
L 6.56166673 5.13708297 6.56833346 5.13708297 2 P 0 ;0,1,2=55,3=0.000000
L 6.56166673 5.13708297 6.55766663 5.125 2 P 0 ;0,1,2=55,3=0.000000
L 6.5390003 5.125 6.5390003 5.15 2 P 0 ;0,1,2=55,3=0.000000
L 6.5390003 5.15 6.5422001 5.1450003 2 P 0 ;0,1,2=55,3=0.000000
L 6.5422001 5.125 6.53580049 5.125 2 P 0 ;0,1,2=55,3=0.000000
L 6.5118 5.125 6.5118 5.15 2 P 0 ;0,1,2=55,3=0.000000
L 6.5118 5.15 6.52166703 5.13208327 2 P 0 ;0,1,2=55,3=0.000000
L 6.52166703 5.13208327 6.50833307 5.13208327 2 P 0 ;0,1,2=55,3=0.000000
L 6.55618996 5.10491998 6.55618996 5.08918002 3 P 0 
L 6.57333346 5.175 6.57333346 5.2 2 P 0 ;0,1,2=56,3=0.000000
L 6.57333346 5.2 6.56693337 5.2 2 P 0 ;0,1,2=56,3=0.000000
L 6.56693337 5.2 6.5648 5.19874941 2 P 0 ;0,1,2=56,3=0.000000
L 6.5648 5.19874941 6.5631999 5.19583337 2 P 0 ;0,1,2=56,3=0.000000
L 6.5631999 5.19583337 6.56266663 5.1925 2 P 0 ;0,1,2=56,3=0.000000
L 6.56266663 5.1925 6.5631999 5.18916663 2 P 0 ;0,1,2=56,3=0.000000
L 6.5631999 5.18916663 6.56453337 5.18666644 2 P 0 ;0,1,2=56,3=0.000000
L 6.56453337 5.18666644 6.56693337 5.18541594 2 P 0 ;0,1,2=56,3=0.000000
L 6.56693337 5.18541594 6.57333346 5.18541594 2 P 0 ;0,1,2=56,3=0.000000
L 6.5496001 5.17833258 6.54746673 5.1762497 2 P 0 ;0,1,2=56,3=0.000000
L 6.54746673 5.1762497 6.54506673 5.175 2 P 0 ;0,1,2=56,3=0.000000
L 6.54506673 5.175 6.54293337 5.175 2 P 0 ;0,1,2=56,3=0.000000
L 6.54293337 5.175 6.5408 5.1762497 2 P 0 ;0,1,2=56,3=0.000000
L 6.5408 5.1762497 6.5391999 5.17833258 2 P 0 ;0,1,2=56,3=0.000000
L 6.5391999 5.17833258 6.5384 5.1812501 2 P 0 ;0,1,2=56,3=0.000000
L 6.5384 5.1812501 6.53893327 5.18416614 2 P 0 ;0,1,2=56,3=0.000000
L 6.53893327 5.18416614 6.54026673 5.18666644 2 P 0 ;0,1,2=56,3=0.000000
L 6.54026673 5.18666644 6.54266673 5.18833346 2 P 0 ;0,1,2=56,3=0.000000
L 6.54266673 5.18833346 6.54586654 5.18916663 2 P 0 ;0,1,2=56,3=0.000000
L 6.54586654 5.18916663 6.54773337 5.19083297 2 P 0 ;0,1,2=56,3=0.000000
L 6.54773337 5.19083297 6.54853366 5.1937498 2 P 0 ;0,1,2=56,3=0.000000
L 6.54853366 5.1937498 6.5479999 5.19666654 2 P 0 ;0,1,2=56,3=0.000000
L 6.5479999 5.19666654 6.54666683 5.19874941 2 P 0 ;0,1,2=56,3=0.000000
L 6.54666683 5.19874941 6.5448001 5.2 2 P 0 ;0,1,2=56,3=0.000000
L 6.5448001 5.2 6.54293337 5.2 2 P 0 ;0,1,2=56,3=0.000000
L 6.54293337 5.2 6.54106663 5.19916683 2 P 0 ;0,1,2=56,3=0.000000
L 6.54106663 5.19916683 6.53946644 5.19708317 2 P 0 ;0,1,2=56,3=0.000000
L 6.5200003 5.2 6.5200003 5.175 2 P 0 ;0,1,2=56,3=0.000000
L 6.52613327 5.2 6.51386683 5.2 2 P 0 ;0,1,2=56,3=0.000000
L 6.50133346 5.175 6.50133346 5.2 2 P 0 ;0,1,2=56,3=0.000000
L 6.50133346 5.2 6.49466673 5.2 2 P 0 ;0,1,2=56,3=0.000000
L 6.49466673 5.2 6.49253337 5.19874941 2 P 0 ;0,1,2=56,3=0.000000
L 6.49253337 5.19874941 6.4911999 5.19708317 2 P 0 ;0,1,2=56,3=0.000000
L 6.4911999 5.19708317 6.49066663 5.1937498 2 P 0 ;0,1,2=56,3=0.000000
L 6.49066663 5.1937498 6.4911999 5.19041634 2 P 0 ;0,1,2=56,3=0.000000
L 6.4911999 5.19041634 6.4928 5.18833346 2 P 0 ;0,1,2=56,3=0.000000
L 6.4928 5.18833346 6.49466673 5.18708297 2 P 0 ;0,1,2=56,3=0.000000
L 6.49466673 5.18708297 6.50133346 5.18708297 2 P 0 ;0,1,2=56,3=0.000000
L 6.49466673 5.18708297 6.49066663 5.175 2 P 0 ;0,1,2=56,3=0.000000
L 6.47253346 5.175 6.4720003 5.18041624 2 P 0 ;0,1,2=56,3=0.000000
L 6.4720003 5.18041624 6.4712 5.18499931 2 P 0 ;0,1,2=56,3=0.000000
L 6.4712 5.18499931 6.47013356 5.18916663 2 P 0 ;0,1,2=56,3=0.000000
L 6.47013356 5.18916663 6.4688 5.1937498 2 P 0 ;0,1,2=56,3=0.000000
L 6.4688 5.1937498 6.46666663 5.2 2 P 0 ;0,1,2=56,3=0.000000
L 6.46666663 5.2 6.47733346 5.2 2 P 0 ;0,1,2=56,3=0.000000
L 6.81618996 4.88918002 6.81618996 4.90491998 3 P 0 
L 7.03833346 4.885 7.03833346 4.91 2 P 0 ;0,1,2=57,3=0.000000
L 7.03833346 4.91 7.03193337 4.91 2 P 0 ;0,1,2=57,3=0.000000
L 7.03193337 4.91 7.0298 4.90874941 2 P 0 ;0,1,2=57,3=0.000000
L 7.0298 4.90874941 7.0281999 4.90583337 2 P 0 ;0,1,2=57,3=0.000000
L 7.0281999 4.90583337 7.02766663 4.9025 2 P 0 ;0,1,2=57,3=0.000000
L 7.02766663 4.9025 7.0281999 4.89916663 2 P 0 ;0,1,2=57,3=0.000000
L 7.0281999 4.89916663 7.02953337 4.89666644 2 P 0 ;0,1,2=57,3=0.000000
L 7.02953337 4.89666644 7.03193337 4.89541594 2 P 0 ;0,1,2=57,3=0.000000
L 7.03193337 4.89541594 7.03833346 4.89541594 2 P 0 ;0,1,2=57,3=0.000000
L 7.0146001 4.88833258 7.01246673 4.8862497 2 P 0 ;0,1,2=57,3=0.000000
L 7.01246673 4.8862497 7.01006673 4.885 2 P 0 ;0,1,2=57,3=0.000000
L 7.01006673 4.885 7.00793337 4.885 2 P 0 ;0,1,2=57,3=0.000000
L 7.00793337 4.885 7.0058 4.8862497 2 P 0 ;0,1,2=57,3=0.000000
L 7.0058 4.8862497 7.0041999 4.88833258 2 P 0 ;0,1,2=57,3=0.000000
L 7.0041999 4.88833258 7.0034 4.8912501 2 P 0 ;0,1,2=57,3=0.000000
L 7.0034 4.8912501 7.00393327 4.89416614 2 P 0 ;0,1,2=57,3=0.000000
L 7.00393327 4.89416614 7.00526673 4.89666644 2 P 0 ;0,1,2=57,3=0.000000
L 7.00526673 4.89666644 7.00766673 4.89833346 2 P 0 ;0,1,2=57,3=0.000000
L 7.00766673 4.89833346 7.01086654 4.89916663 2 P 0 ;0,1,2=57,3=0.000000
L 7.01086654 4.89916663 7.01273337 4.90083297 2 P 0 ;0,1,2=57,3=0.000000
L 7.01273337 4.90083297 7.01353366 4.9037498 2 P 0 ;0,1,2=57,3=0.000000
L 7.01353366 4.9037498 7.0129999 4.90666654 2 P 0 ;0,1,2=57,3=0.000000
L 7.0129999 4.90666654 7.01166683 4.90874941 2 P 0 ;0,1,2=57,3=0.000000
L 7.01166683 4.90874941 7.0098001 4.91 2 P 0 ;0,1,2=57,3=0.000000
L 7.0098001 4.91 7.00793337 4.91 2 P 0 ;0,1,2=57,3=0.000000
L 7.00793337 4.91 7.00606663 4.90916683 2 P 0 ;0,1,2=57,3=0.000000
L 7.00606663 4.90916683 7.00446644 4.90708317 2 P 0 ;0,1,2=57,3=0.000000
L 6.9850003 4.91 6.9850003 4.885 2 P 0 ;0,1,2=57,3=0.000000
L 6.99113327 4.91 6.97886683 4.91 2 P 0 ;0,1,2=57,3=0.000000
L 6.96633346 4.885 6.96633346 4.91 2 P 0 ;0,1,2=57,3=0.000000
L 6.96633346 4.91 6.95966673 4.91 2 P 0 ;0,1,2=57,3=0.000000
L 6.95966673 4.91 6.95753337 4.90874941 2 P 0 ;0,1,2=57,3=0.000000
L 6.95753337 4.90874941 6.9561999 4.90708317 2 P 0 ;0,1,2=57,3=0.000000
L 6.9561999 4.90708317 6.95566663 4.9037498 2 P 0 ;0,1,2=57,3=0.000000
L 6.95566663 4.9037498 6.9561999 4.90041634 2 P 0 ;0,1,2=57,3=0.000000
L 6.9561999 4.90041634 6.9578 4.89833346 2 P 0 ;0,1,2=57,3=0.000000
L 6.9578 4.89833346 6.95966673 4.89708297 2 P 0 ;0,1,2=57,3=0.000000
L 6.95966673 4.89708297 6.96633346 4.89708297 2 P 0 ;0,1,2=57,3=0.000000
L 6.95966673 4.89708297 6.95566663 4.885 2 P 0 ;0,1,2=57,3=0.000000
L 6.94286673 4.88874911 6.94126703 4.88666624 2 P 0 ;0,1,2=57,3=0.000000
L 6.94126703 4.88666624 6.9394003 4.88541654 2 P 0 ;0,1,2=57,3=0.000000
L 6.9394003 4.88541654 6.9370003 4.885 2 P 0 ;0,1,2=57,3=0.000000
L 6.9370003 4.885 6.9345998 4.88583307 2 P 0 ;0,1,2=57,3=0.000000
L 6.9345998 4.88583307 6.93273356 4.88749941 2 P 0 ;0,1,2=57,3=0.000000
L 6.93273356 4.88749941 6.9314 4.89041624 2 P 0 ;0,1,2=57,3=0.000000
L 6.9314 4.89041624 6.93113337 4.89374961 2 P 0 ;0,1,2=57,3=0.000000
L 6.93113337 4.89374961 6.93166663 4.89708297 2 P 0 ;0,1,2=57,3=0.000000
L 6.93166663 4.89708297 6.9330002 4.89916663 2 P 0 ;0,1,2=57,3=0.000000
L 6.9330002 4.89916663 6.93486693 4.90083297 2 P 0 ;0,1,2=57,3=0.000000
L 6.93486693 4.90083297 6.93673317 4.90124951 2 P 0 ;0,1,2=57,3=0.000000
L 6.93673317 4.90124951 6.9386 4.90083297 2 P 0 ;0,1,2=57,3=0.000000
L 6.9386 4.90083297 6.9409999 4.89916663 2 P 0 ;0,1,2=57,3=0.000000
L 6.9409999 4.89916663 6.9402001 4.91 2 P 0 ;0,1,2=57,3=0.000000
L 6.9402001 4.91 6.9330002 4.91 2 P 0 ;0,1,2=57,3=0.000000
L 6.82 5.00786998 6.82 4.99213002 3 P 0 
L 6.96033346 5.125 6.96033346 5.15 2 P 0 ;0,1,2=58,3=0.000000
L 6.96033346 5.15 6.95393337 5.15 2 P 0 ;0,1,2=58,3=0.000000
L 6.95393337 5.15 6.9518 5.14874941 2 P 0 ;0,1,2=58,3=0.000000
L 6.9518 5.14874941 6.9501999 5.14583337 2 P 0 ;0,1,2=58,3=0.000000
L 6.9501999 5.14583337 6.94966663 5.1425 2 P 0 ;0,1,2=58,3=0.000000
L 6.94966663 5.1425 6.9501999 5.13916663 2 P 0 ;0,1,2=58,3=0.000000
L 6.9501999 5.13916663 6.95153337 5.13666644 2 P 0 ;0,1,2=58,3=0.000000
L 6.95153337 5.13666644 6.95393337 5.13541594 2 P 0 ;0,1,2=58,3=0.000000
L 6.95393337 5.13541594 6.96033346 5.13541594 2 P 0 ;0,1,2=58,3=0.000000
L 6.9366001 5.12833258 6.93446673 5.1262497 2 P 0 ;0,1,2=58,3=0.000000
L 6.93446673 5.1262497 6.93206673 5.125 2 P 0 ;0,1,2=58,3=0.000000
L 6.93206673 5.125 6.92993337 5.125 2 P 0 ;0,1,2=58,3=0.000000
L 6.92993337 5.125 6.9278 5.1262497 2 P 0 ;0,1,2=58,3=0.000000
L 6.9278 5.1262497 6.9261999 5.12833258 2 P 0 ;0,1,2=58,3=0.000000
L 6.9261999 5.12833258 6.9254 5.1312501 2 P 0 ;0,1,2=58,3=0.000000
L 6.9254 5.1312501 6.92593327 5.13416614 2 P 0 ;0,1,2=58,3=0.000000
L 6.92593327 5.13416614 6.92726673 5.13666644 2 P 0 ;0,1,2=58,3=0.000000
L 6.92726673 5.13666644 6.92966673 5.13833346 2 P 0 ;0,1,2=58,3=0.000000
L 6.92966673 5.13833346 6.93286654 5.13916663 2 P 0 ;0,1,2=58,3=0.000000
L 6.93286654 5.13916663 6.93473337 5.14083297 2 P 0 ;0,1,2=58,3=0.000000
L 6.93473337 5.14083297 6.93553366 5.1437498 2 P 0 ;0,1,2=58,3=0.000000
L 6.93553366 5.1437498 6.9349999 5.14666654 2 P 0 ;0,1,2=58,3=0.000000
L 6.9349999 5.14666654 6.93366683 5.14874941 2 P 0 ;0,1,2=58,3=0.000000
L 6.93366683 5.14874941 6.9318001 5.15 2 P 0 ;0,1,2=58,3=0.000000
L 6.9318001 5.15 6.92993337 5.15 2 P 0 ;0,1,2=58,3=0.000000
L 6.92993337 5.15 6.92806663 5.14916683 2 P 0 ;0,1,2=58,3=0.000000
L 6.92806663 5.14916683 6.92646644 5.14708317 2 P 0 ;0,1,2=58,3=0.000000
L 6.9070003 5.15 6.9070003 5.125 2 P 0 ;0,1,2=58,3=0.000000
L 6.91313327 5.15 6.90086683 5.15 2 P 0 ;0,1,2=58,3=0.000000
L 6.88833346 5.125 6.88833346 5.15 2 P 0 ;0,1,2=58,3=0.000000
L 6.88833346 5.15 6.88166673 5.15 2 P 0 ;0,1,2=58,3=0.000000
L 6.88166673 5.15 6.87953337 5.14874941 2 P 0 ;0,1,2=58,3=0.000000
L 6.87953337 5.14874941 6.8781999 5.14708317 2 P 0 ;0,1,2=58,3=0.000000
L 6.8781999 5.14708317 6.87766663 5.1437498 2 P 0 ;0,1,2=58,3=0.000000
L 6.87766663 5.1437498 6.8781999 5.14041634 2 P 0 ;0,1,2=58,3=0.000000
L 6.8781999 5.14041634 6.8798 5.13833346 2 P 0 ;0,1,2=58,3=0.000000
L 6.8798 5.13833346 6.88166673 5.13708297 2 P 0 ;0,1,2=58,3=0.000000
L 6.88166673 5.13708297 6.88833346 5.13708297 2 P 0 ;0,1,2=58,3=0.000000
L 6.88166673 5.13708297 6.87766663 5.125 2 P 0 ;0,1,2=58,3=0.000000
L 6.8590003 5.125 6.8590003 5.15 2 P 0 ;0,1,2=58,3=0.000000
L 6.8590003 5.15 6.8622001 5.1450003 2 P 0 ;0,1,2=58,3=0.000000
L 6.8622001 5.125 6.85580049 5.125 2 P 0 ;0,1,2=58,3=0.000000
L 6.84006683 5.14583337 6.83846673 5.14833287 2 P 0 ;0,1,2=58,3=0.000000
L 6.83846673 5.14833287 6.8366 5.14958337 2 P 0 ;0,1,2=58,3=0.000000
L 6.8366 5.14958337 6.83446663 5.15 2 P 0 ;0,1,2=58,3=0.000000
L 6.83446663 5.15 6.8318 5.14916683 2 P 0 ;0,1,2=58,3=0.000000
L 6.8318 5.14916683 6.82993327 5.14708317 2 P 0 ;0,1,2=58,3=0.000000
L 6.82993327 5.14708317 6.8294 5.14458366 2 P 0 ;0,1,2=58,3=0.000000
L 6.8294 5.14458366 6.82966663 5.14208268 2 P 0 ;0,1,2=58,3=0.000000
L 6.82966663 5.14208268 6.83073356 5.1399998 2 P 0 ;0,1,2=58,3=0.000000
L 6.83073356 5.1399998 6.83606673 5.13583327 2 P 0 ;0,1,2=58,3=0.000000
L 6.83606673 5.13583327 6.83846673 5.13291644 2 P 0 ;0,1,2=58,3=0.000000
L 6.83846673 5.13291644 6.84006683 5.12874911 2 P 0 ;0,1,2=58,3=0.000000
L 6.84006683 5.12874911 6.8406001 5.125 2 P 0 ;0,1,2=58,3=0.000000
L 6.8406001 5.125 6.8294 5.125 2 P 0 ;0,1,2=58,3=0.000000
L 6.67118996 5.00491998 6.67118996 4.98918002 3 P 0 
L 6.80033346 5.125 6.80033346 5.15 2 P 0 ;0,1,2=59,3=0.000000
L 6.80033346 5.15 6.79393337 5.15 2 P 0 ;0,1,2=59,3=0.000000
L 6.79393337 5.15 6.7918 5.14874941 2 P 0 ;0,1,2=59,3=0.000000
L 6.7918 5.14874941 6.7901999 5.14583337 2 P 0 ;0,1,2=59,3=0.000000
L 6.7901999 5.14583337 6.78966663 5.1425 2 P 0 ;0,1,2=59,3=0.000000
L 6.78966663 5.1425 6.7901999 5.13916663 2 P 0 ;0,1,2=59,3=0.000000
L 6.7901999 5.13916663 6.79153337 5.13666644 2 P 0 ;0,1,2=59,3=0.000000
L 6.79153337 5.13666644 6.79393337 5.13541594 2 P 0 ;0,1,2=59,3=0.000000
L 6.79393337 5.13541594 6.80033346 5.13541594 2 P 0 ;0,1,2=59,3=0.000000
L 6.7766001 5.12833258 6.77446673 5.1262497 2 P 0 ;0,1,2=59,3=0.000000
L 6.77446673 5.1262497 6.77206673 5.125 2 P 0 ;0,1,2=59,3=0.000000
L 6.77206673 5.125 6.76993337 5.125 2 P 0 ;0,1,2=59,3=0.000000
L 6.76993337 5.125 6.7678 5.1262497 2 P 0 ;0,1,2=59,3=0.000000
L 6.7678 5.1262497 6.7661999 5.12833258 2 P 0 ;0,1,2=59,3=0.000000
L 6.7661999 5.12833258 6.7654 5.1312501 2 P 0 ;0,1,2=59,3=0.000000
L 6.7654 5.1312501 6.76593327 5.13416614 2 P 0 ;0,1,2=59,3=0.000000
L 6.76593327 5.13416614 6.76726673 5.13666644 2 P 0 ;0,1,2=59,3=0.000000
L 6.76726673 5.13666644 6.76966673 5.13833346 2 P 0 ;0,1,2=59,3=0.000000
L 6.76966673 5.13833346 6.77286654 5.13916663 2 P 0 ;0,1,2=59,3=0.000000
L 6.77286654 5.13916663 6.77473337 5.14083297 2 P 0 ;0,1,2=59,3=0.000000
L 6.77473337 5.14083297 6.77553366 5.1437498 2 P 0 ;0,1,2=59,3=0.000000
L 6.77553366 5.1437498 6.7749999 5.14666654 2 P 0 ;0,1,2=59,3=0.000000
L 6.7749999 5.14666654 6.77366683 5.14874941 2 P 0 ;0,1,2=59,3=0.000000
L 6.77366683 5.14874941 6.7718001 5.15 2 P 0 ;0,1,2=59,3=0.000000
L 6.7718001 5.15 6.76993337 5.15 2 P 0 ;0,1,2=59,3=0.000000
L 6.76993337 5.15 6.76806663 5.14916683 2 P 0 ;0,1,2=59,3=0.000000
L 6.76806663 5.14916683 6.76646644 5.14708317 2 P 0 ;0,1,2=59,3=0.000000
L 6.7470003 5.15 6.7470003 5.125 2 P 0 ;0,1,2=59,3=0.000000
L 6.75313327 5.15 6.74086683 5.15 2 P 0 ;0,1,2=59,3=0.000000
L 6.72833346 5.125 6.72833346 5.15 2 P 0 ;0,1,2=59,3=0.000000
L 6.72833346 5.15 6.72166673 5.15 2 P 0 ;0,1,2=59,3=0.000000
L 6.72166673 5.15 6.71953337 5.14874941 2 P 0 ;0,1,2=59,3=0.000000
L 6.71953337 5.14874941 6.7181999 5.14708317 2 P 0 ;0,1,2=59,3=0.000000
L 6.7181999 5.14708317 6.71766663 5.1437498 2 P 0 ;0,1,2=59,3=0.000000
L 6.71766663 5.1437498 6.7181999 5.14041634 2 P 0 ;0,1,2=59,3=0.000000
L 6.7181999 5.14041634 6.7198 5.13833346 2 P 0 ;0,1,2=59,3=0.000000
L 6.7198 5.13833346 6.72166673 5.13708297 2 P 0 ;0,1,2=59,3=0.000000
L 6.72166673 5.13708297 6.72833346 5.13708297 2 P 0 ;0,1,2=59,3=0.000000
L 6.72166673 5.13708297 6.71766663 5.125 2 P 0 ;0,1,2=59,3=0.000000
L 6.6990003 5.125 6.6990003 5.15 2 P 0 ;0,1,2=59,3=0.000000
L 6.6990003 5.15 6.7022001 5.1450003 2 P 0 ;0,1,2=59,3=0.000000
L 6.7022001 5.125 6.69580049 5.125 2 P 0 ;0,1,2=59,3=0.000000
L 6.6750003 5.125 6.6750003 5.15 2 P 0 ;0,1,2=59,3=0.000000
L 6.6750003 5.15 6.6782001 5.1450003 2 P 0 ;0,1,2=59,3=0.000000
L 6.6782001 5.125 6.67180049 5.125 2 P 0 ;0,1,2=59,3=0.000000
L 5.6322 3.00786998 5.6322 2.99213002 3 P 0 
L 5.59233346 3.02 5.59233346 3.045 2 P 0 ;0,1,2=60,3=0.000000
L 5.59233346 3.045 5.58566673 3.045 2 P 0 ;0,1,2=60,3=0.000000
L 5.58566673 3.045 5.58353337 3.04374941 2 P 0 ;0,1,2=60,3=0.000000
L 5.58353337 3.04374941 5.5821999 3.04208317 2 P 0 ;0,1,2=60,3=0.000000
L 5.5821999 3.04208317 5.58166663 3.0387498 2 P 0 ;0,1,2=60,3=0.000000
L 5.58166663 3.0387498 5.5821999 3.03541634 2 P 0 ;0,1,2=60,3=0.000000
L 5.5821999 3.03541634 5.5838 3.03333346 2 P 0 ;0,1,2=60,3=0.000000
L 5.5838 3.03333346 5.58566673 3.03208297 2 P 0 ;0,1,2=60,3=0.000000
L 5.58566673 3.03208297 5.59233346 3.03208297 2 P 0 ;0,1,2=60,3=0.000000
L 5.58566673 3.03208297 5.58166663 3.02 2 P 0 ;0,1,2=60,3=0.000000
L 5.5630003 3.02 5.5630003 3.045 2 P 0 ;0,1,2=60,3=0.000000
L 5.5630003 3.045 5.5662001 3.0400003 2 P 0 ;0,1,2=60,3=0.000000
L 5.5662001 3.02 5.55980049 3.02 2 P 0 ;0,1,2=60,3=0.000000
L 5.54486673 3.02374911 5.54326703 3.02166624 2 P 0 ;0,1,2=60,3=0.000000
L 5.54326703 3.02166624 5.5414003 3.02041654 2 P 0 ;0,1,2=60,3=0.000000
L 5.5414003 3.02041654 5.5390003 3.02 2 P 0 ;0,1,2=60,3=0.000000
L 5.5390003 3.02 5.5365998 3.02083307 2 P 0 ;0,1,2=60,3=0.000000
L 5.5365998 3.02083307 5.53473356 3.02249941 2 P 0 ;0,1,2=60,3=0.000000
L 5.53473356 3.02249941 5.5334 3.02541624 2 P 0 ;0,1,2=60,3=0.000000
L 5.5334 3.02541624 5.53313337 3.02874961 2 P 0 ;0,1,2=60,3=0.000000
L 5.53313337 3.02874961 5.53366663 3.03208297 2 P 0 ;0,1,2=60,3=0.000000
L 5.53366663 3.03208297 5.5350002 3.03416663 2 P 0 ;0,1,2=60,3=0.000000
L 5.5350002 3.03416663 5.53686693 3.03583297 2 P 0 ;0,1,2=60,3=0.000000
L 5.53686693 3.03583297 5.53873317 3.03624951 2 P 0 ;0,1,2=60,3=0.000000
L 5.53873317 3.03624951 5.5406 3.03583297 2 P 0 ;0,1,2=60,3=0.000000
L 5.5406 3.03583297 5.5429999 3.03416663 2 P 0 ;0,1,2=60,3=0.000000
L 5.5429999 3.03416663 5.5422001 3.045 2 P 0 ;0,1,2=60,3=0.000000
L 5.5422001 3.045 5.5350002 3.045 2 P 0 ;0,1,2=60,3=0.000000
L 5.5150003 3.02 5.51313356 3.02041654 2 P 0 ;0,1,2=60,3=0.000000
L 5.51313356 3.02041654 5.5110002 3.02166624 2 P 0 ;0,1,2=60,3=0.000000
L 5.5110002 3.02166624 5.50966663 3.02374911 2 P 0 ;0,1,2=60,3=0.000000
L 5.50966663 3.02374911 5.50913337 3.02666673 2 P 0 ;0,1,2=60,3=0.000000
L 5.50913337 3.02666673 5.50966663 3.02958278 2 P 0 ;0,1,2=60,3=0.000000
L 5.50966663 3.02958278 5.51126673 3.03208297 2 P 0 ;0,1,2=60,3=0.000000
L 5.51126673 3.03208297 5.51366673 3.03333346 2 P 0 ;0,1,2=60,3=0.000000
L 5.51366673 3.03333346 5.51633337 3.03333346 2 P 0 ;0,1,2=60,3=0.000000
L 5.51633337 3.03333346 5.51793346 3.03416663 2 P 0 ;0,1,2=60,3=0.000000
L 5.51793346 3.03416663 5.51926703 3.03624951 2 P 0 ;0,1,2=60,3=0.000000
L 5.51926703 3.03624951 5.5198002 3.03916634 2 P 0 ;0,1,2=60,3=0.000000
L 5.5198002 3.03916634 5.5189999 3.04208317 2 P 0 ;0,1,2=60,3=0.000000
L 5.5189999 3.04208317 5.51713366 3.04416683 2 P 0 ;0,1,2=60,3=0.000000
L 5.51713366 3.04416683 5.5150003 3.045 2 P 0 ;0,1,2=60,3=0.000000
L 5.5150003 3.045 5.51286693 3.04416683 2 P 0 ;0,1,2=60,3=0.000000
L 5.51286693 3.04416683 5.5110002 3.04208317 2 P 0 ;0,1,2=60,3=0.000000
L 5.5110002 3.04208317 5.5101999 3.03916634 2 P 0 ;0,1,2=60,3=0.000000
L 5.5101999 3.03916634 5.51073356 3.03624951 2 P 0 ;0,1,2=60,3=0.000000
L 5.51073356 3.03624951 5.51206663 3.03416663 2 P 0 ;0,1,2=60,3=0.000000
L 5.51206663 3.03416663 5.51366673 3.03333346 2 P 0 ;0,1,2=60,3=0.000000
L 5.51366673 3.03333346 5.51633337 3.03333346 2 P 0 ;0,1,2=60,3=0.000000
L 5.51633337 3.03333346 5.51873337 3.03208297 2 P 0 ;0,1,2=60,3=0.000000
L 5.51873337 3.03208297 5.52033346 3.02958278 2 P 0 ;0,1,2=60,3=0.000000
L 5.52033346 3.02958278 5.52086673 3.02666673 2 P 0 ;0,1,2=60,3=0.000000
L 5.52086673 3.02666673 5.52033346 3.02374911 2 P 0 ;0,1,2=60,3=0.000000
L 5.52033346 3.02374911 5.5189999 3.02166624 2 P 0 ;0,1,2=60,3=0.000000
L 5.5189999 3.02166624 5.51686654 3.02041654 2 P 0 ;0,1,2=60,3=0.000000
L 5.51686654 3.02041654 5.5150003 3.02 2 P 0 ;0,1,2=60,3=0.000000
L 5.49153346 3.02 5.4910003 3.02541624 2 P 0 ;0,1,2=60,3=0.000000
L 5.4910003 3.02541624 5.4902 3.02999931 2 P 0 ;0,1,2=60,3=0.000000
L 5.4902 3.02999931 5.48913356 3.03416663 2 P 0 ;0,1,2=60,3=0.000000
L 5.48913356 3.03416663 5.4878 3.0387498 2 P 0 ;0,1,2=60,3=0.000000
L 5.4878 3.0387498 5.48566663 3.045 2 P 0 ;0,1,2=60,3=0.000000
L 5.48566663 3.045 5.49633346 3.045 2 P 0 ;0,1,2=60,3=0.000000
L 8.65778996 2.86213002 8.65778996 2.87786998 3 P 0 
L 8.71733346 2.9 8.71733346 2.925 2 P 0 ;0,1,2=61,3=0.000000
L 8.71733346 2.925 8.71066673 2.925 2 P 0 ;0,1,2=61,3=0.000000
L 8.71066673 2.925 8.70853337 2.92374941 2 P 0 ;0,1,2=61,3=0.000000
L 8.70853337 2.92374941 8.7071999 2.92208317 2 P 0 ;0,1,2=61,3=0.000000
L 8.7071999 2.92208317 8.70666663 2.9187498 2 P 0 ;0,1,2=61,3=0.000000
L 8.70666663 2.9187498 8.7071999 2.91541634 2 P 0 ;0,1,2=61,3=0.000000
L 8.7071999 2.91541634 8.7088 2.91333346 2 P 0 ;0,1,2=61,3=0.000000
L 8.7088 2.91333346 8.71066673 2.91208297 2 P 0 ;0,1,2=61,3=0.000000
L 8.71066673 2.91208297 8.71733346 2.91208297 2 P 0 ;0,1,2=61,3=0.000000
L 8.71066673 2.91208297 8.70666663 2.9 2 P 0 ;0,1,2=61,3=0.000000
L 8.6880003 2.9 8.6880003 2.925 2 P 0 ;0,1,2=61,3=0.000000
L 8.6880003 2.925 8.6912001 2.9200003 2 P 0 ;0,1,2=61,3=0.000000
L 8.6912001 2.9 8.68480049 2.9 2 P 0 ;0,1,2=61,3=0.000000
L 8.66986673 2.90374911 8.66826703 2.90166624 2 P 0 ;0,1,2=61,3=0.000000
L 8.66826703 2.90166624 8.6664003 2.90041654 2 P 0 ;0,1,2=61,3=0.000000
L 8.6664003 2.90041654 8.6640003 2.9 2 P 0 ;0,1,2=61,3=0.000000
L 8.6640003 2.9 8.6615998 2.90083307 2 P 0 ;0,1,2=61,3=0.000000
L 8.6615998 2.90083307 8.65973356 2.90249941 2 P 0 ;0,1,2=61,3=0.000000
L 8.65973356 2.90249941 8.6584 2.90541624 2 P 0 ;0,1,2=61,3=0.000000
L 8.6584 2.90541624 8.65813337 2.90874961 2 P 0 ;0,1,2=61,3=0.000000
L 8.65813337 2.90874961 8.65866663 2.91208297 2 P 0 ;0,1,2=61,3=0.000000
L 8.65866663 2.91208297 8.6600002 2.91416663 2 P 0 ;0,1,2=61,3=0.000000
L 8.6600002 2.91416663 8.66186693 2.91583297 2 P 0 ;0,1,2=61,3=0.000000
L 8.66186693 2.91583297 8.66373317 2.91624951 2 P 0 ;0,1,2=61,3=0.000000
L 8.66373317 2.91624951 8.6656 2.91583297 2 P 0 ;0,1,2=61,3=0.000000
L 8.6656 2.91583297 8.6679999 2.91416663 2 P 0 ;0,1,2=61,3=0.000000
L 8.6679999 2.91416663 8.6672001 2.925 2 P 0 ;0,1,2=61,3=0.000000
L 8.6672001 2.925 8.6600002 2.925 2 P 0 ;0,1,2=61,3=0.000000
L 8.64053346 2.9 8.6400003 2.90541624 2 P 0 ;0,1,2=61,3=0.000000
L 8.6400003 2.90541624 8.6392 2.90999931 2 P 0 ;0,1,2=61,3=0.000000
L 8.6392 2.90999931 8.63813356 2.91416663 2 P 0 ;0,1,2=61,3=0.000000
L 8.63813356 2.91416663 8.6368 2.9187498 2 P 0 ;0,1,2=61,3=0.000000
L 8.6368 2.9187498 8.63466663 2.925 2 P 0 ;0,1,2=61,3=0.000000
L 8.63466663 2.925 8.64533346 2.925 2 P 0 ;0,1,2=61,3=0.000000
L 8.6128 2.9 8.6128 2.925 2 P 0 ;0,1,2=61,3=0.000000
L 8.6128 2.925 8.62266703 2.90708327 2 P 0 ;0,1,2=61,3=0.000000
L 8.62266703 2.90708327 8.60933307 2.90708327 2 P 0 ;0,1,2=61,3=0.000000
L 8.65778996 2.81213002 8.65778996 2.82786998 3 P 0 
L 8.71733346 2.765 8.71733346 2.79 2 P 0 ;0,1,2=62,3=0.000000
L 8.71733346 2.79 8.71066673 2.79 2 P 0 ;0,1,2=62,3=0.000000
L 8.71066673 2.79 8.70853337 2.78874941 2 P 0 ;0,1,2=62,3=0.000000
L 8.70853337 2.78874941 8.7071999 2.78708317 2 P 0 ;0,1,2=62,3=0.000000
L 8.7071999 2.78708317 8.70666663 2.7837498 2 P 0 ;0,1,2=62,3=0.000000
L 8.70666663 2.7837498 8.7071999 2.78041634 2 P 0 ;0,1,2=62,3=0.000000
L 8.7071999 2.78041634 8.7088 2.77833346 2 P 0 ;0,1,2=62,3=0.000000
L 8.7088 2.77833346 8.71066673 2.77708297 2 P 0 ;0,1,2=62,3=0.000000
L 8.71066673 2.77708297 8.71733346 2.77708297 2 P 0 ;0,1,2=62,3=0.000000
L 8.71066673 2.77708297 8.70666663 2.765 2 P 0 ;0,1,2=62,3=0.000000
L 8.6880003 2.765 8.6880003 2.79 2 P 0 ;0,1,2=62,3=0.000000
L 8.6880003 2.79 8.6912001 2.7850003 2 P 0 ;0,1,2=62,3=0.000000
L 8.6912001 2.765 8.68480049 2.765 2 P 0 ;0,1,2=62,3=0.000000
L 8.66986673 2.76874911 8.66826703 2.76666624 2 P 0 ;0,1,2=62,3=0.000000
L 8.66826703 2.76666624 8.6664003 2.76541654 2 P 0 ;0,1,2=62,3=0.000000
L 8.6664003 2.76541654 8.6640003 2.765 2 P 0 ;0,1,2=62,3=0.000000
L 8.6640003 2.765 8.6615998 2.76583307 2 P 0 ;0,1,2=62,3=0.000000
L 8.6615998 2.76583307 8.65973356 2.76749941 2 P 0 ;0,1,2=62,3=0.000000
L 8.65973356 2.76749941 8.6584 2.77041624 2 P 0 ;0,1,2=62,3=0.000000
L 8.6584 2.77041624 8.65813337 2.77374961 2 P 0 ;0,1,2=62,3=0.000000
L 8.65813337 2.77374961 8.65866663 2.77708297 2 P 0 ;0,1,2=62,3=0.000000
L 8.65866663 2.77708297 8.6600002 2.77916663 2 P 0 ;0,1,2=62,3=0.000000
L 8.6600002 2.77916663 8.66186693 2.78083297 2 P 0 ;0,1,2=62,3=0.000000
L 8.66186693 2.78083297 8.66373317 2.78124951 2 P 0 ;0,1,2=62,3=0.000000
L 8.66373317 2.78124951 8.6656 2.78083297 2 P 0 ;0,1,2=62,3=0.000000
L 8.6656 2.78083297 8.6679999 2.77916663 2 P 0 ;0,1,2=62,3=0.000000
L 8.6679999 2.77916663 8.6672001 2.79 2 P 0 ;0,1,2=62,3=0.000000
L 8.6672001 2.79 8.6600002 2.79 2 P 0 ;0,1,2=62,3=0.000000
L 8.64053346 2.765 8.6400003 2.77041624 2 P 0 ;0,1,2=62,3=0.000000
L 8.6400003 2.77041624 8.6392 2.77499931 2 P 0 ;0,1,2=62,3=0.000000
L 8.6392 2.77499931 8.63813356 2.77916663 2 P 0 ;0,1,2=62,3=0.000000
L 8.63813356 2.77916663 8.6368 2.7837498 2 P 0 ;0,1,2=62,3=0.000000
L 8.6368 2.7837498 8.63466663 2.79 2 P 0 ;0,1,2=62,3=0.000000
L 8.63466663 2.79 8.64533346 2.79 2 P 0 ;0,1,2=62,3=0.000000
L 8.62186673 2.76999961 8.62026703 2.76708287 2 P 0 ;0,1,2=62,3=0.000000
L 8.62026703 2.76708287 8.61813366 2.76541654 2 P 0 ;0,1,2=62,3=0.000000
L 8.61813366 2.76541654 8.61573317 2.765 2 P 0 ;0,1,2=62,3=0.000000
L 8.61573317 2.765 8.6135998 2.76541654 2 P 0 ;0,1,2=62,3=0.000000
L 8.6135998 2.76541654 8.61146644 2.76749941 2 P 0 ;0,1,2=62,3=0.000000
L 8.61146644 2.76749941 8.61013337 2.76999961 2 P 0 ;0,1,2=62,3=0.000000
L 8.61013337 2.76999961 8.60986683 2.7724999 2 P 0 ;0,1,2=62,3=0.000000
L 8.60986683 2.7724999 8.6104 2.77541594 2 P 0 ;0,1,2=62,3=0.000000
L 8.6104 2.77541594 8.61226673 2.77749961 2 P 0 ;0,1,2=62,3=0.000000
L 8.61226673 2.77749961 8.61413356 2.77833346 2 P 0 ;0,1,2=62,3=0.000000
L 8.61413356 2.77833346 8.61653346 2.77833346 2 P 0 ;0,1,2=62,3=0.000000
L 8.61413356 2.77833346 8.61253337 2.77958327 2 P 0 ;0,1,2=62,3=0.000000
L 8.61253337 2.77958327 8.6111999 2.78166614 2 P 0 ;0,1,2=62,3=0.000000
L 8.6111999 2.78166614 8.61066663 2.78416634 2 P 0 ;0,1,2=62,3=0.000000
L 8.61066663 2.78416634 8.6111999 2.78666654 2 P 0 ;0,1,2=62,3=0.000000
L 8.6111999 2.78666654 8.61253337 2.78874941 2 P 0 ;0,1,2=62,3=0.000000
L 8.61253337 2.78874941 8.61493337 2.79 2 P 0 ;0,1,2=62,3=0.000000
L 8.61493337 2.79 8.61733337 2.78958337 2 P 0 ;0,1,2=62,3=0.000000
L 8.61733337 2.78958337 8.61973337 2.78791634 2 P 0 ;0,1,2=62,3=0.000000
L 9.10786998 5.315 9.09213002 5.315 3 P 0 
L 9.085 5.36266654 9.11 5.36266654 2 P 0 ;0,1,2=63,3=90.000000
L 9.11 5.36266654 9.11 5.36933327 2 P 0 ;0,1,2=63,3=90.000000
L 9.11 5.36933327 9.10874941 5.37146663 2 P 0 ;0,1,2=63,3=90.000000
L 9.10874941 5.37146663 9.10708317 5.3728001 2 P 0 ;0,1,2=63,3=90.000000
L 9.10708317 5.3728001 9.1037498 5.37333337 2 P 0 ;0,1,2=63,3=90.000000
L 9.1037498 5.37333337 9.10041634 5.3728001 2 P 0 ;0,1,2=63,3=90.000000
L 9.10041634 5.3728001 9.09833346 5.3712 2 P 0 ;0,1,2=63,3=90.000000
L 9.09833346 5.3712 9.09708297 5.36933327 2 P 0 ;0,1,2=63,3=90.000000
L 9.09708297 5.36933327 9.09708297 5.36266654 2 P 0 ;0,1,2=63,3=90.000000
L 9.09708297 5.36933327 9.085 5.37333337 2 P 0 ;0,1,2=63,3=90.000000
L 9.085 5.3919997 9.11 5.3919997 2 P 0 ;0,1,2=63,3=90.000000
L 9.11 5.3919997 9.1050003 5.3887999 2 P 0 ;0,1,2=63,3=90.000000
L 9.085 5.3887999 9.085 5.39519951 2 P 0 ;0,1,2=63,3=90.000000
L 9.08874911 5.41013327 9.08666624 5.41173297 2 P 0 ;0,1,2=63,3=90.000000
L 9.08666624 5.41173297 9.08541654 5.4135997 2 P 0 ;0,1,2=63,3=90.000000
L 9.08541654 5.4135997 9.085 5.4159997 2 P 0 ;0,1,2=63,3=90.000000
L 9.085 5.4159997 9.08583307 5.4184002 2 P 0 ;0,1,2=63,3=90.000000
L 9.08583307 5.4184002 9.08749941 5.42026644 2 P 0 ;0,1,2=63,3=90.000000
L 9.08749941 5.42026644 9.09041624 5.4216 2 P 0 ;0,1,2=63,3=90.000000
L 9.09041624 5.4216 9.09374961 5.42186663 2 P 0 ;0,1,2=63,3=90.000000
L 9.09374961 5.42186663 9.09708297 5.42133337 2 P 0 ;0,1,2=63,3=90.000000
L 9.09708297 5.42133337 9.09916663 5.4199998 2 P 0 ;0,1,2=63,3=90.000000
L 9.09916663 5.4199998 9.10083297 5.41813307 2 P 0 ;0,1,2=63,3=90.000000
L 9.10083297 5.41813307 9.10124951 5.41626683 2 P 0 ;0,1,2=63,3=90.000000
L 9.10124951 5.41626683 9.10083297 5.4144 2 P 0 ;0,1,2=63,3=90.000000
L 9.10083297 5.4144 9.09916663 5.4120001 2 P 0 ;0,1,2=63,3=90.000000
L 9.09916663 5.4120001 9.11 5.4127999 2 P 0 ;0,1,2=63,3=90.000000
L 9.11 5.4127999 9.11 5.4199998 2 P 0 ;0,1,2=63,3=90.000000
L 9.085 5.43946654 9.09041624 5.4399997 2 P 0 ;0,1,2=63,3=90.000000
L 9.09041624 5.4399997 9.09499931 5.4408 2 P 0 ;0,1,2=63,3=90.000000
L 9.09499931 5.4408 9.09916663 5.44186644 2 P 0 ;0,1,2=63,3=90.000000
L 9.09916663 5.44186644 9.1037498 5.4432 2 P 0 ;0,1,2=63,3=90.000000
L 9.1037498 5.4432 9.11 5.44533337 2 P 0 ;0,1,2=63,3=90.000000
L 9.11 5.44533337 9.11 5.43466654 2 P 0 ;0,1,2=63,3=90.000000
L 9.10583337 5.45893317 9.10833287 5.46053327 2 P 0 ;0,1,2=63,3=90.000000
L 9.10833287 5.46053327 9.10958337 5.4624 2 P 0 ;0,1,2=63,3=90.000000
L 9.10958337 5.4624 9.11 5.46453337 2 P 0 ;0,1,2=63,3=90.000000
L 9.11 5.46453337 9.10916683 5.4672 2 P 0 ;0,1,2=63,3=90.000000
L 9.10916683 5.4672 9.10708317 5.46906673 2 P 0 ;0,1,2=63,3=90.000000
L 9.10708317 5.46906673 9.10458366 5.4696 2 P 0 ;0,1,2=63,3=90.000000
L 9.10458366 5.4696 9.10208268 5.46933337 2 P 0 ;0,1,2=63,3=90.000000
L 9.10208268 5.46933337 9.0999998 5.46826644 2 P 0 ;0,1,2=63,3=90.000000
L 9.0999998 5.46826644 9.09583327 5.46293327 2 P 0 ;0,1,2=63,3=90.000000
L 9.09583327 5.46293327 9.09291644 5.46053327 2 P 0 ;0,1,2=63,3=90.000000
L 9.09291644 5.46053327 9.08874911 5.45893317 2 P 0 ;0,1,2=63,3=90.000000
L 9.08874911 5.45893317 9.085 5.4583999 2 P 0 ;0,1,2=63,3=90.000000
L 9.085 5.4583999 9.085 5.4696 2 P 0 ;0,1,2=63,3=90.000000
L 9.24286998 5.315 9.22713002 5.315 3 P 0 
L 9.22 5.36266654 9.245 5.36266654 2 P 0 ;0,1,2=64,3=90.000000
L 9.245 5.36266654 9.245 5.36933327 2 P 0 ;0,1,2=64,3=90.000000
L 9.245 5.36933327 9.24374941 5.37146663 2 P 0 ;0,1,2=64,3=90.000000
L 9.24374941 5.37146663 9.24208317 5.3728001 2 P 0 ;0,1,2=64,3=90.000000
L 9.24208317 5.3728001 9.2387498 5.37333337 2 P 0 ;0,1,2=64,3=90.000000
L 9.2387498 5.37333337 9.23541634 5.3728001 2 P 0 ;0,1,2=64,3=90.000000
L 9.23541634 5.3728001 9.23333346 5.3712 2 P 0 ;0,1,2=64,3=90.000000
L 9.23333346 5.3712 9.23208297 5.36933327 2 P 0 ;0,1,2=64,3=90.000000
L 9.23208297 5.36933327 9.23208297 5.36266654 2 P 0 ;0,1,2=64,3=90.000000
L 9.23208297 5.36933327 9.22 5.37333337 2 P 0 ;0,1,2=64,3=90.000000
L 9.22 5.3919997 9.245 5.3919997 2 P 0 ;0,1,2=64,3=90.000000
L 9.245 5.3919997 9.2400003 5.3887999 2 P 0 ;0,1,2=64,3=90.000000
L 9.22 5.3887999 9.22 5.39519951 2 P 0 ;0,1,2=64,3=90.000000
L 9.22374911 5.41013327 9.22166624 5.41173297 2 P 0 ;0,1,2=64,3=90.000000
L 9.22166624 5.41173297 9.22041654 5.4135997 2 P 0 ;0,1,2=64,3=90.000000
L 9.22041654 5.4135997 9.22 5.4159997 2 P 0 ;0,1,2=64,3=90.000000
L 9.22 5.4159997 9.22083307 5.4184002 2 P 0 ;0,1,2=64,3=90.000000
L 9.22083307 5.4184002 9.22249941 5.42026644 2 P 0 ;0,1,2=64,3=90.000000
L 9.22249941 5.42026644 9.22541624 5.4216 2 P 0 ;0,1,2=64,3=90.000000
L 9.22541624 5.4216 9.22874961 5.42186663 2 P 0 ;0,1,2=64,3=90.000000
L 9.22874961 5.42186663 9.23208297 5.42133337 2 P 0 ;0,1,2=64,3=90.000000
L 9.23208297 5.42133337 9.23416663 5.4199998 2 P 0 ;0,1,2=64,3=90.000000
L 9.23416663 5.4199998 9.23583297 5.41813307 2 P 0 ;0,1,2=64,3=90.000000
L 9.23583297 5.41813307 9.23624951 5.41626683 2 P 0 ;0,1,2=64,3=90.000000
L 9.23624951 5.41626683 9.23583297 5.4144 2 P 0 ;0,1,2=64,3=90.000000
L 9.23583297 5.4144 9.23416663 5.4120001 2 P 0 ;0,1,2=64,3=90.000000
L 9.23416663 5.4120001 9.245 5.4127999 2 P 0 ;0,1,2=64,3=90.000000
L 9.245 5.4127999 9.245 5.4199998 2 P 0 ;0,1,2=64,3=90.000000
L 9.22 5.43946654 9.22541624 5.4399997 2 P 0 ;0,1,2=64,3=90.000000
L 9.22541624 5.4399997 9.22999931 5.4408 2 P 0 ;0,1,2=64,3=90.000000
L 9.22999931 5.4408 9.23416663 5.44186644 2 P 0 ;0,1,2=64,3=90.000000
L 9.23416663 5.44186644 9.2387498 5.4432 2 P 0 ;0,1,2=64,3=90.000000
L 9.2387498 5.4432 9.245 5.44533337 2 P 0 ;0,1,2=64,3=90.000000
L 9.245 5.44533337 9.245 5.43466654 2 P 0 ;0,1,2=64,3=90.000000
L 9.245 5.4639997 9.24416683 5.46186634 2 P 0 ;0,1,2=64,3=90.000000
L 9.24416683 5.46186634 9.24208317 5.46026663 2 P 0 ;0,1,2=64,3=90.000000
L 9.24208317 5.46026663 9.23958366 5.4591998 2 P 0 ;0,1,2=64,3=90.000000
L 9.23958366 5.4591998 9.23624951 5.4583999 2 P 0 ;0,1,2=64,3=90.000000
L 9.23624951 5.4583999 9.23249961 5.45813327 2 P 0 ;0,1,2=64,3=90.000000
L 9.23249961 5.45813327 9.22874961 5.4583999 2 P 0 ;0,1,2=64,3=90.000000
L 9.22874961 5.4583999 9.22541624 5.4591998 2 P 0 ;0,1,2=64,3=90.000000
L 9.22541624 5.4591998 9.22291604 5.46026663 2 P 0 ;0,1,2=64,3=90.000000
L 9.22291604 5.46026663 9.22083307 5.46186634 2 P 0 ;0,1,2=64,3=90.000000
L 9.22083307 5.46186634 9.22 5.4639997 2 P 0 ;0,1,2=64,3=90.000000
L 9.22 5.4639997 9.22083307 5.46613307 2 P 0 ;0,1,2=64,3=90.000000
L 9.22083307 5.46613307 9.22291604 5.46773327 2 P 0 ;0,1,2=64,3=90.000000
L 9.22291604 5.46773327 9.22541624 5.4688001 2 P 0 ;0,1,2=64,3=90.000000
L 9.22541624 5.4688001 9.22874961 5.4696 2 P 0 ;0,1,2=64,3=90.000000
L 9.22874961 5.4696 9.23249961 5.46986663 2 P 0 ;0,1,2=64,3=90.000000
L 9.23249961 5.46986663 9.23624951 5.4696 2 P 0 ;0,1,2=64,3=90.000000
L 9.23624951 5.4696 9.23958366 5.4688001 2 P 0 ;0,1,2=64,3=90.000000
L 9.23958366 5.4688001 9.24208317 5.46773327 2 P 0 ;0,1,2=64,3=90.000000
L 9.24208317 5.46773327 9.24416683 5.46613307 2 P 0 ;0,1,2=64,3=90.000000
L 9.24416683 5.46613307 9.245 5.4639997 2 P 0 ;0,1,2=64,3=90.000000
L 9.39286998 5.315 9.37713002 5.315 3 P 0 
L 9.38 5.36266654 9.405 5.36266654 2 P 0 ;0,1,2=65,3=90.000000
L 9.405 5.36266654 9.405 5.36933327 2 P 0 ;0,1,2=65,3=90.000000
L 9.405 5.36933327 9.40374941 5.37146663 2 P 0 ;0,1,2=65,3=90.000000
L 9.40374941 5.37146663 9.40208317 5.3728001 2 P 0 ;0,1,2=65,3=90.000000
L 9.40208317 5.3728001 9.3987498 5.37333337 2 P 0 ;0,1,2=65,3=90.000000
L 9.3987498 5.37333337 9.39541634 5.3728001 2 P 0 ;0,1,2=65,3=90.000000
L 9.39541634 5.3728001 9.39333346 5.3712 2 P 0 ;0,1,2=65,3=90.000000
L 9.39333346 5.3712 9.39208297 5.36933327 2 P 0 ;0,1,2=65,3=90.000000
L 9.39208297 5.36933327 9.39208297 5.36266654 2 P 0 ;0,1,2=65,3=90.000000
L 9.39208297 5.36933327 9.38 5.37333337 2 P 0 ;0,1,2=65,3=90.000000
L 9.38 5.3919997 9.405 5.3919997 2 P 0 ;0,1,2=65,3=90.000000
L 9.405 5.3919997 9.4000003 5.3887999 2 P 0 ;0,1,2=65,3=90.000000
L 9.38 5.3887999 9.38 5.39519951 2 P 0 ;0,1,2=65,3=90.000000
L 9.38374911 5.41013327 9.38166624 5.41173297 2 P 0 ;0,1,2=65,3=90.000000
L 9.38166624 5.41173297 9.38041654 5.4135997 2 P 0 ;0,1,2=65,3=90.000000
L 9.38041654 5.4135997 9.38 5.4159997 2 P 0 ;0,1,2=65,3=90.000000
L 9.38 5.4159997 9.38083307 5.4184002 2 P 0 ;0,1,2=65,3=90.000000
L 9.38083307 5.4184002 9.38249941 5.42026644 2 P 0 ;0,1,2=65,3=90.000000
L 9.38249941 5.42026644 9.38541624 5.4216 2 P 0 ;0,1,2=65,3=90.000000
L 9.38541624 5.4216 9.38874961 5.42186663 2 P 0 ;0,1,2=65,3=90.000000
L 9.38874961 5.42186663 9.39208297 5.42133337 2 P 0 ;0,1,2=65,3=90.000000
L 9.39208297 5.42133337 9.39416663 5.4199998 2 P 0 ;0,1,2=65,3=90.000000
L 9.39416663 5.4199998 9.39583297 5.41813307 2 P 0 ;0,1,2=65,3=90.000000
L 9.39583297 5.41813307 9.39624951 5.41626683 2 P 0 ;0,1,2=65,3=90.000000
L 9.39624951 5.41626683 9.39583297 5.4144 2 P 0 ;0,1,2=65,3=90.000000
L 9.39583297 5.4144 9.39416663 5.4120001 2 P 0 ;0,1,2=65,3=90.000000
L 9.39416663 5.4120001 9.405 5.4127999 2 P 0 ;0,1,2=65,3=90.000000
L 9.405 5.4127999 9.405 5.4199998 2 P 0 ;0,1,2=65,3=90.000000
L 9.39041594 5.43493317 9.39333346 5.4367999 2 P 0 ;0,1,2=65,3=90.000000
L 9.39333346 5.4367999 9.3949998 5.4384 2 P 0 ;0,1,2=65,3=90.000000
L 9.3949998 5.4384 9.39583297 5.44053337 2 P 0 ;0,1,2=65,3=90.000000
L 9.39583297 5.44053337 9.3949998 5.4424002 2 P 0 ;0,1,2=65,3=90.000000
L 9.3949998 5.4424002 9.39333346 5.44373327 2 P 0 ;0,1,2=65,3=90.000000
L 9.39333346 5.44373327 9.39083327 5.4448001 2 P 0 ;0,1,2=65,3=90.000000
L 9.39083327 5.4448001 9.38791644 5.44506673 2 P 0 ;0,1,2=65,3=90.000000
L 9.38791644 5.44506673 9.38541624 5.4448001 2 P 0 ;0,1,2=65,3=90.000000
L 9.38541624 5.4448001 9.38291604 5.44373327 2 P 0 ;0,1,2=65,3=90.000000
L 9.38291604 5.44373327 9.38083307 5.44213307 2 P 0 ;0,1,2=65,3=90.000000
L 9.38083307 5.44213307 9.38 5.44026683 2 P 0 ;0,1,2=65,3=90.000000
L 9.38 5.44026683 9.38083307 5.43813346 2 P 0 ;0,1,2=65,3=90.000000
L 9.38083307 5.43813346 9.38333258 5.43626663 2 P 0 ;0,1,2=65,3=90.000000
L 9.38333258 5.43626663 9.38708327 5.4351998 2 P 0 ;0,1,2=65,3=90.000000
L 9.38708327 5.4351998 9.3912498 5.43493317 2 P 0 ;0,1,2=65,3=90.000000
L 9.3912498 5.43493317 9.39666614 5.43546634 2 P 0 ;0,1,2=65,3=90.000000
L 9.39666614 5.43546634 9.39958366 5.43626663 2 P 0 ;0,1,2=65,3=90.000000
L 9.39958366 5.43626663 9.4024997 5.4375997 2 P 0 ;0,1,2=65,3=90.000000
L 9.4024997 5.4375997 9.40458337 5.43946654 2 P 0 ;0,1,2=65,3=90.000000
L 9.40458337 5.43946654 9.405 5.44133327 2 P 0 ;0,1,2=65,3=90.000000
L 9.405 5.44133327 9.40416683 5.4432 2 P 0 ;0,1,2=65,3=90.000000
L 9.40416683 5.4432 9.40208317 5.44453356 2 P 0 ;0,1,2=65,3=90.000000
L 9.38 5.4639997 9.38041654 5.46586644 2 P 0 ;0,1,2=65,3=90.000000
L 9.38041654 5.46586644 9.38166624 5.4679998 2 P 0 ;0,1,2=65,3=90.000000
L 9.38166624 5.4679998 9.38374911 5.46933337 2 P 0 ;0,1,2=65,3=90.000000
L 9.38374911 5.46933337 9.38666673 5.46986663 2 P 0 ;0,1,2=65,3=90.000000
L 9.38666673 5.46986663 9.38958278 5.46933337 2 P 0 ;0,1,2=65,3=90.000000
L 9.38958278 5.46933337 9.39208297 5.46773327 2 P 0 ;0,1,2=65,3=90.000000
L 9.39208297 5.46773327 9.39333346 5.46533327 2 P 0 ;0,1,2=65,3=90.000000
L 9.39333346 5.46533327 9.39333346 5.46266663 2 P 0 ;0,1,2=65,3=90.000000
L 9.39333346 5.46266663 9.39416663 5.46106654 2 P 0 ;0,1,2=65,3=90.000000
L 9.39416663 5.46106654 9.39624951 5.45973297 2 P 0 ;0,1,2=65,3=90.000000
L 9.39624951 5.45973297 9.39916634 5.4591998 2 P 0 ;0,1,2=65,3=90.000000
L 9.39916634 5.4591998 9.40208317 5.4600001 2 P 0 ;0,1,2=65,3=90.000000
L 9.40208317 5.4600001 9.40416683 5.46186634 2 P 0 ;0,1,2=65,3=90.000000
L 9.40416683 5.46186634 9.405 5.4639997 2 P 0 ;0,1,2=65,3=90.000000
L 9.405 5.4639997 9.40416683 5.46613307 2 P 0 ;0,1,2=65,3=90.000000
L 9.40416683 5.46613307 9.40208317 5.4679998 2 P 0 ;0,1,2=65,3=90.000000
L 9.40208317 5.4679998 9.39916634 5.4688001 2 P 0 ;0,1,2=65,3=90.000000
L 9.39916634 5.4688001 9.39624951 5.46826644 2 P 0 ;0,1,2=65,3=90.000000
L 9.39624951 5.46826644 9.39416663 5.46693337 2 P 0 ;0,1,2=65,3=90.000000
L 9.39416663 5.46693337 9.39333346 5.46533327 2 P 0 ;0,1,2=65,3=90.000000
L 9.39333346 5.46533327 9.39333346 5.46266663 2 P 0 ;0,1,2=65,3=90.000000
L 9.39333346 5.46266663 9.39208297 5.46026663 2 P 0 ;0,1,2=65,3=90.000000
L 9.39208297 5.46026663 9.38958278 5.45866654 2 P 0 ;0,1,2=65,3=90.000000
L 9.38958278 5.45866654 9.38666673 5.45813327 2 P 0 ;0,1,2=65,3=90.000000
L 9.38666673 5.45813327 9.38374911 5.45866654 2 P 0 ;0,1,2=65,3=90.000000
L 9.38374911 5.45866654 9.38166624 5.4600001 2 P 0 ;0,1,2=65,3=90.000000
L 9.38166624 5.4600001 9.38041654 5.46213346 2 P 0 ;0,1,2=65,3=90.000000
L 9.38041654 5.46213346 9.38 5.4639997 2 P 0 ;0,1,2=65,3=90.000000
L 3.38933002 5.315 3.37358996 5.315 3 P 0 
L 3.37 5.36266654 3.395 5.36266654 2 P 0 ;0,1,2=66,3=90.000000
L 3.395 5.36266654 3.395 5.36933327 2 P 0 ;0,1,2=66,3=90.000000
L 3.395 5.36933327 3.39374941 5.37146663 2 P 0 ;0,1,2=66,3=90.000000
L 3.39374941 5.37146663 3.39208317 5.3728001 2 P 0 ;0,1,2=66,3=90.000000
L 3.39208317 5.3728001 3.3887498 5.37333337 2 P 0 ;0,1,2=66,3=90.000000
L 3.3887498 5.37333337 3.38541634 5.3728001 2 P 0 ;0,1,2=66,3=90.000000
L 3.38541634 5.3728001 3.38333346 5.3712 2 P 0 ;0,1,2=66,3=90.000000
L 3.38333346 5.3712 3.38208297 5.36933327 2 P 0 ;0,1,2=66,3=90.000000
L 3.38208297 5.36933327 3.38208297 5.36266654 2 P 0 ;0,1,2=66,3=90.000000
L 3.38208297 5.36933327 3.37 5.37333337 2 P 0 ;0,1,2=66,3=90.000000
L 3.37 5.3919997 3.395 5.3919997 2 P 0 ;0,1,2=66,3=90.000000
L 3.395 5.3919997 3.3900003 5.3887999 2 P 0 ;0,1,2=66,3=90.000000
L 3.37 5.3887999 3.37 5.39519951 2 P 0 ;0,1,2=66,3=90.000000
L 3.37374911 5.41013327 3.37166624 5.41173297 2 P 0 ;0,1,2=66,3=90.000000
L 3.37166624 5.41173297 3.37041654 5.4135997 2 P 0 ;0,1,2=66,3=90.000000
L 3.37041654 5.4135997 3.37 5.4159997 2 P 0 ;0,1,2=66,3=90.000000
L 3.37 5.4159997 3.37083307 5.4184002 2 P 0 ;0,1,2=66,3=90.000000
L 3.37083307 5.4184002 3.37249941 5.42026644 2 P 0 ;0,1,2=66,3=90.000000
L 3.37249941 5.42026644 3.37541624 5.4216 2 P 0 ;0,1,2=66,3=90.000000
L 3.37541624 5.4216 3.37874961 5.42186663 2 P 0 ;0,1,2=66,3=90.000000
L 3.37874961 5.42186663 3.38208297 5.42133337 2 P 0 ;0,1,2=66,3=90.000000
L 3.38208297 5.42133337 3.38416663 5.4199998 2 P 0 ;0,1,2=66,3=90.000000
L 3.38416663 5.4199998 3.38583297 5.41813307 2 P 0 ;0,1,2=66,3=90.000000
L 3.38583297 5.41813307 3.38624951 5.41626683 2 P 0 ;0,1,2=66,3=90.000000
L 3.38624951 5.41626683 3.38583297 5.4144 2 P 0 ;0,1,2=66,3=90.000000
L 3.38583297 5.4144 3.38416663 5.4120001 2 P 0 ;0,1,2=66,3=90.000000
L 3.38416663 5.4120001 3.395 5.4127999 2 P 0 ;0,1,2=66,3=90.000000
L 3.395 5.4127999 3.395 5.4199998 2 P 0 ;0,1,2=66,3=90.000000
L 3.38041594 5.43493317 3.38333346 5.4367999 2 P 0 ;0,1,2=66,3=90.000000
L 3.38333346 5.4367999 3.3849998 5.4384 2 P 0 ;0,1,2=66,3=90.000000
L 3.3849998 5.4384 3.38583297 5.44053337 2 P 0 ;0,1,2=66,3=90.000000
L 3.38583297 5.44053337 3.3849998 5.4424002 2 P 0 ;0,1,2=66,3=90.000000
L 3.3849998 5.4424002 3.38333346 5.44373327 2 P 0 ;0,1,2=66,3=90.000000
L 3.38333346 5.44373327 3.38083327 5.4448001 2 P 0 ;0,1,2=66,3=90.000000
L 3.38083327 5.4448001 3.37791644 5.44506673 2 P 0 ;0,1,2=66,3=90.000000
L 3.37791644 5.44506673 3.37541624 5.4448001 2 P 0 ;0,1,2=66,3=90.000000
L 3.37541624 5.4448001 3.37291604 5.44373327 2 P 0 ;0,1,2=66,3=90.000000
L 3.37291604 5.44373327 3.37083307 5.44213307 2 P 0 ;0,1,2=66,3=90.000000
L 3.37083307 5.44213307 3.37 5.44026683 2 P 0 ;0,1,2=66,3=90.000000
L 3.37 5.44026683 3.37083307 5.43813346 2 P 0 ;0,1,2=66,3=90.000000
L 3.37083307 5.43813346 3.37333258 5.43626663 2 P 0 ;0,1,2=66,3=90.000000
L 3.37333258 5.43626663 3.37708327 5.4351998 2 P 0 ;0,1,2=66,3=90.000000
L 3.37708327 5.4351998 3.3812498 5.43493317 2 P 0 ;0,1,2=66,3=90.000000
L 3.3812498 5.43493317 3.38666614 5.43546634 2 P 0 ;0,1,2=66,3=90.000000
L 3.38666614 5.43546634 3.38958366 5.43626663 2 P 0 ;0,1,2=66,3=90.000000
L 3.38958366 5.43626663 3.3924997 5.4375997 2 P 0 ;0,1,2=66,3=90.000000
L 3.3924997 5.4375997 3.39458337 5.43946654 2 P 0 ;0,1,2=66,3=90.000000
L 3.39458337 5.43946654 3.395 5.44133327 2 P 0 ;0,1,2=66,3=90.000000
L 3.395 5.44133327 3.39416683 5.4432 2 P 0 ;0,1,2=66,3=90.000000
L 3.39416683 5.4432 3.39208317 5.44453356 2 P 0 ;0,1,2=66,3=90.000000
L 3.38041594 5.45893317 3.38333346 5.4607999 2 P 0 ;0,1,2=66,3=90.000000
L 3.38333346 5.4607999 3.3849998 5.4624 2 P 0 ;0,1,2=66,3=90.000000
L 3.3849998 5.4624 3.38583297 5.46453337 2 P 0 ;0,1,2=66,3=90.000000
L 3.38583297 5.46453337 3.3849998 5.4664002 2 P 0 ;0,1,2=66,3=90.000000
L 3.3849998 5.4664002 3.38333346 5.46773327 2 P 0 ;0,1,2=66,3=90.000000
L 3.38333346 5.46773327 3.38083327 5.4688001 2 P 0 ;0,1,2=66,3=90.000000
L 3.38083327 5.4688001 3.37791644 5.46906673 2 P 0 ;0,1,2=66,3=90.000000
L 3.37791644 5.46906673 3.37541624 5.4688001 2 P 0 ;0,1,2=66,3=90.000000
L 3.37541624 5.4688001 3.37291604 5.46773327 2 P 0 ;0,1,2=66,3=90.000000
L 3.37291604 5.46773327 3.37083307 5.46613307 2 P 0 ;0,1,2=66,3=90.000000
L 3.37083307 5.46613307 3.37 5.46426683 2 P 0 ;0,1,2=66,3=90.000000
L 3.37 5.46426683 3.37083307 5.46213346 2 P 0 ;0,1,2=66,3=90.000000
L 3.37083307 5.46213346 3.37333258 5.46026663 2 P 0 ;0,1,2=66,3=90.000000
L 3.37333258 5.46026663 3.37708327 5.4591998 2 P 0 ;0,1,2=66,3=90.000000
L 3.37708327 5.4591998 3.3812498 5.45893317 2 P 0 ;0,1,2=66,3=90.000000
L 3.3812498 5.45893317 3.38666614 5.45946634 2 P 0 ;0,1,2=66,3=90.000000
L 3.38666614 5.45946634 3.38958366 5.46026663 2 P 0 ;0,1,2=66,3=90.000000
L 3.38958366 5.46026663 3.3924997 5.4615997 2 P 0 ;0,1,2=66,3=90.000000
L 3.3924997 5.4615997 3.39458337 5.46346654 2 P 0 ;0,1,2=66,3=90.000000
L 3.39458337 5.46346654 3.395 5.46533327 2 P 0 ;0,1,2=66,3=90.000000
L 3.395 5.46533327 3.39416683 5.4672 2 P 0 ;0,1,2=66,3=90.000000
L 3.39416683 5.4672 3.39208317 5.46853356 2 P 0 ;0,1,2=66,3=90.000000
L 9.13713002 5.315 9.15286998 5.315 3 P 0 
L 9.13 5.36266654 9.155 5.36266654 2 P 0 ;0,1,2=67,3=90.000000
L 9.155 5.36266654 9.155 5.36933327 2 P 0 ;0,1,2=67,3=90.000000
L 9.155 5.36933327 9.15374941 5.37146663 2 P 0 ;0,1,2=67,3=90.000000
L 9.15374941 5.37146663 9.15208317 5.3728001 2 P 0 ;0,1,2=67,3=90.000000
L 9.15208317 5.3728001 9.1487498 5.37333337 2 P 0 ;0,1,2=67,3=90.000000
L 9.1487498 5.37333337 9.14541634 5.3728001 2 P 0 ;0,1,2=67,3=90.000000
L 9.14541634 5.3728001 9.14333346 5.3712 2 P 0 ;0,1,2=67,3=90.000000
L 9.14333346 5.3712 9.14208297 5.36933327 2 P 0 ;0,1,2=67,3=90.000000
L 9.14208297 5.36933327 9.14208297 5.36266654 2 P 0 ;0,1,2=67,3=90.000000
L 9.14208297 5.36933327 9.13 5.37333337 2 P 0 ;0,1,2=67,3=90.000000
L 9.13 5.3919997 9.155 5.3919997 2 P 0 ;0,1,2=67,3=90.000000
L 9.155 5.3919997 9.1500003 5.3887999 2 P 0 ;0,1,2=67,3=90.000000
L 9.13 5.3887999 9.13 5.39519951 2 P 0 ;0,1,2=67,3=90.000000
L 9.13374911 5.41013327 9.13166624 5.41173297 2 P 0 ;0,1,2=67,3=90.000000
L 9.13166624 5.41173297 9.13041654 5.4135997 2 P 0 ;0,1,2=67,3=90.000000
L 9.13041654 5.4135997 9.13 5.4159997 2 P 0 ;0,1,2=67,3=90.000000
L 9.13 5.4159997 9.13083307 5.4184002 2 P 0 ;0,1,2=67,3=90.000000
L 9.13083307 5.4184002 9.13249941 5.42026644 2 P 0 ;0,1,2=67,3=90.000000
L 9.13249941 5.42026644 9.13541624 5.4216 2 P 0 ;0,1,2=67,3=90.000000
L 9.13541624 5.4216 9.13874961 5.42186663 2 P 0 ;0,1,2=67,3=90.000000
L 9.13874961 5.42186663 9.14208297 5.42133337 2 P 0 ;0,1,2=67,3=90.000000
L 9.14208297 5.42133337 9.14416663 5.4199998 2 P 0 ;0,1,2=67,3=90.000000
L 9.14416663 5.4199998 9.14583297 5.41813307 2 P 0 ;0,1,2=67,3=90.000000
L 9.14583297 5.41813307 9.14624951 5.41626683 2 P 0 ;0,1,2=67,3=90.000000
L 9.14624951 5.41626683 9.14583297 5.4144 2 P 0 ;0,1,2=67,3=90.000000
L 9.14583297 5.4144 9.14416663 5.4120001 2 P 0 ;0,1,2=67,3=90.000000
L 9.14416663 5.4120001 9.155 5.4127999 2 P 0 ;0,1,2=67,3=90.000000
L 9.155 5.4127999 9.155 5.4199998 2 P 0 ;0,1,2=67,3=90.000000
L 9.13 5.43946654 9.13541624 5.4399997 2 P 0 ;0,1,2=67,3=90.000000
L 9.13541624 5.4399997 9.13999931 5.4408 2 P 0 ;0,1,2=67,3=90.000000
L 9.13999931 5.4408 9.14416663 5.44186644 2 P 0 ;0,1,2=67,3=90.000000
L 9.14416663 5.44186644 9.1487498 5.4432 2 P 0 ;0,1,2=67,3=90.000000
L 9.1487498 5.4432 9.155 5.44533337 2 P 0 ;0,1,2=67,3=90.000000
L 9.155 5.44533337 9.155 5.43466654 2 P 0 ;0,1,2=67,3=90.000000
L 9.13 5.4639997 9.155 5.4639997 2 P 0 ;0,1,2=67,3=90.000000
L 9.155 5.4639997 9.1500003 5.4607999 2 P 0 ;0,1,2=67,3=90.000000
L 9.13 5.4607999 9.13 5.46719951 2 P 0 ;0,1,2=67,3=90.000000
L 9.18213002 5.315 9.19786998 5.315 3 P 0 
L 9.175 5.36266654 9.2 5.36266654 2 P 0 ;0,1,2=68,3=90.000000
L 9.2 5.36266654 9.2 5.36933327 2 P 0 ;0,1,2=68,3=90.000000
L 9.2 5.36933327 9.19874941 5.37146663 2 P 0 ;0,1,2=68,3=90.000000
L 9.19874941 5.37146663 9.19708317 5.3728001 2 P 0 ;0,1,2=68,3=90.000000
L 9.19708317 5.3728001 9.1937498 5.37333337 2 P 0 ;0,1,2=68,3=90.000000
L 9.1937498 5.37333337 9.19041634 5.3728001 2 P 0 ;0,1,2=68,3=90.000000
L 9.19041634 5.3728001 9.18833346 5.3712 2 P 0 ;0,1,2=68,3=90.000000
L 9.18833346 5.3712 9.18708297 5.36933327 2 P 0 ;0,1,2=68,3=90.000000
L 9.18708297 5.36933327 9.18708297 5.36266654 2 P 0 ;0,1,2=68,3=90.000000
L 9.18708297 5.36933327 9.175 5.37333337 2 P 0 ;0,1,2=68,3=90.000000
L 9.175 5.3919997 9.2 5.3919997 2 P 0 ;0,1,2=68,3=90.000000
L 9.2 5.3919997 9.1950003 5.3887999 2 P 0 ;0,1,2=68,3=90.000000
L 9.175 5.3887999 9.175 5.39519951 2 P 0 ;0,1,2=68,3=90.000000
L 9.17874911 5.41013327 9.17666624 5.41173297 2 P 0 ;0,1,2=68,3=90.000000
L 9.17666624 5.41173297 9.17541654 5.4135997 2 P 0 ;0,1,2=68,3=90.000000
L 9.17541654 5.4135997 9.175 5.4159997 2 P 0 ;0,1,2=68,3=90.000000
L 9.175 5.4159997 9.17583307 5.4184002 2 P 0 ;0,1,2=68,3=90.000000
L 9.17583307 5.4184002 9.17749941 5.42026644 2 P 0 ;0,1,2=68,3=90.000000
L 9.17749941 5.42026644 9.18041624 5.4216 2 P 0 ;0,1,2=68,3=90.000000
L 9.18041624 5.4216 9.18374961 5.42186663 2 P 0 ;0,1,2=68,3=90.000000
L 9.18374961 5.42186663 9.18708297 5.42133337 2 P 0 ;0,1,2=68,3=90.000000
L 9.18708297 5.42133337 9.18916663 5.4199998 2 P 0 ;0,1,2=68,3=90.000000
L 9.18916663 5.4199998 9.19083297 5.41813307 2 P 0 ;0,1,2=68,3=90.000000
L 9.19083297 5.41813307 9.19124951 5.41626683 2 P 0 ;0,1,2=68,3=90.000000
L 9.19124951 5.41626683 9.19083297 5.4144 2 P 0 ;0,1,2=68,3=90.000000
L 9.19083297 5.4144 9.18916663 5.4120001 2 P 0 ;0,1,2=68,3=90.000000
L 9.18916663 5.4120001 9.2 5.4127999 2 P 0 ;0,1,2=68,3=90.000000
L 9.2 5.4127999 9.2 5.4199998 2 P 0 ;0,1,2=68,3=90.000000
L 9.18541594 5.43493317 9.18833346 5.4367999 2 P 0 ;0,1,2=68,3=90.000000
L 9.18833346 5.4367999 9.1899998 5.4384 2 P 0 ;0,1,2=68,3=90.000000
L 9.1899998 5.4384 9.19083297 5.44053337 2 P 0 ;0,1,2=68,3=90.000000
L 9.19083297 5.44053337 9.1899998 5.4424002 2 P 0 ;0,1,2=68,3=90.000000
L 9.1899998 5.4424002 9.18833346 5.44373327 2 P 0 ;0,1,2=68,3=90.000000
L 9.18833346 5.44373327 9.18583327 5.4448001 2 P 0 ;0,1,2=68,3=90.000000
L 9.18583327 5.4448001 9.18291644 5.44506673 2 P 0 ;0,1,2=68,3=90.000000
L 9.18291644 5.44506673 9.18041624 5.4448001 2 P 0 ;0,1,2=68,3=90.000000
L 9.18041624 5.4448001 9.17791604 5.44373327 2 P 0 ;0,1,2=68,3=90.000000
L 9.17791604 5.44373327 9.17583307 5.44213307 2 P 0 ;0,1,2=68,3=90.000000
L 9.17583307 5.44213307 9.175 5.44026683 2 P 0 ;0,1,2=68,3=90.000000
L 9.175 5.44026683 9.17583307 5.43813346 2 P 0 ;0,1,2=68,3=90.000000
L 9.17583307 5.43813346 9.17833258 5.43626663 2 P 0 ;0,1,2=68,3=90.000000
L 9.17833258 5.43626663 9.18208327 5.4351998 2 P 0 ;0,1,2=68,3=90.000000
L 9.18208327 5.4351998 9.1862498 5.43493317 2 P 0 ;0,1,2=68,3=90.000000
L 9.1862498 5.43493317 9.19166614 5.43546634 2 P 0 ;0,1,2=68,3=90.000000
L 9.19166614 5.43546634 9.19458366 5.43626663 2 P 0 ;0,1,2=68,3=90.000000
L 9.19458366 5.43626663 9.1974997 5.4375997 2 P 0 ;0,1,2=68,3=90.000000
L 9.1974997 5.4375997 9.19958337 5.43946654 2 P 0 ;0,1,2=68,3=90.000000
L 9.19958337 5.43946654 9.2 5.44133327 2 P 0 ;0,1,2=68,3=90.000000
L 9.2 5.44133327 9.19916683 5.4432 2 P 0 ;0,1,2=68,3=90.000000
L 9.19916683 5.4432 9.19708317 5.44453356 2 P 0 ;0,1,2=68,3=90.000000
L 9.17791604 5.45946634 9.17583307 5.46133317 2 P 0 ;0,1,2=68,3=90.000000
L 9.17583307 5.46133317 9.175 5.46346654 2 P 0 ;0,1,2=68,3=90.000000
L 9.175 5.46346654 9.17583307 5.4655999 2 P 0 ;0,1,2=68,3=90.000000
L 9.17583307 5.4655999 9.17833258 5.46746663 2 P 0 ;0,1,2=68,3=90.000000
L 9.17833258 5.46746663 9.18208327 5.4688001 2 P 0 ;0,1,2=68,3=90.000000
L 9.18208327 5.4688001 9.18583327 5.46933337 2 P 0 ;0,1,2=68,3=90.000000
L 9.18583327 5.46933337 9.19041634 5.46933337 2 P 0 ;0,1,2=68,3=90.000000
L 9.19041634 5.46933337 9.19416634 5.4688001 2 P 0 ;0,1,2=68,3=90.000000
L 9.19416634 5.4688001 9.1974997 5.46746663 2 P 0 ;0,1,2=68,3=90.000000
L 9.1974997 5.46746663 9.19916683 5.46586644 2 P 0 ;0,1,2=68,3=90.000000
L 9.19916683 5.46586644 9.2 5.4639997 2 P 0 ;0,1,2=68,3=90.000000
L 9.2 5.4639997 9.19916683 5.46186634 2 P 0 ;0,1,2=68,3=90.000000
L 9.19916683 5.46186634 9.1974997 5.46026663 2 P 0 ;0,1,2=68,3=90.000000
L 9.1974997 5.46026663 9.1950003 5.4591998 2 P 0 ;0,1,2=68,3=90.000000
L 9.1950003 5.4591998 9.19166614 5.45866654 2 P 0 ;0,1,2=68,3=90.000000
L 9.19166614 5.45866654 9.1887501 5.4591998 2 P 0 ;0,1,2=68,3=90.000000
L 9.1887501 5.4591998 9.18583327 5.46053327 2 P 0 ;0,1,2=68,3=90.000000
L 9.18583327 5.46053327 9.18416614 5.46213346 2 P 0 ;0,1,2=68,3=90.000000
L 9.18416614 5.46213346 9.18374961 5.4639997 2 P 0 ;0,1,2=68,3=90.000000
L 9.18374961 5.4639997 9.18458278 5.46613307 2 P 0 ;0,1,2=68,3=90.000000
L 9.18458278 5.46613307 9.18666644 5.46773327 2 P 0 ;0,1,2=68,3=90.000000
L 9.18666644 5.46773327 9.19041634 5.46933337 2 P 0 ;0,1,2=68,3=90.000000
L 9.33213002 5.315 9.34786998 5.315 3 P 0 
L 9.325 5.36266654 9.35 5.36266654 2 P 0 ;0,1,2=69,3=90.000000
L 9.35 5.36266654 9.35 5.36933327 2 P 0 ;0,1,2=69,3=90.000000
L 9.35 5.36933327 9.34874941 5.37146663 2 P 0 ;0,1,2=69,3=90.000000
L 9.34874941 5.37146663 9.34708317 5.3728001 2 P 0 ;0,1,2=69,3=90.000000
L 9.34708317 5.3728001 9.3437498 5.37333337 2 P 0 ;0,1,2=69,3=90.000000
L 9.3437498 5.37333337 9.34041634 5.3728001 2 P 0 ;0,1,2=69,3=90.000000
L 9.34041634 5.3728001 9.33833346 5.3712 2 P 0 ;0,1,2=69,3=90.000000
L 9.33833346 5.3712 9.33708297 5.36933327 2 P 0 ;0,1,2=69,3=90.000000
L 9.33708297 5.36933327 9.33708297 5.36266654 2 P 0 ;0,1,2=69,3=90.000000
L 9.33708297 5.36933327 9.325 5.37333337 2 P 0 ;0,1,2=69,3=90.000000
L 9.325 5.3919997 9.35 5.3919997 2 P 0 ;0,1,2=69,3=90.000000
L 9.35 5.3919997 9.3450003 5.3887999 2 P 0 ;0,1,2=69,3=90.000000
L 9.325 5.3887999 9.325 5.39519951 2 P 0 ;0,1,2=69,3=90.000000
L 9.32874911 5.41013327 9.32666624 5.41173297 2 P 0 ;0,1,2=69,3=90.000000
L 9.32666624 5.41173297 9.32541654 5.4135997 2 P 0 ;0,1,2=69,3=90.000000
L 9.32541654 5.4135997 9.325 5.4159997 2 P 0 ;0,1,2=69,3=90.000000
L 9.325 5.4159997 9.32583307 5.4184002 2 P 0 ;0,1,2=69,3=90.000000
L 9.32583307 5.4184002 9.32749941 5.42026644 2 P 0 ;0,1,2=69,3=90.000000
L 9.32749941 5.42026644 9.33041624 5.4216 2 P 0 ;0,1,2=69,3=90.000000
L 9.33041624 5.4216 9.33374961 5.42186663 2 P 0 ;0,1,2=69,3=90.000000
L 9.33374961 5.42186663 9.33708297 5.42133337 2 P 0 ;0,1,2=69,3=90.000000
L 9.33708297 5.42133337 9.33916663 5.4199998 2 P 0 ;0,1,2=69,3=90.000000
L 9.33916663 5.4199998 9.34083297 5.41813307 2 P 0 ;0,1,2=69,3=90.000000
L 9.34083297 5.41813307 9.34124951 5.41626683 2 P 0 ;0,1,2=69,3=90.000000
L 9.34124951 5.41626683 9.34083297 5.4144 2 P 0 ;0,1,2=69,3=90.000000
L 9.34083297 5.4144 9.33916663 5.4120001 2 P 0 ;0,1,2=69,3=90.000000
L 9.33916663 5.4120001 9.35 5.4127999 2 P 0 ;0,1,2=69,3=90.000000
L 9.35 5.4127999 9.35 5.4199998 2 P 0 ;0,1,2=69,3=90.000000
L 9.33541594 5.43493317 9.33833346 5.4367999 2 P 0 ;0,1,2=69,3=90.000000
L 9.33833346 5.4367999 9.3399998 5.4384 2 P 0 ;0,1,2=69,3=90.000000
L 9.3399998 5.4384 9.34083297 5.44053337 2 P 0 ;0,1,2=69,3=90.000000
L 9.34083297 5.44053337 9.3399998 5.4424002 2 P 0 ;0,1,2=69,3=90.000000
L 9.3399998 5.4424002 9.33833346 5.44373327 2 P 0 ;0,1,2=69,3=90.000000
L 9.33833346 5.44373327 9.33583327 5.4448001 2 P 0 ;0,1,2=69,3=90.000000
L 9.33583327 5.4448001 9.33291644 5.44506673 2 P 0 ;0,1,2=69,3=90.000000
L 9.33291644 5.44506673 9.33041624 5.4448001 2 P 0 ;0,1,2=69,3=90.000000
L 9.33041624 5.4448001 9.32791604 5.44373327 2 P 0 ;0,1,2=69,3=90.000000
L 9.32791604 5.44373327 9.32583307 5.44213307 2 P 0 ;0,1,2=69,3=90.000000
L 9.32583307 5.44213307 9.325 5.44026683 2 P 0 ;0,1,2=69,3=90.000000
L 9.325 5.44026683 9.32583307 5.43813346 2 P 0 ;0,1,2=69,3=90.000000
L 9.32583307 5.43813346 9.32833258 5.43626663 2 P 0 ;0,1,2=69,3=90.000000
L 9.32833258 5.43626663 9.33208327 5.4351998 2 P 0 ;0,1,2=69,3=90.000000
L 9.33208327 5.4351998 9.3362498 5.43493317 2 P 0 ;0,1,2=69,3=90.000000
L 9.3362498 5.43493317 9.34166614 5.43546634 2 P 0 ;0,1,2=69,3=90.000000
L 9.34166614 5.43546634 9.34458366 5.43626663 2 P 0 ;0,1,2=69,3=90.000000
L 9.34458366 5.43626663 9.3474997 5.4375997 2 P 0 ;0,1,2=69,3=90.000000
L 9.3474997 5.4375997 9.34958337 5.43946654 2 P 0 ;0,1,2=69,3=90.000000
L 9.34958337 5.43946654 9.35 5.44133327 2 P 0 ;0,1,2=69,3=90.000000
L 9.35 5.44133327 9.34916683 5.4432 2 P 0 ;0,1,2=69,3=90.000000
L 9.34916683 5.4432 9.34708317 5.44453356 2 P 0 ;0,1,2=69,3=90.000000
L 9.325 5.46346654 9.33041624 5.4639997 2 P 0 ;0,1,2=69,3=90.000000
L 9.33041624 5.4639997 9.33499931 5.4648 2 P 0 ;0,1,2=69,3=90.000000
L 9.33499931 5.4648 9.33916663 5.46586644 2 P 0 ;0,1,2=69,3=90.000000
L 9.33916663 5.46586644 9.3437498 5.4672 2 P 0 ;0,1,2=69,3=90.000000
L 9.3437498 5.4672 9.35 5.46933337 2 P 0 ;0,1,2=69,3=90.000000
L 9.35 5.46933337 9.35 5.45866654 2 P 0 ;0,1,2=69,3=90.000000
L 3.32858996 5.315 3.34433002 5.315 3 P 0 
L 3.325 5.36266654 3.35 5.36266654 2 P 0 ;0,1,2=70,3=90.000000
L 3.35 5.36266654 3.35 5.36933327 2 P 0 ;0,1,2=70,3=90.000000
L 3.35 5.36933327 3.34874941 5.37146663 2 P 0 ;0,1,2=70,3=90.000000
L 3.34874941 5.37146663 3.34708317 5.3728001 2 P 0 ;0,1,2=70,3=90.000000
L 3.34708317 5.3728001 3.3437498 5.37333337 2 P 0 ;0,1,2=70,3=90.000000
L 3.3437498 5.37333337 3.34041634 5.3728001 2 P 0 ;0,1,2=70,3=90.000000
L 3.34041634 5.3728001 3.33833346 5.3712 2 P 0 ;0,1,2=70,3=90.000000
L 3.33833346 5.3712 3.33708297 5.36933327 2 P 0 ;0,1,2=70,3=90.000000
L 3.33708297 5.36933327 3.33708297 5.36266654 2 P 0 ;0,1,2=70,3=90.000000
L 3.33708297 5.36933327 3.325 5.37333337 2 P 0 ;0,1,2=70,3=90.000000
L 3.325 5.3919997 3.35 5.3919997 2 P 0 ;0,1,2=70,3=90.000000
L 3.35 5.3919997 3.3450003 5.3887999 2 P 0 ;0,1,2=70,3=90.000000
L 3.325 5.3887999 3.325 5.39519951 2 P 0 ;0,1,2=70,3=90.000000
L 3.32874911 5.41013327 3.32666624 5.41173297 2 P 0 ;0,1,2=70,3=90.000000
L 3.32666624 5.41173297 3.32541654 5.4135997 2 P 0 ;0,1,2=70,3=90.000000
L 3.32541654 5.4135997 3.325 5.4159997 2 P 0 ;0,1,2=70,3=90.000000
L 3.325 5.4159997 3.32583307 5.4184002 2 P 0 ;0,1,2=70,3=90.000000
L 3.32583307 5.4184002 3.32749941 5.42026644 2 P 0 ;0,1,2=70,3=90.000000
L 3.32749941 5.42026644 3.33041624 5.4216 2 P 0 ;0,1,2=70,3=90.000000
L 3.33041624 5.4216 3.33374961 5.42186663 2 P 0 ;0,1,2=70,3=90.000000
L 3.33374961 5.42186663 3.33708297 5.42133337 2 P 0 ;0,1,2=70,3=90.000000
L 3.33708297 5.42133337 3.33916663 5.4199998 2 P 0 ;0,1,2=70,3=90.000000
L 3.33916663 5.4199998 3.34083297 5.41813307 2 P 0 ;0,1,2=70,3=90.000000
L 3.34083297 5.41813307 3.34124951 5.41626683 2 P 0 ;0,1,2=70,3=90.000000
L 3.34124951 5.41626683 3.34083297 5.4144 2 P 0 ;0,1,2=70,3=90.000000
L 3.34083297 5.4144 3.33916663 5.4120001 2 P 0 ;0,1,2=70,3=90.000000
L 3.33916663 5.4120001 3.35 5.4127999 2 P 0 ;0,1,2=70,3=90.000000
L 3.35 5.4127999 3.35 5.4199998 2 P 0 ;0,1,2=70,3=90.000000
L 3.33541594 5.43493317 3.33833346 5.4367999 2 P 0 ;0,1,2=70,3=90.000000
L 3.33833346 5.4367999 3.3399998 5.4384 2 P 0 ;0,1,2=70,3=90.000000
L 3.3399998 5.4384 3.34083297 5.44053337 2 P 0 ;0,1,2=70,3=90.000000
L 3.34083297 5.44053337 3.3399998 5.4424002 2 P 0 ;0,1,2=70,3=90.000000
L 3.3399998 5.4424002 3.33833346 5.44373327 2 P 0 ;0,1,2=70,3=90.000000
L 3.33833346 5.44373327 3.33583327 5.4448001 2 P 0 ;0,1,2=70,3=90.000000
L 3.33583327 5.4448001 3.33291644 5.44506673 2 P 0 ;0,1,2=70,3=90.000000
L 3.33291644 5.44506673 3.33041624 5.4448001 2 P 0 ;0,1,2=70,3=90.000000
L 3.33041624 5.4448001 3.32791604 5.44373327 2 P 0 ;0,1,2=70,3=90.000000
L 3.32791604 5.44373327 3.32583307 5.44213307 2 P 0 ;0,1,2=70,3=90.000000
L 3.32583307 5.44213307 3.325 5.44026683 2 P 0 ;0,1,2=70,3=90.000000
L 3.325 5.44026683 3.32583307 5.43813346 2 P 0 ;0,1,2=70,3=90.000000
L 3.32583307 5.43813346 3.32833258 5.43626663 2 P 0 ;0,1,2=70,3=90.000000
L 3.32833258 5.43626663 3.33208327 5.4351998 2 P 0 ;0,1,2=70,3=90.000000
L 3.33208327 5.4351998 3.3362498 5.43493317 2 P 0 ;0,1,2=70,3=90.000000
L 3.3362498 5.43493317 3.34166614 5.43546634 2 P 0 ;0,1,2=70,3=90.000000
L 3.34166614 5.43546634 3.34458366 5.43626663 2 P 0 ;0,1,2=70,3=90.000000
L 3.34458366 5.43626663 3.3474997 5.4375997 2 P 0 ;0,1,2=70,3=90.000000
L 3.3474997 5.4375997 3.34958337 5.43946654 2 P 0 ;0,1,2=70,3=90.000000
L 3.34958337 5.43946654 3.35 5.44133327 2 P 0 ;0,1,2=70,3=90.000000
L 3.35 5.44133327 3.34916683 5.4432 2 P 0 ;0,1,2=70,3=90.000000
L 3.34916683 5.4432 3.34708317 5.44453356 2 P 0 ;0,1,2=70,3=90.000000
L 3.32874911 5.45813327 3.32666624 5.45973297 2 P 0 ;0,1,2=70,3=90.000000
L 3.32666624 5.45973297 3.32541654 5.4615997 2 P 0 ;0,1,2=70,3=90.000000
L 3.32541654 5.4615997 3.325 5.4639997 2 P 0 ;0,1,2=70,3=90.000000
L 3.325 5.4639997 3.32583307 5.4664002 2 P 0 ;0,1,2=70,3=90.000000
L 3.32583307 5.4664002 3.32749941 5.46826644 2 P 0 ;0,1,2=70,3=90.000000
L 3.32749941 5.46826644 3.33041624 5.4696 2 P 0 ;0,1,2=70,3=90.000000
L 3.33041624 5.4696 3.33374961 5.46986663 2 P 0 ;0,1,2=70,3=90.000000
L 3.33374961 5.46986663 3.33708297 5.46933337 2 P 0 ;0,1,2=70,3=90.000000
L 3.33708297 5.46933337 3.33916663 5.4679998 2 P 0 ;0,1,2=70,3=90.000000
L 3.33916663 5.4679998 3.34083297 5.46613307 2 P 0 ;0,1,2=70,3=90.000000
L 3.34083297 5.46613307 3.34124951 5.46426683 2 P 0 ;0,1,2=70,3=90.000000
L 3.34124951 5.46426683 3.34083297 5.4624 2 P 0 ;0,1,2=70,3=90.000000
L 3.34083297 5.4624 3.33916663 5.4600001 2 P 0 ;0,1,2=70,3=90.000000
L 3.33916663 5.4600001 3.35 5.4607999 2 P 0 ;0,1,2=70,3=90.000000
L 3.35 5.4607999 3.35 5.4679998 2 P 0 ;0,1,2=70,3=90.000000
L 12.32498002 2.16286998 12.32498002 2.14713002 3 P 0 
L 12.37733346 2.21 12.37733346 2.235 2 P 0 ;0,1,2=71,3=0.000000
L 12.37733346 2.235 12.37066673 2.235 2 P 0 ;0,1,2=71,3=0.000000
L 12.37066673 2.235 12.36853337 2.23374941 2 P 0 ;0,1,2=71,3=0.000000
L 12.36853337 2.23374941 12.3671999 2.23208317 2 P 0 ;0,1,2=71,3=0.000000
L 12.3671999 2.23208317 12.36666663 2.2287498 2 P 0 ;0,1,2=71,3=0.000000
L 12.36666663 2.2287498 12.3671999 2.22541634 2 P 0 ;0,1,2=71,3=0.000000
L 12.3671999 2.22541634 12.3688 2.22333346 2 P 0 ;0,1,2=71,3=0.000000
L 12.3688 2.22333346 12.37066673 2.22208297 2 P 0 ;0,1,2=71,3=0.000000
L 12.37066673 2.22208297 12.37733346 2.22208297 2 P 0 ;0,1,2=71,3=0.000000
L 12.37066673 2.22208297 12.36666663 2.21 2 P 0 ;0,1,2=71,3=0.000000
L 12.3480003 2.21 12.3480003 2.235 2 P 0 ;0,1,2=71,3=0.000000
L 12.3480003 2.235 12.3512001 2.2300003 2 P 0 ;0,1,2=71,3=0.000000
L 12.3512001 2.21 12.34480049 2.21 2 P 0 ;0,1,2=71,3=0.000000
L 12.32986673 2.21374911 12.32826703 2.21166624 2 P 0 ;0,1,2=71,3=0.000000
L 12.32826703 2.21166624 12.3264003 2.21041654 2 P 0 ;0,1,2=71,3=0.000000
L 12.3264003 2.21041654 12.3240003 2.21 2 P 0 ;0,1,2=71,3=0.000000
L 12.3240003 2.21 12.3215998 2.21083307 2 P 0 ;0,1,2=71,3=0.000000
L 12.3215998 2.21083307 12.31973356 2.21249941 2 P 0 ;0,1,2=71,3=0.000000
L 12.31973356 2.21249941 12.3184 2.21541624 2 P 0 ;0,1,2=71,3=0.000000
L 12.3184 2.21541624 12.31813337 2.21874961 2 P 0 ;0,1,2=71,3=0.000000
L 12.31813337 2.21874961 12.31866663 2.22208297 2 P 0 ;0,1,2=71,3=0.000000
L 12.31866663 2.22208297 12.3200002 2.22416663 2 P 0 ;0,1,2=71,3=0.000000
L 12.3200002 2.22416663 12.32186693 2.22583297 2 P 0 ;0,1,2=71,3=0.000000
L 12.32186693 2.22583297 12.32373317 2.22624951 2 P 0 ;0,1,2=71,3=0.000000
L 12.32373317 2.22624951 12.3256 2.22583297 2 P 0 ;0,1,2=71,3=0.000000
L 12.3256 2.22583297 12.3279999 2.22416663 2 P 0 ;0,1,2=71,3=0.000000
L 12.3279999 2.22416663 12.3272001 2.235 2 P 0 ;0,1,2=71,3=0.000000
L 12.3272001 2.235 12.3200002 2.235 2 P 0 ;0,1,2=71,3=0.000000
L 12.30506683 2.22041594 12.3032001 2.22333346 2 P 0 ;0,1,2=71,3=0.000000
L 12.3032001 2.22333346 12.3016 2.2249998 2 P 0 ;0,1,2=71,3=0.000000
L 12.3016 2.2249998 12.29946663 2.22583297 2 P 0 ;0,1,2=71,3=0.000000
L 12.29946663 2.22583297 12.2975998 2.2249998 2 P 0 ;0,1,2=71,3=0.000000
L 12.2975998 2.2249998 12.29626673 2.22333346 2 P 0 ;0,1,2=71,3=0.000000
L 12.29626673 2.22333346 12.2951999 2.22083327 2 P 0 ;0,1,2=71,3=0.000000
L 12.2951999 2.22083327 12.29493327 2.21791644 2 P 0 ;0,1,2=71,3=0.000000
L 12.29493327 2.21791644 12.2951999 2.21541624 2 P 0 ;0,1,2=71,3=0.000000
L 12.2951999 2.21541624 12.29626673 2.21291604 2 P 0 ;0,1,2=71,3=0.000000
L 12.29626673 2.21291604 12.29786693 2.21083307 2 P 0 ;0,1,2=71,3=0.000000
L 12.29786693 2.21083307 12.29973317 2.21 2 P 0 ;0,1,2=71,3=0.000000
L 12.29973317 2.21 12.30186654 2.21083307 2 P 0 ;0,1,2=71,3=0.000000
L 12.30186654 2.21083307 12.30373337 2.21333258 2 P 0 ;0,1,2=71,3=0.000000
L 12.30373337 2.21333258 12.3048002 2.21708327 2 P 0 ;0,1,2=71,3=0.000000
L 12.3048002 2.21708327 12.30506683 2.2212498 2 P 0 ;0,1,2=71,3=0.000000
L 12.30506683 2.2212498 12.30453366 2.22666614 2 P 0 ;0,1,2=71,3=0.000000
L 12.30453366 2.22666614 12.30373337 2.22958366 2 P 0 ;0,1,2=71,3=0.000000
L 12.30373337 2.22958366 12.3024003 2.2324997 2 P 0 ;0,1,2=71,3=0.000000
L 12.3024003 2.2324997 12.30053346 2.23458337 2 P 0 ;0,1,2=71,3=0.000000
L 12.30053346 2.23458337 12.29866673 2.235 2 P 0 ;0,1,2=71,3=0.000000
L 12.29866673 2.235 12.2968 2.23416683 2 P 0 ;0,1,2=71,3=0.000000
L 12.2968 2.23416683 12.29546644 2.23208317 2 P 0 ;0,1,2=71,3=0.000000
L 12.2728 2.21 12.2728 2.235 2 P 0 ;0,1,2=71,3=0.000000
L 12.2728 2.235 12.28266703 2.21708327 2 P 0 ;0,1,2=71,3=0.000000
L 12.28266703 2.21708327 12.26933307 2.21708327 2 P 0 ;0,1,2=71,3=0.000000
L 0.59998002 2.03713002 0.59998002 2.05286998 3 P 0 
L 0.81727343 2.03083002 0.81727343 2.05583002 2 P 0 ;0,1,2=72,3=0.000000
L 0.81727343 2.05583002 0.81060669 2.05583002 2 P 0 ;0,1,2=72,3=0.000000
L 0.81060669 2.05583002 0.80847333 2.05457943 2 P 0 ;0,1,2=72,3=0.000000
L 0.80847333 2.05457943 0.80713986 2.05291319 2 P 0 ;0,1,2=72,3=0.000000
L 0.80713986 2.05291319 0.80660659 2.04957982 2 P 0 ;0,1,2=72,3=0.000000
L 0.80660659 2.04957982 0.80713986 2.04624636 2 P 0 ;0,1,2=72,3=0.000000
L 0.80713986 2.04624636 0.80873996 2.04416348 2 P 0 ;0,1,2=72,3=0.000000
L 0.80873996 2.04416348 0.81060669 2.04291299 2 P 0 ;0,1,2=72,3=0.000000
L 0.81060669 2.04291299 0.81727343 2.04291299 2 P 0 ;0,1,2=72,3=0.000000
L 0.81060669 2.04291299 0.80660659 2.03083002 2 P 0 ;0,1,2=72,3=0.000000
L 0.78794026 2.03083002 0.78794026 2.05583002 2 P 0 ;0,1,2=72,3=0.000000
L 0.78794026 2.05583002 0.79114006 2.05083032 2 P 0 ;0,1,2=72,3=0.000000
L 0.79114006 2.03083002 0.78474045 2.03083002 2 P 0 ;0,1,2=72,3=0.000000
L 0.76980669 2.03457913 0.76820699 2.03249626 2 P 0 ;0,1,2=72,3=0.000000
L 0.76820699 2.03249626 0.76634026 2.03124656 2 P 0 ;0,1,2=72,3=0.000000
L 0.76634026 2.03124656 0.76394026 2.03083002 2 P 0 ;0,1,2=72,3=0.000000
L 0.76394026 2.03083002 0.76153976 2.03166309 2 P 0 ;0,1,2=72,3=0.000000
L 0.76153976 2.03166309 0.75967352 2.03332943 2 P 0 ;0,1,2=72,3=0.000000
L 0.75967352 2.03332943 0.75833996 2.03624626 2 P 0 ;0,1,2=72,3=0.000000
L 0.75833996 2.03624626 0.75807333 2.03957963 2 P 0 ;0,1,2=72,3=0.000000
L 0.75807333 2.03957963 0.75860659 2.04291299 2 P 0 ;0,1,2=72,3=0.000000
L 0.75860659 2.04291299 0.75994016 2.04499665 2 P 0 ;0,1,2=72,3=0.000000
L 0.75994016 2.04499665 0.76180689 2.04666299 2 P 0 ;0,1,2=72,3=0.000000
L 0.76180689 2.04666299 0.76367313 2.04707953 2 P 0 ;0,1,2=72,3=0.000000
L 0.76367313 2.04707953 0.76553996 2.04666299 2 P 0 ;0,1,2=72,3=0.000000
L 0.76553996 2.04666299 0.76793986 2.04499665 2 P 0 ;0,1,2=72,3=0.000000
L 0.76793986 2.04499665 0.76714006 2.05583002 2 P 0 ;0,1,2=72,3=0.000000
L 0.76714006 2.05583002 0.75994016 2.05583002 2 P 0 ;0,1,2=72,3=0.000000
L 0.74500679 2.04124596 0.74314006 2.04416348 2 P 0 ;0,1,2=72,3=0.000000
L 0.74314006 2.04416348 0.74153996 2.04582982 2 P 0 ;0,1,2=72,3=0.000000
L 0.74153996 2.04582982 0.73940659 2.04666299 2 P 0 ;0,1,2=72,3=0.000000
L 0.73940659 2.04666299 0.73753976 2.04582982 2 P 0 ;0,1,2=72,3=0.000000
L 0.73753976 2.04582982 0.73620669 2.04416348 2 P 0 ;0,1,2=72,3=0.000000
L 0.73620669 2.04416348 0.73513986 2.04166329 2 P 0 ;0,1,2=72,3=0.000000
L 0.73513986 2.04166329 0.73487323 2.03874646 2 P 0 ;0,1,2=72,3=0.000000
L 0.73487323 2.03874646 0.73513986 2.03624626 2 P 0 ;0,1,2=72,3=0.000000
L 0.73513986 2.03624626 0.73620669 2.03374606 2 P 0 ;0,1,2=72,3=0.000000
L 0.73620669 2.03374606 0.73780689 2.03166309 2 P 0 ;0,1,2=72,3=0.000000
L 0.73780689 2.03166309 0.73967313 2.03083002 2 P 0 ;0,1,2=72,3=0.000000
L 0.73967313 2.03083002 0.7418065 2.03166309 2 P 0 ;0,1,2=72,3=0.000000
L 0.7418065 2.03166309 0.74367333 2.0341626 2 P 0 ;0,1,2=72,3=0.000000
L 0.74367333 2.0341626 0.74474016 2.03791329 2 P 0 ;0,1,2=72,3=0.000000
L 0.74474016 2.03791329 0.74500679 2.04207982 2 P 0 ;0,1,2=72,3=0.000000
L 0.74500679 2.04207982 0.74447362 2.04749616 2 P 0 ;0,1,2=72,3=0.000000
L 0.74447362 2.04749616 0.74367333 2.05041368 2 P 0 ;0,1,2=72,3=0.000000
L 0.74367333 2.05041368 0.74234026 2.05332972 2 P 0 ;0,1,2=72,3=0.000000
L 0.74234026 2.05332972 0.74047343 2.05541339 2 P 0 ;0,1,2=72,3=0.000000
L 0.74047343 2.05541339 0.73860669 2.05583002 2 P 0 ;0,1,2=72,3=0.000000
L 0.73860669 2.05583002 0.73673996 2.05499685 2 P 0 ;0,1,2=72,3=0.000000
L 0.73673996 2.05499685 0.7354064 2.05291319 2 P 0 ;0,1,2=72,3=0.000000
L 0.72180669 2.03582963 0.72020699 2.03291289 2 P 0 ;0,1,2=72,3=0.000000
L 0.72020699 2.03291289 0.71807362 2.03124656 2 P 0 ;0,1,2=72,3=0.000000
L 0.71807362 2.03124656 0.71567313 2.03083002 2 P 0 ;0,1,2=72,3=0.000000
L 0.71567313 2.03083002 0.71353976 2.03124656 2 P 0 ;0,1,2=72,3=0.000000
L 0.71353976 2.03124656 0.7114064 2.03332943 2 P 0 ;0,1,2=72,3=0.000000
L 0.7114064 2.03332943 0.71007333 2.03582963 2 P 0 ;0,1,2=72,3=0.000000
L 0.71007333 2.03582963 0.70980679 2.03832992 2 P 0 ;0,1,2=72,3=0.000000
L 0.70980679 2.03832992 0.71033996 2.04124596 2 P 0 ;0,1,2=72,3=0.000000
L 0.71033996 2.04124596 0.71220669 2.04332963 2 P 0 ;0,1,2=72,3=0.000000
L 0.71220669 2.04332963 0.71407352 2.04416348 2 P 0 ;0,1,2=72,3=0.000000
L 0.71407352 2.04416348 0.71647343 2.04416348 2 P 0 ;0,1,2=72,3=0.000000
L 0.71407352 2.04416348 0.71247333 2.04541329 2 P 0 ;0,1,2=72,3=0.000000
L 0.71247333 2.04541329 0.71113986 2.04749616 2 P 0 ;0,1,2=72,3=0.000000
L 0.71113986 2.04749616 0.71060659 2.04999636 2 P 0 ;0,1,2=72,3=0.000000
L 0.71060659 2.04999636 0.71113986 2.05249656 2 P 0 ;0,1,2=72,3=0.000000
L 0.71113986 2.05249656 0.71247333 2.05457943 2 P 0 ;0,1,2=72,3=0.000000
L 0.71247333 2.05457943 0.71487333 2.05583002 2 P 0 ;0,1,2=72,3=0.000000
L 0.71487333 2.05583002 0.71727333 2.05541339 2 P 0 ;0,1,2=72,3=0.000000
L 0.71727333 2.05541339 0.71967333 2.05374636 2 P 0 ;0,1,2=72,3=0.000000
L 8.12786998 5.36 8.11213002 5.36 3 P 0 
L 8.11 5.40766654 8.135 5.40766654 2 P 0 ;0,1,2=73,3=90.000000
L 8.135 5.40766654 8.135 5.41433327 2 P 0 ;0,1,2=73,3=90.000000
L 8.135 5.41433327 8.13374941 5.41646663 2 P 0 ;0,1,2=73,3=90.000000
L 8.13374941 5.41646663 8.13208317 5.4178001 2 P 0 ;0,1,2=73,3=90.000000
L 8.13208317 5.4178001 8.1287498 5.41833337 2 P 0 ;0,1,2=73,3=90.000000
L 8.1287498 5.41833337 8.12541634 5.4178001 2 P 0 ;0,1,2=73,3=90.000000
L 8.12541634 5.4178001 8.12333346 5.4162 2 P 0 ;0,1,2=73,3=90.000000
L 8.12333346 5.4162 8.12208297 5.41433327 2 P 0 ;0,1,2=73,3=90.000000
L 8.12208297 5.41433327 8.12208297 5.40766654 2 P 0 ;0,1,2=73,3=90.000000
L 8.12208297 5.41433327 8.11 5.41833337 2 P 0 ;0,1,2=73,3=90.000000
L 8.11 5.4369997 8.135 5.4369997 2 P 0 ;0,1,2=73,3=90.000000
L 8.135 5.4369997 8.1300003 5.4337999 2 P 0 ;0,1,2=73,3=90.000000
L 8.11 5.4337999 8.11 5.44019951 2 P 0 ;0,1,2=73,3=90.000000
L 8.11374911 5.45513327 8.11166624 5.45673297 2 P 0 ;0,1,2=73,3=90.000000
L 8.11166624 5.45673297 8.11041654 5.4585997 2 P 0 ;0,1,2=73,3=90.000000
L 8.11041654 5.4585997 8.11 5.4609997 2 P 0 ;0,1,2=73,3=90.000000
L 8.11 5.4609997 8.11083307 5.4634002 2 P 0 ;0,1,2=73,3=90.000000
L 8.11083307 5.4634002 8.11249941 5.46526644 2 P 0 ;0,1,2=73,3=90.000000
L 8.11249941 5.46526644 8.11541624 5.4666 2 P 0 ;0,1,2=73,3=90.000000
L 8.11541624 5.4666 8.11874961 5.46686663 2 P 0 ;0,1,2=73,3=90.000000
L 8.11874961 5.46686663 8.12208297 5.46633337 2 P 0 ;0,1,2=73,3=90.000000
L 8.12208297 5.46633337 8.12416663 5.4649998 2 P 0 ;0,1,2=73,3=90.000000
L 8.12416663 5.4649998 8.12583297 5.46313307 2 P 0 ;0,1,2=73,3=90.000000
L 8.12583297 5.46313307 8.12624951 5.46126683 2 P 0 ;0,1,2=73,3=90.000000
L 8.12624951 5.46126683 8.12583297 5.4594 2 P 0 ;0,1,2=73,3=90.000000
L 8.12583297 5.4594 8.12416663 5.4570001 2 P 0 ;0,1,2=73,3=90.000000
L 8.12416663 5.4570001 8.135 5.4577999 2 P 0 ;0,1,2=73,3=90.000000
L 8.135 5.4577999 8.135 5.4649998 2 P 0 ;0,1,2=73,3=90.000000
L 8.11374911 5.47913327 8.11166624 5.48073297 2 P 0 ;0,1,2=73,3=90.000000
L 8.11166624 5.48073297 8.11041654 5.4825997 2 P 0 ;0,1,2=73,3=90.000000
L 8.11041654 5.4825997 8.11 5.4849997 2 P 0 ;0,1,2=73,3=90.000000
L 8.11 5.4849997 8.11083307 5.4874002 2 P 0 ;0,1,2=73,3=90.000000
L 8.11083307 5.4874002 8.11249941 5.48926644 2 P 0 ;0,1,2=73,3=90.000000
L 8.11249941 5.48926644 8.11541624 5.4906 2 P 0 ;0,1,2=73,3=90.000000
L 8.11541624 5.4906 8.11874961 5.49086663 2 P 0 ;0,1,2=73,3=90.000000
L 8.11874961 5.49086663 8.12208297 5.49033337 2 P 0 ;0,1,2=73,3=90.000000
L 8.12208297 5.49033337 8.12416663 5.4889998 2 P 0 ;0,1,2=73,3=90.000000
L 8.12416663 5.4889998 8.12583297 5.48713307 2 P 0 ;0,1,2=73,3=90.000000
L 8.12583297 5.48713307 8.12624951 5.48526683 2 P 0 ;0,1,2=73,3=90.000000
L 8.12624951 5.48526683 8.12583297 5.4834 2 P 0 ;0,1,2=73,3=90.000000
L 8.12583297 5.4834 8.12416663 5.4810001 2 P 0 ;0,1,2=73,3=90.000000
L 8.12416663 5.4810001 8.135 5.4817999 2 P 0 ;0,1,2=73,3=90.000000
L 8.135 5.4817999 8.135 5.4889998 2 P 0 ;0,1,2=73,3=90.000000
L 8.12041594 5.50393317 8.12333346 5.5057999 2 P 0 ;0,1,2=73,3=90.000000
L 8.12333346 5.5057999 8.1249998 5.5074 2 P 0 ;0,1,2=73,3=90.000000
L 8.1249998 5.5074 8.12583297 5.50953337 2 P 0 ;0,1,2=73,3=90.000000
L 8.12583297 5.50953337 8.1249998 5.5114002 2 P 0 ;0,1,2=73,3=90.000000
L 8.1249998 5.5114002 8.12333346 5.51273327 2 P 0 ;0,1,2=73,3=90.000000
L 8.12333346 5.51273327 8.12083327 5.5138001 2 P 0 ;0,1,2=73,3=90.000000
L 8.12083327 5.5138001 8.11791644 5.51406673 2 P 0 ;0,1,2=73,3=90.000000
L 8.11791644 5.51406673 8.11541624 5.5138001 2 P 0 ;0,1,2=73,3=90.000000
L 8.11541624 5.5138001 8.11291604 5.51273327 2 P 0 ;0,1,2=73,3=90.000000
L 8.11291604 5.51273327 8.11083307 5.51113307 2 P 0 ;0,1,2=73,3=90.000000
L 8.11083307 5.51113307 8.11 5.50926683 2 P 0 ;0,1,2=73,3=90.000000
L 8.11 5.50926683 8.11083307 5.50713346 2 P 0 ;0,1,2=73,3=90.000000
L 8.11083307 5.50713346 8.11333258 5.50526663 2 P 0 ;0,1,2=73,3=90.000000
L 8.11333258 5.50526663 8.11708327 5.5041998 2 P 0 ;0,1,2=73,3=90.000000
L 8.11708327 5.5041998 8.1212498 5.50393317 2 P 0 ;0,1,2=73,3=90.000000
L 8.1212498 5.50393317 8.12666614 5.50446634 2 P 0 ;0,1,2=73,3=90.000000
L 8.12666614 5.50446634 8.12958366 5.50526663 2 P 0 ;0,1,2=73,3=90.000000
L 8.12958366 5.50526663 8.1324997 5.5065997 2 P 0 ;0,1,2=73,3=90.000000
L 8.1324997 5.5065997 8.13458337 5.50846654 2 P 0 ;0,1,2=73,3=90.000000
L 8.13458337 5.50846654 8.135 5.51033327 2 P 0 ;0,1,2=73,3=90.000000
L 8.135 5.51033327 8.13416683 5.5122 2 P 0 ;0,1,2=73,3=90.000000
L 8.13416683 5.5122 8.13208317 5.51353356 2 P 0 ;0,1,2=73,3=90.000000
L 3.23933002 5.315 3.22358996 5.315 3 P 0 
L 3.225 5.36266654 3.25 5.36266654 2 P 0 ;0,1,2=74,3=90.000000
L 3.25 5.36266654 3.25 5.36933327 2 P 0 ;0,1,2=74,3=90.000000
L 3.25 5.36933327 3.24874941 5.37146663 2 P 0 ;0,1,2=74,3=90.000000
L 3.24874941 5.37146663 3.24708317 5.3728001 2 P 0 ;0,1,2=74,3=90.000000
L 3.24708317 5.3728001 3.2437498 5.37333337 2 P 0 ;0,1,2=74,3=90.000000
L 3.2437498 5.37333337 3.24041634 5.3728001 2 P 0 ;0,1,2=74,3=90.000000
L 3.24041634 5.3728001 3.23833346 5.3712 2 P 0 ;0,1,2=74,3=90.000000
L 3.23833346 5.3712 3.23708297 5.36933327 2 P 0 ;0,1,2=74,3=90.000000
L 3.23708297 5.36933327 3.23708297 5.36266654 2 P 0 ;0,1,2=74,3=90.000000
L 3.23708297 5.36933327 3.225 5.37333337 2 P 0 ;0,1,2=74,3=90.000000
L 3.225 5.3919997 3.25 5.3919997 2 P 0 ;0,1,2=74,3=90.000000
L 3.25 5.3919997 3.2450003 5.3887999 2 P 0 ;0,1,2=74,3=90.000000
L 3.225 5.3887999 3.225 5.39519951 2 P 0 ;0,1,2=74,3=90.000000
L 3.22874911 5.41013327 3.22666624 5.41173297 2 P 0 ;0,1,2=74,3=90.000000
L 3.22666624 5.41173297 3.22541654 5.4135997 2 P 0 ;0,1,2=74,3=90.000000
L 3.22541654 5.4135997 3.225 5.4159997 2 P 0 ;0,1,2=74,3=90.000000
L 3.225 5.4159997 3.22583307 5.4184002 2 P 0 ;0,1,2=74,3=90.000000
L 3.22583307 5.4184002 3.22749941 5.42026644 2 P 0 ;0,1,2=74,3=90.000000
L 3.22749941 5.42026644 3.23041624 5.4216 2 P 0 ;0,1,2=74,3=90.000000
L 3.23041624 5.4216 3.23374961 5.42186663 2 P 0 ;0,1,2=74,3=90.000000
L 3.23374961 5.42186663 3.23708297 5.42133337 2 P 0 ;0,1,2=74,3=90.000000
L 3.23708297 5.42133337 3.23916663 5.4199998 2 P 0 ;0,1,2=74,3=90.000000
L 3.23916663 5.4199998 3.24083297 5.41813307 2 P 0 ;0,1,2=74,3=90.000000
L 3.24083297 5.41813307 3.24124951 5.41626683 2 P 0 ;0,1,2=74,3=90.000000
L 3.24124951 5.41626683 3.24083297 5.4144 2 P 0 ;0,1,2=74,3=90.000000
L 3.24083297 5.4144 3.23916663 5.4120001 2 P 0 ;0,1,2=74,3=90.000000
L 3.23916663 5.4120001 3.25 5.4127999 2 P 0 ;0,1,2=74,3=90.000000
L 3.25 5.4127999 3.25 5.4199998 2 P 0 ;0,1,2=74,3=90.000000
L 3.22874911 5.43413327 3.22666624 5.43573297 2 P 0 ;0,1,2=74,3=90.000000
L 3.22666624 5.43573297 3.22541654 5.4375997 2 P 0 ;0,1,2=74,3=90.000000
L 3.22541654 5.4375997 3.225 5.4399997 2 P 0 ;0,1,2=74,3=90.000000
L 3.225 5.4399997 3.22583307 5.4424002 2 P 0 ;0,1,2=74,3=90.000000
L 3.22583307 5.4424002 3.22749941 5.44426644 2 P 0 ;0,1,2=74,3=90.000000
L 3.22749941 5.44426644 3.23041624 5.4456 2 P 0 ;0,1,2=74,3=90.000000
L 3.23041624 5.4456 3.23374961 5.44586663 2 P 0 ;0,1,2=74,3=90.000000
L 3.23374961 5.44586663 3.23708297 5.44533337 2 P 0 ;0,1,2=74,3=90.000000
L 3.23708297 5.44533337 3.23916663 5.4439998 2 P 0 ;0,1,2=74,3=90.000000
L 3.23916663 5.4439998 3.24083297 5.44213307 2 P 0 ;0,1,2=74,3=90.000000
L 3.24083297 5.44213307 3.24124951 5.44026683 2 P 0 ;0,1,2=74,3=90.000000
L 3.24124951 5.44026683 3.24083297 5.4384 2 P 0 ;0,1,2=74,3=90.000000
L 3.24083297 5.4384 3.23916663 5.4360001 2 P 0 ;0,1,2=74,3=90.000000
L 3.23916663 5.4360001 3.25 5.4367999 2 P 0 ;0,1,2=74,3=90.000000
L 3.25 5.4367999 3.25 5.4439998 2 P 0 ;0,1,2=74,3=90.000000
L 3.25 5.4639997 3.24916683 5.46186634 2 P 0 ;0,1,2=74,3=90.000000
L 3.24916683 5.46186634 3.24708317 5.46026663 2 P 0 ;0,1,2=74,3=90.000000
L 3.24708317 5.46026663 3.24458366 5.4591998 2 P 0 ;0,1,2=74,3=90.000000
L 3.24458366 5.4591998 3.24124951 5.4583999 2 P 0 ;0,1,2=74,3=90.000000
L 3.24124951 5.4583999 3.23749961 5.45813327 2 P 0 ;0,1,2=74,3=90.000000
L 3.23749961 5.45813327 3.23374961 5.4583999 2 P 0 ;0,1,2=74,3=90.000000
L 3.23374961 5.4583999 3.23041624 5.4591998 2 P 0 ;0,1,2=74,3=90.000000
L 3.23041624 5.4591998 3.22791604 5.46026663 2 P 0 ;0,1,2=74,3=90.000000
L 3.22791604 5.46026663 3.22583307 5.46186634 2 P 0 ;0,1,2=74,3=90.000000
L 3.22583307 5.46186634 3.225 5.4639997 2 P 0 ;0,1,2=74,3=90.000000
L 3.225 5.4639997 3.22583307 5.46613307 2 P 0 ;0,1,2=74,3=90.000000
L 3.22583307 5.46613307 3.22791604 5.46773327 2 P 0 ;0,1,2=74,3=90.000000
L 3.22791604 5.46773327 3.23041624 5.4688001 2 P 0 ;0,1,2=74,3=90.000000
L 3.23041624 5.4688001 3.23374961 5.4696 2 P 0 ;0,1,2=74,3=90.000000
L 3.23374961 5.4696 3.23749961 5.46986663 2 P 0 ;0,1,2=74,3=90.000000
L 3.23749961 5.46986663 3.24124951 5.4696 2 P 0 ;0,1,2=74,3=90.000000
L 3.24124951 5.4696 3.24458366 5.4688001 2 P 0 ;0,1,2=74,3=90.000000
L 3.24458366 5.4688001 3.24708317 5.46773327 2 P 0 ;0,1,2=74,3=90.000000
L 3.24708317 5.46773327 3.24916683 5.46613307 2 P 0 ;0,1,2=74,3=90.000000
L 3.24916683 5.46613307 3.25 5.4639997 2 P 0 ;0,1,2=74,3=90.000000
L 2.05858996 5.36 2.07433002 5.36 3 P 0 
L 2.055 5.40766654 2.08 5.40766654 2 P 0 ;0,1,2=75,3=90.000000
L 2.08 5.40766654 2.08 5.41433327 2 P 0 ;0,1,2=75,3=90.000000
L 2.08 5.41433327 2.07874941 5.41646663 2 P 0 ;0,1,2=75,3=90.000000
L 2.07874941 5.41646663 2.07708317 5.4178001 2 P 0 ;0,1,2=75,3=90.000000
L 2.07708317 5.4178001 2.0737498 5.41833337 2 P 0 ;0,1,2=75,3=90.000000
L 2.0737498 5.41833337 2.07041634 5.4178001 2 P 0 ;0,1,2=75,3=90.000000
L 2.07041634 5.4178001 2.06833346 5.4162 2 P 0 ;0,1,2=75,3=90.000000
L 2.06833346 5.4162 2.06708297 5.41433327 2 P 0 ;0,1,2=75,3=90.000000
L 2.06708297 5.41433327 2.06708297 5.40766654 2 P 0 ;0,1,2=75,3=90.000000
L 2.06708297 5.41433327 2.055 5.41833337 2 P 0 ;0,1,2=75,3=90.000000
L 2.055 5.4369997 2.08 5.4369997 2 P 0 ;0,1,2=75,3=90.000000
L 2.08 5.4369997 2.0750003 5.4337999 2 P 0 ;0,1,2=75,3=90.000000
L 2.055 5.4337999 2.055 5.44019951 2 P 0 ;0,1,2=75,3=90.000000
L 2.05874911 5.45513327 2.05666624 5.45673297 2 P 0 ;0,1,2=75,3=90.000000
L 2.05666624 5.45673297 2.05541654 5.4585997 2 P 0 ;0,1,2=75,3=90.000000
L 2.05541654 5.4585997 2.055 5.4609997 2 P 0 ;0,1,2=75,3=90.000000
L 2.055 5.4609997 2.05583307 5.4634002 2 P 0 ;0,1,2=75,3=90.000000
L 2.05583307 5.4634002 2.05749941 5.46526644 2 P 0 ;0,1,2=75,3=90.000000
L 2.05749941 5.46526644 2.06041624 5.4666 2 P 0 ;0,1,2=75,3=90.000000
L 2.06041624 5.4666 2.06374961 5.46686663 2 P 0 ;0,1,2=75,3=90.000000
L 2.06374961 5.46686663 2.06708297 5.46633337 2 P 0 ;0,1,2=75,3=90.000000
L 2.06708297 5.46633337 2.06916663 5.4649998 2 P 0 ;0,1,2=75,3=90.000000
L 2.06916663 5.4649998 2.07083297 5.46313307 2 P 0 ;0,1,2=75,3=90.000000
L 2.07083297 5.46313307 2.07124951 5.46126683 2 P 0 ;0,1,2=75,3=90.000000
L 2.07124951 5.46126683 2.07083297 5.4594 2 P 0 ;0,1,2=75,3=90.000000
L 2.07083297 5.4594 2.06916663 5.4570001 2 P 0 ;0,1,2=75,3=90.000000
L 2.06916663 5.4570001 2.08 5.4577999 2 P 0 ;0,1,2=75,3=90.000000
L 2.08 5.4577999 2.08 5.4649998 2 P 0 ;0,1,2=75,3=90.000000
L 2.05874911 5.47913327 2.05666624 5.48073297 2 P 0 ;0,1,2=75,3=90.000000
L 2.05666624 5.48073297 2.05541654 5.4825997 2 P 0 ;0,1,2=75,3=90.000000
L 2.05541654 5.4825997 2.055 5.4849997 2 P 0 ;0,1,2=75,3=90.000000
L 2.055 5.4849997 2.05583307 5.4874002 2 P 0 ;0,1,2=75,3=90.000000
L 2.05583307 5.4874002 2.05749941 5.48926644 2 P 0 ;0,1,2=75,3=90.000000
L 2.05749941 5.48926644 2.06041624 5.4906 2 P 0 ;0,1,2=75,3=90.000000
L 2.06041624 5.4906 2.06374961 5.49086663 2 P 0 ;0,1,2=75,3=90.000000
L 2.06374961 5.49086663 2.06708297 5.49033337 2 P 0 ;0,1,2=75,3=90.000000
L 2.06708297 5.49033337 2.06916663 5.4889998 2 P 0 ;0,1,2=75,3=90.000000
L 2.06916663 5.4889998 2.07083297 5.48713307 2 P 0 ;0,1,2=75,3=90.000000
L 2.07083297 5.48713307 2.07124951 5.48526683 2 P 0 ;0,1,2=75,3=90.000000
L 2.07124951 5.48526683 2.07083297 5.4834 2 P 0 ;0,1,2=75,3=90.000000
L 2.07083297 5.4834 2.06916663 5.4810001 2 P 0 ;0,1,2=75,3=90.000000
L 2.06916663 5.4810001 2.08 5.4817999 2 P 0 ;0,1,2=75,3=90.000000
L 2.08 5.4817999 2.08 5.4889998 2 P 0 ;0,1,2=75,3=90.000000
L 2.055 5.5089997 2.08 5.5089997 2 P 0 ;0,1,2=75,3=90.000000
L 2.08 5.5089997 2.0750003 5.5057999 2 P 0 ;0,1,2=75,3=90.000000
L 2.055 5.5057999 2.055 5.51219951 2 P 0 ;0,1,2=75,3=90.000000
L 8.06213002 5.36 8.07786998 5.36 3 P 0 
L 8.06 5.40766654 8.085 5.40766654 2 P 0 ;0,1,2=76,3=90.000000
L 8.085 5.40766654 8.085 5.41433327 2 P 0 ;0,1,2=76,3=90.000000
L 8.085 5.41433327 8.08374941 5.41646663 2 P 0 ;0,1,2=76,3=90.000000
L 8.08374941 5.41646663 8.08208317 5.4178001 2 P 0 ;0,1,2=76,3=90.000000
L 8.08208317 5.4178001 8.0787498 5.41833337 2 P 0 ;0,1,2=76,3=90.000000
L 8.0787498 5.41833337 8.07541634 5.4178001 2 P 0 ;0,1,2=76,3=90.000000
L 8.07541634 5.4178001 8.07333346 5.4162 2 P 0 ;0,1,2=76,3=90.000000
L 8.07333346 5.4162 8.07208297 5.41433327 2 P 0 ;0,1,2=76,3=90.000000
L 8.07208297 5.41433327 8.07208297 5.40766654 2 P 0 ;0,1,2=76,3=90.000000
L 8.07208297 5.41433327 8.06 5.41833337 2 P 0 ;0,1,2=76,3=90.000000
L 8.06 5.4369997 8.085 5.4369997 2 P 0 ;0,1,2=76,3=90.000000
L 8.085 5.4369997 8.0800003 5.4337999 2 P 0 ;0,1,2=76,3=90.000000
L 8.06 5.4337999 8.06 5.44019951 2 P 0 ;0,1,2=76,3=90.000000
L 8.06374911 5.45513327 8.06166624 5.45673297 2 P 0 ;0,1,2=76,3=90.000000
L 8.06166624 5.45673297 8.06041654 5.4585997 2 P 0 ;0,1,2=76,3=90.000000
L 8.06041654 5.4585997 8.06 5.4609997 2 P 0 ;0,1,2=76,3=90.000000
L 8.06 5.4609997 8.06083307 5.4634002 2 P 0 ;0,1,2=76,3=90.000000
L 8.06083307 5.4634002 8.06249941 5.46526644 2 P 0 ;0,1,2=76,3=90.000000
L 8.06249941 5.46526644 8.06541624 5.4666 2 P 0 ;0,1,2=76,3=90.000000
L 8.06541624 5.4666 8.06874961 5.46686663 2 P 0 ;0,1,2=76,3=90.000000
L 8.06874961 5.46686663 8.07208297 5.46633337 2 P 0 ;0,1,2=76,3=90.000000
L 8.07208297 5.46633337 8.07416663 5.4649998 2 P 0 ;0,1,2=76,3=90.000000
L 8.07416663 5.4649998 8.07583297 5.46313307 2 P 0 ;0,1,2=76,3=90.000000
L 8.07583297 5.46313307 8.07624951 5.46126683 2 P 0 ;0,1,2=76,3=90.000000
L 8.07624951 5.46126683 8.07583297 5.4594 2 P 0 ;0,1,2=76,3=90.000000
L 8.07583297 5.4594 8.07416663 5.4570001 2 P 0 ;0,1,2=76,3=90.000000
L 8.07416663 5.4570001 8.085 5.4577999 2 P 0 ;0,1,2=76,3=90.000000
L 8.085 5.4577999 8.085 5.4649998 2 P 0 ;0,1,2=76,3=90.000000
L 8.06374911 5.47913327 8.06166624 5.48073297 2 P 0 ;0,1,2=76,3=90.000000
L 8.06166624 5.48073297 8.06041654 5.4825997 2 P 0 ;0,1,2=76,3=90.000000
L 8.06041654 5.4825997 8.06 5.4849997 2 P 0 ;0,1,2=76,3=90.000000
L 8.06 5.4849997 8.06083307 5.4874002 2 P 0 ;0,1,2=76,3=90.000000
L 8.06083307 5.4874002 8.06249941 5.48926644 2 P 0 ;0,1,2=76,3=90.000000
L 8.06249941 5.48926644 8.06541624 5.4906 2 P 0 ;0,1,2=76,3=90.000000
L 8.06541624 5.4906 8.06874961 5.49086663 2 P 0 ;0,1,2=76,3=90.000000
L 8.06874961 5.49086663 8.07208297 5.49033337 2 P 0 ;0,1,2=76,3=90.000000
L 8.07208297 5.49033337 8.07416663 5.4889998 2 P 0 ;0,1,2=76,3=90.000000
L 8.07416663 5.4889998 8.07583297 5.48713307 2 P 0 ;0,1,2=76,3=90.000000
L 8.07583297 5.48713307 8.07624951 5.48526683 2 P 0 ;0,1,2=76,3=90.000000
L 8.07624951 5.48526683 8.07583297 5.4834 2 P 0 ;0,1,2=76,3=90.000000
L 8.07583297 5.4834 8.07416663 5.4810001 2 P 0 ;0,1,2=76,3=90.000000
L 8.07416663 5.4810001 8.085 5.4817999 2 P 0 ;0,1,2=76,3=90.000000
L 8.085 5.4817999 8.085 5.4889998 2 P 0 ;0,1,2=76,3=90.000000
L 8.06374911 5.50313327 8.06166624 5.50473297 2 P 0 ;0,1,2=76,3=90.000000
L 8.06166624 5.50473297 8.06041654 5.5065997 2 P 0 ;0,1,2=76,3=90.000000
L 8.06041654 5.5065997 8.06 5.5089997 2 P 0 ;0,1,2=76,3=90.000000
L 8.06 5.5089997 8.06083307 5.5114002 2 P 0 ;0,1,2=76,3=90.000000
L 8.06083307 5.5114002 8.06249941 5.51326644 2 P 0 ;0,1,2=76,3=90.000000
L 8.06249941 5.51326644 8.06541624 5.5146 2 P 0 ;0,1,2=76,3=90.000000
L 8.06541624 5.5146 8.06874961 5.51486663 2 P 0 ;0,1,2=76,3=90.000000
L 8.06874961 5.51486663 8.07208297 5.51433337 2 P 0 ;0,1,2=76,3=90.000000
L 8.07208297 5.51433337 8.07416663 5.5129998 2 P 0 ;0,1,2=76,3=90.000000
L 8.07416663 5.5129998 8.07583297 5.51113307 2 P 0 ;0,1,2=76,3=90.000000
L 8.07583297 5.51113307 8.07624951 5.50926683 2 P 0 ;0,1,2=76,3=90.000000
L 8.07624951 5.50926683 8.07583297 5.5074 2 P 0 ;0,1,2=76,3=90.000000
L 8.07583297 5.5074 8.07416663 5.5050001 2 P 0 ;0,1,2=76,3=90.000000
L 8.07416663 5.5050001 8.085 5.5057999 2 P 0 ;0,1,2=76,3=90.000000
L 8.085 5.5057999 8.085 5.5129998 2 P 0 ;0,1,2=76,3=90.000000
L 7.99713002 5.36 8.01286998 5.36 3 P 0 
L 7.99 5.40766654 8.015 5.40766654 2 P 0 ;0,1,2=77,3=90.000000
L 8.015 5.40766654 8.015 5.41433327 2 P 0 ;0,1,2=77,3=90.000000
L 8.015 5.41433327 8.01374941 5.41646663 2 P 0 ;0,1,2=77,3=90.000000
L 8.01374941 5.41646663 8.01208317 5.4178001 2 P 0 ;0,1,2=77,3=90.000000
L 8.01208317 5.4178001 8.0087498 5.41833337 2 P 0 ;0,1,2=77,3=90.000000
L 8.0087498 5.41833337 8.00541634 5.4178001 2 P 0 ;0,1,2=77,3=90.000000
L 8.00541634 5.4178001 8.00333346 5.4162 2 P 0 ;0,1,2=77,3=90.000000
L 8.00333346 5.4162 8.00208297 5.41433327 2 P 0 ;0,1,2=77,3=90.000000
L 8.00208297 5.41433327 8.00208297 5.40766654 2 P 0 ;0,1,2=77,3=90.000000
L 8.00208297 5.41433327 7.99 5.41833337 2 P 0 ;0,1,2=77,3=90.000000
L 7.99 5.4369997 8.015 5.4369997 2 P 0 ;0,1,2=77,3=90.000000
L 8.015 5.4369997 8.0100003 5.4337999 2 P 0 ;0,1,2=77,3=90.000000
L 7.99 5.4337999 7.99 5.44019951 2 P 0 ;0,1,2=77,3=90.000000
L 7.99374911 5.45513327 7.99166624 5.45673297 2 P 0 ;0,1,2=77,3=90.000000
L 7.99166624 5.45673297 7.99041654 5.4585997 2 P 0 ;0,1,2=77,3=90.000000
L 7.99041654 5.4585997 7.99 5.4609997 2 P 0 ;0,1,2=77,3=90.000000
L 7.99 5.4609997 7.99083307 5.4634002 2 P 0 ;0,1,2=77,3=90.000000
L 7.99083307 5.4634002 7.99249941 5.46526644 2 P 0 ;0,1,2=77,3=90.000000
L 7.99249941 5.46526644 7.99541624 5.4666 2 P 0 ;0,1,2=77,3=90.000000
L 7.99541624 5.4666 7.99874961 5.46686663 2 P 0 ;0,1,2=77,3=90.000000
L 7.99874961 5.46686663 8.00208297 5.46633337 2 P 0 ;0,1,2=77,3=90.000000
L 8.00208297 5.46633337 8.00416663 5.4649998 2 P 0 ;0,1,2=77,3=90.000000
L 8.00416663 5.4649998 8.00583297 5.46313307 2 P 0 ;0,1,2=77,3=90.000000
L 8.00583297 5.46313307 8.00624951 5.46126683 2 P 0 ;0,1,2=77,3=90.000000
L 8.00624951 5.46126683 8.00583297 5.4594 2 P 0 ;0,1,2=77,3=90.000000
L 8.00583297 5.4594 8.00416663 5.4570001 2 P 0 ;0,1,2=77,3=90.000000
L 8.00416663 5.4570001 8.015 5.4577999 2 P 0 ;0,1,2=77,3=90.000000
L 8.015 5.4577999 8.015 5.4649998 2 P 0 ;0,1,2=77,3=90.000000
L 7.99374911 5.47913327 7.99166624 5.48073297 2 P 0 ;0,1,2=77,3=90.000000
L 7.99166624 5.48073297 7.99041654 5.4825997 2 P 0 ;0,1,2=77,3=90.000000
L 7.99041654 5.4825997 7.99 5.4849997 2 P 0 ;0,1,2=77,3=90.000000
L 7.99 5.4849997 7.99083307 5.4874002 2 P 0 ;0,1,2=77,3=90.000000
L 7.99083307 5.4874002 7.99249941 5.48926644 2 P 0 ;0,1,2=77,3=90.000000
L 7.99249941 5.48926644 7.99541624 5.4906 2 P 0 ;0,1,2=77,3=90.000000
L 7.99541624 5.4906 7.99874961 5.49086663 2 P 0 ;0,1,2=77,3=90.000000
L 7.99874961 5.49086663 8.00208297 5.49033337 2 P 0 ;0,1,2=77,3=90.000000
L 8.00208297 5.49033337 8.00416663 5.4889998 2 P 0 ;0,1,2=77,3=90.000000
L 8.00416663 5.4889998 8.00583297 5.48713307 2 P 0 ;0,1,2=77,3=90.000000
L 8.00583297 5.48713307 8.00624951 5.48526683 2 P 0 ;0,1,2=77,3=90.000000
L 8.00624951 5.48526683 8.00583297 5.4834 2 P 0 ;0,1,2=77,3=90.000000
L 8.00583297 5.4834 8.00416663 5.4810001 2 P 0 ;0,1,2=77,3=90.000000
L 8.00416663 5.4810001 8.015 5.4817999 2 P 0 ;0,1,2=77,3=90.000000
L 8.015 5.4817999 8.015 5.4889998 2 P 0 ;0,1,2=77,3=90.000000
L 7.99 5.50846654 7.99541624 5.5089997 2 P 0 ;0,1,2=77,3=90.000000
L 7.99541624 5.5089997 7.99999931 5.5098 2 P 0 ;0,1,2=77,3=90.000000
L 7.99999931 5.5098 8.00416663 5.51086644 2 P 0 ;0,1,2=77,3=90.000000
L 8.00416663 5.51086644 8.0087498 5.5122 2 P 0 ;0,1,2=77,3=90.000000
L 8.0087498 5.5122 8.015 5.51433337 2 P 0 ;0,1,2=77,3=90.000000
L 8.015 5.51433337 8.015 5.50366654 2 P 0 ;0,1,2=77,3=90.000000
L 3.17858996 5.315 3.19433002 5.315 3 P 0 
L 3.175 5.36266654 3.2 5.36266654 2 P 0 ;0,1,2=78,3=90.000000
L 3.2 5.36266654 3.2 5.36933327 2 P 0 ;0,1,2=78,3=90.000000
L 3.2 5.36933327 3.19874941 5.37146663 2 P 0 ;0,1,2=78,3=90.000000
L 3.19874941 5.37146663 3.19708317 5.3728001 2 P 0 ;0,1,2=78,3=90.000000
L 3.19708317 5.3728001 3.1937498 5.37333337 2 P 0 ;0,1,2=78,3=90.000000
L 3.1937498 5.37333337 3.19041634 5.3728001 2 P 0 ;0,1,2=78,3=90.000000
L 3.19041634 5.3728001 3.18833346 5.3712 2 P 0 ;0,1,2=78,3=90.000000
L 3.18833346 5.3712 3.18708297 5.36933327 2 P 0 ;0,1,2=78,3=90.000000
L 3.18708297 5.36933327 3.18708297 5.36266654 2 P 0 ;0,1,2=78,3=90.000000
L 3.18708297 5.36933327 3.175 5.37333337 2 P 0 ;0,1,2=78,3=90.000000
L 3.175 5.3919997 3.2 5.3919997 2 P 0 ;0,1,2=78,3=90.000000
L 3.2 5.3919997 3.1950003 5.3887999 2 P 0 ;0,1,2=78,3=90.000000
L 3.175 5.3887999 3.175 5.39519951 2 P 0 ;0,1,2=78,3=90.000000
L 3.17874911 5.41013327 3.17666624 5.41173297 2 P 0 ;0,1,2=78,3=90.000000
L 3.17666624 5.41173297 3.17541654 5.4135997 2 P 0 ;0,1,2=78,3=90.000000
L 3.17541654 5.4135997 3.175 5.4159997 2 P 0 ;0,1,2=78,3=90.000000
L 3.175 5.4159997 3.17583307 5.4184002 2 P 0 ;0,1,2=78,3=90.000000
L 3.17583307 5.4184002 3.17749941 5.42026644 2 P 0 ;0,1,2=78,3=90.000000
L 3.17749941 5.42026644 3.18041624 5.4216 2 P 0 ;0,1,2=78,3=90.000000
L 3.18041624 5.4216 3.18374961 5.42186663 2 P 0 ;0,1,2=78,3=90.000000
L 3.18374961 5.42186663 3.18708297 5.42133337 2 P 0 ;0,1,2=78,3=90.000000
L 3.18708297 5.42133337 3.18916663 5.4199998 2 P 0 ;0,1,2=78,3=90.000000
L 3.18916663 5.4199998 3.19083297 5.41813307 2 P 0 ;0,1,2=78,3=90.000000
L 3.19083297 5.41813307 3.19124951 5.41626683 2 P 0 ;0,1,2=78,3=90.000000
L 3.19124951 5.41626683 3.19083297 5.4144 2 P 0 ;0,1,2=78,3=90.000000
L 3.19083297 5.4144 3.18916663 5.4120001 2 P 0 ;0,1,2=78,3=90.000000
L 3.18916663 5.4120001 3.2 5.4127999 2 P 0 ;0,1,2=78,3=90.000000
L 3.2 5.4127999 3.2 5.4199998 2 P 0 ;0,1,2=78,3=90.000000
L 3.175 5.4432 3.2 5.4432 2 P 0 ;0,1,2=78,3=90.000000
L 3.2 5.4432 3.18208327 5.43333297 2 P 0 ;0,1,2=78,3=90.000000
L 3.18208327 5.43333297 3.18208327 5.44666693 2 P 0 ;0,1,2=78,3=90.000000
L 3.17791604 5.45946634 3.17583307 5.46133317 2 P 0 ;0,1,2=78,3=90.000000
L 3.17583307 5.46133317 3.175 5.46346654 2 P 0 ;0,1,2=78,3=90.000000
L 3.175 5.46346654 3.17583307 5.4655999 2 P 0 ;0,1,2=78,3=90.000000
L 3.17583307 5.4655999 3.17833258 5.46746663 2 P 0 ;0,1,2=78,3=90.000000
L 3.17833258 5.46746663 3.18208327 5.4688001 2 P 0 ;0,1,2=78,3=90.000000
L 3.18208327 5.4688001 3.18583327 5.46933337 2 P 0 ;0,1,2=78,3=90.000000
L 3.18583327 5.46933337 3.19041634 5.46933337 2 P 0 ;0,1,2=78,3=90.000000
L 3.19041634 5.46933337 3.19416634 5.4688001 2 P 0 ;0,1,2=78,3=90.000000
L 3.19416634 5.4688001 3.1974997 5.46746663 2 P 0 ;0,1,2=78,3=90.000000
L 3.1974997 5.46746663 3.19916683 5.46586644 2 P 0 ;0,1,2=78,3=90.000000
L 3.19916683 5.46586644 3.2 5.4639997 2 P 0 ;0,1,2=78,3=90.000000
L 3.2 5.4639997 3.19916683 5.46186634 2 P 0 ;0,1,2=78,3=90.000000
L 3.19916683 5.46186634 3.1974997 5.46026663 2 P 0 ;0,1,2=78,3=90.000000
L 3.1974997 5.46026663 3.1950003 5.4591998 2 P 0 ;0,1,2=78,3=90.000000
L 3.1950003 5.4591998 3.19166614 5.45866654 2 P 0 ;0,1,2=78,3=90.000000
L 3.19166614 5.45866654 3.1887501 5.4591998 2 P 0 ;0,1,2=78,3=90.000000
L 3.1887501 5.4591998 3.18583327 5.46053327 2 P 0 ;0,1,2=78,3=90.000000
L 3.18583327 5.46053327 3.18416614 5.46213346 2 P 0 ;0,1,2=78,3=90.000000
L 3.18416614 5.46213346 3.18374961 5.4639997 2 P 0 ;0,1,2=78,3=90.000000
L 3.18374961 5.4639997 3.18458278 5.46613307 2 P 0 ;0,1,2=78,3=90.000000
L 3.18458278 5.46613307 3.18666644 5.46773327 2 P 0 ;0,1,2=78,3=90.000000
L 3.18666644 5.46773327 3.19041634 5.46933337 2 P 0 ;0,1,2=78,3=90.000000
L 2.12433002 5.36 2.10858996 5.36 3 P 0 
L 2.105 5.40766654 2.13 5.40766654 2 P 0 ;0,1,2=79,3=90.000000
L 2.13 5.40766654 2.13 5.41433327 2 P 0 ;0,1,2=79,3=90.000000
L 2.13 5.41433327 2.12874941 5.41646663 2 P 0 ;0,1,2=79,3=90.000000
L 2.12874941 5.41646663 2.12708317 5.4178001 2 P 0 ;0,1,2=79,3=90.000000
L 2.12708317 5.4178001 2.1237498 5.41833337 2 P 0 ;0,1,2=79,3=90.000000
L 2.1237498 5.41833337 2.12041634 5.4178001 2 P 0 ;0,1,2=79,3=90.000000
L 2.12041634 5.4178001 2.11833346 5.4162 2 P 0 ;0,1,2=79,3=90.000000
L 2.11833346 5.4162 2.11708297 5.41433327 2 P 0 ;0,1,2=79,3=90.000000
L 2.11708297 5.41433327 2.11708297 5.40766654 2 P 0 ;0,1,2=79,3=90.000000
L 2.11708297 5.41433327 2.105 5.41833337 2 P 0 ;0,1,2=79,3=90.000000
L 2.105 5.4369997 2.13 5.4369997 2 P 0 ;0,1,2=79,3=90.000000
L 2.13 5.4369997 2.1250003 5.4337999 2 P 0 ;0,1,2=79,3=90.000000
L 2.105 5.4337999 2.105 5.44019951 2 P 0 ;0,1,2=79,3=90.000000
L 2.10874911 5.45513327 2.10666624 5.45673297 2 P 0 ;0,1,2=79,3=90.000000
L 2.10666624 5.45673297 2.10541654 5.4585997 2 P 0 ;0,1,2=79,3=90.000000
L 2.10541654 5.4585997 2.105 5.4609997 2 P 0 ;0,1,2=79,3=90.000000
L 2.105 5.4609997 2.10583307 5.4634002 2 P 0 ;0,1,2=79,3=90.000000
L 2.10583307 5.4634002 2.10749941 5.46526644 2 P 0 ;0,1,2=79,3=90.000000
L 2.10749941 5.46526644 2.11041624 5.4666 2 P 0 ;0,1,2=79,3=90.000000
L 2.11041624 5.4666 2.11374961 5.46686663 2 P 0 ;0,1,2=79,3=90.000000
L 2.11374961 5.46686663 2.11708297 5.46633337 2 P 0 ;0,1,2=79,3=90.000000
L 2.11708297 5.46633337 2.11916663 5.4649998 2 P 0 ;0,1,2=79,3=90.000000
L 2.11916663 5.4649998 2.12083297 5.46313307 2 P 0 ;0,1,2=79,3=90.000000
L 2.12083297 5.46313307 2.12124951 5.46126683 2 P 0 ;0,1,2=79,3=90.000000
L 2.12124951 5.46126683 2.12083297 5.4594 2 P 0 ;0,1,2=79,3=90.000000
L 2.12083297 5.4594 2.11916663 5.4570001 2 P 0 ;0,1,2=79,3=90.000000
L 2.11916663 5.4570001 2.13 5.4577999 2 P 0 ;0,1,2=79,3=90.000000
L 2.13 5.4577999 2.13 5.4649998 2 P 0 ;0,1,2=79,3=90.000000
L 2.10874911 5.47913327 2.10666624 5.48073297 2 P 0 ;0,1,2=79,3=90.000000
L 2.10666624 5.48073297 2.10541654 5.4825997 2 P 0 ;0,1,2=79,3=90.000000
L 2.10541654 5.4825997 2.105 5.4849997 2 P 0 ;0,1,2=79,3=90.000000
L 2.105 5.4849997 2.10583307 5.4874002 2 P 0 ;0,1,2=79,3=90.000000
L 2.10583307 5.4874002 2.10749941 5.48926644 2 P 0 ;0,1,2=79,3=90.000000
L 2.10749941 5.48926644 2.11041624 5.4906 2 P 0 ;0,1,2=79,3=90.000000
L 2.11041624 5.4906 2.11374961 5.49086663 2 P 0 ;0,1,2=79,3=90.000000
L 2.11374961 5.49086663 2.11708297 5.49033337 2 P 0 ;0,1,2=79,3=90.000000
L 2.11708297 5.49033337 2.11916663 5.4889998 2 P 0 ;0,1,2=79,3=90.000000
L 2.11916663 5.4889998 2.12083297 5.48713307 2 P 0 ;0,1,2=79,3=90.000000
L 2.12083297 5.48713307 2.12124951 5.48526683 2 P 0 ;0,1,2=79,3=90.000000
L 2.12124951 5.48526683 2.12083297 5.4834 2 P 0 ;0,1,2=79,3=90.000000
L 2.12083297 5.4834 2.11916663 5.4810001 2 P 0 ;0,1,2=79,3=90.000000
L 2.11916663 5.4810001 2.13 5.4817999 2 P 0 ;0,1,2=79,3=90.000000
L 2.13 5.4817999 2.13 5.4889998 2 P 0 ;0,1,2=79,3=90.000000
L 2.12583337 5.50393317 2.12833287 5.50553327 2 P 0 ;0,1,2=79,3=90.000000
L 2.12833287 5.50553327 2.12958337 5.5074 2 P 0 ;0,1,2=79,3=90.000000
L 2.12958337 5.5074 2.13 5.50953337 2 P 0 ;0,1,2=79,3=90.000000
L 2.13 5.50953337 2.12916683 5.5122 2 P 0 ;0,1,2=79,3=90.000000
L 2.12916683 5.5122 2.12708317 5.51406673 2 P 0 ;0,1,2=79,3=90.000000
L 2.12708317 5.51406673 2.12458366 5.5146 2 P 0 ;0,1,2=79,3=90.000000
L 2.12458366 5.5146 2.12208268 5.51433337 2 P 0 ;0,1,2=79,3=90.000000
L 2.12208268 5.51433337 2.1199998 5.51326644 2 P 0 ;0,1,2=79,3=90.000000
L 2.1199998 5.51326644 2.11583327 5.50793327 2 P 0 ;0,1,2=79,3=90.000000
L 2.11583327 5.50793327 2.11291644 5.50553327 2 P 0 ;0,1,2=79,3=90.000000
L 2.11291644 5.50553327 2.10874911 5.50393317 2 P 0 ;0,1,2=79,3=90.000000
L 2.10874911 5.50393317 2.105 5.5033999 2 P 0 ;0,1,2=79,3=90.000000
L 2.105 5.5033999 2.105 5.5146 2 P 0 ;0,1,2=79,3=90.000000
L 1.99358996 5.36 2.00933002 5.36 3 P 0 
L 1.99 5.40766654 2.015 5.40766654 2 P 0 ;0,1,2=80,3=90.000000
L 2.015 5.40766654 2.015 5.41433327 2 P 0 ;0,1,2=80,3=90.000000
L 2.015 5.41433327 2.01374941 5.41646663 2 P 0 ;0,1,2=80,3=90.000000
L 2.01374941 5.41646663 2.01208317 5.4178001 2 P 0 ;0,1,2=80,3=90.000000
L 2.01208317 5.4178001 2.0087498 5.41833337 2 P 0 ;0,1,2=80,3=90.000000
L 2.0087498 5.41833337 2.00541634 5.4178001 2 P 0 ;0,1,2=80,3=90.000000
L 2.00541634 5.4178001 2.00333346 5.4162 2 P 0 ;0,1,2=80,3=90.000000
L 2.00333346 5.4162 2.00208297 5.41433327 2 P 0 ;0,1,2=80,3=90.000000
L 2.00208297 5.41433327 2.00208297 5.40766654 2 P 0 ;0,1,2=80,3=90.000000
L 2.00208297 5.41433327 1.99 5.41833337 2 P 0 ;0,1,2=80,3=90.000000
L 1.99 5.4369997 2.015 5.4369997 2 P 0 ;0,1,2=80,3=90.000000
L 2.015 5.4369997 2.0100003 5.4337999 2 P 0 ;0,1,2=80,3=90.000000
L 1.99 5.4337999 1.99 5.44019951 2 P 0 ;0,1,2=80,3=90.000000
L 1.99374911 5.45513327 1.99166624 5.45673297 2 P 0 ;0,1,2=80,3=90.000000
L 1.99166624 5.45673297 1.99041654 5.4585997 2 P 0 ;0,1,2=80,3=90.000000
L 1.99041654 5.4585997 1.99 5.4609997 2 P 0 ;0,1,2=80,3=90.000000
L 1.99 5.4609997 1.99083307 5.4634002 2 P 0 ;0,1,2=80,3=90.000000
L 1.99083307 5.4634002 1.99249941 5.46526644 2 P 0 ;0,1,2=80,3=90.000000
L 1.99249941 5.46526644 1.99541624 5.4666 2 P 0 ;0,1,2=80,3=90.000000
L 1.99541624 5.4666 1.99874961 5.46686663 2 P 0 ;0,1,2=80,3=90.000000
L 1.99874961 5.46686663 2.00208297 5.46633337 2 P 0 ;0,1,2=80,3=90.000000
L 2.00208297 5.46633337 2.00416663 5.4649998 2 P 0 ;0,1,2=80,3=90.000000
L 2.00416663 5.4649998 2.00583297 5.46313307 2 P 0 ;0,1,2=80,3=90.000000
L 2.00583297 5.46313307 2.00624951 5.46126683 2 P 0 ;0,1,2=80,3=90.000000
L 2.00624951 5.46126683 2.00583297 5.4594 2 P 0 ;0,1,2=80,3=90.000000
L 2.00583297 5.4594 2.00416663 5.4570001 2 P 0 ;0,1,2=80,3=90.000000
L 2.00416663 5.4570001 2.015 5.4577999 2 P 0 ;0,1,2=80,3=90.000000
L 2.015 5.4577999 2.015 5.4649998 2 P 0 ;0,1,2=80,3=90.000000
L 1.99374911 5.47913327 1.99166624 5.48073297 2 P 0 ;0,1,2=80,3=90.000000
L 1.99166624 5.48073297 1.99041654 5.4825997 2 P 0 ;0,1,2=80,3=90.000000
L 1.99041654 5.4825997 1.99 5.4849997 2 P 0 ;0,1,2=80,3=90.000000
L 1.99 5.4849997 1.99083307 5.4874002 2 P 0 ;0,1,2=80,3=90.000000
L 1.99083307 5.4874002 1.99249941 5.48926644 2 P 0 ;0,1,2=80,3=90.000000
L 1.99249941 5.48926644 1.99541624 5.4906 2 P 0 ;0,1,2=80,3=90.000000
L 1.99541624 5.4906 1.99874961 5.49086663 2 P 0 ;0,1,2=80,3=90.000000
L 1.99874961 5.49086663 2.00208297 5.49033337 2 P 0 ;0,1,2=80,3=90.000000
L 2.00208297 5.49033337 2.00416663 5.4889998 2 P 0 ;0,1,2=80,3=90.000000
L 2.00416663 5.4889998 2.00583297 5.48713307 2 P 0 ;0,1,2=80,3=90.000000
L 2.00583297 5.48713307 2.00624951 5.48526683 2 P 0 ;0,1,2=80,3=90.000000
L 2.00624951 5.48526683 2.00583297 5.4834 2 P 0 ;0,1,2=80,3=90.000000
L 2.00583297 5.4834 2.00416663 5.4810001 2 P 0 ;0,1,2=80,3=90.000000
L 2.00416663 5.4810001 2.015 5.4817999 2 P 0 ;0,1,2=80,3=90.000000
L 2.015 5.4817999 2.015 5.4889998 2 P 0 ;0,1,2=80,3=90.000000
L 1.99499961 5.50313327 1.99208287 5.50473297 2 P 0 ;0,1,2=80,3=90.000000
L 1.99208287 5.50473297 1.99041654 5.50686634 2 P 0 ;0,1,2=80,3=90.000000
L 1.99041654 5.50686634 1.99 5.50926683 2 P 0 ;0,1,2=80,3=90.000000
L 1.99 5.50926683 1.99041654 5.5114002 2 P 0 ;0,1,2=80,3=90.000000
L 1.99041654 5.5114002 1.99249941 5.51353356 2 P 0 ;0,1,2=80,3=90.000000
L 1.99249941 5.51353356 1.99499961 5.51486663 2 P 0 ;0,1,2=80,3=90.000000
L 1.99499961 5.51486663 1.9974999 5.51513317 2 P 0 ;0,1,2=80,3=90.000000
L 1.9974999 5.51513317 2.00041594 5.5146 2 P 0 ;0,1,2=80,3=90.000000
L 2.00041594 5.5146 2.00249961 5.51273327 2 P 0 ;0,1,2=80,3=90.000000
L 2.00249961 5.51273327 2.00333346 5.51086644 2 P 0 ;0,1,2=80,3=90.000000
L 2.00333346 5.51086644 2.00333346 5.50846654 2 P 0 ;0,1,2=80,3=90.000000
L 2.00333346 5.51086644 2.00458327 5.51246663 2 P 0 ;0,1,2=80,3=90.000000
L 2.00458327 5.51246663 2.00666614 5.5138001 2 P 0 ;0,1,2=80,3=90.000000
L 2.00666614 5.5138001 2.00916634 5.51433337 2 P 0 ;0,1,2=80,3=90.000000
L 2.00916634 5.51433337 2.01166654 5.5138001 2 P 0 ;0,1,2=80,3=90.000000
L 2.01166654 5.5138001 2.01374941 5.51246663 2 P 0 ;0,1,2=80,3=90.000000
L 2.01374941 5.51246663 2.015 5.51006663 2 P 0 ;0,1,2=80,3=90.000000
L 2.015 5.51006663 2.01458337 5.50766663 2 P 0 ;0,1,2=80,3=90.000000
L 2.01458337 5.50766663 2.01291634 5.50526663 2 P 0 ;0,1,2=80,3=90.000000
L 7.96286998 5.36 7.94713002 5.36 3 P 0 
L 7.94 5.40766654 7.965 5.40766654 2 P 0 ;0,1,2=81,3=90.000000
L 7.965 5.40766654 7.965 5.41433327 2 P 0 ;0,1,2=81,3=90.000000
L 7.965 5.41433327 7.96374941 5.41646663 2 P 0 ;0,1,2=81,3=90.000000
L 7.96374941 5.41646663 7.96208317 5.4178001 2 P 0 ;0,1,2=81,3=90.000000
L 7.96208317 5.4178001 7.9587498 5.41833337 2 P 0 ;0,1,2=81,3=90.000000
L 7.9587498 5.41833337 7.95541634 5.4178001 2 P 0 ;0,1,2=81,3=90.000000
L 7.95541634 5.4178001 7.95333346 5.4162 2 P 0 ;0,1,2=81,3=90.000000
L 7.95333346 5.4162 7.95208297 5.41433327 2 P 0 ;0,1,2=81,3=90.000000
L 7.95208297 5.41433327 7.95208297 5.40766654 2 P 0 ;0,1,2=81,3=90.000000
L 7.95208297 5.41433327 7.94 5.41833337 2 P 0 ;0,1,2=81,3=90.000000
L 7.94 5.4369997 7.965 5.4369997 2 P 0 ;0,1,2=81,3=90.000000
L 7.965 5.4369997 7.9600003 5.4337999 2 P 0 ;0,1,2=81,3=90.000000
L 7.94 5.4337999 7.94 5.44019951 2 P 0 ;0,1,2=81,3=90.000000
L 7.94374911 5.45513327 7.94166624 5.45673297 2 P 0 ;0,1,2=81,3=90.000000
L 7.94166624 5.45673297 7.94041654 5.4585997 2 P 0 ;0,1,2=81,3=90.000000
L 7.94041654 5.4585997 7.94 5.4609997 2 P 0 ;0,1,2=81,3=90.000000
L 7.94 5.4609997 7.94083307 5.4634002 2 P 0 ;0,1,2=81,3=90.000000
L 7.94083307 5.4634002 7.94249941 5.46526644 2 P 0 ;0,1,2=81,3=90.000000
L 7.94249941 5.46526644 7.94541624 5.4666 2 P 0 ;0,1,2=81,3=90.000000
L 7.94541624 5.4666 7.94874961 5.46686663 2 P 0 ;0,1,2=81,3=90.000000
L 7.94874961 5.46686663 7.95208297 5.46633337 2 P 0 ;0,1,2=81,3=90.000000
L 7.95208297 5.46633337 7.95416663 5.4649998 2 P 0 ;0,1,2=81,3=90.000000
L 7.95416663 5.4649998 7.95583297 5.46313307 2 P 0 ;0,1,2=81,3=90.000000
L 7.95583297 5.46313307 7.95624951 5.46126683 2 P 0 ;0,1,2=81,3=90.000000
L 7.95624951 5.46126683 7.95583297 5.4594 2 P 0 ;0,1,2=81,3=90.000000
L 7.95583297 5.4594 7.95416663 5.4570001 2 P 0 ;0,1,2=81,3=90.000000
L 7.95416663 5.4570001 7.965 5.4577999 2 P 0 ;0,1,2=81,3=90.000000
L 7.965 5.4577999 7.965 5.4649998 2 P 0 ;0,1,2=81,3=90.000000
L 7.94374911 5.47913327 7.94166624 5.48073297 2 P 0 ;0,1,2=81,3=90.000000
L 7.94166624 5.48073297 7.94041654 5.4825997 2 P 0 ;0,1,2=81,3=90.000000
L 7.94041654 5.4825997 7.94 5.4849997 2 P 0 ;0,1,2=81,3=90.000000
L 7.94 5.4849997 7.94083307 5.4874002 2 P 0 ;0,1,2=81,3=90.000000
L 7.94083307 5.4874002 7.94249941 5.48926644 2 P 0 ;0,1,2=81,3=90.000000
L 7.94249941 5.48926644 7.94541624 5.4906 2 P 0 ;0,1,2=81,3=90.000000
L 7.94541624 5.4906 7.94874961 5.49086663 2 P 0 ;0,1,2=81,3=90.000000
L 7.94874961 5.49086663 7.95208297 5.49033337 2 P 0 ;0,1,2=81,3=90.000000
L 7.95208297 5.49033337 7.95416663 5.4889998 2 P 0 ;0,1,2=81,3=90.000000
L 7.95416663 5.4889998 7.95583297 5.48713307 2 P 0 ;0,1,2=81,3=90.000000
L 7.95583297 5.48713307 7.95624951 5.48526683 2 P 0 ;0,1,2=81,3=90.000000
L 7.95624951 5.48526683 7.95583297 5.4834 2 P 0 ;0,1,2=81,3=90.000000
L 7.95583297 5.4834 7.95416663 5.4810001 2 P 0 ;0,1,2=81,3=90.000000
L 7.95416663 5.4810001 7.965 5.4817999 2 P 0 ;0,1,2=81,3=90.000000
L 7.965 5.4817999 7.965 5.4889998 2 P 0 ;0,1,2=81,3=90.000000
L 7.94 5.5089997 7.94041654 5.51086644 2 P 0 ;0,1,2=81,3=90.000000
L 7.94041654 5.51086644 7.94166624 5.5129998 2 P 0 ;0,1,2=81,3=90.000000
L 7.94166624 5.5129998 7.94374911 5.51433337 2 P 0 ;0,1,2=81,3=90.000000
L 7.94374911 5.51433337 7.94666673 5.51486663 2 P 0 ;0,1,2=81,3=90.000000
L 7.94666673 5.51486663 7.94958278 5.51433337 2 P 0 ;0,1,2=81,3=90.000000
L 7.94958278 5.51433337 7.95208297 5.51273327 2 P 0 ;0,1,2=81,3=90.000000
L 7.95208297 5.51273327 7.95333346 5.51033327 2 P 0 ;0,1,2=81,3=90.000000
L 7.95333346 5.51033327 7.95333346 5.50766663 2 P 0 ;0,1,2=81,3=90.000000
L 7.95333346 5.50766663 7.95416663 5.50606654 2 P 0 ;0,1,2=81,3=90.000000
L 7.95416663 5.50606654 7.95624951 5.50473297 2 P 0 ;0,1,2=81,3=90.000000
L 7.95624951 5.50473297 7.95916634 5.5041998 2 P 0 ;0,1,2=81,3=90.000000
L 7.95916634 5.5041998 7.96208317 5.5050001 2 P 0 ;0,1,2=81,3=90.000000
L 7.96208317 5.5050001 7.96416683 5.50686634 2 P 0 ;0,1,2=81,3=90.000000
L 7.96416683 5.50686634 7.965 5.5089997 2 P 0 ;0,1,2=81,3=90.000000
L 7.965 5.5089997 7.96416683 5.51113307 2 P 0 ;0,1,2=81,3=90.000000
L 7.96416683 5.51113307 7.96208317 5.5129998 2 P 0 ;0,1,2=81,3=90.000000
L 7.96208317 5.5129998 7.95916634 5.5138001 2 P 0 ;0,1,2=81,3=90.000000
L 7.95916634 5.5138001 7.95624951 5.51326644 2 P 0 ;0,1,2=81,3=90.000000
L 7.95624951 5.51326644 7.95416663 5.51193337 2 P 0 ;0,1,2=81,3=90.000000
L 7.95416663 5.51193337 7.95333346 5.51033327 2 P 0 ;0,1,2=81,3=90.000000
L 7.95333346 5.51033327 7.95333346 5.50766663 2 P 0 ;0,1,2=81,3=90.000000
L 7.95333346 5.50766663 7.95208297 5.50526663 2 P 0 ;0,1,2=81,3=90.000000
L 7.95208297 5.50526663 7.94958278 5.50366654 2 P 0 ;0,1,2=81,3=90.000000
L 7.94958278 5.50366654 7.94666673 5.50313327 2 P 0 ;0,1,2=81,3=90.000000
L 7.94666673 5.50313327 7.94374911 5.50366654 2 P 0 ;0,1,2=81,3=90.000000
L 7.94374911 5.50366654 7.94166624 5.5050001 2 P 0 ;0,1,2=81,3=90.000000
L 7.94166624 5.5050001 7.94041654 5.50713346 2 P 0 ;0,1,2=81,3=90.000000
L 7.94041654 5.50713346 7.94 5.5089997 2 P 0 ;0,1,2=81,3=90.000000
L 1.95933002 5.36 1.94358996 5.36 3 P 0 
L 1.94 5.40766654 1.965 5.40766654 2 P 0 ;0,1,2=82,3=90.000000
L 1.965 5.40766654 1.965 5.41433327 2 P 0 ;0,1,2=82,3=90.000000
L 1.965 5.41433327 1.96374941 5.41646663 2 P 0 ;0,1,2=82,3=90.000000
L 1.96374941 5.41646663 1.96208317 5.4178001 2 P 0 ;0,1,2=82,3=90.000000
L 1.96208317 5.4178001 1.9587498 5.41833337 2 P 0 ;0,1,2=82,3=90.000000
L 1.9587498 5.41833337 1.95541634 5.4178001 2 P 0 ;0,1,2=82,3=90.000000
L 1.95541634 5.4178001 1.95333346 5.4162 2 P 0 ;0,1,2=82,3=90.000000
L 1.95333346 5.4162 1.95208297 5.41433327 2 P 0 ;0,1,2=82,3=90.000000
L 1.95208297 5.41433327 1.95208297 5.40766654 2 P 0 ;0,1,2=82,3=90.000000
L 1.95208297 5.41433327 1.94 5.41833337 2 P 0 ;0,1,2=82,3=90.000000
L 1.94 5.4369997 1.965 5.4369997 2 P 0 ;0,1,2=82,3=90.000000
L 1.965 5.4369997 1.9600003 5.4337999 2 P 0 ;0,1,2=82,3=90.000000
L 1.94 5.4337999 1.94 5.44019951 2 P 0 ;0,1,2=82,3=90.000000
L 1.94374911 5.45513327 1.94166624 5.45673297 2 P 0 ;0,1,2=82,3=90.000000
L 1.94166624 5.45673297 1.94041654 5.4585997 2 P 0 ;0,1,2=82,3=90.000000
L 1.94041654 5.4585997 1.94 5.4609997 2 P 0 ;0,1,2=82,3=90.000000
L 1.94 5.4609997 1.94083307 5.4634002 2 P 0 ;0,1,2=82,3=90.000000
L 1.94083307 5.4634002 1.94249941 5.46526644 2 P 0 ;0,1,2=82,3=90.000000
L 1.94249941 5.46526644 1.94541624 5.4666 2 P 0 ;0,1,2=82,3=90.000000
L 1.94541624 5.4666 1.94874961 5.46686663 2 P 0 ;0,1,2=82,3=90.000000
L 1.94874961 5.46686663 1.95208297 5.46633337 2 P 0 ;0,1,2=82,3=90.000000
L 1.95208297 5.46633337 1.95416663 5.4649998 2 P 0 ;0,1,2=82,3=90.000000
L 1.95416663 5.4649998 1.95583297 5.46313307 2 P 0 ;0,1,2=82,3=90.000000
L 1.95583297 5.46313307 1.95624951 5.46126683 2 P 0 ;0,1,2=82,3=90.000000
L 1.95624951 5.46126683 1.95583297 5.4594 2 P 0 ;0,1,2=82,3=90.000000
L 1.95583297 5.4594 1.95416663 5.4570001 2 P 0 ;0,1,2=82,3=90.000000
L 1.95416663 5.4570001 1.965 5.4577999 2 P 0 ;0,1,2=82,3=90.000000
L 1.965 5.4577999 1.965 5.4649998 2 P 0 ;0,1,2=82,3=90.000000
L 1.94374911 5.47913327 1.94166624 5.48073297 2 P 0 ;0,1,2=82,3=90.000000
L 1.94166624 5.48073297 1.94041654 5.4825997 2 P 0 ;0,1,2=82,3=90.000000
L 1.94041654 5.4825997 1.94 5.4849997 2 P 0 ;0,1,2=82,3=90.000000
L 1.94 5.4849997 1.94083307 5.4874002 2 P 0 ;0,1,2=82,3=90.000000
L 1.94083307 5.4874002 1.94249941 5.48926644 2 P 0 ;0,1,2=82,3=90.000000
L 1.94249941 5.48926644 1.94541624 5.4906 2 P 0 ;0,1,2=82,3=90.000000
L 1.94541624 5.4906 1.94874961 5.49086663 2 P 0 ;0,1,2=82,3=90.000000
L 1.94874961 5.49086663 1.95208297 5.49033337 2 P 0 ;0,1,2=82,3=90.000000
L 1.95208297 5.49033337 1.95416663 5.4889998 2 P 0 ;0,1,2=82,3=90.000000
L 1.95416663 5.4889998 1.95583297 5.48713307 2 P 0 ;0,1,2=82,3=90.000000
L 1.95583297 5.48713307 1.95624951 5.48526683 2 P 0 ;0,1,2=82,3=90.000000
L 1.95624951 5.48526683 1.95583297 5.4834 2 P 0 ;0,1,2=82,3=90.000000
L 1.95583297 5.4834 1.95416663 5.4810001 2 P 0 ;0,1,2=82,3=90.000000
L 1.95416663 5.4810001 1.965 5.4817999 2 P 0 ;0,1,2=82,3=90.000000
L 1.965 5.4817999 1.965 5.4889998 2 P 0 ;0,1,2=82,3=90.000000
L 1.94 5.5122 1.965 5.5122 2 P 0 ;0,1,2=82,3=90.000000
L 1.965 5.5122 1.94708327 5.50233297 2 P 0 ;0,1,2=82,3=90.000000
L 1.94708327 5.50233297 1.94708327 5.51566693 2 P 0 ;0,1,2=82,3=90.000000
L 3.10433002 5.315 3.08858996 5.315 3 P 0 
L 3.09 5.36266654 3.115 5.36266654 2 P 0 ;0,1,2=83,3=90.000000
L 3.115 5.36266654 3.115 5.36933327 2 P 0 ;0,1,2=83,3=90.000000
L 3.115 5.36933327 3.11374941 5.37146663 2 P 0 ;0,1,2=83,3=90.000000
L 3.11374941 5.37146663 3.11208317 5.3728001 2 P 0 ;0,1,2=83,3=90.000000
L 3.11208317 5.3728001 3.1087498 5.37333337 2 P 0 ;0,1,2=83,3=90.000000
L 3.1087498 5.37333337 3.10541634 5.3728001 2 P 0 ;0,1,2=83,3=90.000000
L 3.10541634 5.3728001 3.10333346 5.3712 2 P 0 ;0,1,2=83,3=90.000000
L 3.10333346 5.3712 3.10208297 5.36933327 2 P 0 ;0,1,2=83,3=90.000000
L 3.10208297 5.36933327 3.10208297 5.36266654 2 P 0 ;0,1,2=83,3=90.000000
L 3.10208297 5.36933327 3.09 5.37333337 2 P 0 ;0,1,2=83,3=90.000000
L 3.09 5.3919997 3.115 5.3919997 2 P 0 ;0,1,2=83,3=90.000000
L 3.115 5.3919997 3.1100003 5.3887999 2 P 0 ;0,1,2=83,3=90.000000
L 3.09 5.3887999 3.09 5.39519951 2 P 0 ;0,1,2=83,3=90.000000
L 3.09374911 5.41013327 3.09166624 5.41173297 2 P 0 ;0,1,2=83,3=90.000000
L 3.09166624 5.41173297 3.09041654 5.4135997 2 P 0 ;0,1,2=83,3=90.000000
L 3.09041654 5.4135997 3.09 5.4159997 2 P 0 ;0,1,2=83,3=90.000000
L 3.09 5.4159997 3.09083307 5.4184002 2 P 0 ;0,1,2=83,3=90.000000
L 3.09083307 5.4184002 3.09249941 5.42026644 2 P 0 ;0,1,2=83,3=90.000000
L 3.09249941 5.42026644 3.09541624 5.4216 2 P 0 ;0,1,2=83,3=90.000000
L 3.09541624 5.4216 3.09874961 5.42186663 2 P 0 ;0,1,2=83,3=90.000000
L 3.09874961 5.42186663 3.10208297 5.42133337 2 P 0 ;0,1,2=83,3=90.000000
L 3.10208297 5.42133337 3.10416663 5.4199998 2 P 0 ;0,1,2=83,3=90.000000
L 3.10416663 5.4199998 3.10583297 5.41813307 2 P 0 ;0,1,2=83,3=90.000000
L 3.10583297 5.41813307 3.10624951 5.41626683 2 P 0 ;0,1,2=83,3=90.000000
L 3.10624951 5.41626683 3.10583297 5.4144 2 P 0 ;0,1,2=83,3=90.000000
L 3.10583297 5.4144 3.10416663 5.4120001 2 P 0 ;0,1,2=83,3=90.000000
L 3.10416663 5.4120001 3.115 5.4127999 2 P 0 ;0,1,2=83,3=90.000000
L 3.115 5.4127999 3.115 5.4199998 2 P 0 ;0,1,2=83,3=90.000000
L 3.09 5.4432 3.115 5.4432 2 P 0 ;0,1,2=83,3=90.000000
L 3.115 5.4432 3.09708327 5.43333297 2 P 0 ;0,1,2=83,3=90.000000
L 3.09708327 5.43333297 3.09708327 5.44666693 2 P 0 ;0,1,2=83,3=90.000000
L 3.09374911 5.45813327 3.09166624 5.45973297 2 P 0 ;0,1,2=83,3=90.000000
L 3.09166624 5.45973297 3.09041654 5.4615997 2 P 0 ;0,1,2=83,3=90.000000
L 3.09041654 5.4615997 3.09 5.4639997 2 P 0 ;0,1,2=83,3=90.000000
L 3.09 5.4639997 3.09083307 5.4664002 2 P 0 ;0,1,2=83,3=90.000000
L 3.09083307 5.4664002 3.09249941 5.46826644 2 P 0 ;0,1,2=83,3=90.000000
L 3.09249941 5.46826644 3.09541624 5.4696 2 P 0 ;0,1,2=83,3=90.000000
L 3.09541624 5.4696 3.09874961 5.46986663 2 P 0 ;0,1,2=83,3=90.000000
L 3.09874961 5.46986663 3.10208297 5.46933337 2 P 0 ;0,1,2=83,3=90.000000
L 3.10208297 5.46933337 3.10416663 5.4679998 2 P 0 ;0,1,2=83,3=90.000000
L 3.10416663 5.4679998 3.10583297 5.46613307 2 P 0 ;0,1,2=83,3=90.000000
L 3.10583297 5.46613307 3.10624951 5.46426683 2 P 0 ;0,1,2=83,3=90.000000
L 3.10624951 5.46426683 3.10583297 5.4624 2 P 0 ;0,1,2=83,3=90.000000
L 3.10583297 5.4624 3.10416663 5.4600001 2 P 0 ;0,1,2=83,3=90.000000
L 3.10416663 5.4600001 3.115 5.4607999 2 P 0 ;0,1,2=83,3=90.000000
L 3.115 5.4607999 3.115 5.4679998 2 P 0 ;0,1,2=83,3=90.000000
L 2.65385 2.86213002 2.65385 2.87786998 3 P 0 
L 2.70733346 2.895 2.70733346 2.92 2 P 0 ;0,1,2=84,3=0.000000
L 2.70733346 2.92 2.70066673 2.92 2 P 0 ;0,1,2=84,3=0.000000
L 2.70066673 2.92 2.69853337 2.91874941 2 P 0 ;0,1,2=84,3=0.000000
L 2.69853337 2.91874941 2.6971999 2.91708317 2 P 0 ;0,1,2=84,3=0.000000
L 2.6971999 2.91708317 2.69666663 2.9137498 2 P 0 ;0,1,2=84,3=0.000000
L 2.69666663 2.9137498 2.6971999 2.91041634 2 P 0 ;0,1,2=84,3=0.000000
L 2.6971999 2.91041634 2.6988 2.90833346 2 P 0 ;0,1,2=84,3=0.000000
L 2.6988 2.90833346 2.70066673 2.90708297 2 P 0 ;0,1,2=84,3=0.000000
L 2.70066673 2.90708297 2.70733346 2.90708297 2 P 0 ;0,1,2=84,3=0.000000
L 2.70066673 2.90708297 2.69666663 2.895 2 P 0 ;0,1,2=84,3=0.000000
L 2.6780003 2.895 2.6780003 2.92 2 P 0 ;0,1,2=84,3=0.000000
L 2.6780003 2.92 2.6812001 2.9150003 2 P 0 ;0,1,2=84,3=0.000000
L 2.6812001 2.895 2.67480049 2.895 2 P 0 ;0,1,2=84,3=0.000000
L 2.65986673 2.89874911 2.65826703 2.89666624 2 P 0 ;0,1,2=84,3=0.000000
L 2.65826703 2.89666624 2.6564003 2.89541654 2 P 0 ;0,1,2=84,3=0.000000
L 2.6564003 2.89541654 2.6540003 2.895 2 P 0 ;0,1,2=84,3=0.000000
L 2.6540003 2.895 2.6515998 2.89583307 2 P 0 ;0,1,2=84,3=0.000000
L 2.6515998 2.89583307 2.64973356 2.89749941 2 P 0 ;0,1,2=84,3=0.000000
L 2.64973356 2.89749941 2.6484 2.90041624 2 P 0 ;0,1,2=84,3=0.000000
L 2.6484 2.90041624 2.64813337 2.90374961 2 P 0 ;0,1,2=84,3=0.000000
L 2.64813337 2.90374961 2.64866663 2.90708297 2 P 0 ;0,1,2=84,3=0.000000
L 2.64866663 2.90708297 2.6500002 2.90916663 2 P 0 ;0,1,2=84,3=0.000000
L 2.6500002 2.90916663 2.65186693 2.91083297 2 P 0 ;0,1,2=84,3=0.000000
L 2.65186693 2.91083297 2.65373317 2.91124951 2 P 0 ;0,1,2=84,3=0.000000
L 2.65373317 2.91124951 2.6556 2.91083297 2 P 0 ;0,1,2=84,3=0.000000
L 2.6556 2.91083297 2.6579999 2.90916663 2 P 0 ;0,1,2=84,3=0.000000
L 2.6579999 2.90916663 2.6572001 2.92 2 P 0 ;0,1,2=84,3=0.000000
L 2.6572001 2.92 2.6500002 2.92 2 P 0 ;0,1,2=84,3=0.000000
L 2.63586673 2.89999961 2.63426703 2.89708287 2 P 0 ;0,1,2=84,3=0.000000
L 2.63426703 2.89708287 2.63213366 2.89541654 2 P 0 ;0,1,2=84,3=0.000000
L 2.63213366 2.89541654 2.62973317 2.895 2 P 0 ;0,1,2=84,3=0.000000
L 2.62973317 2.895 2.6275998 2.89541654 2 P 0 ;0,1,2=84,3=0.000000
L 2.6275998 2.89541654 2.62546644 2.89749941 2 P 0 ;0,1,2=84,3=0.000000
L 2.62546644 2.89749941 2.62413337 2.89999961 2 P 0 ;0,1,2=84,3=0.000000
L 2.62413337 2.89999961 2.62386683 2.9024999 2 P 0 ;0,1,2=84,3=0.000000
L 2.62386683 2.9024999 2.6244 2.90541594 2 P 0 ;0,1,2=84,3=0.000000
L 2.6244 2.90541594 2.62626673 2.90749961 2 P 0 ;0,1,2=84,3=0.000000
L 2.62626673 2.90749961 2.62813356 2.90833346 2 P 0 ;0,1,2=84,3=0.000000
L 2.62813356 2.90833346 2.63053346 2.90833346 2 P 0 ;0,1,2=84,3=0.000000
L 2.62813356 2.90833346 2.62653337 2.90958327 2 P 0 ;0,1,2=84,3=0.000000
L 2.62653337 2.90958327 2.6251999 2.91166614 2 P 0 ;0,1,2=84,3=0.000000
L 2.6251999 2.91166614 2.62466663 2.91416634 2 P 0 ;0,1,2=84,3=0.000000
L 2.62466663 2.91416634 2.6251999 2.91666654 2 P 0 ;0,1,2=84,3=0.000000
L 2.6251999 2.91666654 2.62653337 2.91874941 2 P 0 ;0,1,2=84,3=0.000000
L 2.62653337 2.91874941 2.62893337 2.92 2 P 0 ;0,1,2=84,3=0.000000
L 2.62893337 2.92 2.63133337 2.91958337 2 P 0 ;0,1,2=84,3=0.000000
L 2.63133337 2.91958337 2.63373337 2.91791634 2 P 0 ;0,1,2=84,3=0.000000
L 2.61106683 2.90541594 2.6092001 2.90833346 2 P 0 ;0,1,2=84,3=0.000000
L 2.6092001 2.90833346 2.6076 2.9099998 2 P 0 ;0,1,2=84,3=0.000000
L 2.6076 2.9099998 2.60546663 2.91083297 2 P 0 ;0,1,2=84,3=0.000000
L 2.60546663 2.91083297 2.6035998 2.9099998 2 P 0 ;0,1,2=84,3=0.000000
L 2.6035998 2.9099998 2.60226673 2.90833346 2 P 0 ;0,1,2=84,3=0.000000
L 2.60226673 2.90833346 2.6011999 2.90583327 2 P 0 ;0,1,2=84,3=0.000000
L 2.6011999 2.90583327 2.60093327 2.90291644 2 P 0 ;0,1,2=84,3=0.000000
L 2.60093327 2.90291644 2.6011999 2.90041624 2 P 0 ;0,1,2=84,3=0.000000
L 2.6011999 2.90041624 2.60226673 2.89791604 2 P 0 ;0,1,2=84,3=0.000000
L 2.60226673 2.89791604 2.60386693 2.89583307 2 P 0 ;0,1,2=84,3=0.000000
L 2.60386693 2.89583307 2.60573317 2.895 2 P 0 ;0,1,2=84,3=0.000000
L 2.60573317 2.895 2.60786654 2.89583307 2 P 0 ;0,1,2=84,3=0.000000
L 2.60786654 2.89583307 2.60973337 2.89833258 2 P 0 ;0,1,2=84,3=0.000000
L 2.60973337 2.89833258 2.6108002 2.90208327 2 P 0 ;0,1,2=84,3=0.000000
L 2.6108002 2.90208327 2.61106683 2.9062498 2 P 0 ;0,1,2=84,3=0.000000
L 2.61106683 2.9062498 2.61053366 2.91166614 2 P 0 ;0,1,2=84,3=0.000000
L 2.61053366 2.91166614 2.60973337 2.91458366 2 P 0 ;0,1,2=84,3=0.000000
L 2.60973337 2.91458366 2.6084003 2.9174997 2 P 0 ;0,1,2=84,3=0.000000
L 2.6084003 2.9174997 2.60653346 2.91958337 2 P 0 ;0,1,2=84,3=0.000000
L 2.60653346 2.91958337 2.60466673 2.92 2 P 0 ;0,1,2=84,3=0.000000
L 2.60466673 2.92 2.6028 2.91916683 2 P 0 ;0,1,2=84,3=0.000000
L 2.6028 2.91916683 2.60146644 2.91708317 2 P 0 ;0,1,2=84,3=0.000000
L 2.65385 2.81213002 2.65385 2.82786998 3 P 0 
L 2.70733346 2.77 2.70733346 2.795 2 P 0 ;0,1,2=85,3=0.000000
L 2.70733346 2.795 2.70066673 2.795 2 P 0 ;0,1,2=85,3=0.000000
L 2.70066673 2.795 2.69853337 2.79374941 2 P 0 ;0,1,2=85,3=0.000000
L 2.69853337 2.79374941 2.6971999 2.79208317 2 P 0 ;0,1,2=85,3=0.000000
L 2.6971999 2.79208317 2.69666663 2.7887498 2 P 0 ;0,1,2=85,3=0.000000
L 2.69666663 2.7887498 2.6971999 2.78541634 2 P 0 ;0,1,2=85,3=0.000000
L 2.6971999 2.78541634 2.6988 2.78333346 2 P 0 ;0,1,2=85,3=0.000000
L 2.6988 2.78333346 2.70066673 2.78208297 2 P 0 ;0,1,2=85,3=0.000000
L 2.70066673 2.78208297 2.70733346 2.78208297 2 P 0 ;0,1,2=85,3=0.000000
L 2.70066673 2.78208297 2.69666663 2.77 2 P 0 ;0,1,2=85,3=0.000000
L 2.6780003 2.77 2.6780003 2.795 2 P 0 ;0,1,2=85,3=0.000000
L 2.6780003 2.795 2.6812001 2.7900003 2 P 0 ;0,1,2=85,3=0.000000
L 2.6812001 2.77 2.67480049 2.77 2 P 0 ;0,1,2=85,3=0.000000
L 2.65986673 2.77374911 2.65826703 2.77166624 2 P 0 ;0,1,2=85,3=0.000000
L 2.65826703 2.77166624 2.6564003 2.77041654 2 P 0 ;0,1,2=85,3=0.000000
L 2.6564003 2.77041654 2.6540003 2.77 2 P 0 ;0,1,2=85,3=0.000000
L 2.6540003 2.77 2.6515998 2.77083307 2 P 0 ;0,1,2=85,3=0.000000
L 2.6515998 2.77083307 2.64973356 2.77249941 2 P 0 ;0,1,2=85,3=0.000000
L 2.64973356 2.77249941 2.6484 2.77541624 2 P 0 ;0,1,2=85,3=0.000000
L 2.6484 2.77541624 2.64813337 2.77874961 2 P 0 ;0,1,2=85,3=0.000000
L 2.64813337 2.77874961 2.64866663 2.78208297 2 P 0 ;0,1,2=85,3=0.000000
L 2.64866663 2.78208297 2.6500002 2.78416663 2 P 0 ;0,1,2=85,3=0.000000
L 2.6500002 2.78416663 2.65186693 2.78583297 2 P 0 ;0,1,2=85,3=0.000000
L 2.65186693 2.78583297 2.65373317 2.78624951 2 P 0 ;0,1,2=85,3=0.000000
L 2.65373317 2.78624951 2.6556 2.78583297 2 P 0 ;0,1,2=85,3=0.000000
L 2.6556 2.78583297 2.6579999 2.78416663 2 P 0 ;0,1,2=85,3=0.000000
L 2.6579999 2.78416663 2.6572001 2.795 2 P 0 ;0,1,2=85,3=0.000000
L 2.6572001 2.795 2.6500002 2.795 2 P 0 ;0,1,2=85,3=0.000000
L 2.63586673 2.77499961 2.63426703 2.77208287 2 P 0 ;0,1,2=85,3=0.000000
L 2.63426703 2.77208287 2.63213366 2.77041654 2 P 0 ;0,1,2=85,3=0.000000
L 2.63213366 2.77041654 2.62973317 2.77 2 P 0 ;0,1,2=85,3=0.000000
L 2.62973317 2.77 2.6275998 2.77041654 2 P 0 ;0,1,2=85,3=0.000000
L 2.6275998 2.77041654 2.62546644 2.77249941 2 P 0 ;0,1,2=85,3=0.000000
L 2.62546644 2.77249941 2.62413337 2.77499961 2 P 0 ;0,1,2=85,3=0.000000
L 2.62413337 2.77499961 2.62386683 2.7774999 2 P 0 ;0,1,2=85,3=0.000000
L 2.62386683 2.7774999 2.6244 2.78041594 2 P 0 ;0,1,2=85,3=0.000000
L 2.6244 2.78041594 2.62626673 2.78249961 2 P 0 ;0,1,2=85,3=0.000000
L 2.62626673 2.78249961 2.62813356 2.78333346 2 P 0 ;0,1,2=85,3=0.000000
L 2.62813356 2.78333346 2.63053346 2.78333346 2 P 0 ;0,1,2=85,3=0.000000
L 2.62813356 2.78333346 2.62653337 2.78458327 2 P 0 ;0,1,2=85,3=0.000000
L 2.62653337 2.78458327 2.6251999 2.78666614 2 P 0 ;0,1,2=85,3=0.000000
L 2.6251999 2.78666614 2.62466663 2.78916634 2 P 0 ;0,1,2=85,3=0.000000
L 2.62466663 2.78916634 2.6251999 2.79166654 2 P 0 ;0,1,2=85,3=0.000000
L 2.6251999 2.79166654 2.62653337 2.79374941 2 P 0 ;0,1,2=85,3=0.000000
L 2.62653337 2.79374941 2.62893337 2.795 2 P 0 ;0,1,2=85,3=0.000000
L 2.62893337 2.795 2.63133337 2.79458337 2 P 0 ;0,1,2=85,3=0.000000
L 2.63133337 2.79458337 2.63373337 2.79291634 2 P 0 ;0,1,2=85,3=0.000000
L 2.61186673 2.77374911 2.61026703 2.77166624 2 P 0 ;0,1,2=85,3=0.000000
L 2.61026703 2.77166624 2.6084003 2.77041654 2 P 0 ;0,1,2=85,3=0.000000
L 2.6084003 2.77041654 2.6060003 2.77 2 P 0 ;0,1,2=85,3=0.000000
L 2.6060003 2.77 2.6035998 2.77083307 2 P 0 ;0,1,2=85,3=0.000000
L 2.6035998 2.77083307 2.60173356 2.77249941 2 P 0 ;0,1,2=85,3=0.000000
L 2.60173356 2.77249941 2.6004 2.77541624 2 P 0 ;0,1,2=85,3=0.000000
L 2.6004 2.77541624 2.60013337 2.77874961 2 P 0 ;0,1,2=85,3=0.000000
L 2.60013337 2.77874961 2.60066663 2.78208297 2 P 0 ;0,1,2=85,3=0.000000
L 2.60066663 2.78208297 2.6020002 2.78416663 2 P 0 ;0,1,2=85,3=0.000000
L 2.6020002 2.78416663 2.60386693 2.78583297 2 P 0 ;0,1,2=85,3=0.000000
L 2.60386693 2.78583297 2.60573317 2.78624951 2 P 0 ;0,1,2=85,3=0.000000
L 2.60573317 2.78624951 2.6076 2.78583297 2 P 0 ;0,1,2=85,3=0.000000
L 2.6076 2.78583297 2.6099999 2.78416663 2 P 0 ;0,1,2=85,3=0.000000
L 2.6099999 2.78416663 2.6092001 2.795 2 P 0 ;0,1,2=85,3=0.000000
L 2.6092001 2.795 2.6020002 2.795 2 P 0 ;0,1,2=85,3=0.000000
L 12.32201004 1.99746004 12.32201004 1.98171998 3 P 0 
L 12.37733346 2.015 12.37733346 2.04 2 P 0 ;0,1,2=86,3=0.000000
L 12.37733346 2.04 12.37066673 2.04 2 P 0 ;0,1,2=86,3=0.000000
L 12.37066673 2.04 12.36853337 2.03874941 2 P 0 ;0,1,2=86,3=0.000000
L 12.36853337 2.03874941 12.3671999 2.03708317 2 P 0 ;0,1,2=86,3=0.000000
L 12.3671999 2.03708317 12.36666663 2.0337498 2 P 0 ;0,1,2=86,3=0.000000
L 12.36666663 2.0337498 12.3671999 2.03041634 2 P 0 ;0,1,2=86,3=0.000000
L 12.3671999 2.03041634 12.3688 2.02833346 2 P 0 ;0,1,2=86,3=0.000000
L 12.3688 2.02833346 12.37066673 2.02708297 2 P 0 ;0,1,2=86,3=0.000000
L 12.37066673 2.02708297 12.37733346 2.02708297 2 P 0 ;0,1,2=86,3=0.000000
L 12.37066673 2.02708297 12.36666663 2.015 2 P 0 ;0,1,2=86,3=0.000000
L 12.3480003 2.015 12.3480003 2.04 2 P 0 ;0,1,2=86,3=0.000000
L 12.3480003 2.04 12.3512001 2.0350003 2 P 0 ;0,1,2=86,3=0.000000
L 12.3512001 2.015 12.34480049 2.015 2 P 0 ;0,1,2=86,3=0.000000
L 12.32986673 2.01874911 12.32826703 2.01666624 2 P 0 ;0,1,2=86,3=0.000000
L 12.32826703 2.01666624 12.3264003 2.01541654 2 P 0 ;0,1,2=86,3=0.000000
L 12.3264003 2.01541654 12.3240003 2.015 2 P 0 ;0,1,2=86,3=0.000000
L 12.3240003 2.015 12.3215998 2.01583307 2 P 0 ;0,1,2=86,3=0.000000
L 12.3215998 2.01583307 12.31973356 2.01749941 2 P 0 ;0,1,2=86,3=0.000000
L 12.31973356 2.01749941 12.3184 2.02041624 2 P 0 ;0,1,2=86,3=0.000000
L 12.3184 2.02041624 12.31813337 2.02374961 2 P 0 ;0,1,2=86,3=0.000000
L 12.31813337 2.02374961 12.31866663 2.02708297 2 P 0 ;0,1,2=86,3=0.000000
L 12.31866663 2.02708297 12.3200002 2.02916663 2 P 0 ;0,1,2=86,3=0.000000
L 12.3200002 2.02916663 12.32186693 2.03083297 2 P 0 ;0,1,2=86,3=0.000000
L 12.32186693 2.03083297 12.32373317 2.03124951 2 P 0 ;0,1,2=86,3=0.000000
L 12.32373317 2.03124951 12.3256 2.03083297 2 P 0 ;0,1,2=86,3=0.000000
L 12.3256 2.03083297 12.3279999 2.02916663 2 P 0 ;0,1,2=86,3=0.000000
L 12.3279999 2.02916663 12.3272001 2.04 2 P 0 ;0,1,2=86,3=0.000000
L 12.3272001 2.04 12.3200002 2.04 2 P 0 ;0,1,2=86,3=0.000000
L 12.30586673 2.01999961 12.30426703 2.01708287 2 P 0 ;0,1,2=86,3=0.000000
L 12.30426703 2.01708287 12.30213366 2.01541654 2 P 0 ;0,1,2=86,3=0.000000
L 12.30213366 2.01541654 12.29973317 2.015 2 P 0 ;0,1,2=86,3=0.000000
L 12.29973317 2.015 12.2975998 2.01541654 2 P 0 ;0,1,2=86,3=0.000000
L 12.2975998 2.01541654 12.29546644 2.01749941 2 P 0 ;0,1,2=86,3=0.000000
L 12.29546644 2.01749941 12.29413337 2.01999961 2 P 0 ;0,1,2=86,3=0.000000
L 12.29413337 2.01999961 12.29386683 2.0224999 2 P 0 ;0,1,2=86,3=0.000000
L 12.29386683 2.0224999 12.2944 2.02541594 2 P 0 ;0,1,2=86,3=0.000000
L 12.2944 2.02541594 12.29626673 2.02749961 2 P 0 ;0,1,2=86,3=0.000000
L 12.29626673 2.02749961 12.29813356 2.02833346 2 P 0 ;0,1,2=86,3=0.000000
L 12.29813356 2.02833346 12.30053346 2.02833346 2 P 0 ;0,1,2=86,3=0.000000
L 12.29813356 2.02833346 12.29653337 2.02958327 2 P 0 ;0,1,2=86,3=0.000000
L 12.29653337 2.02958327 12.2951999 2.03166614 2 P 0 ;0,1,2=86,3=0.000000
L 12.2951999 2.03166614 12.29466663 2.03416634 2 P 0 ;0,1,2=86,3=0.000000
L 12.29466663 2.03416634 12.2951999 2.03666654 2 P 0 ;0,1,2=86,3=0.000000
L 12.2951999 2.03666654 12.29653337 2.03874941 2 P 0 ;0,1,2=86,3=0.000000
L 12.29653337 2.03874941 12.29893337 2.04 2 P 0 ;0,1,2=86,3=0.000000
L 12.29893337 2.04 12.30133337 2.03958337 2 P 0 ;0,1,2=86,3=0.000000
L 12.30133337 2.03958337 12.30373337 2.03791634 2 P 0 ;0,1,2=86,3=0.000000
L 12.28106683 2.03583337 12.27946673 2.03833287 2 P 0 ;0,1,2=86,3=0.000000
L 12.27946673 2.03833287 12.2776 2.03958337 2 P 0 ;0,1,2=86,3=0.000000
L 12.2776 2.03958337 12.27546663 2.04 2 P 0 ;0,1,2=86,3=0.000000
L 12.27546663 2.04 12.2728 2.03916683 2 P 0 ;0,1,2=86,3=0.000000
L 12.2728 2.03916683 12.27093327 2.03708317 2 P 0 ;0,1,2=86,3=0.000000
L 12.27093327 2.03708317 12.2704 2.03458366 2 P 0 ;0,1,2=86,3=0.000000
L 12.2704 2.03458366 12.27066663 2.03208268 2 P 0 ;0,1,2=86,3=0.000000
L 12.27066663 2.03208268 12.27173356 2.0299998 2 P 0 ;0,1,2=86,3=0.000000
L 12.27173356 2.0299998 12.27706673 2.02583327 2 P 0 ;0,1,2=86,3=0.000000
L 12.27706673 2.02583327 12.27946673 2.02291644 2 P 0 ;0,1,2=86,3=0.000000
L 12.27946673 2.02291644 12.28106683 2.01874911 2 P 0 ;0,1,2=86,3=0.000000
L 12.28106683 2.01874911 12.2816001 2.015 2 P 0 ;0,1,2=86,3=0.000000
L 12.2816001 2.015 12.2704 2.015 2 P 0 ;0,1,2=86,3=0.000000
L 12.32201004 1.94746004 12.32201004 1.93171998 3 P 0 
L 12.37733346 1.885 12.37733346 1.91 2 P 0 ;0,1,2=87,3=0.000000
L 12.37733346 1.91 12.37066673 1.91 2 P 0 ;0,1,2=87,3=0.000000
L 12.37066673 1.91 12.36853337 1.90874941 2 P 0 ;0,1,2=87,3=0.000000
L 12.36853337 1.90874941 12.3671999 1.90708317 2 P 0 ;0,1,2=87,3=0.000000
L 12.3671999 1.90708317 12.36666663 1.9037498 2 P 0 ;0,1,2=87,3=0.000000
L 12.36666663 1.9037498 12.3671999 1.90041634 2 P 0 ;0,1,2=87,3=0.000000
L 12.3671999 1.90041634 12.3688 1.89833346 2 P 0 ;0,1,2=87,3=0.000000
L 12.3688 1.89833346 12.37066673 1.89708297 2 P 0 ;0,1,2=87,3=0.000000
L 12.37066673 1.89708297 12.37733346 1.89708297 2 P 0 ;0,1,2=87,3=0.000000
L 12.37066673 1.89708297 12.36666663 1.885 2 P 0 ;0,1,2=87,3=0.000000
L 12.3480003 1.885 12.3480003 1.91 2 P 0 ;0,1,2=87,3=0.000000
L 12.3480003 1.91 12.3512001 1.9050003 2 P 0 ;0,1,2=87,3=0.000000
L 12.3512001 1.885 12.34480049 1.885 2 P 0 ;0,1,2=87,3=0.000000
L 12.32986673 1.88874911 12.32826703 1.88666624 2 P 0 ;0,1,2=87,3=0.000000
L 12.32826703 1.88666624 12.3264003 1.88541654 2 P 0 ;0,1,2=87,3=0.000000
L 12.3264003 1.88541654 12.3240003 1.885 2 P 0 ;0,1,2=87,3=0.000000
L 12.3240003 1.885 12.3215998 1.88583307 2 P 0 ;0,1,2=87,3=0.000000
L 12.3215998 1.88583307 12.31973356 1.88749941 2 P 0 ;0,1,2=87,3=0.000000
L 12.31973356 1.88749941 12.3184 1.89041624 2 P 0 ;0,1,2=87,3=0.000000
L 12.3184 1.89041624 12.31813337 1.89374961 2 P 0 ;0,1,2=87,3=0.000000
L 12.31813337 1.89374961 12.31866663 1.89708297 2 P 0 ;0,1,2=87,3=0.000000
L 12.31866663 1.89708297 12.3200002 1.89916663 2 P 0 ;0,1,2=87,3=0.000000
L 12.3200002 1.89916663 12.32186693 1.90083297 2 P 0 ;0,1,2=87,3=0.000000
L 12.32186693 1.90083297 12.32373317 1.90124951 2 P 0 ;0,1,2=87,3=0.000000
L 12.32373317 1.90124951 12.3256 1.90083297 2 P 0 ;0,1,2=87,3=0.000000
L 12.3256 1.90083297 12.3279999 1.89916663 2 P 0 ;0,1,2=87,3=0.000000
L 12.3279999 1.89916663 12.3272001 1.91 2 P 0 ;0,1,2=87,3=0.000000
L 12.3272001 1.91 12.3200002 1.91 2 P 0 ;0,1,2=87,3=0.000000
L 12.30586673 1.88999961 12.30426703 1.88708287 2 P 0 ;0,1,2=87,3=0.000000
L 12.30426703 1.88708287 12.30213366 1.88541654 2 P 0 ;0,1,2=87,3=0.000000
L 12.30213366 1.88541654 12.29973317 1.885 2 P 0 ;0,1,2=87,3=0.000000
L 12.29973317 1.885 12.2975998 1.88541654 2 P 0 ;0,1,2=87,3=0.000000
L 12.2975998 1.88541654 12.29546644 1.88749941 2 P 0 ;0,1,2=87,3=0.000000
L 12.29546644 1.88749941 12.29413337 1.88999961 2 P 0 ;0,1,2=87,3=0.000000
L 12.29413337 1.88999961 12.29386683 1.8924999 2 P 0 ;0,1,2=87,3=0.000000
L 12.29386683 1.8924999 12.2944 1.89541594 2 P 0 ;0,1,2=87,3=0.000000
L 12.2944 1.89541594 12.29626673 1.89749961 2 P 0 ;0,1,2=87,3=0.000000
L 12.29626673 1.89749961 12.29813356 1.89833346 2 P 0 ;0,1,2=87,3=0.000000
L 12.29813356 1.89833346 12.30053346 1.89833346 2 P 0 ;0,1,2=87,3=0.000000
L 12.29813356 1.89833346 12.29653337 1.89958327 2 P 0 ;0,1,2=87,3=0.000000
L 12.29653337 1.89958327 12.2951999 1.90166614 2 P 0 ;0,1,2=87,3=0.000000
L 12.2951999 1.90166614 12.29466663 1.90416634 2 P 0 ;0,1,2=87,3=0.000000
L 12.29466663 1.90416634 12.2951999 1.90666654 2 P 0 ;0,1,2=87,3=0.000000
L 12.2951999 1.90666654 12.29653337 1.90874941 2 P 0 ;0,1,2=87,3=0.000000
L 12.29653337 1.90874941 12.29893337 1.91 2 P 0 ;0,1,2=87,3=0.000000
L 12.29893337 1.91 12.30133337 1.90958337 2 P 0 ;0,1,2=87,3=0.000000
L 12.30133337 1.90958337 12.30373337 1.90791634 2 P 0 ;0,1,2=87,3=0.000000
L 12.28186673 1.88999961 12.28026703 1.88708287 2 P 0 ;0,1,2=87,3=0.000000
L 12.28026703 1.88708287 12.27813366 1.88541654 2 P 0 ;0,1,2=87,3=0.000000
L 12.27813366 1.88541654 12.27573317 1.885 2 P 0 ;0,1,2=87,3=0.000000
L 12.27573317 1.885 12.2735998 1.88541654 2 P 0 ;0,1,2=87,3=0.000000
L 12.2735998 1.88541654 12.27146644 1.88749941 2 P 0 ;0,1,2=87,3=0.000000
L 12.27146644 1.88749941 12.27013337 1.88999961 2 P 0 ;0,1,2=87,3=0.000000
L 12.27013337 1.88999961 12.26986683 1.8924999 2 P 0 ;0,1,2=87,3=0.000000
L 12.26986683 1.8924999 12.2704 1.89541594 2 P 0 ;0,1,2=87,3=0.000000
L 12.2704 1.89541594 12.27226673 1.89749961 2 P 0 ;0,1,2=87,3=0.000000
L 12.27226673 1.89749961 12.27413356 1.89833346 2 P 0 ;0,1,2=87,3=0.000000
L 12.27413356 1.89833346 12.27653346 1.89833346 2 P 0 ;0,1,2=87,3=0.000000
L 12.27413356 1.89833346 12.27253337 1.89958327 2 P 0 ;0,1,2=87,3=0.000000
L 12.27253337 1.89958327 12.2711999 1.90166614 2 P 0 ;0,1,2=87,3=0.000000
L 12.2711999 1.90166614 12.27066663 1.90416634 2 P 0 ;0,1,2=87,3=0.000000
L 12.27066663 1.90416634 12.2711999 1.90666654 2 P 0 ;0,1,2=87,3=0.000000
L 12.2711999 1.90666654 12.27253337 1.90874941 2 P 0 ;0,1,2=87,3=0.000000
L 12.27253337 1.90874941 12.27493337 1.91 2 P 0 ;0,1,2=87,3=0.000000
L 12.27493337 1.91 12.27733337 1.90958337 2 P 0 ;0,1,2=87,3=0.000000
L 12.27733337 1.90958337 12.27973337 1.90791634 2 P 0 ;0,1,2=87,3=0.000000
L 7.84115 2.47023002 7.84115 2.48596998 3 P 0 
L 7.87233346 2.515 7.87233346 2.54 2 P 0 ;0,1,2=88,3=0.000000
L 7.87233346 2.54 7.86566673 2.54 2 P 0 ;0,1,2=88,3=0.000000
L 7.86566673 2.54 7.86353337 2.53874941 2 P 0 ;0,1,2=88,3=0.000000
L 7.86353337 2.53874941 7.8621999 2.53708317 2 P 0 ;0,1,2=88,3=0.000000
L 7.8621999 2.53708317 7.86166663 2.5337498 2 P 0 ;0,1,2=88,3=0.000000
L 7.86166663 2.5337498 7.8621999 2.53041634 2 P 0 ;0,1,2=88,3=0.000000
L 7.8621999 2.53041634 7.8638 2.52833346 2 P 0 ;0,1,2=88,3=0.000000
L 7.8638 2.52833346 7.86566673 2.52708297 2 P 0 ;0,1,2=88,3=0.000000
L 7.86566673 2.52708297 7.87233346 2.52708297 2 P 0 ;0,1,2=88,3=0.000000
L 7.86566673 2.52708297 7.86166663 2.515 2 P 0 ;0,1,2=88,3=0.000000
L 7.8430003 2.515 7.8430003 2.54 2 P 0 ;0,1,2=88,3=0.000000
L 7.8430003 2.54 7.8462001 2.5350003 2 P 0 ;0,1,2=88,3=0.000000
L 7.8462001 2.515 7.83980049 2.515 2 P 0 ;0,1,2=88,3=0.000000
L 7.82486673 2.51874911 7.82326703 2.51666624 2 P 0 ;0,1,2=88,3=0.000000
L 7.82326703 2.51666624 7.8214003 2.51541654 2 P 0 ;0,1,2=88,3=0.000000
L 7.8214003 2.51541654 7.8190003 2.515 2 P 0 ;0,1,2=88,3=0.000000
L 7.8190003 2.515 7.8165998 2.51583307 2 P 0 ;0,1,2=88,3=0.000000
L 7.8165998 2.51583307 7.81473356 2.51749941 2 P 0 ;0,1,2=88,3=0.000000
L 7.81473356 2.51749941 7.8134 2.52041624 2 P 0 ;0,1,2=88,3=0.000000
L 7.8134 2.52041624 7.81313337 2.52374961 2 P 0 ;0,1,2=88,3=0.000000
L 7.81313337 2.52374961 7.81366663 2.52708297 2 P 0 ;0,1,2=88,3=0.000000
L 7.81366663 2.52708297 7.8150002 2.52916663 2 P 0 ;0,1,2=88,3=0.000000
L 7.8150002 2.52916663 7.81686693 2.53083297 2 P 0 ;0,1,2=88,3=0.000000
L 7.81686693 2.53083297 7.81873317 2.53124951 2 P 0 ;0,1,2=88,3=0.000000
L 7.81873317 2.53124951 7.8206 2.53083297 2 P 0 ;0,1,2=88,3=0.000000
L 7.8206 2.53083297 7.8229999 2.52916663 2 P 0 ;0,1,2=88,3=0.000000
L 7.8229999 2.52916663 7.8222001 2.54 2 P 0 ;0,1,2=88,3=0.000000
L 7.8222001 2.54 7.8150002 2.54 2 P 0 ;0,1,2=88,3=0.000000
L 7.80006683 2.53583337 7.79846673 2.53833287 2 P 0 ;0,1,2=88,3=0.000000
L 7.79846673 2.53833287 7.7966 2.53958337 2 P 0 ;0,1,2=88,3=0.000000
L 7.7966 2.53958337 7.79446663 2.54 2 P 0 ;0,1,2=88,3=0.000000
L 7.79446663 2.54 7.7918 2.53916683 2 P 0 ;0,1,2=88,3=0.000000
L 7.7918 2.53916683 7.78993327 2.53708317 2 P 0 ;0,1,2=88,3=0.000000
L 7.78993327 2.53708317 7.7894 2.53458366 2 P 0 ;0,1,2=88,3=0.000000
L 7.7894 2.53458366 7.78966663 2.53208268 2 P 0 ;0,1,2=88,3=0.000000
L 7.78966663 2.53208268 7.79073356 2.5299998 2 P 0 ;0,1,2=88,3=0.000000
L 7.79073356 2.5299998 7.79606673 2.52583327 2 P 0 ;0,1,2=88,3=0.000000
L 7.79606673 2.52583327 7.79846673 2.52291644 2 P 0 ;0,1,2=88,3=0.000000
L 7.79846673 2.52291644 7.80006683 2.51874911 2 P 0 ;0,1,2=88,3=0.000000
L 7.80006683 2.51874911 7.8006001 2.515 2 P 0 ;0,1,2=88,3=0.000000
L 7.8006001 2.515 7.7894 2.515 2 P 0 ;0,1,2=88,3=0.000000
L 7.77153346 2.515 7.7710003 2.52041624 2 P 0 ;0,1,2=88,3=0.000000
L 7.7710003 2.52041624 7.7702 2.52499931 2 P 0 ;0,1,2=88,3=0.000000
L 7.7702 2.52499931 7.76913356 2.52916663 2 P 0 ;0,1,2=88,3=0.000000
L 7.76913356 2.52916663 7.7678 2.5337498 2 P 0 ;0,1,2=88,3=0.000000
L 7.7678 2.5337498 7.76566663 2.54 2 P 0 ;0,1,2=88,3=0.000000
L 7.76566663 2.54 7.77633346 2.54 2 P 0 ;0,1,2=88,3=0.000000
L 7.84393996 3.50213002 7.84393996 3.51786998 3 P 0 
L 7.78623346 3.49583002 7.78623346 3.52083002 2 P 0 ;0,1,2=89,3=0.000000
L 7.78623346 3.52083002 7.77956673 3.52083002 2 P 0 ;0,1,2=89,3=0.000000
L 7.77956673 3.52083002 7.77743337 3.51957943 2 P 0 ;0,1,2=89,3=0.000000
L 7.77743337 3.51957943 7.7760999 3.51791319 2 P 0 ;0,1,2=89,3=0.000000
L 7.7760999 3.51791319 7.77556663 3.51457982 2 P 0 ;0,1,2=89,3=0.000000
L 7.77556663 3.51457982 7.7760999 3.51124636 2 P 0 ;0,1,2=89,3=0.000000
L 7.7760999 3.51124636 7.7777 3.50916348 2 P 0 ;0,1,2=89,3=0.000000
L 7.7777 3.50916348 7.77956673 3.50791299 2 P 0 ;0,1,2=89,3=0.000000
L 7.77956673 3.50791299 7.78623346 3.50791299 2 P 0 ;0,1,2=89,3=0.000000
L 7.77956673 3.50791299 7.77556663 3.49583002 2 P 0 ;0,1,2=89,3=0.000000
L 7.7569003 3.49583002 7.7569003 3.52083002 2 P 0 ;0,1,2=89,3=0.000000
L 7.7569003 3.52083002 7.7601001 3.51583032 2 P 0 ;0,1,2=89,3=0.000000
L 7.7601001 3.49583002 7.75370049 3.49583002 2 P 0 ;0,1,2=89,3=0.000000
L 7.73876673 3.49957913 7.73716703 3.49749626 2 P 0 ;0,1,2=89,3=0.000000
L 7.73716703 3.49749626 7.7353003 3.49624656 2 P 0 ;0,1,2=89,3=0.000000
L 7.7353003 3.49624656 7.7329003 3.49583002 2 P 0 ;0,1,2=89,3=0.000000
L 7.7329003 3.49583002 7.7304998 3.49666309 2 P 0 ;0,1,2=89,3=0.000000
L 7.7304998 3.49666309 7.72863356 3.49832943 2 P 0 ;0,1,2=89,3=0.000000
L 7.72863356 3.49832943 7.7273 3.50124626 2 P 0 ;0,1,2=89,3=0.000000
L 7.7273 3.50124626 7.72703337 3.50457963 2 P 0 ;0,1,2=89,3=0.000000
L 7.72703337 3.50457963 7.72756663 3.50791299 2 P 0 ;0,1,2=89,3=0.000000
L 7.72756663 3.50791299 7.7289002 3.50999665 2 P 0 ;0,1,2=89,3=0.000000
L 7.7289002 3.50999665 7.73076693 3.51166299 2 P 0 ;0,1,2=89,3=0.000000
L 7.73076693 3.51166299 7.73263317 3.51207953 2 P 0 ;0,1,2=89,3=0.000000
L 7.73263317 3.51207953 7.7345 3.51166299 2 P 0 ;0,1,2=89,3=0.000000
L 7.7345 3.51166299 7.7368999 3.50999665 2 P 0 ;0,1,2=89,3=0.000000
L 7.7368999 3.50999665 7.7361001 3.52083002 2 P 0 ;0,1,2=89,3=0.000000
L 7.7361001 3.52083002 7.7289002 3.52083002 2 P 0 ;0,1,2=89,3=0.000000
L 7.71396683 3.51666339 7.71236673 3.51916289 2 P 0 ;0,1,2=89,3=0.000000
L 7.71236673 3.51916289 7.7105 3.52041339 2 P 0 ;0,1,2=89,3=0.000000
L 7.7105 3.52041339 7.70836663 3.52083002 2 P 0 ;0,1,2=89,3=0.000000
L 7.70836663 3.52083002 7.7057 3.51999685 2 P 0 ;0,1,2=89,3=0.000000
L 7.7057 3.51999685 7.70383327 3.51791319 2 P 0 ;0,1,2=89,3=0.000000
L 7.70383327 3.51791319 7.7033 3.51541368 2 P 0 ;0,1,2=89,3=0.000000
L 7.7033 3.51541368 7.70356663 3.5129127 2 P 0 ;0,1,2=89,3=0.000000
L 7.70356663 3.5129127 7.70463356 3.51082982 2 P 0 ;0,1,2=89,3=0.000000
L 7.70463356 3.51082982 7.70996673 3.50666329 2 P 0 ;0,1,2=89,3=0.000000
L 7.70996673 3.50666329 7.71236673 3.50374646 2 P 0 ;0,1,2=89,3=0.000000
L 7.71236673 3.50374646 7.71396683 3.49957913 2 P 0 ;0,1,2=89,3=0.000000
L 7.71396683 3.49957913 7.7145001 3.49583002 2 P 0 ;0,1,2=89,3=0.000000
L 7.7145001 3.49583002 7.7033 3.49583002 2 P 0 ;0,1,2=89,3=0.000000
L 7.68996683 3.50624596 7.6881001 3.50916348 2 P 0 ;0,1,2=89,3=0.000000
L 7.6881001 3.50916348 7.6865 3.51082982 2 P 0 ;0,1,2=89,3=0.000000
L 7.6865 3.51082982 7.68436663 3.51166299 2 P 0 ;0,1,2=89,3=0.000000
L 7.68436663 3.51166299 7.6824998 3.51082982 2 P 0 ;0,1,2=89,3=0.000000
L 7.6824998 3.51082982 7.68116673 3.50916348 2 P 0 ;0,1,2=89,3=0.000000
L 7.68116673 3.50916348 7.6800999 3.50666329 2 P 0 ;0,1,2=89,3=0.000000
L 7.6800999 3.50666329 7.67983327 3.50374646 2 P 0 ;0,1,2=89,3=0.000000
L 7.67983327 3.50374646 7.6800999 3.50124626 2 P 0 ;0,1,2=89,3=0.000000
L 7.6800999 3.50124626 7.68116673 3.49874606 2 P 0 ;0,1,2=89,3=0.000000
L 7.68116673 3.49874606 7.68276693 3.49666309 2 P 0 ;0,1,2=89,3=0.000000
L 7.68276693 3.49666309 7.68463317 3.49583002 2 P 0 ;0,1,2=89,3=0.000000
L 7.68463317 3.49583002 7.68676654 3.49666309 2 P 0 ;0,1,2=89,3=0.000000
L 7.68676654 3.49666309 7.68863337 3.4991626 2 P 0 ;0,1,2=89,3=0.000000
L 7.68863337 3.4991626 7.6897002 3.50291329 2 P 0 ;0,1,2=89,3=0.000000
L 7.6897002 3.50291329 7.68996683 3.50707982 2 P 0 ;0,1,2=89,3=0.000000
L 7.68996683 3.50707982 7.68943366 3.51249616 2 P 0 ;0,1,2=89,3=0.000000
L 7.68943366 3.51249616 7.68863337 3.51541368 2 P 0 ;0,1,2=89,3=0.000000
L 7.68863337 3.51541368 7.6873003 3.51832972 2 P 0 ;0,1,2=89,3=0.000000
L 7.6873003 3.51832972 7.68543346 3.52041339 2 P 0 ;0,1,2=89,3=0.000000
L 7.68543346 3.52041339 7.68356673 3.52083002 2 P 0 ;0,1,2=89,3=0.000000
L 7.68356673 3.52083002 7.6817 3.51999685 2 P 0 ;0,1,2=89,3=0.000000
L 7.6817 3.51999685 7.68036644 3.51791319 2 P 0 ;0,1,2=89,3=0.000000
L 7.84393996 3.55213002 7.84393996 3.56786998 3 P 0 
L 7.78623346 3.54583002 7.78623346 3.57083002 2 P 0 ;0,1,2=90,3=0.000000
L 7.78623346 3.57083002 7.77956673 3.57083002 2 P 0 ;0,1,2=90,3=0.000000
L 7.77956673 3.57083002 7.77743337 3.56957943 2 P 0 ;0,1,2=90,3=0.000000
L 7.77743337 3.56957943 7.7760999 3.56791319 2 P 0 ;0,1,2=90,3=0.000000
L 7.7760999 3.56791319 7.77556663 3.56457982 2 P 0 ;0,1,2=90,3=0.000000
L 7.77556663 3.56457982 7.7760999 3.56124636 2 P 0 ;0,1,2=90,3=0.000000
L 7.7760999 3.56124636 7.7777 3.55916348 2 P 0 ;0,1,2=90,3=0.000000
L 7.7777 3.55916348 7.77956673 3.55791299 2 P 0 ;0,1,2=90,3=0.000000
L 7.77956673 3.55791299 7.78623346 3.55791299 2 P 0 ;0,1,2=90,3=0.000000
L 7.77956673 3.55791299 7.77556663 3.54583002 2 P 0 ;0,1,2=90,3=0.000000
L 7.7569003 3.54583002 7.7569003 3.57083002 2 P 0 ;0,1,2=90,3=0.000000
L 7.7569003 3.57083002 7.7601001 3.56583032 2 P 0 ;0,1,2=90,3=0.000000
L 7.7601001 3.54583002 7.75370049 3.54583002 2 P 0 ;0,1,2=90,3=0.000000
L 7.73876673 3.54957913 7.73716703 3.54749626 2 P 0 ;0,1,2=90,3=0.000000
L 7.73716703 3.54749626 7.7353003 3.54624656 2 P 0 ;0,1,2=90,3=0.000000
L 7.7353003 3.54624656 7.7329003 3.54583002 2 P 0 ;0,1,2=90,3=0.000000
L 7.7329003 3.54583002 7.7304998 3.54666309 2 P 0 ;0,1,2=90,3=0.000000
L 7.7304998 3.54666309 7.72863356 3.54832943 2 P 0 ;0,1,2=90,3=0.000000
L 7.72863356 3.54832943 7.7273 3.55124626 2 P 0 ;0,1,2=90,3=0.000000
L 7.7273 3.55124626 7.72703337 3.55457963 2 P 0 ;0,1,2=90,3=0.000000
L 7.72703337 3.55457963 7.72756663 3.55791299 2 P 0 ;0,1,2=90,3=0.000000
L 7.72756663 3.55791299 7.7289002 3.55999665 2 P 0 ;0,1,2=90,3=0.000000
L 7.7289002 3.55999665 7.73076693 3.56166299 2 P 0 ;0,1,2=90,3=0.000000
L 7.73076693 3.56166299 7.73263317 3.56207953 2 P 0 ;0,1,2=90,3=0.000000
L 7.73263317 3.56207953 7.7345 3.56166299 2 P 0 ;0,1,2=90,3=0.000000
L 7.7345 3.56166299 7.7368999 3.55999665 2 P 0 ;0,1,2=90,3=0.000000
L 7.7368999 3.55999665 7.7361001 3.57083002 2 P 0 ;0,1,2=90,3=0.000000
L 7.7361001 3.57083002 7.7289002 3.57083002 2 P 0 ;0,1,2=90,3=0.000000
L 7.71396683 3.56666339 7.71236673 3.56916289 2 P 0 ;0,1,2=90,3=0.000000
L 7.71236673 3.56916289 7.7105 3.57041339 2 P 0 ;0,1,2=90,3=0.000000
L 7.7105 3.57041339 7.70836663 3.57083002 2 P 0 ;0,1,2=90,3=0.000000
L 7.70836663 3.57083002 7.7057 3.56999685 2 P 0 ;0,1,2=90,3=0.000000
L 7.7057 3.56999685 7.70383327 3.56791319 2 P 0 ;0,1,2=90,3=0.000000
L 7.70383327 3.56791319 7.7033 3.56541368 2 P 0 ;0,1,2=90,3=0.000000
L 7.7033 3.56541368 7.70356663 3.5629127 2 P 0 ;0,1,2=90,3=0.000000
L 7.70356663 3.5629127 7.70463356 3.56082982 2 P 0 ;0,1,2=90,3=0.000000
L 7.70463356 3.56082982 7.70996673 3.55666329 2 P 0 ;0,1,2=90,3=0.000000
L 7.70996673 3.55666329 7.71236673 3.55374646 2 P 0 ;0,1,2=90,3=0.000000
L 7.71236673 3.55374646 7.71396683 3.54957913 2 P 0 ;0,1,2=90,3=0.000000
L 7.71396683 3.54957913 7.7145001 3.54583002 2 P 0 ;0,1,2=90,3=0.000000
L 7.7145001 3.54583002 7.7033 3.54583002 2 P 0 ;0,1,2=90,3=0.000000
L 7.69076673 3.54957913 7.68916703 3.54749626 2 P 0 ;0,1,2=90,3=0.000000
L 7.68916703 3.54749626 7.6873003 3.54624656 2 P 0 ;0,1,2=90,3=0.000000
L 7.6873003 3.54624656 7.6849003 3.54583002 2 P 0 ;0,1,2=90,3=0.000000
L 7.6849003 3.54583002 7.6824998 3.54666309 2 P 0 ;0,1,2=90,3=0.000000
L 7.6824998 3.54666309 7.68063356 3.54832943 2 P 0 ;0,1,2=90,3=0.000000
L 7.68063356 3.54832943 7.6793 3.55124626 2 P 0 ;0,1,2=90,3=0.000000
L 7.6793 3.55124626 7.67903337 3.55457963 2 P 0 ;0,1,2=90,3=0.000000
L 7.67903337 3.55457963 7.67956663 3.55791299 2 P 0 ;0,1,2=90,3=0.000000
L 7.67956663 3.55791299 7.6809002 3.55999665 2 P 0 ;0,1,2=90,3=0.000000
L 7.6809002 3.55999665 7.68276693 3.56166299 2 P 0 ;0,1,2=90,3=0.000000
L 7.68276693 3.56166299 7.68463317 3.56207953 2 P 0 ;0,1,2=90,3=0.000000
L 7.68463317 3.56207953 7.6865 3.56166299 2 P 0 ;0,1,2=90,3=0.000000
L 7.6865 3.56166299 7.6888999 3.55999665 2 P 0 ;0,1,2=90,3=0.000000
L 7.6888999 3.55999665 7.6881001 3.57083002 2 P 0 ;0,1,2=90,3=0.000000
L 7.6881001 3.57083002 7.6809002 3.57083002 2 P 0 ;0,1,2=90,3=0.000000
L 0.59998002 1.64713002 0.59998002 1.66286998 3 P 0 
L 0.67733346 1.605 0.67733346 1.63 2 P 0 ;0,1,2=91,3=0.000000
L 0.67733346 1.63 0.67066673 1.63 2 P 0 ;0,1,2=91,3=0.000000
L 0.67066673 1.63 0.66853337 1.62874941 2 P 0 ;0,1,2=91,3=0.000000
L 0.66853337 1.62874941 0.6671999 1.62708317 2 P 0 ;0,1,2=91,3=0.000000
L 0.6671999 1.62708317 0.66666663 1.6237498 2 P 0 ;0,1,2=91,3=0.000000
L 0.66666663 1.6237498 0.6671999 1.62041634 2 P 0 ;0,1,2=91,3=0.000000
L 0.6671999 1.62041634 0.6688 1.61833346 2 P 0 ;0,1,2=91,3=0.000000
L 0.6688 1.61833346 0.67066673 1.61708297 2 P 0 ;0,1,2=91,3=0.000000
L 0.67066673 1.61708297 0.67733346 1.61708297 2 P 0 ;0,1,2=91,3=0.000000
L 0.67066673 1.61708297 0.66666663 1.605 2 P 0 ;0,1,2=91,3=0.000000
L 0.6480003 1.605 0.6480003 1.63 2 P 0 ;0,1,2=91,3=0.000000
L 0.6480003 1.63 0.6512001 1.6250003 2 P 0 ;0,1,2=91,3=0.000000
L 0.6512001 1.605 0.64480049 1.605 2 P 0 ;0,1,2=91,3=0.000000
L 0.62986673 1.60874911 0.62826703 1.60666624 2 P 0 ;0,1,2=91,3=0.000000
L 0.62826703 1.60666624 0.6264003 1.60541654 2 P 0 ;0,1,2=91,3=0.000000
L 0.6264003 1.60541654 0.6240003 1.605 2 P 0 ;0,1,2=91,3=0.000000
L 0.6240003 1.605 0.6215998 1.60583307 2 P 0 ;0,1,2=91,3=0.000000
L 0.6215998 1.60583307 0.61973356 1.60749941 2 P 0 ;0,1,2=91,3=0.000000
L 0.61973356 1.60749941 0.6184 1.61041624 2 P 0 ;0,1,2=91,3=0.000000
L 0.6184 1.61041624 0.61813337 1.61374961 2 P 0 ;0,1,2=91,3=0.000000
L 0.61813337 1.61374961 0.61866663 1.61708297 2 P 0 ;0,1,2=91,3=0.000000
L 0.61866663 1.61708297 0.6200002 1.61916663 2 P 0 ;0,1,2=91,3=0.000000
L 0.6200002 1.61916663 0.62186693 1.62083297 2 P 0 ;0,1,2=91,3=0.000000
L 0.62186693 1.62083297 0.62373317 1.62124951 2 P 0 ;0,1,2=91,3=0.000000
L 0.62373317 1.62124951 0.6256 1.62083297 2 P 0 ;0,1,2=91,3=0.000000
L 0.6256 1.62083297 0.6279999 1.61916663 2 P 0 ;0,1,2=91,3=0.000000
L 0.6279999 1.61916663 0.6272001 1.63 2 P 0 ;0,1,2=91,3=0.000000
L 0.6272001 1.63 0.6200002 1.63 2 P 0 ;0,1,2=91,3=0.000000
L 0.6000003 1.605 0.6000003 1.63 2 P 0 ;0,1,2=91,3=0.000000
L 0.6000003 1.63 0.6032001 1.6250003 2 P 0 ;0,1,2=91,3=0.000000
L 0.6032001 1.605 0.59680049 1.605 2 P 0 ;0,1,2=91,3=0.000000
L 0.58186673 1.60999961 0.58026703 1.60708287 2 P 0 ;0,1,2=91,3=0.000000
L 0.58026703 1.60708287 0.57813366 1.60541654 2 P 0 ;0,1,2=91,3=0.000000
L 0.57813366 1.60541654 0.57573317 1.605 2 P 0 ;0,1,2=91,3=0.000000
L 0.57573317 1.605 0.5735998 1.60541654 2 P 0 ;0,1,2=91,3=0.000000
L 0.5735998 1.60541654 0.57146644 1.60749941 2 P 0 ;0,1,2=91,3=0.000000
L 0.57146644 1.60749941 0.57013337 1.60999961 2 P 0 ;0,1,2=91,3=0.000000
L 0.57013337 1.60999961 0.56986683 1.6124999 2 P 0 ;0,1,2=91,3=0.000000
L 0.56986683 1.6124999 0.5704 1.61541594 2 P 0 ;0,1,2=91,3=0.000000
L 0.5704 1.61541594 0.57226673 1.61749961 2 P 0 ;0,1,2=91,3=0.000000
L 0.57226673 1.61749961 0.57413356 1.61833346 2 P 0 ;0,1,2=91,3=0.000000
L 0.57413356 1.61833346 0.57653346 1.61833346 2 P 0 ;0,1,2=91,3=0.000000
L 0.57413356 1.61833346 0.57253337 1.61958327 2 P 0 ;0,1,2=91,3=0.000000
L 0.57253337 1.61958327 0.5711999 1.62166614 2 P 0 ;0,1,2=91,3=0.000000
L 0.5711999 1.62166614 0.57066663 1.62416634 2 P 0 ;0,1,2=91,3=0.000000
L 0.57066663 1.62416634 0.5711999 1.62666654 2 P 0 ;0,1,2=91,3=0.000000
L 0.5711999 1.62666654 0.57253337 1.62874941 2 P 0 ;0,1,2=91,3=0.000000
L 0.57253337 1.62874941 0.57493337 1.63 2 P 0 ;0,1,2=91,3=0.000000
L 0.57493337 1.63 0.57733337 1.62958337 2 P 0 ;0,1,2=91,3=0.000000
L 0.57733337 1.62958337 0.57973337 1.62791634 2 P 0 ;0,1,2=91,3=0.000000
L 0.59998996 1.90395 0.59998996 1.91968996 3 P 0 
L 0.66233346 1.94 0.66233346 1.965 2 P 0 ;0,1,2=92,3=0.000000
L 0.66233346 1.965 0.65566673 1.965 2 P 0 ;0,1,2=92,3=0.000000
L 0.65566673 1.965 0.65353337 1.96374941 2 P 0 ;0,1,2=92,3=0.000000
L 0.65353337 1.96374941 0.6521999 1.96208317 2 P 0 ;0,1,2=92,3=0.000000
L 0.6521999 1.96208317 0.65166663 1.9587498 2 P 0 ;0,1,2=92,3=0.000000
L 0.65166663 1.9587498 0.6521999 1.95541634 2 P 0 ;0,1,2=92,3=0.000000
L 0.6521999 1.95541634 0.6538 1.95333346 2 P 0 ;0,1,2=92,3=0.000000
L 0.6538 1.95333346 0.65566673 1.95208297 2 P 0 ;0,1,2=92,3=0.000000
L 0.65566673 1.95208297 0.66233346 1.95208297 2 P 0 ;0,1,2=92,3=0.000000
L 0.65566673 1.95208297 0.65166663 1.94 2 P 0 ;0,1,2=92,3=0.000000
L 0.6330003 1.94 0.6330003 1.965 2 P 0 ;0,1,2=92,3=0.000000
L 0.6330003 1.965 0.6362001 1.9600003 2 P 0 ;0,1,2=92,3=0.000000
L 0.6362001 1.94 0.62980049 1.94 2 P 0 ;0,1,2=92,3=0.000000
L 0.61486673 1.94374911 0.61326703 1.94166624 2 P 0 ;0,1,2=92,3=0.000000
L 0.61326703 1.94166624 0.6114003 1.94041654 2 P 0 ;0,1,2=92,3=0.000000
L 0.6114003 1.94041654 0.6090003 1.94 2 P 0 ;0,1,2=92,3=0.000000
L 0.6090003 1.94 0.6065998 1.94083307 2 P 0 ;0,1,2=92,3=0.000000
L 0.6065998 1.94083307 0.60473356 1.94249941 2 P 0 ;0,1,2=92,3=0.000000
L 0.60473356 1.94249941 0.6034 1.94541624 2 P 0 ;0,1,2=92,3=0.000000
L 0.6034 1.94541624 0.60313337 1.94874961 2 P 0 ;0,1,2=92,3=0.000000
L 0.60313337 1.94874961 0.60366663 1.95208297 2 P 0 ;0,1,2=92,3=0.000000
L 0.60366663 1.95208297 0.6050002 1.95416663 2 P 0 ;0,1,2=92,3=0.000000
L 0.6050002 1.95416663 0.60686693 1.95583297 2 P 0 ;0,1,2=92,3=0.000000
L 0.60686693 1.95583297 0.60873317 1.95624951 2 P 0 ;0,1,2=92,3=0.000000
L 0.60873317 1.95624951 0.6106 1.95583297 2 P 0 ;0,1,2=92,3=0.000000
L 0.6106 1.95583297 0.6129999 1.95416663 2 P 0 ;0,1,2=92,3=0.000000
L 0.6129999 1.95416663 0.6122001 1.965 2 P 0 ;0,1,2=92,3=0.000000
L 0.6122001 1.965 0.6050002 1.965 2 P 0 ;0,1,2=92,3=0.000000
L 0.5850003 1.94 0.5850003 1.965 2 P 0 ;0,1,2=92,3=0.000000
L 0.5850003 1.965 0.5882001 1.9600003 2 P 0 ;0,1,2=92,3=0.000000
L 0.5882001 1.94 0.58180049 1.94 2 P 0 ;0,1,2=92,3=0.000000
L 0.56606683 1.96083337 0.56446673 1.96333287 2 P 0 ;0,1,2=92,3=0.000000
L 0.56446673 1.96333287 0.5626 1.96458337 2 P 0 ;0,1,2=92,3=0.000000
L 0.5626 1.96458337 0.56046663 1.965 2 P 0 ;0,1,2=92,3=0.000000
L 0.56046663 1.965 0.5578 1.96416683 2 P 0 ;0,1,2=92,3=0.000000
L 0.5578 1.96416683 0.55593327 1.96208317 2 P 0 ;0,1,2=92,3=0.000000
L 0.55593327 1.96208317 0.5554 1.95958366 2 P 0 ;0,1,2=92,3=0.000000
L 0.5554 1.95958366 0.55566663 1.95708268 2 P 0 ;0,1,2=92,3=0.000000
L 0.55566663 1.95708268 0.55673356 1.9549998 2 P 0 ;0,1,2=92,3=0.000000
L 0.55673356 1.9549998 0.56206673 1.95083327 2 P 0 ;0,1,2=92,3=0.000000
L 0.56206673 1.95083327 0.56446673 1.94791644 2 P 0 ;0,1,2=92,3=0.000000
L 0.56446673 1.94791644 0.56606683 1.94374911 2 P 0 ;0,1,2=92,3=0.000000
L 0.56606683 1.94374911 0.5666001 1.94 2 P 0 ;0,1,2=92,3=0.000000
L 0.5666001 1.94 0.5554 1.94 2 P 0 ;0,1,2=92,3=0.000000
L 0.59998996 1.85395 0.59998996 1.86968996 3 P 0 
L 0.66233346 1.805 0.66233346 1.83 2 P 0 ;0,1,2=93,3=0.000000
L 0.66233346 1.83 0.65566673 1.83 2 P 0 ;0,1,2=93,3=0.000000
L 0.65566673 1.83 0.65353337 1.82874941 2 P 0 ;0,1,2=93,3=0.000000
L 0.65353337 1.82874941 0.6521999 1.82708317 2 P 0 ;0,1,2=93,3=0.000000
L 0.6521999 1.82708317 0.65166663 1.8237498 2 P 0 ;0,1,2=93,3=0.000000
L 0.65166663 1.8237498 0.6521999 1.82041634 2 P 0 ;0,1,2=93,3=0.000000
L 0.6521999 1.82041634 0.6538 1.81833346 2 P 0 ;0,1,2=93,3=0.000000
L 0.6538 1.81833346 0.65566673 1.81708297 2 P 0 ;0,1,2=93,3=0.000000
L 0.65566673 1.81708297 0.66233346 1.81708297 2 P 0 ;0,1,2=93,3=0.000000
L 0.65566673 1.81708297 0.65166663 1.805 2 P 0 ;0,1,2=93,3=0.000000
L 0.6330003 1.805 0.6330003 1.83 2 P 0 ;0,1,2=93,3=0.000000
L 0.6330003 1.83 0.6362001 1.8250003 2 P 0 ;0,1,2=93,3=0.000000
L 0.6362001 1.805 0.62980049 1.805 2 P 0 ;0,1,2=93,3=0.000000
L 0.61486673 1.80874911 0.61326703 1.80666624 2 P 0 ;0,1,2=93,3=0.000000
L 0.61326703 1.80666624 0.6114003 1.80541654 2 P 0 ;0,1,2=93,3=0.000000
L 0.6114003 1.80541654 0.6090003 1.805 2 P 0 ;0,1,2=93,3=0.000000
L 0.6090003 1.805 0.6065998 1.80583307 2 P 0 ;0,1,2=93,3=0.000000
L 0.6065998 1.80583307 0.60473356 1.80749941 2 P 0 ;0,1,2=93,3=0.000000
L 0.60473356 1.80749941 0.6034 1.81041624 2 P 0 ;0,1,2=93,3=0.000000
L 0.6034 1.81041624 0.60313337 1.81374961 2 P 0 ;0,1,2=93,3=0.000000
L 0.60313337 1.81374961 0.60366663 1.81708297 2 P 0 ;0,1,2=93,3=0.000000
L 0.60366663 1.81708297 0.6050002 1.81916663 2 P 0 ;0,1,2=93,3=0.000000
L 0.6050002 1.81916663 0.60686693 1.82083297 2 P 0 ;0,1,2=93,3=0.000000
L 0.60686693 1.82083297 0.60873317 1.82124951 2 P 0 ;0,1,2=93,3=0.000000
L 0.60873317 1.82124951 0.6106 1.82083297 2 P 0 ;0,1,2=93,3=0.000000
L 0.6106 1.82083297 0.6129999 1.81916663 2 P 0 ;0,1,2=93,3=0.000000
L 0.6129999 1.81916663 0.6122001 1.83 2 P 0 ;0,1,2=93,3=0.000000
L 0.6122001 1.83 0.6050002 1.83 2 P 0 ;0,1,2=93,3=0.000000
L 0.5850003 1.805 0.5850003 1.83 2 P 0 ;0,1,2=93,3=0.000000
L 0.5850003 1.83 0.5882001 1.8250003 2 P 0 ;0,1,2=93,3=0.000000
L 0.5882001 1.805 0.58180049 1.805 2 P 0 ;0,1,2=93,3=0.000000
L 0.5610003 1.805 0.5610003 1.83 2 P 0 ;0,1,2=93,3=0.000000
L 0.5610003 1.83 0.5642001 1.8250003 2 P 0 ;0,1,2=93,3=0.000000
L 0.5642001 1.805 0.55780049 1.805 2 P 0 ;0,1,2=93,3=0.000000
L 7.26473002 4.95851004 7.28046998 4.95851004 3 P 0 
L 7.25 4.80766654 7.275 4.80766654 2 P 0 ;0,1,2=94,3=90.000000
L 7.275 4.80766654 7.275 4.81433327 2 P 0 ;0,1,2=94,3=90.000000
L 7.275 4.81433327 7.27374941 4.81646663 2 P 0 ;0,1,2=94,3=90.000000
L 7.27374941 4.81646663 7.27208317 4.8178001 2 P 0 ;0,1,2=94,3=90.000000
L 7.27208317 4.8178001 7.2687498 4.81833337 2 P 0 ;0,1,2=94,3=90.000000
L 7.2687498 4.81833337 7.26541634 4.8178001 2 P 0 ;0,1,2=94,3=90.000000
L 7.26541634 4.8178001 7.26333346 4.8162 2 P 0 ;0,1,2=94,3=90.000000
L 7.26333346 4.8162 7.26208297 4.81433327 2 P 0 ;0,1,2=94,3=90.000000
L 7.26208297 4.81433327 7.26208297 4.80766654 2 P 0 ;0,1,2=94,3=90.000000
L 7.26208297 4.81433327 7.25 4.81833337 2 P 0 ;0,1,2=94,3=90.000000
L 7.25 4.8369997 7.275 4.8369997 2 P 0 ;0,1,2=94,3=90.000000
L 7.275 4.8369997 7.2700003 4.8337999 2 P 0 ;0,1,2=94,3=90.000000
L 7.25 4.8337999 7.25 4.84019951 2 P 0 ;0,1,2=94,3=90.000000
L 7.25374911 4.85513327 7.25166624 4.85673297 2 P 0 ;0,1,2=94,3=90.000000
L 7.25166624 4.85673297 7.25041654 4.8585997 2 P 0 ;0,1,2=94,3=90.000000
L 7.25041654 4.8585997 7.25 4.8609997 2 P 0 ;0,1,2=94,3=90.000000
L 7.25 4.8609997 7.25083307 4.8634002 2 P 0 ;0,1,2=94,3=90.000000
L 7.25083307 4.8634002 7.25249941 4.86526644 2 P 0 ;0,1,2=94,3=90.000000
L 7.25249941 4.86526644 7.25541624 4.8666 2 P 0 ;0,1,2=94,3=90.000000
L 7.25541624 4.8666 7.25874961 4.86686663 2 P 0 ;0,1,2=94,3=90.000000
L 7.25874961 4.86686663 7.26208297 4.86633337 2 P 0 ;0,1,2=94,3=90.000000
L 7.26208297 4.86633337 7.26416663 4.8649998 2 P 0 ;0,1,2=94,3=90.000000
L 7.26416663 4.8649998 7.26583297 4.86313307 2 P 0 ;0,1,2=94,3=90.000000
L 7.26583297 4.86313307 7.26624951 4.86126683 2 P 0 ;0,1,2=94,3=90.000000
L 7.26624951 4.86126683 7.26583297 4.8594 2 P 0 ;0,1,2=94,3=90.000000
L 7.26583297 4.8594 7.26416663 4.8570001 2 P 0 ;0,1,2=94,3=90.000000
L 7.26416663 4.8570001 7.275 4.8577999 2 P 0 ;0,1,2=94,3=90.000000
L 7.275 4.8577999 7.275 4.8649998 2 P 0 ;0,1,2=94,3=90.000000
L 7.275 4.8849997 7.27416683 4.88286634 2 P 0 ;0,1,2=94,3=90.000000
L 7.27416683 4.88286634 7.27208317 4.88126663 2 P 0 ;0,1,2=94,3=90.000000
L 7.27208317 4.88126663 7.26958366 4.8801998 2 P 0 ;0,1,2=94,3=90.000000
L 7.26958366 4.8801998 7.26624951 4.8793999 2 P 0 ;0,1,2=94,3=90.000000
L 7.26624951 4.8793999 7.26249961 4.87913327 2 P 0 ;0,1,2=94,3=90.000000
L 7.26249961 4.87913327 7.25874961 4.8793999 2 P 0 ;0,1,2=94,3=90.000000
L 7.25874961 4.8793999 7.25541624 4.8801998 2 P 0 ;0,1,2=94,3=90.000000
L 7.25541624 4.8801998 7.25291604 4.88126663 2 P 0 ;0,1,2=94,3=90.000000
L 7.25291604 4.88126663 7.25083307 4.88286634 2 P 0 ;0,1,2=94,3=90.000000
L 7.25083307 4.88286634 7.25 4.8849997 2 P 0 ;0,1,2=94,3=90.000000
L 7.25 4.8849997 7.25083307 4.88713307 2 P 0 ;0,1,2=94,3=90.000000
L 7.25083307 4.88713307 7.25291604 4.88873327 2 P 0 ;0,1,2=94,3=90.000000
L 7.25291604 4.88873327 7.25541624 4.8898001 2 P 0 ;0,1,2=94,3=90.000000
L 7.25541624 4.8898001 7.25874961 4.8906 2 P 0 ;0,1,2=94,3=90.000000
L 7.25874961 4.8906 7.26249961 4.89086663 2 P 0 ;0,1,2=94,3=90.000000
L 7.26249961 4.89086663 7.26624951 4.8906 2 P 0 ;0,1,2=94,3=90.000000
L 7.26624951 4.8906 7.26958366 4.8898001 2 P 0 ;0,1,2=94,3=90.000000
L 7.26958366 4.8898001 7.27208317 4.88873327 2 P 0 ;0,1,2=94,3=90.000000
L 7.27208317 4.88873327 7.27416683 4.88713307 2 P 0 ;0,1,2=94,3=90.000000
L 7.27416683 4.88713307 7.275 4.8849997 2 P 0 ;0,1,2=94,3=90.000000
L 7.25374911 4.90313327 7.25166624 4.90473297 2 P 0 ;0,1,2=94,3=90.000000
L 7.25166624 4.90473297 7.25041654 4.9065997 2 P 0 ;0,1,2=94,3=90.000000
L 7.25041654 4.9065997 7.25 4.9089997 2 P 0 ;0,1,2=94,3=90.000000
L 7.25 4.9089997 7.25083307 4.9114002 2 P 0 ;0,1,2=94,3=90.000000
L 7.25083307 4.9114002 7.25249941 4.91326644 2 P 0 ;0,1,2=94,3=90.000000
L 7.25249941 4.91326644 7.25541624 4.9146 2 P 0 ;0,1,2=94,3=90.000000
L 7.25541624 4.9146 7.25874961 4.91486663 2 P 0 ;0,1,2=94,3=90.000000
L 7.25874961 4.91486663 7.26208297 4.91433337 2 P 0 ;0,1,2=94,3=90.000000
L 7.26208297 4.91433337 7.26416663 4.9129998 2 P 0 ;0,1,2=94,3=90.000000
L 7.26416663 4.9129998 7.26583297 4.91113307 2 P 0 ;0,1,2=94,3=90.000000
L 7.26583297 4.91113307 7.26624951 4.90926683 2 P 0 ;0,1,2=94,3=90.000000
L 7.26624951 4.90926683 7.26583297 4.9074 2 P 0 ;0,1,2=94,3=90.000000
L 7.26583297 4.9074 7.26416663 4.9050001 2 P 0 ;0,1,2=94,3=90.000000
L 7.26416663 4.9050001 7.275 4.9057999 2 P 0 ;0,1,2=94,3=90.000000
L 7.275 4.9057999 7.275 4.9129998 2 P 0 ;0,1,2=94,3=90.000000
L 7.31473002 4.95851004 7.33046998 4.95851004 3 P 0 
L 7.295 4.80766654 7.32 4.80766654 2 P 0 ;0,1,2=95,3=90.000000
L 7.32 4.80766654 7.32 4.81433327 2 P 0 ;0,1,2=95,3=90.000000
L 7.32 4.81433327 7.31874941 4.81646663 2 P 0 ;0,1,2=95,3=90.000000
L 7.31874941 4.81646663 7.31708317 4.8178001 2 P 0 ;0,1,2=95,3=90.000000
L 7.31708317 4.8178001 7.3137498 4.81833337 2 P 0 ;0,1,2=95,3=90.000000
L 7.3137498 4.81833337 7.31041634 4.8178001 2 P 0 ;0,1,2=95,3=90.000000
L 7.31041634 4.8178001 7.30833346 4.8162 2 P 0 ;0,1,2=95,3=90.000000
L 7.30833346 4.8162 7.30708297 4.81433327 2 P 0 ;0,1,2=95,3=90.000000
L 7.30708297 4.81433327 7.30708297 4.80766654 2 P 0 ;0,1,2=95,3=90.000000
L 7.30708297 4.81433327 7.295 4.81833337 2 P 0 ;0,1,2=95,3=90.000000
L 7.295 4.8369997 7.32 4.8369997 2 P 0 ;0,1,2=95,3=90.000000
L 7.32 4.8369997 7.3150003 4.8337999 2 P 0 ;0,1,2=95,3=90.000000
L 7.295 4.8337999 7.295 4.84019951 2 P 0 ;0,1,2=95,3=90.000000
L 7.29874911 4.85513327 7.29666624 4.85673297 2 P 0 ;0,1,2=95,3=90.000000
L 7.29666624 4.85673297 7.29541654 4.8585997 2 P 0 ;0,1,2=95,3=90.000000
L 7.29541654 4.8585997 7.295 4.8609997 2 P 0 ;0,1,2=95,3=90.000000
L 7.295 4.8609997 7.29583307 4.8634002 2 P 0 ;0,1,2=95,3=90.000000
L 7.29583307 4.8634002 7.29749941 4.86526644 2 P 0 ;0,1,2=95,3=90.000000
L 7.29749941 4.86526644 7.30041624 4.8666 2 P 0 ;0,1,2=95,3=90.000000
L 7.30041624 4.8666 7.30374961 4.86686663 2 P 0 ;0,1,2=95,3=90.000000
L 7.30374961 4.86686663 7.30708297 4.86633337 2 P 0 ;0,1,2=95,3=90.000000
L 7.30708297 4.86633337 7.30916663 4.8649998 2 P 0 ;0,1,2=95,3=90.000000
L 7.30916663 4.8649998 7.31083297 4.86313307 2 P 0 ;0,1,2=95,3=90.000000
L 7.31083297 4.86313307 7.31124951 4.86126683 2 P 0 ;0,1,2=95,3=90.000000
L 7.31124951 4.86126683 7.31083297 4.8594 2 P 0 ;0,1,2=95,3=90.000000
L 7.31083297 4.8594 7.30916663 4.8570001 2 P 0 ;0,1,2=95,3=90.000000
L 7.30916663 4.8570001 7.32 4.8577999 2 P 0 ;0,1,2=95,3=90.000000
L 7.32 4.8577999 7.32 4.8649998 2 P 0 ;0,1,2=95,3=90.000000
L 7.32 4.8849997 7.31916683 4.88286634 2 P 0 ;0,1,2=95,3=90.000000
L 7.31916683 4.88286634 7.31708317 4.88126663 2 P 0 ;0,1,2=95,3=90.000000
L 7.31708317 4.88126663 7.31458366 4.8801998 2 P 0 ;0,1,2=95,3=90.000000
L 7.31458366 4.8801998 7.31124951 4.8793999 2 P 0 ;0,1,2=95,3=90.000000
L 7.31124951 4.8793999 7.30749961 4.87913327 2 P 0 ;0,1,2=95,3=90.000000
L 7.30749961 4.87913327 7.30374961 4.8793999 2 P 0 ;0,1,2=95,3=90.000000
L 7.30374961 4.8793999 7.30041624 4.8801998 2 P 0 ;0,1,2=95,3=90.000000
L 7.30041624 4.8801998 7.29791604 4.88126663 2 P 0 ;0,1,2=95,3=90.000000
L 7.29791604 4.88126663 7.29583307 4.88286634 2 P 0 ;0,1,2=95,3=90.000000
L 7.29583307 4.88286634 7.295 4.8849997 2 P 0 ;0,1,2=95,3=90.000000
L 7.295 4.8849997 7.29583307 4.88713307 2 P 0 ;0,1,2=95,3=90.000000
L 7.29583307 4.88713307 7.29791604 4.88873327 2 P 0 ;0,1,2=95,3=90.000000
L 7.29791604 4.88873327 7.30041624 4.8898001 2 P 0 ;0,1,2=95,3=90.000000
L 7.30041624 4.8898001 7.30374961 4.8906 2 P 0 ;0,1,2=95,3=90.000000
L 7.30374961 4.8906 7.30749961 4.89086663 2 P 0 ;0,1,2=95,3=90.000000
L 7.30749961 4.89086663 7.31124951 4.8906 2 P 0 ;0,1,2=95,3=90.000000
L 7.31124951 4.8906 7.31458366 4.8898001 2 P 0 ;0,1,2=95,3=90.000000
L 7.31458366 4.8898001 7.31708317 4.88873327 2 P 0 ;0,1,2=95,3=90.000000
L 7.31708317 4.88873327 7.31916683 4.88713307 2 P 0 ;0,1,2=95,3=90.000000
L 7.31916683 4.88713307 7.32 4.8849997 2 P 0 ;0,1,2=95,3=90.000000
L 7.295 4.9122 7.32 4.9122 2 P 0 ;0,1,2=95,3=90.000000
L 7.32 4.9122 7.30208327 4.90233297 2 P 0 ;0,1,2=95,3=90.000000
L 7.30208327 4.90233297 7.30208327 4.91566693 2 P 0 ;0,1,2=95,3=90.000000
L 1.83721004 2.47023002 1.83721004 2.48596998 3 P 0 
L 1.76733346 2.465 1.76733346 2.49 2 P 0 ;0,1,2=96,3=0.000000
L 1.76733346 2.49 1.76066673 2.49 2 P 0 ;0,1,2=96,3=0.000000
L 1.76066673 2.49 1.75853337 2.48874941 2 P 0 ;0,1,2=96,3=0.000000
L 1.75853337 2.48874941 1.7571999 2.48708317 2 P 0 ;0,1,2=96,3=0.000000
L 1.7571999 2.48708317 1.75666663 2.4837498 2 P 0 ;0,1,2=96,3=0.000000
L 1.75666663 2.4837498 1.7571999 2.48041634 2 P 0 ;0,1,2=96,3=0.000000
L 1.7571999 2.48041634 1.7588 2.47833346 2 P 0 ;0,1,2=96,3=0.000000
L 1.7588 2.47833346 1.76066673 2.47708297 2 P 0 ;0,1,2=96,3=0.000000
L 1.76066673 2.47708297 1.76733346 2.47708297 2 P 0 ;0,1,2=96,3=0.000000
L 1.76066673 2.47708297 1.75666663 2.465 2 P 0 ;0,1,2=96,3=0.000000
L 1.7380003 2.465 1.7380003 2.49 2 P 0 ;0,1,2=96,3=0.000000
L 1.7380003 2.49 1.7412001 2.4850003 2 P 0 ;0,1,2=96,3=0.000000
L 1.7412001 2.465 1.73480049 2.465 2 P 0 ;0,1,2=96,3=0.000000
L 1.71986673 2.46874911 1.71826703 2.46666624 2 P 0 ;0,1,2=96,3=0.000000
L 1.71826703 2.46666624 1.7164003 2.46541654 2 P 0 ;0,1,2=96,3=0.000000
L 1.7164003 2.46541654 1.7140003 2.465 2 P 0 ;0,1,2=96,3=0.000000
L 1.7140003 2.465 1.7115998 2.46583307 2 P 0 ;0,1,2=96,3=0.000000
L 1.7115998 2.46583307 1.70973356 2.46749941 2 P 0 ;0,1,2=96,3=0.000000
L 1.70973356 2.46749941 1.7084 2.47041624 2 P 0 ;0,1,2=96,3=0.000000
L 1.7084 2.47041624 1.70813337 2.47374961 2 P 0 ;0,1,2=96,3=0.000000
L 1.70813337 2.47374961 1.70866663 2.47708297 2 P 0 ;0,1,2=96,3=0.000000
L 1.70866663 2.47708297 1.7100002 2.47916663 2 P 0 ;0,1,2=96,3=0.000000
L 1.7100002 2.47916663 1.71186693 2.48083297 2 P 0 ;0,1,2=96,3=0.000000
L 1.71186693 2.48083297 1.71373317 2.48124951 2 P 0 ;0,1,2=96,3=0.000000
L 1.71373317 2.48124951 1.7156 2.48083297 2 P 0 ;0,1,2=96,3=0.000000
L 1.7156 2.48083297 1.7179999 2.47916663 2 P 0 ;0,1,2=96,3=0.000000
L 1.7179999 2.47916663 1.7172001 2.49 2 P 0 ;0,1,2=96,3=0.000000
L 1.7172001 2.49 1.7100002 2.49 2 P 0 ;0,1,2=96,3=0.000000
L 1.6900003 2.49 1.69213366 2.48916683 2 P 0 ;0,1,2=96,3=0.000000
L 1.69213366 2.48916683 1.69373337 2.48708317 2 P 0 ;0,1,2=96,3=0.000000
L 1.69373337 2.48708317 1.6948002 2.48458366 2 P 0 ;0,1,2=96,3=0.000000
L 1.6948002 2.48458366 1.6956001 2.48124951 2 P 0 ;0,1,2=96,3=0.000000
L 1.6956001 2.48124951 1.69586673 2.47749961 2 P 0 ;0,1,2=96,3=0.000000
L 1.69586673 2.47749961 1.6956001 2.47374961 2 P 0 ;0,1,2=96,3=0.000000
L 1.6956001 2.47374961 1.6948002 2.47041624 2 P 0 ;0,1,2=96,3=0.000000
L 1.6948002 2.47041624 1.69373337 2.46791604 2 P 0 ;0,1,2=96,3=0.000000
L 1.69373337 2.46791604 1.69213366 2.46583307 2 P 0 ;0,1,2=96,3=0.000000
L 1.69213366 2.46583307 1.6900003 2.465 2 P 0 ;0,1,2=96,3=0.000000
L 1.6900003 2.465 1.68786693 2.46583307 2 P 0 ;0,1,2=96,3=0.000000
L 1.68786693 2.46583307 1.68626673 2.46791604 2 P 0 ;0,1,2=96,3=0.000000
L 1.68626673 2.46791604 1.6851999 2.47041624 2 P 0 ;0,1,2=96,3=0.000000
L 1.6851999 2.47041624 1.6844 2.47374961 2 P 0 ;0,1,2=96,3=0.000000
L 1.6844 2.47374961 1.68413337 2.47749961 2 P 0 ;0,1,2=96,3=0.000000
L 1.68413337 2.47749961 1.6844 2.48124951 2 P 0 ;0,1,2=96,3=0.000000
L 1.6844 2.48124951 1.6851999 2.48458366 2 P 0 ;0,1,2=96,3=0.000000
L 1.6851999 2.48458366 1.68626673 2.48708317 2 P 0 ;0,1,2=96,3=0.000000
L 1.68626673 2.48708317 1.68786693 2.48916683 2 P 0 ;0,1,2=96,3=0.000000
L 1.68786693 2.48916683 1.6900003 2.49 2 P 0 ;0,1,2=96,3=0.000000
L 1.67186673 2.46999961 1.67026703 2.46708287 2 P 0 ;0,1,2=96,3=0.000000
L 1.67026703 2.46708287 1.66813366 2.46541654 2 P 0 ;0,1,2=96,3=0.000000
L 1.66813366 2.46541654 1.66573317 2.465 2 P 0 ;0,1,2=96,3=0.000000
L 1.66573317 2.465 1.6635998 2.46541654 2 P 0 ;0,1,2=96,3=0.000000
L 1.6635998 2.46541654 1.66146644 2.46749941 2 P 0 ;0,1,2=96,3=0.000000
L 1.66146644 2.46749941 1.66013337 2.46999961 2 P 0 ;0,1,2=96,3=0.000000
L 1.66013337 2.46999961 1.65986683 2.4724999 2 P 0 ;0,1,2=96,3=0.000000
L 1.65986683 2.4724999 1.6604 2.47541594 2 P 0 ;0,1,2=96,3=0.000000
L 1.6604 2.47541594 1.66226673 2.47749961 2 P 0 ;0,1,2=96,3=0.000000
L 1.66226673 2.47749961 1.66413356 2.47833346 2 P 0 ;0,1,2=96,3=0.000000
L 1.66413356 2.47833346 1.66653346 2.47833346 2 P 0 ;0,1,2=96,3=0.000000
L 1.66413356 2.47833346 1.66253337 2.47958327 2 P 0 ;0,1,2=96,3=0.000000
L 1.66253337 2.47958327 1.6611999 2.48166614 2 P 0 ;0,1,2=96,3=0.000000
L 1.6611999 2.48166614 1.66066663 2.48416634 2 P 0 ;0,1,2=96,3=0.000000
L 1.66066663 2.48416634 1.6611999 2.48666654 2 P 0 ;0,1,2=96,3=0.000000
L 1.6611999 2.48666654 1.66253337 2.48874941 2 P 0 ;0,1,2=96,3=0.000000
L 1.66253337 2.48874941 1.66493337 2.49 2 P 0 ;0,1,2=96,3=0.000000
L 1.66493337 2.49 1.66733337 2.48958337 2 P 0 ;0,1,2=96,3=0.000000
L 1.66733337 2.48958337 1.66973337 2.48791634 2 P 0 ;0,1,2=96,3=0.000000
L 1.31118996 4.95851004 1.32693002 4.95851004 3 P 0 
L 1.295 4.80766654 1.32 4.80766654 2 P 0 ;0,1,2=97,3=90.000000
L 1.32 4.80766654 1.32 4.81433327 2 P 0 ;0,1,2=97,3=90.000000
L 1.32 4.81433327 1.31874941 4.81646663 2 P 0 ;0,1,2=97,3=90.000000
L 1.31874941 4.81646663 1.31708317 4.8178001 2 P 0 ;0,1,2=97,3=90.000000
L 1.31708317 4.8178001 1.3137498 4.81833337 2 P 0 ;0,1,2=97,3=90.000000
L 1.3137498 4.81833337 1.31041634 4.8178001 2 P 0 ;0,1,2=97,3=90.000000
L 1.31041634 4.8178001 1.30833346 4.8162 2 P 0 ;0,1,2=97,3=90.000000
L 1.30833346 4.8162 1.30708297 4.81433327 2 P 0 ;0,1,2=97,3=90.000000
L 1.30708297 4.81433327 1.30708297 4.80766654 2 P 0 ;0,1,2=97,3=90.000000
L 1.30708297 4.81433327 1.295 4.81833337 2 P 0 ;0,1,2=97,3=90.000000
L 1.295 4.8369997 1.32 4.8369997 2 P 0 ;0,1,2=97,3=90.000000
L 1.32 4.8369997 1.3150003 4.8337999 2 P 0 ;0,1,2=97,3=90.000000
L 1.295 4.8337999 1.295 4.84019951 2 P 0 ;0,1,2=97,3=90.000000
L 1.29874911 4.85513327 1.29666624 4.85673297 2 P 0 ;0,1,2=97,3=90.000000
L 1.29666624 4.85673297 1.29541654 4.8585997 2 P 0 ;0,1,2=97,3=90.000000
L 1.29541654 4.8585997 1.295 4.8609997 2 P 0 ;0,1,2=97,3=90.000000
L 1.295 4.8609997 1.29583307 4.8634002 2 P 0 ;0,1,2=97,3=90.000000
L 1.29583307 4.8634002 1.29749941 4.86526644 2 P 0 ;0,1,2=97,3=90.000000
L 1.29749941 4.86526644 1.30041624 4.8666 2 P 0 ;0,1,2=97,3=90.000000
L 1.30041624 4.8666 1.30374961 4.86686663 2 P 0 ;0,1,2=97,3=90.000000
L 1.30374961 4.86686663 1.30708297 4.86633337 2 P 0 ;0,1,2=97,3=90.000000
L 1.30708297 4.86633337 1.30916663 4.8649998 2 P 0 ;0,1,2=97,3=90.000000
L 1.30916663 4.8649998 1.31083297 4.86313307 2 P 0 ;0,1,2=97,3=90.000000
L 1.31083297 4.86313307 1.31124951 4.86126683 2 P 0 ;0,1,2=97,3=90.000000
L 1.31124951 4.86126683 1.31083297 4.8594 2 P 0 ;0,1,2=97,3=90.000000
L 1.31083297 4.8594 1.30916663 4.8570001 2 P 0 ;0,1,2=97,3=90.000000
L 1.30916663 4.8570001 1.32 4.8577999 2 P 0 ;0,1,2=97,3=90.000000
L 1.32 4.8577999 1.32 4.8649998 2 P 0 ;0,1,2=97,3=90.000000
L 1.32 4.8849997 1.31916683 4.88286634 2 P 0 ;0,1,2=97,3=90.000000
L 1.31916683 4.88286634 1.31708317 4.88126663 2 P 0 ;0,1,2=97,3=90.000000
L 1.31708317 4.88126663 1.31458366 4.8801998 2 P 0 ;0,1,2=97,3=90.000000
L 1.31458366 4.8801998 1.31124951 4.8793999 2 P 0 ;0,1,2=97,3=90.000000
L 1.31124951 4.8793999 1.30749961 4.87913327 2 P 0 ;0,1,2=97,3=90.000000
L 1.30749961 4.87913327 1.30374961 4.8793999 2 P 0 ;0,1,2=97,3=90.000000
L 1.30374961 4.8793999 1.30041624 4.8801998 2 P 0 ;0,1,2=97,3=90.000000
L 1.30041624 4.8801998 1.29791604 4.88126663 2 P 0 ;0,1,2=97,3=90.000000
L 1.29791604 4.88126663 1.29583307 4.88286634 2 P 0 ;0,1,2=97,3=90.000000
L 1.29583307 4.88286634 1.295 4.8849997 2 P 0 ;0,1,2=97,3=90.000000
L 1.295 4.8849997 1.29583307 4.88713307 2 P 0 ;0,1,2=97,3=90.000000
L 1.29583307 4.88713307 1.29791604 4.88873327 2 P 0 ;0,1,2=97,3=90.000000
L 1.29791604 4.88873327 1.30041624 4.8898001 2 P 0 ;0,1,2=97,3=90.000000
L 1.30041624 4.8898001 1.30374961 4.8906 2 P 0 ;0,1,2=97,3=90.000000
L 1.30374961 4.8906 1.30749961 4.89086663 2 P 0 ;0,1,2=97,3=90.000000
L 1.30749961 4.89086663 1.31124951 4.8906 2 P 0 ;0,1,2=97,3=90.000000
L 1.31124951 4.8906 1.31458366 4.8898001 2 P 0 ;0,1,2=97,3=90.000000
L 1.31458366 4.8898001 1.31708317 4.88873327 2 P 0 ;0,1,2=97,3=90.000000
L 1.31708317 4.88873327 1.31916683 4.88713307 2 P 0 ;0,1,2=97,3=90.000000
L 1.31916683 4.88713307 1.32 4.8849997 2 P 0 ;0,1,2=97,3=90.000000
L 1.31583337 4.90393317 1.31833287 4.90553327 2 P 0 ;0,1,2=97,3=90.000000
L 1.31833287 4.90553327 1.31958337 4.9074 2 P 0 ;0,1,2=97,3=90.000000
L 1.31958337 4.9074 1.32 4.90953337 2 P 0 ;0,1,2=97,3=90.000000
L 1.32 4.90953337 1.31916683 4.9122 2 P 0 ;0,1,2=97,3=90.000000
L 1.31916683 4.9122 1.31708317 4.91406673 2 P 0 ;0,1,2=97,3=90.000000
L 1.31708317 4.91406673 1.31458366 4.9146 2 P 0 ;0,1,2=97,3=90.000000
L 1.31458366 4.9146 1.31208268 4.91433337 2 P 0 ;0,1,2=97,3=90.000000
L 1.31208268 4.91433337 1.3099998 4.91326644 2 P 0 ;0,1,2=97,3=90.000000
L 1.3099998 4.91326644 1.30583327 4.90793327 2 P 0 ;0,1,2=97,3=90.000000
L 1.30583327 4.90793327 1.30291644 4.90553327 2 P 0 ;0,1,2=97,3=90.000000
L 1.30291644 4.90553327 1.29874911 4.90393317 2 P 0 ;0,1,2=97,3=90.000000
L 1.29874911 4.90393317 1.295 4.9033999 2 P 0 ;0,1,2=97,3=90.000000
L 1.295 4.9033999 1.295 4.9146 2 P 0 ;0,1,2=97,3=90.000000
L 1.26118996 4.95851004 1.27693002 4.95851004 3 P 0 
L 1.255 4.80766654 1.28 4.80766654 2 P 0 ;0,1,2=98,3=90.000000
L 1.28 4.80766654 1.28 4.81433327 2 P 0 ;0,1,2=98,3=90.000000
L 1.28 4.81433327 1.27874941 4.81646663 2 P 0 ;0,1,2=98,3=90.000000
L 1.27874941 4.81646663 1.27708317 4.8178001 2 P 0 ;0,1,2=98,3=90.000000
L 1.27708317 4.8178001 1.2737498 4.81833337 2 P 0 ;0,1,2=98,3=90.000000
L 1.2737498 4.81833337 1.27041634 4.8178001 2 P 0 ;0,1,2=98,3=90.000000
L 1.27041634 4.8178001 1.26833346 4.8162 2 P 0 ;0,1,2=98,3=90.000000
L 1.26833346 4.8162 1.26708297 4.81433327 2 P 0 ;0,1,2=98,3=90.000000
L 1.26708297 4.81433327 1.26708297 4.80766654 2 P 0 ;0,1,2=98,3=90.000000
L 1.26708297 4.81433327 1.255 4.81833337 2 P 0 ;0,1,2=98,3=90.000000
L 1.255 4.8369997 1.28 4.8369997 2 P 0 ;0,1,2=98,3=90.000000
L 1.28 4.8369997 1.2750003 4.8337999 2 P 0 ;0,1,2=98,3=90.000000
L 1.255 4.8337999 1.255 4.84019951 2 P 0 ;0,1,2=98,3=90.000000
L 1.25874911 4.85513327 1.25666624 4.85673297 2 P 0 ;0,1,2=98,3=90.000000
L 1.25666624 4.85673297 1.25541654 4.8585997 2 P 0 ;0,1,2=98,3=90.000000
L 1.25541654 4.8585997 1.255 4.8609997 2 P 0 ;0,1,2=98,3=90.000000
L 1.255 4.8609997 1.25583307 4.8634002 2 P 0 ;0,1,2=98,3=90.000000
L 1.25583307 4.8634002 1.25749941 4.86526644 2 P 0 ;0,1,2=98,3=90.000000
L 1.25749941 4.86526644 1.26041624 4.8666 2 P 0 ;0,1,2=98,3=90.000000
L 1.26041624 4.8666 1.26374961 4.86686663 2 P 0 ;0,1,2=98,3=90.000000
L 1.26374961 4.86686663 1.26708297 4.86633337 2 P 0 ;0,1,2=98,3=90.000000
L 1.26708297 4.86633337 1.26916663 4.8649998 2 P 0 ;0,1,2=98,3=90.000000
L 1.26916663 4.8649998 1.27083297 4.86313307 2 P 0 ;0,1,2=98,3=90.000000
L 1.27083297 4.86313307 1.27124951 4.86126683 2 P 0 ;0,1,2=98,3=90.000000
L 1.27124951 4.86126683 1.27083297 4.8594 2 P 0 ;0,1,2=98,3=90.000000
L 1.27083297 4.8594 1.26916663 4.8570001 2 P 0 ;0,1,2=98,3=90.000000
L 1.26916663 4.8570001 1.28 4.8577999 2 P 0 ;0,1,2=98,3=90.000000
L 1.28 4.8577999 1.28 4.8649998 2 P 0 ;0,1,2=98,3=90.000000
L 1.28 4.8849997 1.27916683 4.88286634 2 P 0 ;0,1,2=98,3=90.000000
L 1.27916683 4.88286634 1.27708317 4.88126663 2 P 0 ;0,1,2=98,3=90.000000
L 1.27708317 4.88126663 1.27458366 4.8801998 2 P 0 ;0,1,2=98,3=90.000000
L 1.27458366 4.8801998 1.27124951 4.8793999 2 P 0 ;0,1,2=98,3=90.000000
L 1.27124951 4.8793999 1.26749961 4.87913327 2 P 0 ;0,1,2=98,3=90.000000
L 1.26749961 4.87913327 1.26374961 4.8793999 2 P 0 ;0,1,2=98,3=90.000000
L 1.26374961 4.8793999 1.26041624 4.8801998 2 P 0 ;0,1,2=98,3=90.000000
L 1.26041624 4.8801998 1.25791604 4.88126663 2 P 0 ;0,1,2=98,3=90.000000
L 1.25791604 4.88126663 1.25583307 4.88286634 2 P 0 ;0,1,2=98,3=90.000000
L 1.25583307 4.88286634 1.255 4.8849997 2 P 0 ;0,1,2=98,3=90.000000
L 1.255 4.8849997 1.25583307 4.88713307 2 P 0 ;0,1,2=98,3=90.000000
L 1.25583307 4.88713307 1.25791604 4.88873327 2 P 0 ;0,1,2=98,3=90.000000
L 1.25791604 4.88873327 1.26041624 4.8898001 2 P 0 ;0,1,2=98,3=90.000000
L 1.26041624 4.8898001 1.26374961 4.8906 2 P 0 ;0,1,2=98,3=90.000000
L 1.26374961 4.8906 1.26749961 4.89086663 2 P 0 ;0,1,2=98,3=90.000000
L 1.26749961 4.89086663 1.27124951 4.8906 2 P 0 ;0,1,2=98,3=90.000000
L 1.27124951 4.8906 1.27458366 4.8898001 2 P 0 ;0,1,2=98,3=90.000000
L 1.27458366 4.8898001 1.27708317 4.88873327 2 P 0 ;0,1,2=98,3=90.000000
L 1.27708317 4.88873327 1.27916683 4.88713307 2 P 0 ;0,1,2=98,3=90.000000
L 1.27916683 4.88713307 1.28 4.8849997 2 P 0 ;0,1,2=98,3=90.000000
L 1.255 4.9089997 1.28 4.9089997 2 P 0 ;0,1,2=98,3=90.000000
L 1.28 4.9089997 1.2750003 4.9057999 2 P 0 ;0,1,2=98,3=90.000000
L 1.255 4.9057999 1.255 4.91219951 2 P 0 ;0,1,2=98,3=90.000000
L 1.84 3.50213002 1.84 3.51786998 3 P 0 
L 1.7872935 3.49583002 1.7872935 3.52083002 2 P 0 ;0,1,2=99,3=0.000000
L 1.7872935 3.52083002 1.78062677 3.52083002 2 P 0 ;0,1,2=99,3=0.000000
L 1.78062677 3.52083002 1.77849341 3.51957943 2 P 0 ;0,1,2=99,3=0.000000
L 1.77849341 3.51957943 1.77715994 3.51791319 2 P 0 ;0,1,2=99,3=0.000000
L 1.77715994 3.51791319 1.77662667 3.51457982 2 P 0 ;0,1,2=99,3=0.000000
L 1.77662667 3.51457982 1.77715994 3.51124636 2 P 0 ;0,1,2=99,3=0.000000
L 1.77715994 3.51124636 1.77876004 3.50916348 2 P 0 ;0,1,2=99,3=0.000000
L 1.77876004 3.50916348 1.78062677 3.50791299 2 P 0 ;0,1,2=99,3=0.000000
L 1.78062677 3.50791299 1.7872935 3.50791299 2 P 0 ;0,1,2=99,3=0.000000
L 1.78062677 3.50791299 1.77662667 3.49583002 2 P 0 ;0,1,2=99,3=0.000000
L 1.75796033 3.49583002 1.75796033 3.52083002 2 P 0 ;0,1,2=99,3=0.000000
L 1.75796033 3.52083002 1.76116014 3.51583032 2 P 0 ;0,1,2=99,3=0.000000
L 1.76116014 3.49583002 1.75476053 3.49583002 2 P 0 ;0,1,2=99,3=0.000000
L 1.73076004 3.49583002 1.73076004 3.52083002 2 P 0 ;0,1,2=99,3=0.000000
L 1.73076004 3.52083002 1.74062707 3.50291329 2 P 0 ;0,1,2=99,3=0.000000
L 1.74062707 3.50291329 1.72729311 3.50291329 2 P 0 ;0,1,2=99,3=0.000000
L 1.7144937 3.49874606 1.71262687 3.49666309 2 P 0 ;0,1,2=99,3=0.000000
L 1.71262687 3.49666309 1.7104935 3.49583002 2 P 0 ;0,1,2=99,3=0.000000
L 1.7104935 3.49583002 1.70836014 3.49666309 2 P 0 ;0,1,2=99,3=0.000000
L 1.70836014 3.49666309 1.70649341 3.4991626 2 P 0 ;0,1,2=99,3=0.000000
L 1.70649341 3.4991626 1.70515994 3.50291329 2 P 0 ;0,1,2=99,3=0.000000
L 1.70515994 3.50291329 1.70462667 3.50666329 2 P 0 ;0,1,2=99,3=0.000000
L 1.70462667 3.50666329 1.70462667 3.51124636 2 P 0 ;0,1,2=99,3=0.000000
L 1.70462667 3.51124636 1.70515994 3.51499636 2 P 0 ;0,1,2=99,3=0.000000
L 1.70515994 3.51499636 1.70649341 3.51832972 2 P 0 ;0,1,2=99,3=0.000000
L 1.70649341 3.51832972 1.7080936 3.51999685 2 P 0 ;0,1,2=99,3=0.000000
L 1.7080936 3.51999685 1.70996033 3.52083002 2 P 0 ;0,1,2=99,3=0.000000
L 1.70996033 3.52083002 1.7120937 3.51999685 2 P 0 ;0,1,2=99,3=0.000000
L 1.7120937 3.51999685 1.71369341 3.51832972 2 P 0 ;0,1,2=99,3=0.000000
L 1.71369341 3.51832972 1.71476024 3.51583032 2 P 0 ;0,1,2=99,3=0.000000
L 1.71476024 3.51583032 1.7152935 3.51249616 2 P 0 ;0,1,2=99,3=0.000000
L 1.7152935 3.51249616 1.71476024 3.50958012 2 P 0 ;0,1,2=99,3=0.000000
L 1.71476024 3.50958012 1.71342677 3.50666329 2 P 0 ;0,1,2=99,3=0.000000
L 1.71342677 3.50666329 1.71182657 3.50499616 2 P 0 ;0,1,2=99,3=0.000000
L 1.71182657 3.50499616 1.70996033 3.50457963 2 P 0 ;0,1,2=99,3=0.000000
L 1.70996033 3.50457963 1.70782697 3.5054128 2 P 0 ;0,1,2=99,3=0.000000
L 1.70782697 3.5054128 1.70622677 3.50749646 2 P 0 ;0,1,2=99,3=0.000000
L 1.70622677 3.50749646 1.70462667 3.51124636 2 P 0 ;0,1,2=99,3=0.000000
L 1.68276004 3.49583002 1.68276004 3.52083002 2 P 0 ;0,1,2=99,3=0.000000
L 1.68276004 3.52083002 1.69262707 3.50291329 2 P 0 ;0,1,2=99,3=0.000000
L 1.69262707 3.50291329 1.67929311 3.50291329 2 P 0 ;0,1,2=99,3=0.000000
L 1.84 3.55213002 1.84 3.56786998 3 P 0 
L 1.7872935 3.54583002 1.7872935 3.57083002 2 P 0 ;0,1,2=100,3=0.000000
L 1.7872935 3.57083002 1.78062677 3.57083002 2 P 0 ;0,1,2=100,3=0.000000
L 1.78062677 3.57083002 1.77849341 3.56957943 2 P 0 ;0,1,2=100,3=0.000000
L 1.77849341 3.56957943 1.77715994 3.56791319 2 P 0 ;0,1,2=100,3=0.000000
L 1.77715994 3.56791319 1.77662667 3.56457982 2 P 0 ;0,1,2=100,3=0.000000
L 1.77662667 3.56457982 1.77715994 3.56124636 2 P 0 ;0,1,2=100,3=0.000000
L 1.77715994 3.56124636 1.77876004 3.55916348 2 P 0 ;0,1,2=100,3=0.000000
L 1.77876004 3.55916348 1.78062677 3.55791299 2 P 0 ;0,1,2=100,3=0.000000
L 1.78062677 3.55791299 1.7872935 3.55791299 2 P 0 ;0,1,2=100,3=0.000000
L 1.78062677 3.55791299 1.77662667 3.54583002 2 P 0 ;0,1,2=100,3=0.000000
L 1.75796033 3.54583002 1.75796033 3.57083002 2 P 0 ;0,1,2=100,3=0.000000
L 1.75796033 3.57083002 1.76116014 3.56583032 2 P 0 ;0,1,2=100,3=0.000000
L 1.76116014 3.54583002 1.75476053 3.54583002 2 P 0 ;0,1,2=100,3=0.000000
L 1.73076004 3.54583002 1.73076004 3.57083002 2 P 0 ;0,1,2=100,3=0.000000
L 1.73076004 3.57083002 1.74062707 3.55291329 2 P 0 ;0,1,2=100,3=0.000000
L 1.74062707 3.55291329 1.72729311 3.55291329 2 P 0 ;0,1,2=100,3=0.000000
L 1.7144937 3.54874606 1.71262687 3.54666309 2 P 0 ;0,1,2=100,3=0.000000
L 1.71262687 3.54666309 1.7104935 3.54583002 2 P 0 ;0,1,2=100,3=0.000000
L 1.7104935 3.54583002 1.70836014 3.54666309 2 P 0 ;0,1,2=100,3=0.000000
L 1.70836014 3.54666309 1.70649341 3.5491626 2 P 0 ;0,1,2=100,3=0.000000
L 1.70649341 3.5491626 1.70515994 3.55291329 2 P 0 ;0,1,2=100,3=0.000000
L 1.70515994 3.55291329 1.70462667 3.55666329 2 P 0 ;0,1,2=100,3=0.000000
L 1.70462667 3.55666329 1.70462667 3.56124636 2 P 0 ;0,1,2=100,3=0.000000
L 1.70462667 3.56124636 1.70515994 3.56499636 2 P 0 ;0,1,2=100,3=0.000000
L 1.70515994 3.56499636 1.70649341 3.56832972 2 P 0 ;0,1,2=100,3=0.000000
L 1.70649341 3.56832972 1.7080936 3.56999685 2 P 0 ;0,1,2=100,3=0.000000
L 1.7080936 3.56999685 1.70996033 3.57083002 2 P 0 ;0,1,2=100,3=0.000000
L 1.70996033 3.57083002 1.7120937 3.56999685 2 P 0 ;0,1,2=100,3=0.000000
L 1.7120937 3.56999685 1.71369341 3.56832972 2 P 0 ;0,1,2=100,3=0.000000
L 1.71369341 3.56832972 1.71476024 3.56583032 2 P 0 ;0,1,2=100,3=0.000000
L 1.71476024 3.56583032 1.7152935 3.56249616 2 P 0 ;0,1,2=100,3=0.000000
L 1.7152935 3.56249616 1.71476024 3.55958012 2 P 0 ;0,1,2=100,3=0.000000
L 1.71476024 3.55958012 1.71342677 3.55666329 2 P 0 ;0,1,2=100,3=0.000000
L 1.71342677 3.55666329 1.71182657 3.55499616 2 P 0 ;0,1,2=100,3=0.000000
L 1.71182657 3.55499616 1.70996033 3.55457963 2 P 0 ;0,1,2=100,3=0.000000
L 1.70996033 3.55457963 1.70782697 3.5554128 2 P 0 ;0,1,2=100,3=0.000000
L 1.70782697 3.5554128 1.70622677 3.55749646 2 P 0 ;0,1,2=100,3=0.000000
L 1.70622677 3.55749646 1.70462667 3.56124636 2 P 0 ;0,1,2=100,3=0.000000
L 1.69182677 3.55082963 1.69022707 3.54791289 2 P 0 ;0,1,2=100,3=0.000000
L 1.69022707 3.54791289 1.6880937 3.54624656 2 P 0 ;0,1,2=100,3=0.000000
L 1.6880937 3.54624656 1.68569321 3.54583002 2 P 0 ;0,1,2=100,3=0.000000
L 1.68569321 3.54583002 1.68355984 3.54624656 2 P 0 ;0,1,2=100,3=0.000000
L 1.68355984 3.54624656 1.68142648 3.54832943 2 P 0 ;0,1,2=100,3=0.000000
L 1.68142648 3.54832943 1.68009341 3.55082963 2 P 0 ;0,1,2=100,3=0.000000
L 1.68009341 3.55082963 1.67982687 3.55332992 2 P 0 ;0,1,2=100,3=0.000000
L 1.67982687 3.55332992 1.68036004 3.55624596 2 P 0 ;0,1,2=100,3=0.000000
L 1.68036004 3.55624596 1.68222677 3.55832963 2 P 0 ;0,1,2=100,3=0.000000
L 1.68222677 3.55832963 1.6840936 3.55916348 2 P 0 ;0,1,2=100,3=0.000000
L 1.6840936 3.55916348 1.6864935 3.55916348 2 P 0 ;0,1,2=100,3=0.000000
L 1.6840936 3.55916348 1.68249341 3.56041329 2 P 0 ;0,1,2=100,3=0.000000
L 1.68249341 3.56041329 1.68115994 3.56249616 2 P 0 ;0,1,2=100,3=0.000000
L 1.68115994 3.56249616 1.68062667 3.56499636 2 P 0 ;0,1,2=100,3=0.000000
L 1.68062667 3.56499636 1.68115994 3.56749656 2 P 0 ;0,1,2=100,3=0.000000
L 1.68115994 3.56749656 1.68249341 3.56957943 2 P 0 ;0,1,2=100,3=0.000000
L 1.68249341 3.56957943 1.68489341 3.57083002 2 P 0 ;0,1,2=100,3=0.000000
L 1.68489341 3.57083002 1.68729341 3.57041339 2 P 0 ;0,1,2=100,3=0.000000
L 1.68729341 3.57041339 1.68969341 3.56874636 2 P 0 ;0,1,2=100,3=0.000000
L 5.9 3.02786998 5.9 3.01213002 3 P 0 
L 6.05733346 3.005 6.05733346 3.03 2 P 0 ;0,1,2=101,3=0.000000
L 6.05733346 3.03 6.05066673 3.03 2 P 0 ;0,1,2=101,3=0.000000
L 6.05066673 3.03 6.04853337 3.02874941 2 P 0 ;0,1,2=101,3=0.000000
L 6.04853337 3.02874941 6.0471999 3.02708317 2 P 0 ;0,1,2=101,3=0.000000
L 6.0471999 3.02708317 6.04666663 3.0237498 2 P 0 ;0,1,2=101,3=0.000000
L 6.04666663 3.0237498 6.0471999 3.02041634 2 P 0 ;0,1,2=101,3=0.000000
L 6.0471999 3.02041634 6.0488 3.01833346 2 P 0 ;0,1,2=101,3=0.000000
L 6.0488 3.01833346 6.05066673 3.01708297 2 P 0 ;0,1,2=101,3=0.000000
L 6.05066673 3.01708297 6.05733346 3.01708297 2 P 0 ;0,1,2=101,3=0.000000
L 6.05066673 3.01708297 6.04666663 3.005 2 P 0 ;0,1,2=101,3=0.000000
L 6.0280003 3.005 6.0280003 3.03 2 P 0 ;0,1,2=101,3=0.000000
L 6.0280003 3.03 6.0312001 3.0250003 2 P 0 ;0,1,2=101,3=0.000000
L 6.0312001 3.005 6.02480049 3.005 2 P 0 ;0,1,2=101,3=0.000000
L 6.0008 3.005 6.0008 3.03 2 P 0 ;0,1,2=101,3=0.000000
L 6.0008 3.03 6.01066703 3.01208327 2 P 0 ;0,1,2=101,3=0.000000
L 6.01066703 3.01208327 5.99733307 3.01208327 2 P 0 ;0,1,2=101,3=0.000000
L 5.98053346 3.005 5.9800003 3.01041624 2 P 0 ;0,1,2=101,3=0.000000
L 5.9800003 3.01041624 5.9792 3.01499931 2 P 0 ;0,1,2=101,3=0.000000
L 5.9792 3.01499931 5.97813356 3.01916663 2 P 0 ;0,1,2=101,3=0.000000
L 5.97813356 3.01916663 5.9768 3.0237498 2 P 0 ;0,1,2=101,3=0.000000
L 5.9768 3.0237498 5.97466663 3.03 2 P 0 ;0,1,2=101,3=0.000000
L 5.97466663 3.03 5.98533346 3.03 2 P 0 ;0,1,2=101,3=0.000000
L 5.96106683 3.02583337 5.95946673 3.02833287 2 P 0 ;0,1,2=101,3=0.000000
L 5.95946673 3.02833287 5.9576 3.02958337 2 P 0 ;0,1,2=101,3=0.000000
L 5.9576 3.02958337 5.95546663 3.03 2 P 0 ;0,1,2=101,3=0.000000
L 5.95546663 3.03 5.9528 3.02916683 2 P 0 ;0,1,2=101,3=0.000000
L 5.9528 3.02916683 5.95093327 3.02708317 2 P 0 ;0,1,2=101,3=0.000000
L 5.95093327 3.02708317 5.9504 3.02458366 2 P 0 ;0,1,2=101,3=0.000000
L 5.9504 3.02458366 5.95066663 3.02208268 2 P 0 ;0,1,2=101,3=0.000000
L 5.95066663 3.02208268 5.95173356 3.0199998 2 P 0 ;0,1,2=101,3=0.000000
L 5.95173356 3.0199998 5.95706673 3.01583327 2 P 0 ;0,1,2=101,3=0.000000
L 5.95706673 3.01583327 5.95946673 3.01291644 2 P 0 ;0,1,2=101,3=0.000000
L 5.95946673 3.01291644 5.96106683 3.00874911 2 P 0 ;0,1,2=101,3=0.000000
L 5.96106683 3.00874911 5.9616001 3.005 2 P 0 ;0,1,2=101,3=0.000000
L 5.9616001 3.005 5.9504 3.005 2 P 0 ;0,1,2=101,3=0.000000
L 3.13358996 5.315 3.14933002 5.315 3 P 0 
L 3.13 5.36266654 3.155 5.36266654 2 P 0 ;0,1,2=102,3=90.000000
L 3.155 5.36266654 3.155 5.36933327 2 P 0 ;0,1,2=102,3=90.000000
L 3.155 5.36933327 3.15374941 5.37146663 2 P 0 ;0,1,2=102,3=90.000000
L 3.15374941 5.37146663 3.15208317 5.3728001 2 P 0 ;0,1,2=102,3=90.000000
L 3.15208317 5.3728001 3.1487498 5.37333337 2 P 0 ;0,1,2=102,3=90.000000
L 3.1487498 5.37333337 3.14541634 5.3728001 2 P 0 ;0,1,2=102,3=90.000000
L 3.14541634 5.3728001 3.14333346 5.3712 2 P 0 ;0,1,2=102,3=90.000000
L 3.14333346 5.3712 3.14208297 5.36933327 2 P 0 ;0,1,2=102,3=90.000000
L 3.14208297 5.36933327 3.14208297 5.36266654 2 P 0 ;0,1,2=102,3=90.000000
L 3.14208297 5.36933327 3.13 5.37333337 2 P 0 ;0,1,2=102,3=90.000000
L 3.13 5.3919997 3.155 5.3919997 2 P 0 ;0,1,2=102,3=90.000000
L 3.155 5.3919997 3.1500003 5.3887999 2 P 0 ;0,1,2=102,3=90.000000
L 3.13 5.3887999 3.13 5.39519951 2 P 0 ;0,1,2=102,3=90.000000
L 3.13374911 5.41013327 3.13166624 5.41173297 2 P 0 ;0,1,2=102,3=90.000000
L 3.13166624 5.41173297 3.13041654 5.4135997 2 P 0 ;0,1,2=102,3=90.000000
L 3.13041654 5.4135997 3.13 5.4159997 2 P 0 ;0,1,2=102,3=90.000000
L 3.13 5.4159997 3.13083307 5.4184002 2 P 0 ;0,1,2=102,3=90.000000
L 3.13083307 5.4184002 3.13249941 5.42026644 2 P 0 ;0,1,2=102,3=90.000000
L 3.13249941 5.42026644 3.13541624 5.4216 2 P 0 ;0,1,2=102,3=90.000000
L 3.13541624 5.4216 3.13874961 5.42186663 2 P 0 ;0,1,2=102,3=90.000000
L 3.13874961 5.42186663 3.14208297 5.42133337 2 P 0 ;0,1,2=102,3=90.000000
L 3.14208297 5.42133337 3.14416663 5.4199998 2 P 0 ;0,1,2=102,3=90.000000
L 3.14416663 5.4199998 3.14583297 5.41813307 2 P 0 ;0,1,2=102,3=90.000000
L 3.14583297 5.41813307 3.14624951 5.41626683 2 P 0 ;0,1,2=102,3=90.000000
L 3.14624951 5.41626683 3.14583297 5.4144 2 P 0 ;0,1,2=102,3=90.000000
L 3.14583297 5.4144 3.14416663 5.4120001 2 P 0 ;0,1,2=102,3=90.000000
L 3.14416663 5.4120001 3.155 5.4127999 2 P 0 ;0,1,2=102,3=90.000000
L 3.155 5.4127999 3.155 5.4199998 2 P 0 ;0,1,2=102,3=90.000000
L 3.13 5.4432 3.155 5.4432 2 P 0 ;0,1,2=102,3=90.000000
L 3.155 5.4432 3.13708327 5.43333297 2 P 0 ;0,1,2=102,3=90.000000
L 3.13708327 5.43333297 3.13708327 5.44666693 2 P 0 ;0,1,2=102,3=90.000000
L 3.13 5.4672 3.155 5.4672 2 P 0 ;0,1,2=102,3=90.000000
L 3.155 5.4672 3.13708327 5.45733297 2 P 0 ;0,1,2=102,3=90.000000
L 3.13708327 5.45733297 3.13708327 5.47066693 2 P 0 ;0,1,2=102,3=90.000000
L 11.33361998 2.73786998 11.33361998 2.72213002 3 P 0 
L 11.36233346 2.675 11.36233346 2.7 2 P 0 ;0,1,2=103,3=0.000000
L 11.36233346 2.7 11.35566673 2.7 2 P 0 ;0,1,2=103,3=0.000000
L 11.35566673 2.7 11.35353337 2.69874941 2 P 0 ;0,1,2=103,3=0.000000
L 11.35353337 2.69874941 11.3521999 2.69708317 2 P 0 ;0,1,2=103,3=0.000000
L 11.3521999 2.69708317 11.35166663 2.6937498 2 P 0 ;0,1,2=103,3=0.000000
L 11.35166663 2.6937498 11.3521999 2.69041634 2 P 0 ;0,1,2=103,3=0.000000
L 11.3521999 2.69041634 11.3538 2.68833346 2 P 0 ;0,1,2=103,3=0.000000
L 11.3538 2.68833346 11.35566673 2.68708297 2 P 0 ;0,1,2=103,3=0.000000
L 11.35566673 2.68708297 11.36233346 2.68708297 2 P 0 ;0,1,2=103,3=0.000000
L 11.35566673 2.68708297 11.35166663 2.675 2 P 0 ;0,1,2=103,3=0.000000
L 11.3330003 2.675 11.3330003 2.7 2 P 0 ;0,1,2=103,3=0.000000
L 11.3330003 2.7 11.3362001 2.6950003 2 P 0 ;0,1,2=103,3=0.000000
L 11.3362001 2.675 11.32980049 2.675 2 P 0 ;0,1,2=103,3=0.000000
L 11.31486673 2.67874911 11.31326703 2.67666624 2 P 0 ;0,1,2=103,3=0.000000
L 11.31326703 2.67666624 11.3114003 2.67541654 2 P 0 ;0,1,2=103,3=0.000000
L 11.3114003 2.67541654 11.3090003 2.675 2 P 0 ;0,1,2=103,3=0.000000
L 11.3090003 2.675 11.3065998 2.67583307 2 P 0 ;0,1,2=103,3=0.000000
L 11.3065998 2.67583307 11.30473356 2.67749941 2 P 0 ;0,1,2=103,3=0.000000
L 11.30473356 2.67749941 11.3034 2.68041624 2 P 0 ;0,1,2=103,3=0.000000
L 11.3034 2.68041624 11.30313337 2.68374961 2 P 0 ;0,1,2=103,3=0.000000
L 11.30313337 2.68374961 11.30366663 2.68708297 2 P 0 ;0,1,2=103,3=0.000000
L 11.30366663 2.68708297 11.3050002 2.68916663 2 P 0 ;0,1,2=103,3=0.000000
L 11.3050002 2.68916663 11.30686693 2.69083297 2 P 0 ;0,1,2=103,3=0.000000
L 11.30686693 2.69083297 11.30873317 2.69124951 2 P 0 ;0,1,2=103,3=0.000000
L 11.30873317 2.69124951 11.3106 2.69083297 2 P 0 ;0,1,2=103,3=0.000000
L 11.3106 2.69083297 11.3129999 2.68916663 2 P 0 ;0,1,2=103,3=0.000000
L 11.3129999 2.68916663 11.3122001 2.7 2 P 0 ;0,1,2=103,3=0.000000
L 11.3122001 2.7 11.3050002 2.7 2 P 0 ;0,1,2=103,3=0.000000
L 11.2850003 2.675 11.2850003 2.7 2 P 0 ;0,1,2=103,3=0.000000
L 11.2850003 2.7 11.2882001 2.6950003 2 P 0 ;0,1,2=103,3=0.000000
L 11.2882001 2.675 11.28180049 2.675 2 P 0 ;0,1,2=103,3=0.000000
L 11.26153346 2.675 11.2610003 2.68041624 2 P 0 ;0,1,2=103,3=0.000000
L 11.2610003 2.68041624 11.2602 2.68499931 2 P 0 ;0,1,2=103,3=0.000000
L 11.2602 2.68499931 11.25913356 2.68916663 2 P 0 ;0,1,2=103,3=0.000000
L 11.25913356 2.68916663 11.2578 2.6937498 2 P 0 ;0,1,2=103,3=0.000000
L 11.2578 2.6937498 11.25566663 2.7 2 P 0 ;0,1,2=103,3=0.000000
L 11.25566663 2.7 11.26633346 2.7 2 P 0 ;0,1,2=103,3=0.000000
L 11.33361998 2.80786998 11.33361998 2.79213002 3 P 0 
L 11.36233346 2.825 11.36233346 2.85 2 P 0 ;0,1,2=104,3=0.000000
L 11.36233346 2.85 11.35566673 2.85 2 P 0 ;0,1,2=104,3=0.000000
L 11.35566673 2.85 11.35353337 2.84874941 2 P 0 ;0,1,2=104,3=0.000000
L 11.35353337 2.84874941 11.3521999 2.84708317 2 P 0 ;0,1,2=104,3=0.000000
L 11.3521999 2.84708317 11.35166663 2.8437498 2 P 0 ;0,1,2=104,3=0.000000
L 11.35166663 2.8437498 11.3521999 2.84041634 2 P 0 ;0,1,2=104,3=0.000000
L 11.3521999 2.84041634 11.3538 2.83833346 2 P 0 ;0,1,2=104,3=0.000000
L 11.3538 2.83833346 11.35566673 2.83708297 2 P 0 ;0,1,2=104,3=0.000000
L 11.35566673 2.83708297 11.36233346 2.83708297 2 P 0 ;0,1,2=104,3=0.000000
L 11.35566673 2.83708297 11.35166663 2.825 2 P 0 ;0,1,2=104,3=0.000000
L 11.3330003 2.825 11.3330003 2.85 2 P 0 ;0,1,2=104,3=0.000000
L 11.3330003 2.85 11.3362001 2.8450003 2 P 0 ;0,1,2=104,3=0.000000
L 11.3362001 2.825 11.32980049 2.825 2 P 0 ;0,1,2=104,3=0.000000
L 11.31486673 2.82874911 11.31326703 2.82666624 2 P 0 ;0,1,2=104,3=0.000000
L 11.31326703 2.82666624 11.3114003 2.82541654 2 P 0 ;0,1,2=104,3=0.000000
L 11.3114003 2.82541654 11.3090003 2.825 2 P 0 ;0,1,2=104,3=0.000000
L 11.3090003 2.825 11.3065998 2.82583307 2 P 0 ;0,1,2=104,3=0.000000
L 11.3065998 2.82583307 11.30473356 2.82749941 2 P 0 ;0,1,2=104,3=0.000000
L 11.30473356 2.82749941 11.3034 2.83041624 2 P 0 ;0,1,2=104,3=0.000000
L 11.3034 2.83041624 11.30313337 2.83374961 2 P 0 ;0,1,2=104,3=0.000000
L 11.30313337 2.83374961 11.30366663 2.83708297 2 P 0 ;0,1,2=104,3=0.000000
L 11.30366663 2.83708297 11.3050002 2.83916663 2 P 0 ;0,1,2=104,3=0.000000
L 11.3050002 2.83916663 11.30686693 2.84083297 2 P 0 ;0,1,2=104,3=0.000000
L 11.30686693 2.84083297 11.30873317 2.84124951 2 P 0 ;0,1,2=104,3=0.000000
L 11.30873317 2.84124951 11.3106 2.84083297 2 P 0 ;0,1,2=104,3=0.000000
L 11.3106 2.84083297 11.3129999 2.83916663 2 P 0 ;0,1,2=104,3=0.000000
L 11.3129999 2.83916663 11.3122001 2.85 2 P 0 ;0,1,2=104,3=0.000000
L 11.3122001 2.85 11.3050002 2.85 2 P 0 ;0,1,2=104,3=0.000000
L 11.2850003 2.825 11.2850003 2.85 2 P 0 ;0,1,2=104,3=0.000000
L 11.2850003 2.85 11.2882001 2.8450003 2 P 0 ;0,1,2=104,3=0.000000
L 11.2882001 2.825 11.28180049 2.825 2 P 0 ;0,1,2=104,3=0.000000
L 11.26606683 2.83541594 11.2642001 2.83833346 2 P 0 ;0,1,2=104,3=0.000000
L 11.2642001 2.83833346 11.2626 2.8399998 2 P 0 ;0,1,2=104,3=0.000000
L 11.2626 2.8399998 11.26046663 2.84083297 2 P 0 ;0,1,2=104,3=0.000000
L 11.26046663 2.84083297 11.2585998 2.8399998 2 P 0 ;0,1,2=104,3=0.000000
L 11.2585998 2.8399998 11.25726673 2.83833346 2 P 0 ;0,1,2=104,3=0.000000
L 11.25726673 2.83833346 11.2561999 2.83583327 2 P 0 ;0,1,2=104,3=0.000000
L 11.2561999 2.83583327 11.25593327 2.83291644 2 P 0 ;0,1,2=104,3=0.000000
L 11.25593327 2.83291644 11.2561999 2.83041624 2 P 0 ;0,1,2=104,3=0.000000
L 11.2561999 2.83041624 11.25726673 2.82791604 2 P 0 ;0,1,2=104,3=0.000000
L 11.25726673 2.82791604 11.25886693 2.82583307 2 P 0 ;0,1,2=104,3=0.000000
L 11.25886693 2.82583307 11.26073317 2.825 2 P 0 ;0,1,2=104,3=0.000000
L 11.26073317 2.825 11.26286654 2.82583307 2 P 0 ;0,1,2=104,3=0.000000
L 11.26286654 2.82583307 11.26473337 2.82833258 2 P 0 ;0,1,2=104,3=0.000000
L 11.26473337 2.82833258 11.2658002 2.83208327 2 P 0 ;0,1,2=104,3=0.000000
L 11.2658002 2.83208327 11.26606683 2.8362498 2 P 0 ;0,1,2=104,3=0.000000
L 11.26606683 2.8362498 11.26553366 2.84166614 2 P 0 ;0,1,2=104,3=0.000000
L 11.26553366 2.84166614 11.26473337 2.84458366 2 P 0 ;0,1,2=104,3=0.000000
L 11.26473337 2.84458366 11.2634003 2.8474997 2 P 0 ;0,1,2=104,3=0.000000
L 11.2634003 2.8474997 11.26153346 2.84958337 2 P 0 ;0,1,2=104,3=0.000000
L 11.26153346 2.84958337 11.25966673 2.85 2 P 0 ;0,1,2=104,3=0.000000
L 11.25966673 2.85 11.2578 2.84916683 2 P 0 ;0,1,2=104,3=0.000000
L 11.2578 2.84916683 11.25646644 2.84708317 2 P 0 ;0,1,2=104,3=0.000000
L 11.63361998 2.77713002 11.63361998 2.79286998 3 P 0 
L 12.01233346 2.795 12.01233346 2.82 2 P 0 ;0,1,2=105,3=0.000000
L 12.01233346 2.82 12.00566673 2.82 2 P 0 ;0,1,2=105,3=0.000000
L 12.00566673 2.82 12.00353337 2.81874941 2 P 0 ;0,1,2=105,3=0.000000
L 12.00353337 2.81874941 12.0021999 2.81708317 2 P 0 ;0,1,2=105,3=0.000000
L 12.0021999 2.81708317 12.00166663 2.8137498 2 P 0 ;0,1,2=105,3=0.000000
L 12.00166663 2.8137498 12.0021999 2.81041634 2 P 0 ;0,1,2=105,3=0.000000
L 12.0021999 2.81041634 12.0038 2.80833346 2 P 0 ;0,1,2=105,3=0.000000
L 12.0038 2.80833346 12.00566673 2.80708297 2 P 0 ;0,1,2=105,3=0.000000
L 12.00566673 2.80708297 12.01233346 2.80708297 2 P 0 ;0,1,2=105,3=0.000000
L 12.00566673 2.80708297 12.00166663 2.795 2 P 0 ;0,1,2=105,3=0.000000
L 11.9830003 2.795 11.9830003 2.82 2 P 0 ;0,1,2=105,3=0.000000
L 11.9830003 2.82 11.9862001 2.8150003 2 P 0 ;0,1,2=105,3=0.000000
L 11.9862001 2.795 11.97980049 2.795 2 P 0 ;0,1,2=105,3=0.000000
L 11.96486673 2.79874911 11.96326703 2.79666624 2 P 0 ;0,1,2=105,3=0.000000
L 11.96326703 2.79666624 11.9614003 2.79541654 2 P 0 ;0,1,2=105,3=0.000000
L 11.9614003 2.79541654 11.9590003 2.795 2 P 0 ;0,1,2=105,3=0.000000
L 11.9590003 2.795 11.9565998 2.79583307 2 P 0 ;0,1,2=105,3=0.000000
L 11.9565998 2.79583307 11.95473356 2.79749941 2 P 0 ;0,1,2=105,3=0.000000
L 11.95473356 2.79749941 11.9534 2.80041624 2 P 0 ;0,1,2=105,3=0.000000
L 11.9534 2.80041624 11.95313337 2.80374961 2 P 0 ;0,1,2=105,3=0.000000
L 11.95313337 2.80374961 11.95366663 2.80708297 2 P 0 ;0,1,2=105,3=0.000000
L 11.95366663 2.80708297 11.9550002 2.80916663 2 P 0 ;0,1,2=105,3=0.000000
L 11.9550002 2.80916663 11.95686693 2.81083297 2 P 0 ;0,1,2=105,3=0.000000
L 11.95686693 2.81083297 11.95873317 2.81124951 2 P 0 ;0,1,2=105,3=0.000000
L 11.95873317 2.81124951 11.9606 2.81083297 2 P 0 ;0,1,2=105,3=0.000000
L 11.9606 2.81083297 11.9629999 2.80916663 2 P 0 ;0,1,2=105,3=0.000000
L 11.9629999 2.80916663 11.9622001 2.82 2 P 0 ;0,1,2=105,3=0.000000
L 11.9622001 2.82 11.9550002 2.82 2 P 0 ;0,1,2=105,3=0.000000
L 11.9350003 2.795 11.9350003 2.82 2 P 0 ;0,1,2=105,3=0.000000
L 11.9350003 2.82 11.9382001 2.8150003 2 P 0 ;0,1,2=105,3=0.000000
L 11.9382001 2.795 11.93180049 2.795 2 P 0 ;0,1,2=105,3=0.000000
L 11.91686673 2.79874911 11.91526703 2.79666624 2 P 0 ;0,1,2=105,3=0.000000
L 11.91526703 2.79666624 11.9134003 2.79541654 2 P 0 ;0,1,2=105,3=0.000000
L 11.9134003 2.79541654 11.9110003 2.795 2 P 0 ;0,1,2=105,3=0.000000
L 11.9110003 2.795 11.9085998 2.79583307 2 P 0 ;0,1,2=105,3=0.000000
L 11.9085998 2.79583307 11.90673356 2.79749941 2 P 0 ;0,1,2=105,3=0.000000
L 11.90673356 2.79749941 11.9054 2.80041624 2 P 0 ;0,1,2=105,3=0.000000
L 11.9054 2.80041624 11.90513337 2.80374961 2 P 0 ;0,1,2=105,3=0.000000
L 11.90513337 2.80374961 11.90566663 2.80708297 2 P 0 ;0,1,2=105,3=0.000000
L 11.90566663 2.80708297 11.9070002 2.80916663 2 P 0 ;0,1,2=105,3=0.000000
L 11.9070002 2.80916663 11.90886693 2.81083297 2 P 0 ;0,1,2=105,3=0.000000
L 11.90886693 2.81083297 11.91073317 2.81124951 2 P 0 ;0,1,2=105,3=0.000000
L 11.91073317 2.81124951 11.9126 2.81083297 2 P 0 ;0,1,2=105,3=0.000000
L 11.9126 2.81083297 11.9149999 2.80916663 2 P 0 ;0,1,2=105,3=0.000000
L 11.9149999 2.80916663 11.9142001 2.82 2 P 0 ;0,1,2=105,3=0.000000
L 11.9142001 2.82 11.9070002 2.82 2 P 0 ;0,1,2=105,3=0.000000
L 11.63361998 2.89713002 11.63361998 2.91286998 3 P 0 
L 12.01233346 2.89 12.01233346 2.915 2 P 0 ;0,1,2=106,3=0.000000
L 12.01233346 2.915 12.00566673 2.915 2 P 0 ;0,1,2=106,3=0.000000
L 12.00566673 2.915 12.00353337 2.91374941 2 P 0 ;0,1,2=106,3=0.000000
L 12.00353337 2.91374941 12.0021999 2.91208317 2 P 0 ;0,1,2=106,3=0.000000
L 12.0021999 2.91208317 12.00166663 2.9087498 2 P 0 ;0,1,2=106,3=0.000000
L 12.00166663 2.9087498 12.0021999 2.90541634 2 P 0 ;0,1,2=106,3=0.000000
L 12.0021999 2.90541634 12.0038 2.90333346 2 P 0 ;0,1,2=106,3=0.000000
L 12.0038 2.90333346 12.00566673 2.90208297 2 P 0 ;0,1,2=106,3=0.000000
L 12.00566673 2.90208297 12.01233346 2.90208297 2 P 0 ;0,1,2=106,3=0.000000
L 12.00566673 2.90208297 12.00166663 2.89 2 P 0 ;0,1,2=106,3=0.000000
L 11.9830003 2.89 11.9830003 2.915 2 P 0 ;0,1,2=106,3=0.000000
L 11.9830003 2.915 11.9862001 2.9100003 2 P 0 ;0,1,2=106,3=0.000000
L 11.9862001 2.89 11.97980049 2.89 2 P 0 ;0,1,2=106,3=0.000000
L 11.96486673 2.89374911 11.96326703 2.89166624 2 P 0 ;0,1,2=106,3=0.000000
L 11.96326703 2.89166624 11.9614003 2.89041654 2 P 0 ;0,1,2=106,3=0.000000
L 11.9614003 2.89041654 11.9590003 2.89 2 P 0 ;0,1,2=106,3=0.000000
L 11.9590003 2.89 11.9565998 2.89083307 2 P 0 ;0,1,2=106,3=0.000000
L 11.9565998 2.89083307 11.95473356 2.89249941 2 P 0 ;0,1,2=106,3=0.000000
L 11.95473356 2.89249941 11.9534 2.89541624 2 P 0 ;0,1,2=106,3=0.000000
L 11.9534 2.89541624 11.95313337 2.89874961 2 P 0 ;0,1,2=106,3=0.000000
L 11.95313337 2.89874961 11.95366663 2.90208297 2 P 0 ;0,1,2=106,3=0.000000
L 11.95366663 2.90208297 11.9550002 2.90416663 2 P 0 ;0,1,2=106,3=0.000000
L 11.9550002 2.90416663 11.95686693 2.90583297 2 P 0 ;0,1,2=106,3=0.000000
L 11.95686693 2.90583297 11.95873317 2.90624951 2 P 0 ;0,1,2=106,3=0.000000
L 11.95873317 2.90624951 11.9606 2.90583297 2 P 0 ;0,1,2=106,3=0.000000
L 11.9606 2.90583297 11.9629999 2.90416663 2 P 0 ;0,1,2=106,3=0.000000
L 11.9629999 2.90416663 11.9622001 2.915 2 P 0 ;0,1,2=106,3=0.000000
L 11.9622001 2.915 11.9550002 2.915 2 P 0 ;0,1,2=106,3=0.000000
L 11.9350003 2.89 11.9350003 2.915 2 P 0 ;0,1,2=106,3=0.000000
L 11.9350003 2.915 11.9382001 2.9100003 2 P 0 ;0,1,2=106,3=0.000000
L 11.9382001 2.89 11.93180049 2.89 2 P 0 ;0,1,2=106,3=0.000000
L 11.9078 2.89 11.9078 2.915 2 P 0 ;0,1,2=106,3=0.000000
L 11.9078 2.915 11.91766703 2.89708327 2 P 0 ;0,1,2=106,3=0.000000
L 11.91766703 2.89708327 11.90433307 2.89708327 2 P 0 ;0,1,2=106,3=0.000000
L 5.32968996 2.73786998 5.32968996 2.72213002 3 P 0 
L 5.34733346 2.68 5.34733346 2.705 2 P 0 ;0,1,2=107,3=0.000000
L 5.34733346 2.705 5.34066673 2.705 2 P 0 ;0,1,2=107,3=0.000000
L 5.34066673 2.705 5.33853337 2.70374941 2 P 0 ;0,1,2=107,3=0.000000
L 5.33853337 2.70374941 5.3371999 2.70208317 2 P 0 ;0,1,2=107,3=0.000000
L 5.3371999 2.70208317 5.33666663 2.6987498 2 P 0 ;0,1,2=107,3=0.000000
L 5.33666663 2.6987498 5.3371999 2.69541634 2 P 0 ;0,1,2=107,3=0.000000
L 5.3371999 2.69541634 5.3388 2.69333346 2 P 0 ;0,1,2=107,3=0.000000
L 5.3388 2.69333346 5.34066673 2.69208297 2 P 0 ;0,1,2=107,3=0.000000
L 5.34066673 2.69208297 5.34733346 2.69208297 2 P 0 ;0,1,2=107,3=0.000000
L 5.34066673 2.69208297 5.33666663 2.68 2 P 0 ;0,1,2=107,3=0.000000
L 5.3180003 2.68 5.3180003 2.705 2 P 0 ;0,1,2=107,3=0.000000
L 5.3180003 2.705 5.3212001 2.7000003 2 P 0 ;0,1,2=107,3=0.000000
L 5.3212001 2.68 5.31480049 2.68 2 P 0 ;0,1,2=107,3=0.000000
L 5.2908 2.68 5.2908 2.705 2 P 0 ;0,1,2=107,3=0.000000
L 5.2908 2.705 5.30066703 2.68708327 2 P 0 ;0,1,2=107,3=0.000000
L 5.30066703 2.68708327 5.28733307 2.68708327 2 P 0 ;0,1,2=107,3=0.000000
L 5.27506683 2.69041594 5.2732001 2.69333346 2 P 0 ;0,1,2=107,3=0.000000
L 5.2732001 2.69333346 5.2716 2.6949998 2 P 0 ;0,1,2=107,3=0.000000
L 5.2716 2.6949998 5.26946663 2.69583297 2 P 0 ;0,1,2=107,3=0.000000
L 5.26946663 2.69583297 5.2675998 2.6949998 2 P 0 ;0,1,2=107,3=0.000000
L 5.2675998 2.6949998 5.26626673 2.69333346 2 P 0 ;0,1,2=107,3=0.000000
L 5.26626673 2.69333346 5.2651999 2.69083327 2 P 0 ;0,1,2=107,3=0.000000
L 5.2651999 2.69083327 5.26493327 2.68791644 2 P 0 ;0,1,2=107,3=0.000000
L 5.26493327 2.68791644 5.2651999 2.68541624 2 P 0 ;0,1,2=107,3=0.000000
L 5.2651999 2.68541624 5.26626673 2.68291604 2 P 0 ;0,1,2=107,3=0.000000
L 5.26626673 2.68291604 5.26786693 2.68083307 2 P 0 ;0,1,2=107,3=0.000000
L 5.26786693 2.68083307 5.26973317 2.68 2 P 0 ;0,1,2=107,3=0.000000
L 5.26973317 2.68 5.27186654 2.68083307 2 P 0 ;0,1,2=107,3=0.000000
L 5.27186654 2.68083307 5.27373337 2.68333258 2 P 0 ;0,1,2=107,3=0.000000
L 5.27373337 2.68333258 5.2748002 2.68708327 2 P 0 ;0,1,2=107,3=0.000000
L 5.2748002 2.68708327 5.27506683 2.6912498 2 P 0 ;0,1,2=107,3=0.000000
L 5.27506683 2.6912498 5.27453366 2.69666614 2 P 0 ;0,1,2=107,3=0.000000
L 5.27453366 2.69666614 5.27373337 2.69958366 2 P 0 ;0,1,2=107,3=0.000000
L 5.27373337 2.69958366 5.2724003 2.7024997 2 P 0 ;0,1,2=107,3=0.000000
L 5.2724003 2.7024997 5.27053346 2.70458337 2 P 0 ;0,1,2=107,3=0.000000
L 5.27053346 2.70458337 5.26866673 2.705 2 P 0 ;0,1,2=107,3=0.000000
L 5.26866673 2.705 5.2668 2.70416683 2 P 0 ;0,1,2=107,3=0.000000
L 5.2668 2.70416683 5.26546644 2.70208317 2 P 0 ;0,1,2=107,3=0.000000
L 5.2460003 2.68 5.2460003 2.705 2 P 0 ;0,1,2=107,3=0.000000
L 5.2460003 2.705 5.2492001 2.7000003 2 P 0 ;0,1,2=107,3=0.000000
L 5.2492001 2.68 5.24280049 2.68 2 P 0 ;0,1,2=107,3=0.000000
L 5.32968996 2.80786998 5.32968996 2.79213002 3 P 0 
L 5.35233346 2.83 5.35233346 2.855 2 P 0 ;0,1,2=108,3=0.000000
L 5.35233346 2.855 5.34566673 2.855 2 P 0 ;0,1,2=108,3=0.000000
L 5.34566673 2.855 5.34353337 2.85374941 2 P 0 ;0,1,2=108,3=0.000000
L 5.34353337 2.85374941 5.3421999 2.85208317 2 P 0 ;0,1,2=108,3=0.000000
L 5.3421999 2.85208317 5.34166663 2.8487498 2 P 0 ;0,1,2=108,3=0.000000
L 5.34166663 2.8487498 5.3421999 2.84541634 2 P 0 ;0,1,2=108,3=0.000000
L 5.3421999 2.84541634 5.3438 2.84333346 2 P 0 ;0,1,2=108,3=0.000000
L 5.3438 2.84333346 5.34566673 2.84208297 2 P 0 ;0,1,2=108,3=0.000000
L 5.34566673 2.84208297 5.35233346 2.84208297 2 P 0 ;0,1,2=108,3=0.000000
L 5.34566673 2.84208297 5.34166663 2.83 2 P 0 ;0,1,2=108,3=0.000000
L 5.3230003 2.83 5.3230003 2.855 2 P 0 ;0,1,2=108,3=0.000000
L 5.3230003 2.855 5.3262001 2.8500003 2 P 0 ;0,1,2=108,3=0.000000
L 5.3262001 2.83 5.31980049 2.83 2 P 0 ;0,1,2=108,3=0.000000
L 5.2958 2.83 5.2958 2.855 2 P 0 ;0,1,2=108,3=0.000000
L 5.2958 2.855 5.30566703 2.83708327 2 P 0 ;0,1,2=108,3=0.000000
L 5.30566703 2.83708327 5.29233307 2.83708327 2 P 0 ;0,1,2=108,3=0.000000
L 5.28006683 2.84041594 5.2782001 2.84333346 2 P 0 ;0,1,2=108,3=0.000000
L 5.2782001 2.84333346 5.2766 2.8449998 2 P 0 ;0,1,2=108,3=0.000000
L 5.2766 2.8449998 5.27446663 2.84583297 2 P 0 ;0,1,2=108,3=0.000000
L 5.27446663 2.84583297 5.2725998 2.8449998 2 P 0 ;0,1,2=108,3=0.000000
L 5.2725998 2.8449998 5.27126673 2.84333346 2 P 0 ;0,1,2=108,3=0.000000
L 5.27126673 2.84333346 5.2701999 2.84083327 2 P 0 ;0,1,2=108,3=0.000000
L 5.2701999 2.84083327 5.26993327 2.83791644 2 P 0 ;0,1,2=108,3=0.000000
L 5.26993327 2.83791644 5.2701999 2.83541624 2 P 0 ;0,1,2=108,3=0.000000
L 5.2701999 2.83541624 5.27126673 2.83291604 2 P 0 ;0,1,2=108,3=0.000000
L 5.27126673 2.83291604 5.27286693 2.83083307 2 P 0 ;0,1,2=108,3=0.000000
L 5.27286693 2.83083307 5.27473317 2.83 2 P 0 ;0,1,2=108,3=0.000000
L 5.27473317 2.83 5.27686654 2.83083307 2 P 0 ;0,1,2=108,3=0.000000
L 5.27686654 2.83083307 5.27873337 2.83333258 2 P 0 ;0,1,2=108,3=0.000000
L 5.27873337 2.83333258 5.2798002 2.83708327 2 P 0 ;0,1,2=108,3=0.000000
L 5.2798002 2.83708327 5.28006683 2.8412498 2 P 0 ;0,1,2=108,3=0.000000
L 5.28006683 2.8412498 5.27953366 2.84666614 2 P 0 ;0,1,2=108,3=0.000000
L 5.27953366 2.84666614 5.27873337 2.84958366 2 P 0 ;0,1,2=108,3=0.000000
L 5.27873337 2.84958366 5.2774003 2.8524997 2 P 0 ;0,1,2=108,3=0.000000
L 5.2774003 2.8524997 5.27553346 2.85458337 2 P 0 ;0,1,2=108,3=0.000000
L 5.27553346 2.85458337 5.27366673 2.855 2 P 0 ;0,1,2=108,3=0.000000
L 5.27366673 2.855 5.2718 2.85416683 2 P 0 ;0,1,2=108,3=0.000000
L 5.2718 2.85416683 5.27046644 2.85208317 2 P 0 ;0,1,2=108,3=0.000000
L 5.2510003 2.855 5.25313366 2.85416683 2 P 0 ;0,1,2=108,3=0.000000
L 5.25313366 2.85416683 5.25473337 2.85208317 2 P 0 ;0,1,2=108,3=0.000000
L 5.25473337 2.85208317 5.2558002 2.84958366 2 P 0 ;0,1,2=108,3=0.000000
L 5.2558002 2.84958366 5.2566001 2.84624951 2 P 0 ;0,1,2=108,3=0.000000
L 5.2566001 2.84624951 5.25686673 2.84249961 2 P 0 ;0,1,2=108,3=0.000000
L 5.25686673 2.84249961 5.2566001 2.83874961 2 P 0 ;0,1,2=108,3=0.000000
L 5.2566001 2.83874961 5.2558002 2.83541624 2 P 0 ;0,1,2=108,3=0.000000
L 5.2558002 2.83541624 5.25473337 2.83291604 2 P 0 ;0,1,2=108,3=0.000000
L 5.25473337 2.83291604 5.25313366 2.83083307 2 P 0 ;0,1,2=108,3=0.000000
L 5.25313366 2.83083307 5.2510003 2.83 2 P 0 ;0,1,2=108,3=0.000000
L 5.2510003 2.83 5.24886693 2.83083307 2 P 0 ;0,1,2=108,3=0.000000
L 5.24886693 2.83083307 5.24726673 2.83291604 2 P 0 ;0,1,2=108,3=0.000000
L 5.24726673 2.83291604 5.2461999 2.83541624 2 P 0 ;0,1,2=108,3=0.000000
L 5.2461999 2.83541624 5.2454 2.83874961 2 P 0 ;0,1,2=108,3=0.000000
L 5.2454 2.83874961 5.24513337 2.84249961 2 P 0 ;0,1,2=108,3=0.000000
L 5.24513337 2.84249961 5.2454 2.84624951 2 P 0 ;0,1,2=108,3=0.000000
L 5.2454 2.84624951 5.2461999 2.84958366 2 P 0 ;0,1,2=108,3=0.000000
L 5.2461999 2.84958366 5.24726673 2.85208317 2 P 0 ;0,1,2=108,3=0.000000
L 5.24726673 2.85208317 5.24886693 2.85416683 2 P 0 ;0,1,2=108,3=0.000000
L 5.24886693 2.85416683 5.2510003 2.855 2 P 0 ;0,1,2=108,3=0.000000
L 5.62968996 2.77713002 5.62968996 2.79286998 3 P 0 
L 5.70233346 2.73 5.70233346 2.755 2 P 0 ;0,1,2=109,3=0.000000
L 5.70233346 2.755 5.69566673 2.755 2 P 0 ;0,1,2=109,3=0.000000
L 5.69566673 2.755 5.69353337 2.75374941 2 P 0 ;0,1,2=109,3=0.000000
L 5.69353337 2.75374941 5.6921999 2.75208317 2 P 0 ;0,1,2=109,3=0.000000
L 5.6921999 2.75208317 5.69166663 2.7487498 2 P 0 ;0,1,2=109,3=0.000000
L 5.69166663 2.7487498 5.6921999 2.74541634 2 P 0 ;0,1,2=109,3=0.000000
L 5.6921999 2.74541634 5.6938 2.74333346 2 P 0 ;0,1,2=109,3=0.000000
L 5.6938 2.74333346 5.69566673 2.74208297 2 P 0 ;0,1,2=109,3=0.000000
L 5.69566673 2.74208297 5.70233346 2.74208297 2 P 0 ;0,1,2=109,3=0.000000
L 5.69566673 2.74208297 5.69166663 2.73 2 P 0 ;0,1,2=109,3=0.000000
L 5.6730003 2.73 5.6730003 2.755 2 P 0 ;0,1,2=109,3=0.000000
L 5.6730003 2.755 5.6762001 2.7500003 2 P 0 ;0,1,2=109,3=0.000000
L 5.6762001 2.73 5.66980049 2.73 2 P 0 ;0,1,2=109,3=0.000000
L 5.6490003 2.73 5.6490003 2.755 2 P 0 ;0,1,2=109,3=0.000000
L 5.6490003 2.755 5.6522001 2.7500003 2 P 0 ;0,1,2=109,3=0.000000
L 5.6522001 2.73 5.64580049 2.73 2 P 0 ;0,1,2=109,3=0.000000
L 5.63086673 2.73374911 5.62926703 2.73166624 2 P 0 ;0,1,2=109,3=0.000000
L 5.62926703 2.73166624 5.6274003 2.73041654 2 P 0 ;0,1,2=109,3=0.000000
L 5.6274003 2.73041654 5.6250003 2.73 2 P 0 ;0,1,2=109,3=0.000000
L 5.6250003 2.73 5.6225998 2.73083307 2 P 0 ;0,1,2=109,3=0.000000
L 5.6225998 2.73083307 5.62073356 2.73249941 2 P 0 ;0,1,2=109,3=0.000000
L 5.62073356 2.73249941 5.6194 2.73541624 2 P 0 ;0,1,2=109,3=0.000000
L 5.6194 2.73541624 5.61913337 2.73874961 2 P 0 ;0,1,2=109,3=0.000000
L 5.61913337 2.73874961 5.61966663 2.74208297 2 P 0 ;0,1,2=109,3=0.000000
L 5.61966663 2.74208297 5.6210002 2.74416663 2 P 0 ;0,1,2=109,3=0.000000
L 5.6210002 2.74416663 5.62286693 2.74583297 2 P 0 ;0,1,2=109,3=0.000000
L 5.62286693 2.74583297 5.62473317 2.74624951 2 P 0 ;0,1,2=109,3=0.000000
L 5.62473317 2.74624951 5.6266 2.74583297 2 P 0 ;0,1,2=109,3=0.000000
L 5.6266 2.74583297 5.6289999 2.74416663 2 P 0 ;0,1,2=109,3=0.000000
L 5.6289999 2.74416663 5.6282001 2.755 2 P 0 ;0,1,2=109,3=0.000000
L 5.6282001 2.755 5.6210002 2.755 2 P 0 ;0,1,2=109,3=0.000000
L 5.5978 2.73 5.5978 2.755 2 P 0 ;0,1,2=109,3=0.000000
L 5.5978 2.755 5.60766703 2.73708327 2 P 0 ;0,1,2=109,3=0.000000
L 5.60766703 2.73708327 5.59433307 2.73708327 2 P 0 ;0,1,2=109,3=0.000000
L 5.62968996 2.89713002 5.62968996 2.91286998 3 P 0 
L 5.55733346 2.895 5.55733346 2.92 2 P 0 ;0,1,2=110,3=0.000000
L 5.55733346 2.92 5.55066673 2.92 2 P 0 ;0,1,2=110,3=0.000000
L 5.55066673 2.92 5.54853337 2.91874941 2 P 0 ;0,1,2=110,3=0.000000
L 5.54853337 2.91874941 5.5471999 2.91708317 2 P 0 ;0,1,2=110,3=0.000000
L 5.5471999 2.91708317 5.54666663 2.9137498 2 P 0 ;0,1,2=110,3=0.000000
L 5.54666663 2.9137498 5.5471999 2.91041634 2 P 0 ;0,1,2=110,3=0.000000
L 5.5471999 2.91041634 5.5488 2.90833346 2 P 0 ;0,1,2=110,3=0.000000
L 5.5488 2.90833346 5.55066673 2.90708297 2 P 0 ;0,1,2=110,3=0.000000
L 5.55066673 2.90708297 5.55733346 2.90708297 2 P 0 ;0,1,2=110,3=0.000000
L 5.55066673 2.90708297 5.54666663 2.895 2 P 0 ;0,1,2=110,3=0.000000
L 5.5280003 2.895 5.5280003 2.92 2 P 0 ;0,1,2=110,3=0.000000
L 5.5280003 2.92 5.5312001 2.9150003 2 P 0 ;0,1,2=110,3=0.000000
L 5.5312001 2.895 5.52480049 2.895 2 P 0 ;0,1,2=110,3=0.000000
L 5.5040003 2.895 5.5040003 2.92 2 P 0 ;0,1,2=110,3=0.000000
L 5.5040003 2.92 5.5072001 2.9150003 2 P 0 ;0,1,2=110,3=0.000000
L 5.5072001 2.895 5.50080049 2.895 2 P 0 ;0,1,2=110,3=0.000000
L 5.48586673 2.89874911 5.48426703 2.89666624 2 P 0 ;0,1,2=110,3=0.000000
L 5.48426703 2.89666624 5.4824003 2.89541654 2 P 0 ;0,1,2=110,3=0.000000
L 5.4824003 2.89541654 5.4800003 2.895 2 P 0 ;0,1,2=110,3=0.000000
L 5.4800003 2.895 5.4775998 2.89583307 2 P 0 ;0,1,2=110,3=0.000000
L 5.4775998 2.89583307 5.47573356 2.89749941 2 P 0 ;0,1,2=110,3=0.000000
L 5.47573356 2.89749941 5.4744 2.90041624 2 P 0 ;0,1,2=110,3=0.000000
L 5.4744 2.90041624 5.47413337 2.90374961 2 P 0 ;0,1,2=110,3=0.000000
L 5.47413337 2.90374961 5.47466663 2.90708297 2 P 0 ;0,1,2=110,3=0.000000
L 5.47466663 2.90708297 5.4760002 2.90916663 2 P 0 ;0,1,2=110,3=0.000000
L 5.4760002 2.90916663 5.47786693 2.91083297 2 P 0 ;0,1,2=110,3=0.000000
L 5.47786693 2.91083297 5.47973317 2.91124951 2 P 0 ;0,1,2=110,3=0.000000
L 5.47973317 2.91124951 5.4816 2.91083297 2 P 0 ;0,1,2=110,3=0.000000
L 5.4816 2.91083297 5.4839999 2.90916663 2 P 0 ;0,1,2=110,3=0.000000
L 5.4839999 2.90916663 5.4832001 2.92 2 P 0 ;0,1,2=110,3=0.000000
L 5.4832001 2.92 5.4760002 2.92 2 P 0 ;0,1,2=110,3=0.000000
L 5.46186673 2.89999961 5.46026703 2.89708287 2 P 0 ;0,1,2=110,3=0.000000
L 5.46026703 2.89708287 5.45813366 2.89541654 2 P 0 ;0,1,2=110,3=0.000000
L 5.45813366 2.89541654 5.45573317 2.895 2 P 0 ;0,1,2=110,3=0.000000
L 5.45573317 2.895 5.4535998 2.89541654 2 P 0 ;0,1,2=110,3=0.000000
L 5.4535998 2.89541654 5.45146644 2.89749941 2 P 0 ;0,1,2=110,3=0.000000
L 5.45146644 2.89749941 5.45013337 2.89999961 2 P 0 ;0,1,2=110,3=0.000000
L 5.45013337 2.89999961 5.44986683 2.9024999 2 P 0 ;0,1,2=110,3=0.000000
L 5.44986683 2.9024999 5.4504 2.90541594 2 P 0 ;0,1,2=110,3=0.000000
L 5.4504 2.90541594 5.45226673 2.90749961 2 P 0 ;0,1,2=110,3=0.000000
L 5.45226673 2.90749961 5.45413356 2.90833346 2 P 0 ;0,1,2=110,3=0.000000
L 5.45413356 2.90833346 5.45653346 2.90833346 2 P 0 ;0,1,2=110,3=0.000000
L 5.45413356 2.90833346 5.45253337 2.90958327 2 P 0 ;0,1,2=110,3=0.000000
L 5.45253337 2.90958327 5.4511999 2.91166614 2 P 0 ;0,1,2=110,3=0.000000
L 5.4511999 2.91166614 5.45066663 2.91416634 2 P 0 ;0,1,2=110,3=0.000000
L 5.45066663 2.91416634 5.4511999 2.91666654 2 P 0 ;0,1,2=110,3=0.000000
L 5.4511999 2.91666654 5.45253337 2.91874941 2 P 0 ;0,1,2=110,3=0.000000
L 5.45253337 2.91874941 5.45493337 2.92 2 P 0 ;0,1,2=110,3=0.000000
L 5.45493337 2.92 5.45733337 2.91958337 2 P 0 ;0,1,2=110,3=0.000000
L 5.45733337 2.91958337 5.45973337 2.91791634 2 P 0 ;0,1,2=110,3=0.000000
L 4.07386004 2.65786998 4.07386004 2.64213002 3 P 0 
L 4.20233346 2.64 4.20233346 2.665 2 P 0 ;0,1,2=111,3=0.000000
L 4.20233346 2.665 4.19566673 2.665 2 P 0 ;0,1,2=111,3=0.000000
L 4.19566673 2.665 4.19353337 2.66374941 2 P 0 ;0,1,2=111,3=0.000000
L 4.19353337 2.66374941 4.1921999 2.66208317 2 P 0 ;0,1,2=111,3=0.000000
L 4.1921999 2.66208317 4.19166663 2.6587498 2 P 0 ;0,1,2=111,3=0.000000
L 4.19166663 2.6587498 4.1921999 2.65541634 2 P 0 ;0,1,2=111,3=0.000000
L 4.1921999 2.65541634 4.1938 2.65333346 2 P 0 ;0,1,2=111,3=0.000000
L 4.1938 2.65333346 4.19566673 2.65208297 2 P 0 ;0,1,2=111,3=0.000000
L 4.19566673 2.65208297 4.20233346 2.65208297 2 P 0 ;0,1,2=111,3=0.000000
L 4.19566673 2.65208297 4.19166663 2.64 2 P 0 ;0,1,2=111,3=0.000000
L 4.17886673 2.64374911 4.17726703 2.64166624 2 P 0 ;0,1,2=111,3=0.000000
L 4.17726703 2.64166624 4.1754003 2.64041654 2 P 0 ;0,1,2=111,3=0.000000
L 4.1754003 2.64041654 4.1730003 2.64 2 P 0 ;0,1,2=111,3=0.000000
L 4.1730003 2.64 4.1705998 2.64083307 2 P 0 ;0,1,2=111,3=0.000000
L 4.1705998 2.64083307 4.16873356 2.64249941 2 P 0 ;0,1,2=111,3=0.000000
L 4.16873356 2.64249941 4.1674 2.64541624 2 P 0 ;0,1,2=111,3=0.000000
L 4.1674 2.64541624 4.16713337 2.64874961 2 P 0 ;0,1,2=111,3=0.000000
L 4.16713337 2.64874961 4.16766663 2.65208297 2 P 0 ;0,1,2=111,3=0.000000
L 4.16766663 2.65208297 4.1690002 2.65416663 2 P 0 ;0,1,2=111,3=0.000000
L 4.1690002 2.65416663 4.17086693 2.65583297 2 P 0 ;0,1,2=111,3=0.000000
L 4.17086693 2.65583297 4.17273317 2.65624951 2 P 0 ;0,1,2=111,3=0.000000
L 4.17273317 2.65624951 4.1746 2.65583297 2 P 0 ;0,1,2=111,3=0.000000
L 4.1746 2.65583297 4.1769999 2.65416663 2 P 0 ;0,1,2=111,3=0.000000
L 4.1769999 2.65416663 4.1762001 2.665 2 P 0 ;0,1,2=111,3=0.000000
L 4.1762001 2.665 4.1690002 2.665 2 P 0 ;0,1,2=111,3=0.000000
L 5.44468996 2.72213002 5.44468996 2.73786998 3 P 0 
L 5.54733346 2.72 5.54733346 2.745 2 P 0 ;0,1,2=112,3=0.000000
L 5.54733346 2.745 5.54066673 2.745 2 P 0 ;0,1,2=112,3=0.000000
L 5.54066673 2.745 5.53853337 2.74374941 2 P 0 ;0,1,2=112,3=0.000000
L 5.53853337 2.74374941 5.5371999 2.74208317 2 P 0 ;0,1,2=112,3=0.000000
L 5.5371999 2.74208317 5.53666663 2.7387498 2 P 0 ;0,1,2=112,3=0.000000
L 5.53666663 2.7387498 5.5371999 2.73541634 2 P 0 ;0,1,2=112,3=0.000000
L 5.5371999 2.73541634 5.5388 2.73333346 2 P 0 ;0,1,2=112,3=0.000000
L 5.5388 2.73333346 5.54066673 2.73208297 2 P 0 ;0,1,2=112,3=0.000000
L 5.54066673 2.73208297 5.54733346 2.73208297 2 P 0 ;0,1,2=112,3=0.000000
L 5.54066673 2.73208297 5.53666663 2.72 2 P 0 ;0,1,2=112,3=0.000000
L 5.52306683 2.74083337 5.52146673 2.74333287 2 P 0 ;0,1,2=112,3=0.000000
L 5.52146673 2.74333287 5.5196 2.74458337 2 P 0 ;0,1,2=112,3=0.000000
L 5.5196 2.74458337 5.51746663 2.745 2 P 0 ;0,1,2=112,3=0.000000
L 5.51746663 2.745 5.5148 2.74416683 2 P 0 ;0,1,2=112,3=0.000000
L 5.5148 2.74416683 5.51293327 2.74208317 2 P 0 ;0,1,2=112,3=0.000000
L 5.51293327 2.74208317 5.5124 2.73958366 2 P 0 ;0,1,2=112,3=0.000000
L 5.5124 2.73958366 5.51266663 2.73708268 2 P 0 ;0,1,2=112,3=0.000000
L 5.51266663 2.73708268 5.51373356 2.7349998 2 P 0 ;0,1,2=112,3=0.000000
L 5.51373356 2.7349998 5.51906673 2.73083327 2 P 0 ;0,1,2=112,3=0.000000
L 5.51906673 2.73083327 5.52146673 2.72791644 2 P 0 ;0,1,2=112,3=0.000000
L 5.52146673 2.72791644 5.52306683 2.72374911 2 P 0 ;0,1,2=112,3=0.000000
L 5.52306683 2.72374911 5.5236001 2.72 2 P 0 ;0,1,2=112,3=0.000000
L 5.5236001 2.72 5.5124 2.72 2 P 0 ;0,1,2=112,3=0.000000
L 11.45361998 2.72213002 11.45361998 2.73786998 3 P 0 
L 11.51233346 2.675 11.51233346 2.7 2 P 0 ;0,1,2=113,3=0.000000
L 11.51233346 2.7 11.50566673 2.7 2 P 0 ;0,1,2=113,3=0.000000
L 11.50566673 2.7 11.50353337 2.69874941 2 P 0 ;0,1,2=113,3=0.000000
L 11.50353337 2.69874941 11.5021999 2.69708317 2 P 0 ;0,1,2=113,3=0.000000
L 11.5021999 2.69708317 11.50166663 2.6937498 2 P 0 ;0,1,2=113,3=0.000000
L 11.50166663 2.6937498 11.5021999 2.69041634 2 P 0 ;0,1,2=113,3=0.000000
L 11.5021999 2.69041634 11.5038 2.68833346 2 P 0 ;0,1,2=113,3=0.000000
L 11.5038 2.68833346 11.50566673 2.68708297 2 P 0 ;0,1,2=113,3=0.000000
L 11.50566673 2.68708297 11.51233346 2.68708297 2 P 0 ;0,1,2=113,3=0.000000
L 11.50566673 2.68708297 11.50166663 2.675 2 P 0 ;0,1,2=113,3=0.000000
L 11.4830003 2.675 11.4830003 2.7 2 P 0 ;0,1,2=113,3=0.000000
L 11.4830003 2.7 11.4862001 2.6950003 2 P 0 ;0,1,2=113,3=0.000000
L 11.4862001 2.675 11.47980049 2.675 2 P 0 ;0,1,2=113,3=0.000000
L 11.46486673 2.67874911 11.46326703 2.67666624 2 P 0 ;0,1,2=113,3=0.000000
L 11.46326703 2.67666624 11.4614003 2.67541654 2 P 0 ;0,1,2=113,3=0.000000
L 11.4614003 2.67541654 11.4590003 2.675 2 P 0 ;0,1,2=113,3=0.000000
L 11.4590003 2.675 11.4565998 2.67583307 2 P 0 ;0,1,2=113,3=0.000000
L 11.4565998 2.67583307 11.45473356 2.67749941 2 P 0 ;0,1,2=113,3=0.000000
L 11.45473356 2.67749941 11.4534 2.68041624 2 P 0 ;0,1,2=113,3=0.000000
L 11.4534 2.68041624 11.45313337 2.68374961 2 P 0 ;0,1,2=113,3=0.000000
L 11.45313337 2.68374961 11.45366663 2.68708297 2 P 0 ;0,1,2=113,3=0.000000
L 11.45366663 2.68708297 11.4550002 2.68916663 2 P 0 ;0,1,2=113,3=0.000000
L 11.4550002 2.68916663 11.45686693 2.69083297 2 P 0 ;0,1,2=113,3=0.000000
L 11.45686693 2.69083297 11.45873317 2.69124951 2 P 0 ;0,1,2=113,3=0.000000
L 11.45873317 2.69124951 11.4606 2.69083297 2 P 0 ;0,1,2=113,3=0.000000
L 11.4606 2.69083297 11.4629999 2.68916663 2 P 0 ;0,1,2=113,3=0.000000
L 11.4629999 2.68916663 11.4622001 2.7 2 P 0 ;0,1,2=113,3=0.000000
L 11.4622001 2.7 11.4550002 2.7 2 P 0 ;0,1,2=113,3=0.000000
L 11.44006683 2.69583337 11.43846673 2.69833287 2 P 0 ;0,1,2=113,3=0.000000
L 11.43846673 2.69833287 11.4366 2.69958337 2 P 0 ;0,1,2=113,3=0.000000
L 11.4366 2.69958337 11.43446663 2.7 2 P 0 ;0,1,2=113,3=0.000000
L 11.43446663 2.7 11.4318 2.69916683 2 P 0 ;0,1,2=113,3=0.000000
L 11.4318 2.69916683 11.42993327 2.69708317 2 P 0 ;0,1,2=113,3=0.000000
L 11.42993327 2.69708317 11.4294 2.69458366 2 P 0 ;0,1,2=113,3=0.000000
L 11.4294 2.69458366 11.42966663 2.69208268 2 P 0 ;0,1,2=113,3=0.000000
L 11.42966663 2.69208268 11.43073356 2.6899998 2 P 0 ;0,1,2=113,3=0.000000
L 11.43073356 2.6899998 11.43606673 2.68583327 2 P 0 ;0,1,2=113,3=0.000000
L 11.43606673 2.68583327 11.43846673 2.68291644 2 P 0 ;0,1,2=113,3=0.000000
L 11.43846673 2.68291644 11.44006683 2.67874911 2 P 0 ;0,1,2=113,3=0.000000
L 11.44006683 2.67874911 11.4406001 2.675 2 P 0 ;0,1,2=113,3=0.000000
L 11.4406001 2.675 11.4294 2.675 2 P 0 ;0,1,2=113,3=0.000000
L 11.41606683 2.69583337 11.41446673 2.69833287 2 P 0 ;0,1,2=113,3=0.000000
L 11.41446673 2.69833287 11.4126 2.69958337 2 P 0 ;0,1,2=113,3=0.000000
L 11.4126 2.69958337 11.41046663 2.7 2 P 0 ;0,1,2=113,3=0.000000
L 11.41046663 2.7 11.4078 2.69916683 2 P 0 ;0,1,2=113,3=0.000000
L 11.4078 2.69916683 11.40593327 2.69708317 2 P 0 ;0,1,2=113,3=0.000000
L 11.40593327 2.69708317 11.4054 2.69458366 2 P 0 ;0,1,2=113,3=0.000000
L 11.4054 2.69458366 11.40566663 2.69208268 2 P 0 ;0,1,2=113,3=0.000000
L 11.40566663 2.69208268 11.40673356 2.6899998 2 P 0 ;0,1,2=113,3=0.000000
L 11.40673356 2.6899998 11.41206673 2.68583327 2 P 0 ;0,1,2=113,3=0.000000
L 11.41206673 2.68583327 11.41446673 2.68291644 2 P 0 ;0,1,2=113,3=0.000000
L 11.41446673 2.68291644 11.41606683 2.67874911 2 P 0 ;0,1,2=113,3=0.000000
L 11.41606683 2.67874911 11.4166001 2.675 2 P 0 ;0,1,2=113,3=0.000000
L 11.4166001 2.675 11.4054 2.675 2 P 0 ;0,1,2=113,3=0.000000
L 11.45361998 2.79213002 11.45361998 2.80786998 3 P 0 
L 11.51233346 2.825 11.51233346 2.85 2 P 0 ;0,1,2=114,3=0.000000
L 11.51233346 2.85 11.50566673 2.85 2 P 0 ;0,1,2=114,3=0.000000
L 11.50566673 2.85 11.50353337 2.84874941 2 P 0 ;0,1,2=114,3=0.000000
L 11.50353337 2.84874941 11.5021999 2.84708317 2 P 0 ;0,1,2=114,3=0.000000
L 11.5021999 2.84708317 11.50166663 2.8437498 2 P 0 ;0,1,2=114,3=0.000000
L 11.50166663 2.8437498 11.5021999 2.84041634 2 P 0 ;0,1,2=114,3=0.000000
L 11.5021999 2.84041634 11.5038 2.83833346 2 P 0 ;0,1,2=114,3=0.000000
L 11.5038 2.83833346 11.50566673 2.83708297 2 P 0 ;0,1,2=114,3=0.000000
L 11.50566673 2.83708297 11.51233346 2.83708297 2 P 0 ;0,1,2=114,3=0.000000
L 11.50566673 2.83708297 11.50166663 2.825 2 P 0 ;0,1,2=114,3=0.000000
L 11.4830003 2.825 11.4830003 2.85 2 P 0 ;0,1,2=114,3=0.000000
L 11.4830003 2.85 11.4862001 2.8450003 2 P 0 ;0,1,2=114,3=0.000000
L 11.4862001 2.825 11.47980049 2.825 2 P 0 ;0,1,2=114,3=0.000000
L 11.46486673 2.82874911 11.46326703 2.82666624 2 P 0 ;0,1,2=114,3=0.000000
L 11.46326703 2.82666624 11.4614003 2.82541654 2 P 0 ;0,1,2=114,3=0.000000
L 11.4614003 2.82541654 11.4590003 2.825 2 P 0 ;0,1,2=114,3=0.000000
L 11.4590003 2.825 11.4565998 2.82583307 2 P 0 ;0,1,2=114,3=0.000000
L 11.4565998 2.82583307 11.45473356 2.82749941 2 P 0 ;0,1,2=114,3=0.000000
L 11.45473356 2.82749941 11.4534 2.83041624 2 P 0 ;0,1,2=114,3=0.000000
L 11.4534 2.83041624 11.45313337 2.83374961 2 P 0 ;0,1,2=114,3=0.000000
L 11.45313337 2.83374961 11.45366663 2.83708297 2 P 0 ;0,1,2=114,3=0.000000
L 11.45366663 2.83708297 11.4550002 2.83916663 2 P 0 ;0,1,2=114,3=0.000000
L 11.4550002 2.83916663 11.45686693 2.84083297 2 P 0 ;0,1,2=114,3=0.000000
L 11.45686693 2.84083297 11.45873317 2.84124951 2 P 0 ;0,1,2=114,3=0.000000
L 11.45873317 2.84124951 11.4606 2.84083297 2 P 0 ;0,1,2=114,3=0.000000
L 11.4606 2.84083297 11.4629999 2.83916663 2 P 0 ;0,1,2=114,3=0.000000
L 11.4629999 2.83916663 11.4622001 2.85 2 P 0 ;0,1,2=114,3=0.000000
L 11.4622001 2.85 11.4550002 2.85 2 P 0 ;0,1,2=114,3=0.000000
L 11.44006683 2.84583337 11.43846673 2.84833287 2 P 0 ;0,1,2=114,3=0.000000
L 11.43846673 2.84833287 11.4366 2.84958337 2 P 0 ;0,1,2=114,3=0.000000
L 11.4366 2.84958337 11.43446663 2.85 2 P 0 ;0,1,2=114,3=0.000000
L 11.43446663 2.85 11.4318 2.84916683 2 P 0 ;0,1,2=114,3=0.000000
L 11.4318 2.84916683 11.42993327 2.84708317 2 P 0 ;0,1,2=114,3=0.000000
L 11.42993327 2.84708317 11.4294 2.84458366 2 P 0 ;0,1,2=114,3=0.000000
L 11.4294 2.84458366 11.42966663 2.84208268 2 P 0 ;0,1,2=114,3=0.000000
L 11.42966663 2.84208268 11.43073356 2.8399998 2 P 0 ;0,1,2=114,3=0.000000
L 11.43073356 2.8399998 11.43606673 2.83583327 2 P 0 ;0,1,2=114,3=0.000000
L 11.43606673 2.83583327 11.43846673 2.83291644 2 P 0 ;0,1,2=114,3=0.000000
L 11.43846673 2.83291644 11.44006683 2.82874911 2 P 0 ;0,1,2=114,3=0.000000
L 11.44006683 2.82874911 11.4406001 2.825 2 P 0 ;0,1,2=114,3=0.000000
L 11.4406001 2.825 11.4294 2.825 2 P 0 ;0,1,2=114,3=0.000000
L 11.4110003 2.825 11.4110003 2.85 2 P 0 ;0,1,2=114,3=0.000000
L 11.4110003 2.85 11.4142001 2.8450003 2 P 0 ;0,1,2=114,3=0.000000
L 11.4142001 2.825 11.40780049 2.825 2 P 0 ;0,1,2=114,3=0.000000
L 10.116 2.88786998 10.116 2.87213002 3 P 0 
L 10.28733346 2.86 10.28733346 2.885 2 P 0 ;0,1,2=115,3=0.000000
L 10.28733346 2.885 10.28066673 2.885 2 P 0 ;0,1,2=115,3=0.000000
L 10.28066673 2.885 10.27853337 2.88374941 2 P 0 ;0,1,2=115,3=0.000000
L 10.27853337 2.88374941 10.2771999 2.88208317 2 P 0 ;0,1,2=115,3=0.000000
L 10.2771999 2.88208317 10.27666663 2.8787498 2 P 0 ;0,1,2=115,3=0.000000
L 10.27666663 2.8787498 10.2771999 2.87541634 2 P 0 ;0,1,2=115,3=0.000000
L 10.2771999 2.87541634 10.2788 2.87333346 2 P 0 ;0,1,2=115,3=0.000000
L 10.2788 2.87333346 10.28066673 2.87208297 2 P 0 ;0,1,2=115,3=0.000000
L 10.28066673 2.87208297 10.28733346 2.87208297 2 P 0 ;0,1,2=115,3=0.000000
L 10.28066673 2.87208297 10.27666663 2.86 2 P 0 ;0,1,2=115,3=0.000000
L 10.2580003 2.86 10.2580003 2.885 2 P 0 ;0,1,2=115,3=0.000000
L 10.2580003 2.885 10.2612001 2.8800003 2 P 0 ;0,1,2=115,3=0.000000
L 10.2612001 2.86 10.25480049 2.86 2 P 0 ;0,1,2=115,3=0.000000
L 10.2308 2.86 10.2308 2.885 2 P 0 ;0,1,2=115,3=0.000000
L 10.2308 2.885 10.24066703 2.86708327 2 P 0 ;0,1,2=115,3=0.000000
L 10.24066703 2.86708327 10.22733307 2.86708327 2 P 0 ;0,1,2=115,3=0.000000
L 10.21453366 2.86291604 10.21266683 2.86083307 2 P 0 ;0,1,2=115,3=0.000000
L 10.21266683 2.86083307 10.21053346 2.86 2 P 0 ;0,1,2=115,3=0.000000
L 10.21053346 2.86 10.2084001 2.86083307 2 P 0 ;0,1,2=115,3=0.000000
L 10.2084001 2.86083307 10.20653337 2.86333258 2 P 0 ;0,1,2=115,3=0.000000
L 10.20653337 2.86333258 10.2051999 2.86708327 2 P 0 ;0,1,2=115,3=0.000000
L 10.2051999 2.86708327 10.20466663 2.87083327 2 P 0 ;0,1,2=115,3=0.000000
L 10.20466663 2.87083327 10.20466663 2.87541634 2 P 0 ;0,1,2=115,3=0.000000
L 10.20466663 2.87541634 10.2051999 2.87916634 2 P 0 ;0,1,2=115,3=0.000000
L 10.2051999 2.87916634 10.20653337 2.8824997 2 P 0 ;0,1,2=115,3=0.000000
L 10.20653337 2.8824997 10.20813356 2.88416683 2 P 0 ;0,1,2=115,3=0.000000
L 10.20813356 2.88416683 10.2100003 2.885 2 P 0 ;0,1,2=115,3=0.000000
L 10.2100003 2.885 10.21213366 2.88416683 2 P 0 ;0,1,2=115,3=0.000000
L 10.21213366 2.88416683 10.21373337 2.8824997 2 P 0 ;0,1,2=115,3=0.000000
L 10.21373337 2.8824997 10.2148002 2.8800003 2 P 0 ;0,1,2=115,3=0.000000
L 10.2148002 2.8800003 10.21533346 2.87666614 2 P 0 ;0,1,2=115,3=0.000000
L 10.21533346 2.87666614 10.2148002 2.8737501 2 P 0 ;0,1,2=115,3=0.000000
L 10.2148002 2.8737501 10.21346673 2.87083327 2 P 0 ;0,1,2=115,3=0.000000
L 10.21346673 2.87083327 10.21186654 2.86916614 2 P 0 ;0,1,2=115,3=0.000000
L 10.21186654 2.86916614 10.2100003 2.86874961 2 P 0 ;0,1,2=115,3=0.000000
L 10.2100003 2.86874961 10.20786693 2.86958278 2 P 0 ;0,1,2=115,3=0.000000
L 10.20786693 2.86958278 10.20626673 2.87166644 2 P 0 ;0,1,2=115,3=0.000000
L 10.20626673 2.87166644 10.20466663 2.87541634 2 P 0 ;0,1,2=115,3=0.000000
L 10.1860003 2.885 10.18813366 2.88416683 2 P 0 ;0,1,2=115,3=0.000000
L 10.18813366 2.88416683 10.18973337 2.88208317 2 P 0 ;0,1,2=115,3=0.000000
L 10.18973337 2.88208317 10.1908002 2.87958366 2 P 0 ;0,1,2=115,3=0.000000
L 10.1908002 2.87958366 10.1916001 2.87624951 2 P 0 ;0,1,2=115,3=0.000000
L 10.1916001 2.87624951 10.19186673 2.87249961 2 P 0 ;0,1,2=115,3=0.000000
L 10.19186673 2.87249961 10.1916001 2.86874961 2 P 0 ;0,1,2=115,3=0.000000
L 10.1916001 2.86874961 10.1908002 2.86541624 2 P 0 ;0,1,2=115,3=0.000000
L 10.1908002 2.86541624 10.18973337 2.86291604 2 P 0 ;0,1,2=115,3=0.000000
L 10.18973337 2.86291604 10.18813366 2.86083307 2 P 0 ;0,1,2=115,3=0.000000
L 10.18813366 2.86083307 10.1860003 2.86 2 P 0 ;0,1,2=115,3=0.000000
L 10.1860003 2.86 10.18386693 2.86083307 2 P 0 ;0,1,2=115,3=0.000000
L 10.18386693 2.86083307 10.18226673 2.86291604 2 P 0 ;0,1,2=115,3=0.000000
L 10.18226673 2.86291604 10.1811999 2.86541624 2 P 0 ;0,1,2=115,3=0.000000
L 10.1811999 2.86541624 10.1804 2.86874961 2 P 0 ;0,1,2=115,3=0.000000
L 10.1804 2.86874961 10.18013337 2.87249961 2 P 0 ;0,1,2=115,3=0.000000
L 10.18013337 2.87249961 10.1804 2.87624951 2 P 0 ;0,1,2=115,3=0.000000
L 10.1804 2.87624951 10.1811999 2.87958366 2 P 0 ;0,1,2=115,3=0.000000
L 10.1811999 2.87958366 10.18226673 2.88208317 2 P 0 ;0,1,2=115,3=0.000000
L 10.18226673 2.88208317 10.18386693 2.88416683 2 P 0 ;0,1,2=115,3=0.000000
L 10.18386693 2.88416683 10.1860003 2.885 2 P 0 ;0,1,2=115,3=0.000000
L 5.44468996 2.79213002 5.44468996 2.80786998 3 P 0 
L 5.52233346 2.79 5.52233346 2.815 2 P 0 ;0,1,2=116,3=0.000000
L 5.52233346 2.815 5.51566673 2.815 2 P 0 ;0,1,2=116,3=0.000000
L 5.51566673 2.815 5.51353337 2.81374941 2 P 0 ;0,1,2=116,3=0.000000
L 5.51353337 2.81374941 5.5121999 2.81208317 2 P 0 ;0,1,2=116,3=0.000000
L 5.5121999 2.81208317 5.51166663 2.8087498 2 P 0 ;0,1,2=116,3=0.000000
L 5.51166663 2.8087498 5.5121999 2.80541634 2 P 0 ;0,1,2=116,3=0.000000
L 5.5121999 2.80541634 5.5138 2.80333346 2 P 0 ;0,1,2=116,3=0.000000
L 5.5138 2.80333346 5.51566673 2.80208297 2 P 0 ;0,1,2=116,3=0.000000
L 5.51566673 2.80208297 5.52233346 2.80208297 2 P 0 ;0,1,2=116,3=0.000000
L 5.51566673 2.80208297 5.51166663 2.79 2 P 0 ;0,1,2=116,3=0.000000
L 5.4930003 2.79 5.4930003 2.815 2 P 0 ;0,1,2=116,3=0.000000
L 5.4930003 2.815 5.4962001 2.8100003 2 P 0 ;0,1,2=116,3=0.000000
L 5.4962001 2.79 5.48980049 2.79 2 P 0 ;0,1,2=116,3=0.000000
L 12.325 2.11786998 12.325 2.10213002 3 P 0 
L 12.37733346 2.06 12.37733346 2.085 2 P 0 ;0,1,2=117,3=0.000000
L 12.37733346 2.085 12.37066673 2.085 2 P 0 ;0,1,2=117,3=0.000000
L 12.37066673 2.085 12.36853337 2.08374941 2 P 0 ;0,1,2=117,3=0.000000
L 12.36853337 2.08374941 12.3671999 2.08208317 2 P 0 ;0,1,2=117,3=0.000000
L 12.3671999 2.08208317 12.36666663 2.0787498 2 P 0 ;0,1,2=117,3=0.000000
L 12.36666663 2.0787498 12.3671999 2.07541634 2 P 0 ;0,1,2=117,3=0.000000
L 12.3671999 2.07541634 12.3688 2.07333346 2 P 0 ;0,1,2=117,3=0.000000
L 12.3688 2.07333346 12.37066673 2.07208297 2 P 0 ;0,1,2=117,3=0.000000
L 12.37066673 2.07208297 12.37733346 2.07208297 2 P 0 ;0,1,2=117,3=0.000000
L 12.37066673 2.07208297 12.36666663 2.06 2 P 0 ;0,1,2=117,3=0.000000
L 12.3480003 2.06 12.3480003 2.085 2 P 0 ;0,1,2=117,3=0.000000
L 12.3480003 2.085 12.3512001 2.0800003 2 P 0 ;0,1,2=117,3=0.000000
L 12.3512001 2.06 12.34480049 2.06 2 P 0 ;0,1,2=117,3=0.000000
L 12.32986673 2.06374911 12.32826703 2.06166624 2 P 0 ;0,1,2=117,3=0.000000
L 12.32826703 2.06166624 12.3264003 2.06041654 2 P 0 ;0,1,2=117,3=0.000000
L 12.3264003 2.06041654 12.3240003 2.06 2 P 0 ;0,1,2=117,3=0.000000
L 12.3240003 2.06 12.3215998 2.06083307 2 P 0 ;0,1,2=117,3=0.000000
L 12.3215998 2.06083307 12.31973356 2.06249941 2 P 0 ;0,1,2=117,3=0.000000
L 12.31973356 2.06249941 12.3184 2.06541624 2 P 0 ;0,1,2=117,3=0.000000
L 12.3184 2.06541624 12.31813337 2.06874961 2 P 0 ;0,1,2=117,3=0.000000
L 12.31813337 2.06874961 12.31866663 2.07208297 2 P 0 ;0,1,2=117,3=0.000000
L 12.31866663 2.07208297 12.3200002 2.07416663 2 P 0 ;0,1,2=117,3=0.000000
L 12.3200002 2.07416663 12.32186693 2.07583297 2 P 0 ;0,1,2=117,3=0.000000
L 12.32186693 2.07583297 12.32373317 2.07624951 2 P 0 ;0,1,2=117,3=0.000000
L 12.32373317 2.07624951 12.3256 2.07583297 2 P 0 ;0,1,2=117,3=0.000000
L 12.3256 2.07583297 12.3279999 2.07416663 2 P 0 ;0,1,2=117,3=0.000000
L 12.3279999 2.07416663 12.3272001 2.085 2 P 0 ;0,1,2=117,3=0.000000
L 12.3272001 2.085 12.3200002 2.085 2 P 0 ;0,1,2=117,3=0.000000
L 12.30586673 2.06499961 12.30426703 2.06208287 2 P 0 ;0,1,2=117,3=0.000000
L 12.30426703 2.06208287 12.30213366 2.06041654 2 P 0 ;0,1,2=117,3=0.000000
L 12.30213366 2.06041654 12.29973317 2.06 2 P 0 ;0,1,2=117,3=0.000000
L 12.29973317 2.06 12.2975998 2.06041654 2 P 0 ;0,1,2=117,3=0.000000
L 12.2975998 2.06041654 12.29546644 2.06249941 2 P 0 ;0,1,2=117,3=0.000000
L 12.29546644 2.06249941 12.29413337 2.06499961 2 P 0 ;0,1,2=117,3=0.000000
L 12.29413337 2.06499961 12.29386683 2.0674999 2 P 0 ;0,1,2=117,3=0.000000
L 12.29386683 2.0674999 12.2944 2.07041594 2 P 0 ;0,1,2=117,3=0.000000
L 12.2944 2.07041594 12.29626673 2.07249961 2 P 0 ;0,1,2=117,3=0.000000
L 12.29626673 2.07249961 12.29813356 2.07333346 2 P 0 ;0,1,2=117,3=0.000000
L 12.29813356 2.07333346 12.30053346 2.07333346 2 P 0 ;0,1,2=117,3=0.000000
L 12.29813356 2.07333346 12.29653337 2.07458327 2 P 0 ;0,1,2=117,3=0.000000
L 12.29653337 2.07458327 12.2951999 2.07666614 2 P 0 ;0,1,2=117,3=0.000000
L 12.2951999 2.07666614 12.29466663 2.07916634 2 P 0 ;0,1,2=117,3=0.000000
L 12.29466663 2.07916634 12.2951999 2.08166654 2 P 0 ;0,1,2=117,3=0.000000
L 12.2951999 2.08166654 12.29653337 2.08374941 2 P 0 ;0,1,2=117,3=0.000000
L 12.29653337 2.08374941 12.29893337 2.085 2 P 0 ;0,1,2=117,3=0.000000
L 12.29893337 2.085 12.30133337 2.08458337 2 P 0 ;0,1,2=117,3=0.000000
L 12.30133337 2.08458337 12.30373337 2.08291634 2 P 0 ;0,1,2=117,3=0.000000
L 12.2760003 2.06 12.2760003 2.085 2 P 0 ;0,1,2=117,3=0.000000
L 12.2760003 2.085 12.2792001 2.0800003 2 P 0 ;0,1,2=117,3=0.000000
L 12.2792001 2.06 12.27280049 2.06 2 P 0 ;0,1,2=117,3=0.000000
A 5.68266004 4.5952 5.68266004 4.5952 5.67708996 4.5952 2 P 0 N
L 5.69708996 4.70986654 5.72208996 4.70986654 2 P 0 ;0,1,2=118,3=90.000000
L 5.72208996 4.70986654 5.72208996 4.71626663 2 P 0 ;0,1,2=118,3=90.000000
L 5.72208996 4.71626663 5.72083937 4.7184 2 P 0 ;0,1,2=118,3=90.000000
L 5.72083937 4.7184 5.71792333 4.7200001 2 P 0 ;0,1,2=118,3=90.000000
L 5.71792333 4.7200001 5.71458996 4.72053337 2 P 0 ;0,1,2=118,3=90.000000
L 5.71458996 4.72053337 5.71125659 4.7200001 2 P 0 ;0,1,2=118,3=90.000000
L 5.71125659 4.7200001 5.7087564 4.71866663 2 P 0 ;0,1,2=118,3=90.000000
L 5.7087564 4.71866663 5.70750591 4.71626663 2 P 0 ;0,1,2=118,3=90.000000
L 5.70750591 4.71626663 5.70750591 4.70986654 2 P 0 ;0,1,2=118,3=90.000000
L 5.70042254 4.7335999 5.69833967 4.73573327 2 P 0 ;0,1,2=118,3=90.000000
L 5.69833967 4.73573327 5.69708996 4.73813327 2 P 0 ;0,1,2=118,3=90.000000
L 5.69708996 4.73813327 5.69708996 4.74026663 2 P 0 ;0,1,2=118,3=90.000000
L 5.69708996 4.74026663 5.69833967 4.7424 2 P 0 ;0,1,2=118,3=90.000000
L 5.69833967 4.7424 5.70042254 4.7440001 2 P 0 ;0,1,2=118,3=90.000000
L 5.70042254 4.7440001 5.70334006 4.7448 2 P 0 ;0,1,2=118,3=90.000000
L 5.70334006 4.7448 5.7062561 4.74426673 2 P 0 ;0,1,2=118,3=90.000000
L 5.7062561 4.74426673 5.7087564 4.74293327 2 P 0 ;0,1,2=118,3=90.000000
L 5.7087564 4.74293327 5.71042343 4.74053327 2 P 0 ;0,1,2=118,3=90.000000
L 5.71042343 4.74053327 5.71125659 4.73733346 2 P 0 ;0,1,2=118,3=90.000000
L 5.71125659 4.73733346 5.71292293 4.73546663 2 P 0 ;0,1,2=118,3=90.000000
L 5.71292293 4.73546663 5.71583976 4.73466634 2 P 0 ;0,1,2=118,3=90.000000
L 5.71583976 4.73466634 5.7187565 4.7352001 2 P 0 ;0,1,2=118,3=90.000000
L 5.7187565 4.7352001 5.72083937 4.73653317 2 P 0 ;0,1,2=118,3=90.000000
L 5.72083937 4.73653317 5.72208996 4.7383999 2 P 0 ;0,1,2=118,3=90.000000
L 5.72208996 4.7383999 5.72208996 4.74026663 2 P 0 ;0,1,2=118,3=90.000000
L 5.72208996 4.74026663 5.72125679 4.74213337 2 P 0 ;0,1,2=118,3=90.000000
L 5.72125679 4.74213337 5.71917313 4.74373356 2 P 0 ;0,1,2=118,3=90.000000
L 5.72208996 4.7631997 5.69708996 4.7631997 2 P 0 ;0,1,2=118,3=90.000000
L 5.72208996 4.75706673 5.72208996 4.76933317 2 P 0 ;0,1,2=118,3=90.000000
L 5.7200063 4.79306663 5.72125679 4.79146644 2 P 0 ;0,1,2=118,3=90.000000
L 5.72125679 4.79146644 5.72208996 4.7896002 2 P 0 ;0,1,2=118,3=90.000000
L 5.72208996 4.7896002 5.72208996 4.78746683 2 P 0 ;0,1,2=118,3=90.000000
L 5.72208996 4.78746683 5.72083937 4.78506634 2 P 0 ;0,1,2=118,3=90.000000
L 5.72083937 4.78506634 5.7187565 4.7832001 2 P 0 ;0,1,2=118,3=90.000000
L 5.7187565 4.7832001 5.7162563 4.78186654 2 P 0 ;0,1,2=118,3=90.000000
L 5.7162563 4.78186654 5.71208976 4.78079961 2 P 0 ;0,1,2=118,3=90.000000
L 5.71208976 4.78079961 5.70833976 4.78053297 2 P 0 ;0,1,2=118,3=90.000000
L 5.70833976 4.78053297 5.70458986 4.78106673 2 P 0 ;0,1,2=118,3=90.000000
L 5.70458986 4.78106673 5.70208957 4.78186654 2 P 0 ;0,1,2=118,3=90.000000
L 5.70208957 4.78186654 5.69958937 4.78346663 2 P 0 ;0,1,2=118,3=90.000000
L 5.69958937 4.78346663 5.69792303 4.78533346 2 P 0 ;0,1,2=118,3=90.000000
L 5.69792303 4.78533346 5.69708996 4.7871997 2 P 0 ;0,1,2=118,3=90.000000
L 5.69708996 4.7871997 5.69708996 4.78906644 2 P 0 ;0,1,2=118,3=90.000000
L 5.69708996 4.78906644 5.69792303 4.79093327 2 P 0 ;0,1,2=118,3=90.000000
L 5.69792303 4.79093327 5.69917283 4.79253337 2 P 0 ;0,1,2=118,3=90.000000
L 5.69917283 4.79253337 5.70083907 4.79386693 2 P 0 ;0,1,2=118,3=90.000000
L 5.71792333 4.80613317 5.72042283 4.80773327 2 P 0 ;0,1,2=118,3=90.000000
L 5.72042283 4.80773327 5.72167333 4.8096 2 P 0 ;0,1,2=118,3=90.000000
L 5.72167333 4.8096 5.72208996 4.81173337 2 P 0 ;0,1,2=118,3=90.000000
L 5.72208996 4.81173337 5.72125679 4.8144 2 P 0 ;0,1,2=118,3=90.000000
L 5.72125679 4.8144 5.71917313 4.81626673 2 P 0 ;0,1,2=118,3=90.000000
L 5.71917313 4.81626673 5.71667362 4.8168 2 P 0 ;0,1,2=118,3=90.000000
L 5.71667362 4.8168 5.71417264 4.81653337 2 P 0 ;0,1,2=118,3=90.000000
L 5.71417264 4.81653337 5.71208976 4.81546644 2 P 0 ;0,1,2=118,3=90.000000
L 5.71208976 4.81546644 5.70792323 4.81013327 2 P 0 ;0,1,2=118,3=90.000000
L 5.70792323 4.81013327 5.7050064 4.80773327 2 P 0 ;0,1,2=118,3=90.000000
L 5.7050064 4.80773327 5.70083907 4.80613317 2 P 0 ;0,1,2=118,3=90.000000
L 5.70083907 4.80613317 5.69708996 4.8055999 2 P 0 ;0,1,2=118,3=90.000000
L 5.69708996 4.8055999 5.69708996 4.8168 2 P 0 ;0,1,2=118,3=90.000000
L 5.70083907 4.82933327 5.6987562 4.83093297 2 P 0 ;0,1,2=118,3=90.000000
L 5.6987562 4.83093297 5.6975065 4.8327997 2 P 0 ;0,1,2=118,3=90.000000
L 5.6975065 4.8327997 5.69708996 4.8351997 2 P 0 ;0,1,2=118,3=90.000000
L 5.69708996 4.8351997 5.69792303 4.8376002 2 P 0 ;0,1,2=118,3=90.000000
L 5.69792303 4.8376002 5.69958937 4.83946644 2 P 0 ;0,1,2=118,3=90.000000
L 5.69958937 4.83946644 5.7025062 4.8408 2 P 0 ;0,1,2=118,3=90.000000
L 5.7025062 4.8408 5.70583957 4.84106663 2 P 0 ;0,1,2=118,3=90.000000
L 5.70583957 4.84106663 5.70917293 4.84053337 2 P 0 ;0,1,2=118,3=90.000000
L 5.70917293 4.84053337 5.71125659 4.8391998 2 P 0 ;0,1,2=118,3=90.000000
L 5.71125659 4.8391998 5.71292293 4.83733307 2 P 0 ;0,1,2=118,3=90.000000
L 5.71292293 4.83733307 5.71333947 4.83546683 2 P 0 ;0,1,2=118,3=90.000000
L 5.71333947 4.83546683 5.71292293 4.8336 2 P 0 ;0,1,2=118,3=90.000000
L 5.71292293 4.8336 5.71125659 4.8312001 2 P 0 ;0,1,2=118,3=90.000000
L 5.71125659 4.8312001 5.72208996 4.8319999 2 P 0 ;0,1,2=118,3=90.000000
L 5.72208996 4.8319999 5.72208996 4.8391998 2 P 0 ;0,1,2=118,3=90.000000
A 5.60336004 4.5952 5.60336004 4.5952 5.59778996 4.5952 2 P 0 N
L 5.62208996 4.71486654 5.64708996 4.71486654 2 P 0 ;0,1,2=119,3=90.000000
L 5.64708996 4.71486654 5.64708996 4.72126663 2 P 0 ;0,1,2=119,3=90.000000
L 5.64708996 4.72126663 5.64583937 4.7234 2 P 0 ;0,1,2=119,3=90.000000
L 5.64583937 4.7234 5.64292333 4.7250001 2 P 0 ;0,1,2=119,3=90.000000
L 5.64292333 4.7250001 5.63958996 4.72553337 2 P 0 ;0,1,2=119,3=90.000000
L 5.63958996 4.72553337 5.63625659 4.7250001 2 P 0 ;0,1,2=119,3=90.000000
L 5.63625659 4.7250001 5.6337564 4.72366663 2 P 0 ;0,1,2=119,3=90.000000
L 5.6337564 4.72366663 5.63250591 4.72126663 2 P 0 ;0,1,2=119,3=90.000000
L 5.63250591 4.72126663 5.63250591 4.71486654 2 P 0 ;0,1,2=119,3=90.000000
L 5.62542254 4.7385999 5.62333967 4.74073327 2 P 0 ;0,1,2=119,3=90.000000
L 5.62333967 4.74073327 5.62208996 4.74313327 2 P 0 ;0,1,2=119,3=90.000000
L 5.62208996 4.74313327 5.62208996 4.74526663 2 P 0 ;0,1,2=119,3=90.000000
L 5.62208996 4.74526663 5.62333967 4.7474 2 P 0 ;0,1,2=119,3=90.000000
L 5.62333967 4.7474 5.62542254 4.7490001 2 P 0 ;0,1,2=119,3=90.000000
L 5.62542254 4.7490001 5.62834006 4.7498 2 P 0 ;0,1,2=119,3=90.000000
L 5.62834006 4.7498 5.6312561 4.74926673 2 P 0 ;0,1,2=119,3=90.000000
L 5.6312561 4.74926673 5.6337564 4.74793327 2 P 0 ;0,1,2=119,3=90.000000
L 5.6337564 4.74793327 5.63542343 4.74553327 2 P 0 ;0,1,2=119,3=90.000000
L 5.63542343 4.74553327 5.63625659 4.74233346 2 P 0 ;0,1,2=119,3=90.000000
L 5.63625659 4.74233346 5.63792293 4.74046663 2 P 0 ;0,1,2=119,3=90.000000
L 5.63792293 4.74046663 5.64083976 4.73966634 2 P 0 ;0,1,2=119,3=90.000000
L 5.64083976 4.73966634 5.6437565 4.7402001 2 P 0 ;0,1,2=119,3=90.000000
L 5.6437565 4.7402001 5.64583937 4.74153317 2 P 0 ;0,1,2=119,3=90.000000
L 5.64583937 4.74153317 5.64708996 4.7433999 2 P 0 ;0,1,2=119,3=90.000000
L 5.64708996 4.7433999 5.64708996 4.74526663 2 P 0 ;0,1,2=119,3=90.000000
L 5.64708996 4.74526663 5.64625679 4.74713337 2 P 0 ;0,1,2=119,3=90.000000
L 5.64625679 4.74713337 5.64417313 4.74873356 2 P 0 ;0,1,2=119,3=90.000000
L 5.64708996 4.7681997 5.62208996 4.7681997 2 P 0 ;0,1,2=119,3=90.000000
L 5.64708996 4.76206673 5.64708996 4.77433317 2 P 0 ;0,1,2=119,3=90.000000
L 5.6450063 4.79806663 5.64625679 4.79646644 2 P 0 ;0,1,2=119,3=90.000000
L 5.64625679 4.79646644 5.64708996 4.7946002 2 P 0 ;0,1,2=119,3=90.000000
L 5.64708996 4.7946002 5.64708996 4.79246683 2 P 0 ;0,1,2=119,3=90.000000
L 5.64708996 4.79246683 5.64583937 4.79006634 2 P 0 ;0,1,2=119,3=90.000000
L 5.64583937 4.79006634 5.6437565 4.7882001 2 P 0 ;0,1,2=119,3=90.000000
L 5.6437565 4.7882001 5.6412563 4.78686654 2 P 0 ;0,1,2=119,3=90.000000
L 5.6412563 4.78686654 5.63708976 4.78579961 2 P 0 ;0,1,2=119,3=90.000000
L 5.63708976 4.78579961 5.63333976 4.78553297 2 P 0 ;0,1,2=119,3=90.000000
L 5.63333976 4.78553297 5.62958986 4.78606673 2 P 0 ;0,1,2=119,3=90.000000
L 5.62958986 4.78606673 5.62708957 4.78686654 2 P 0 ;0,1,2=119,3=90.000000
L 5.62708957 4.78686654 5.62458937 4.78846663 2 P 0 ;0,1,2=119,3=90.000000
L 5.62458937 4.78846663 5.62292303 4.79033346 2 P 0 ;0,1,2=119,3=90.000000
L 5.62292303 4.79033346 5.62208996 4.7921997 2 P 0 ;0,1,2=119,3=90.000000
L 5.62208996 4.7921997 5.62208996 4.79406644 2 P 0 ;0,1,2=119,3=90.000000
L 5.62208996 4.79406644 5.62292303 4.79593327 2 P 0 ;0,1,2=119,3=90.000000
L 5.62292303 4.79593327 5.62417283 4.79753337 2 P 0 ;0,1,2=119,3=90.000000
L 5.62417283 4.79753337 5.62583907 4.79886693 2 P 0 ;0,1,2=119,3=90.000000
L 5.62208996 4.8161997 5.64708996 4.8161997 2 P 0 ;0,1,2=119,3=90.000000
L 5.64708996 4.8161997 5.64209026 4.8129999 2 P 0 ;0,1,2=119,3=90.000000
L 5.62208996 4.8129999 5.62208996 4.81939951 2 P 0 ;0,1,2=119,3=90.000000
L 5.62208996 4.8401997 5.6225065 4.84206644 2 P 0 ;0,1,2=119,3=90.000000
L 5.6225065 4.84206644 5.6237562 4.8441998 2 P 0 ;0,1,2=119,3=90.000000
L 5.6237562 4.8441998 5.62583907 4.84553337 2 P 0 ;0,1,2=119,3=90.000000
L 5.62583907 4.84553337 5.62875669 4.84606663 2 P 0 ;0,1,2=119,3=90.000000
L 5.62875669 4.84606663 5.63167274 4.84553337 2 P 0 ;0,1,2=119,3=90.000000
L 5.63167274 4.84553337 5.63417293 4.84393327 2 P 0 ;0,1,2=119,3=90.000000
L 5.63417293 4.84393327 5.63542343 4.84153327 2 P 0 ;0,1,2=119,3=90.000000
L 5.63542343 4.84153327 5.63542343 4.83886663 2 P 0 ;0,1,2=119,3=90.000000
L 5.63542343 4.83886663 5.63625659 4.83726654 2 P 0 ;0,1,2=119,3=90.000000
L 5.63625659 4.83726654 5.63833947 4.83593297 2 P 0 ;0,1,2=119,3=90.000000
L 5.63833947 4.83593297 5.6412563 4.8353998 2 P 0 ;0,1,2=119,3=90.000000
L 5.6412563 4.8353998 5.64417313 4.8362001 2 P 0 ;0,1,2=119,3=90.000000
L 5.64417313 4.8362001 5.64625679 4.83806634 2 P 0 ;0,1,2=119,3=90.000000
L 5.64625679 4.83806634 5.64708996 4.8401997 2 P 0 ;0,1,2=119,3=90.000000
L 5.64708996 4.8401997 5.64625679 4.84233307 2 P 0 ;0,1,2=119,3=90.000000
L 5.64625679 4.84233307 5.64417313 4.8441998 2 P 0 ;0,1,2=119,3=90.000000
L 5.64417313 4.8441998 5.6412563 4.8450001 2 P 0 ;0,1,2=119,3=90.000000
L 5.6412563 4.8450001 5.63833947 4.84446644 2 P 0 ;0,1,2=119,3=90.000000
L 5.63833947 4.84446644 5.63625659 4.84313337 2 P 0 ;0,1,2=119,3=90.000000
L 5.63625659 4.84313337 5.63542343 4.84153327 2 P 0 ;0,1,2=119,3=90.000000
L 5.63542343 4.84153327 5.63542343 4.83886663 2 P 0 ;0,1,2=119,3=90.000000
L 5.63542343 4.83886663 5.63417293 4.83646663 2 P 0 ;0,1,2=119,3=90.000000
L 5.63417293 4.83646663 5.63167274 4.83486654 2 P 0 ;0,1,2=119,3=90.000000
L 5.63167274 4.83486654 5.62875669 4.83433327 2 P 0 ;0,1,2=119,3=90.000000
L 5.62875669 4.83433327 5.62583907 4.83486654 2 P 0 ;0,1,2=119,3=90.000000
L 5.62583907 4.83486654 5.6237562 4.8362001 2 P 0 ;0,1,2=119,3=90.000000
L 5.6237562 4.8362001 5.6225065 4.83833346 2 P 0 ;0,1,2=119,3=90.000000
L 5.6225065 4.83833346 5.62208996 4.8401997 2 P 0 ;0,1,2=119,3=90.000000
A 5.76266004 4.5952 5.76266004 4.5952 5.75708996 4.5952 2 P 0 N
L 5.77708996 4.70486654 5.80208996 4.70486654 2 P 0 ;0,1,2=120,3=90.000000
L 5.80208996 4.70486654 5.80208996 4.71126663 2 P 0 ;0,1,2=120,3=90.000000
L 5.80208996 4.71126663 5.80083937 4.7134 2 P 0 ;0,1,2=120,3=90.000000
L 5.80083937 4.7134 5.79792333 4.7150001 2 P 0 ;0,1,2=120,3=90.000000
L 5.79792333 4.7150001 5.79458996 4.71553337 2 P 0 ;0,1,2=120,3=90.000000
L 5.79458996 4.71553337 5.79125659 4.7150001 2 P 0 ;0,1,2=120,3=90.000000
L 5.79125659 4.7150001 5.7887564 4.71366663 2 P 0 ;0,1,2=120,3=90.000000
L 5.7887564 4.71366663 5.78750591 4.71126663 2 P 0 ;0,1,2=120,3=90.000000
L 5.78750591 4.71126663 5.78750591 4.70486654 2 P 0 ;0,1,2=120,3=90.000000
L 5.78042254 4.7285999 5.77833967 4.73073327 2 P 0 ;0,1,2=120,3=90.000000
L 5.77833967 4.73073327 5.77708996 4.73313327 2 P 0 ;0,1,2=120,3=90.000000
L 5.77708996 4.73313327 5.77708996 4.73526663 2 P 0 ;0,1,2=120,3=90.000000
L 5.77708996 4.73526663 5.77833967 4.7374 2 P 0 ;0,1,2=120,3=90.000000
L 5.77833967 4.7374 5.78042254 4.7390001 2 P 0 ;0,1,2=120,3=90.000000
L 5.78042254 4.7390001 5.78334006 4.7398 2 P 0 ;0,1,2=120,3=90.000000
L 5.78334006 4.7398 5.7862561 4.73926673 2 P 0 ;0,1,2=120,3=90.000000
L 5.7862561 4.73926673 5.7887564 4.73793327 2 P 0 ;0,1,2=120,3=90.000000
L 5.7887564 4.73793327 5.79042343 4.73553327 2 P 0 ;0,1,2=120,3=90.000000
L 5.79042343 4.73553327 5.79125659 4.73233346 2 P 0 ;0,1,2=120,3=90.000000
L 5.79125659 4.73233346 5.79292293 4.73046663 2 P 0 ;0,1,2=120,3=90.000000
L 5.79292293 4.73046663 5.79583976 4.72966634 2 P 0 ;0,1,2=120,3=90.000000
L 5.79583976 4.72966634 5.7987565 4.7302001 2 P 0 ;0,1,2=120,3=90.000000
L 5.7987565 4.7302001 5.80083937 4.73153317 2 P 0 ;0,1,2=120,3=90.000000
L 5.80083937 4.73153317 5.80208996 4.7333999 2 P 0 ;0,1,2=120,3=90.000000
L 5.80208996 4.7333999 5.80208996 4.73526663 2 P 0 ;0,1,2=120,3=90.000000
L 5.80208996 4.73526663 5.80125679 4.73713337 2 P 0 ;0,1,2=120,3=90.000000
L 5.80125679 4.73713337 5.79917313 4.73873356 2 P 0 ;0,1,2=120,3=90.000000
L 5.80208996 4.7581997 5.77708996 4.7581997 2 P 0 ;0,1,2=120,3=90.000000
L 5.80208996 4.75206673 5.80208996 4.76433317 2 P 0 ;0,1,2=120,3=90.000000
L 5.8000063 4.78806663 5.80125679 4.78646644 2 P 0 ;0,1,2=120,3=90.000000
L 5.80125679 4.78646644 5.80208996 4.7846002 2 P 0 ;0,1,2=120,3=90.000000
L 5.80208996 4.7846002 5.80208996 4.78246683 2 P 0 ;0,1,2=120,3=90.000000
L 5.80208996 4.78246683 5.80083937 4.78006634 2 P 0 ;0,1,2=120,3=90.000000
L 5.80083937 4.78006634 5.7987565 4.7782001 2 P 0 ;0,1,2=120,3=90.000000
L 5.7987565 4.7782001 5.7962563 4.77686654 2 P 0 ;0,1,2=120,3=90.000000
L 5.7962563 4.77686654 5.79208976 4.77579961 2 P 0 ;0,1,2=120,3=90.000000
L 5.79208976 4.77579961 5.78833976 4.77553297 2 P 0 ;0,1,2=120,3=90.000000
L 5.78833976 4.77553297 5.78458986 4.77606673 2 P 0 ;0,1,2=120,3=90.000000
L 5.78458986 4.77606673 5.78208957 4.77686654 2 P 0 ;0,1,2=120,3=90.000000
L 5.78208957 4.77686654 5.77958937 4.77846663 2 P 0 ;0,1,2=120,3=90.000000
L 5.77958937 4.77846663 5.77792303 4.78033346 2 P 0 ;0,1,2=120,3=90.000000
L 5.77792303 4.78033346 5.77708996 4.7821997 2 P 0 ;0,1,2=120,3=90.000000
L 5.77708996 4.7821997 5.77708996 4.78406644 2 P 0 ;0,1,2=120,3=90.000000
L 5.77708996 4.78406644 5.77792303 4.78593327 2 P 0 ;0,1,2=120,3=90.000000
L 5.77792303 4.78593327 5.77917283 4.78753337 2 P 0 ;0,1,2=120,3=90.000000
L 5.77917283 4.78753337 5.78083907 4.78886693 2 P 0 ;0,1,2=120,3=90.000000
L 5.78208957 4.80033327 5.77917283 4.80193297 2 P 0 ;0,1,2=120,3=90.000000
L 5.77917283 4.80193297 5.7775065 4.80406634 2 P 0 ;0,1,2=120,3=90.000000
L 5.7775065 4.80406634 5.77708996 4.80646683 2 P 0 ;0,1,2=120,3=90.000000
L 5.77708996 4.80646683 5.7775065 4.8086002 2 P 0 ;0,1,2=120,3=90.000000
L 5.7775065 4.8086002 5.77958937 4.81073356 2 P 0 ;0,1,2=120,3=90.000000
L 5.77958937 4.81073356 5.78208957 4.81206663 2 P 0 ;0,1,2=120,3=90.000000
L 5.78208957 4.81206663 5.78458986 4.81233317 2 P 0 ;0,1,2=120,3=90.000000
L 5.78458986 4.81233317 5.78750591 4.8118 2 P 0 ;0,1,2=120,3=90.000000
L 5.78750591 4.8118 5.78958957 4.80993327 2 P 0 ;0,1,2=120,3=90.000000
L 5.78958957 4.80993327 5.79042343 4.80806644 2 P 0 ;0,1,2=120,3=90.000000
L 5.79042343 4.80806644 5.79042343 4.80566654 2 P 0 ;0,1,2=120,3=90.000000
L 5.79042343 4.80806644 5.79167323 4.80966663 2 P 0 ;0,1,2=120,3=90.000000
L 5.79167323 4.80966663 5.7937561 4.8110001 2 P 0 ;0,1,2=120,3=90.000000
L 5.7937561 4.8110001 5.7962563 4.81153337 2 P 0 ;0,1,2=120,3=90.000000
L 5.7962563 4.81153337 5.7987565 4.8110001 2 P 0 ;0,1,2=120,3=90.000000
L 5.7987565 4.8110001 5.80083937 4.80966663 2 P 0 ;0,1,2=120,3=90.000000
L 5.80083937 4.80966663 5.80208996 4.80726663 2 P 0 ;0,1,2=120,3=90.000000
L 5.80208996 4.80726663 5.80167333 4.80486663 2 P 0 ;0,1,2=120,3=90.000000
L 5.80167333 4.80486663 5.8000063 4.80246663 2 P 0 ;0,1,2=120,3=90.000000
L 5.79792333 4.82513317 5.80042283 4.82673327 2 P 0 ;0,1,2=120,3=90.000000
L 5.80042283 4.82673327 5.80167333 4.8286 2 P 0 ;0,1,2=120,3=90.000000
L 5.80167333 4.8286 5.80208996 4.83073337 2 P 0 ;0,1,2=120,3=90.000000
L 5.80208996 4.83073337 5.80125679 4.8334 2 P 0 ;0,1,2=120,3=90.000000
L 5.80125679 4.8334 5.79917313 4.83526673 2 P 0 ;0,1,2=120,3=90.000000
L 5.79917313 4.83526673 5.79667362 4.8358 2 P 0 ;0,1,2=120,3=90.000000
L 5.79667362 4.8358 5.79417264 4.83553337 2 P 0 ;0,1,2=120,3=90.000000
L 5.79417264 4.83553337 5.79208976 4.83446644 2 P 0 ;0,1,2=120,3=90.000000
L 5.79208976 4.83446644 5.78792323 4.82913327 2 P 0 ;0,1,2=120,3=90.000000
L 5.78792323 4.82913327 5.7850064 4.82673327 2 P 0 ;0,1,2=120,3=90.000000
L 5.7850064 4.82673327 5.78083907 4.82513317 2 P 0 ;0,1,2=120,3=90.000000
L 5.78083907 4.82513317 5.77708996 4.8245999 2 P 0 ;0,1,2=120,3=90.000000
L 5.77708996 4.8245999 5.77708996 4.8358 2 P 0 ;0,1,2=120,3=90.000000
A 5.84266004 4.5952 5.84266004 4.5952 5.83708996 4.5952 2 P 0 N
L 5.85708996 4.70986654 5.88208996 4.70986654 2 P 0 ;0,1,2=121,3=90.000000
L 5.88208996 4.70986654 5.88208996 4.71626663 2 P 0 ;0,1,2=121,3=90.000000
L 5.88208996 4.71626663 5.88083937 4.7184 2 P 0 ;0,1,2=121,3=90.000000
L 5.88083937 4.7184 5.87792333 4.7200001 2 P 0 ;0,1,2=121,3=90.000000
L 5.87792333 4.7200001 5.87458996 4.72053337 2 P 0 ;0,1,2=121,3=90.000000
L 5.87458996 4.72053337 5.87125659 4.7200001 2 P 0 ;0,1,2=121,3=90.000000
L 5.87125659 4.7200001 5.8687564 4.71866663 2 P 0 ;0,1,2=121,3=90.000000
L 5.8687564 4.71866663 5.86750591 4.71626663 2 P 0 ;0,1,2=121,3=90.000000
L 5.86750591 4.71626663 5.86750591 4.70986654 2 P 0 ;0,1,2=121,3=90.000000
L 5.86042254 4.7335999 5.85833967 4.73573327 2 P 0 ;0,1,2=121,3=90.000000
L 5.85833967 4.73573327 5.85708996 4.73813327 2 P 0 ;0,1,2=121,3=90.000000
L 5.85708996 4.73813327 5.85708996 4.74026663 2 P 0 ;0,1,2=121,3=90.000000
L 5.85708996 4.74026663 5.85833967 4.7424 2 P 0 ;0,1,2=121,3=90.000000
L 5.85833967 4.7424 5.86042254 4.7440001 2 P 0 ;0,1,2=121,3=90.000000
L 5.86042254 4.7440001 5.86334006 4.7448 2 P 0 ;0,1,2=121,3=90.000000
L 5.86334006 4.7448 5.8662561 4.74426673 2 P 0 ;0,1,2=121,3=90.000000
L 5.8662561 4.74426673 5.8687564 4.74293327 2 P 0 ;0,1,2=121,3=90.000000
L 5.8687564 4.74293327 5.87042343 4.74053327 2 P 0 ;0,1,2=121,3=90.000000
L 5.87042343 4.74053327 5.87125659 4.73733346 2 P 0 ;0,1,2=121,3=90.000000
L 5.87125659 4.73733346 5.87292293 4.73546663 2 P 0 ;0,1,2=121,3=90.000000
L 5.87292293 4.73546663 5.87583976 4.73466634 2 P 0 ;0,1,2=121,3=90.000000
L 5.87583976 4.73466634 5.8787565 4.7352001 2 P 0 ;0,1,2=121,3=90.000000
L 5.8787565 4.7352001 5.88083937 4.73653317 2 P 0 ;0,1,2=121,3=90.000000
L 5.88083937 4.73653317 5.88208996 4.7383999 2 P 0 ;0,1,2=121,3=90.000000
L 5.88208996 4.7383999 5.88208996 4.74026663 2 P 0 ;0,1,2=121,3=90.000000
L 5.88208996 4.74026663 5.88125679 4.74213337 2 P 0 ;0,1,2=121,3=90.000000
L 5.88125679 4.74213337 5.87917313 4.74373356 2 P 0 ;0,1,2=121,3=90.000000
L 5.88208996 4.7631997 5.85708996 4.7631997 2 P 0 ;0,1,2=121,3=90.000000
L 5.88208996 4.75706673 5.88208996 4.76933317 2 P 0 ;0,1,2=121,3=90.000000
L 5.8800063 4.79306663 5.88125679 4.79146644 2 P 0 ;0,1,2=121,3=90.000000
L 5.88125679 4.79146644 5.88208996 4.7896002 2 P 0 ;0,1,2=121,3=90.000000
L 5.88208996 4.7896002 5.88208996 4.78746683 2 P 0 ;0,1,2=121,3=90.000000
L 5.88208996 4.78746683 5.88083937 4.78506634 2 P 0 ;0,1,2=121,3=90.000000
L 5.88083937 4.78506634 5.8787565 4.7832001 2 P 0 ;0,1,2=121,3=90.000000
L 5.8787565 4.7832001 5.8762563 4.78186654 2 P 0 ;0,1,2=121,3=90.000000
L 5.8762563 4.78186654 5.87208976 4.78079961 2 P 0 ;0,1,2=121,3=90.000000
L 5.87208976 4.78079961 5.86833976 4.78053297 2 P 0 ;0,1,2=121,3=90.000000
L 5.86833976 4.78053297 5.86458986 4.78106673 2 P 0 ;0,1,2=121,3=90.000000
L 5.86458986 4.78106673 5.86208957 4.78186654 2 P 0 ;0,1,2=121,3=90.000000
L 5.86208957 4.78186654 5.85958937 4.78346663 2 P 0 ;0,1,2=121,3=90.000000
L 5.85958937 4.78346663 5.85792303 4.78533346 2 P 0 ;0,1,2=121,3=90.000000
L 5.85792303 4.78533346 5.85708996 4.7871997 2 P 0 ;0,1,2=121,3=90.000000
L 5.85708996 4.7871997 5.85708996 4.78906644 2 P 0 ;0,1,2=121,3=90.000000
L 5.85708996 4.78906644 5.85792303 4.79093327 2 P 0 ;0,1,2=121,3=90.000000
L 5.85792303 4.79093327 5.85917283 4.79253337 2 P 0 ;0,1,2=121,3=90.000000
L 5.85917283 4.79253337 5.86083907 4.79386693 2 P 0 ;0,1,2=121,3=90.000000
L 5.87792333 4.80613317 5.88042283 4.80773327 2 P 0 ;0,1,2=121,3=90.000000
L 5.88042283 4.80773327 5.88167333 4.8096 2 P 0 ;0,1,2=121,3=90.000000
L 5.88167333 4.8096 5.88208996 4.81173337 2 P 0 ;0,1,2=121,3=90.000000
L 5.88208996 4.81173337 5.88125679 4.8144 2 P 0 ;0,1,2=121,3=90.000000
L 5.88125679 4.8144 5.87917313 4.81626673 2 P 0 ;0,1,2=121,3=90.000000
L 5.87917313 4.81626673 5.87667362 4.8168 2 P 0 ;0,1,2=121,3=90.000000
L 5.87667362 4.8168 5.87417264 4.81653337 2 P 0 ;0,1,2=121,3=90.000000
L 5.87417264 4.81653337 5.87208976 4.81546644 2 P 0 ;0,1,2=121,3=90.000000
L 5.87208976 4.81546644 5.86792323 4.81013327 2 P 0 ;0,1,2=121,3=90.000000
L 5.86792323 4.81013327 5.8650064 4.80773327 2 P 0 ;0,1,2=121,3=90.000000
L 5.8650064 4.80773327 5.86083907 4.80613317 2 P 0 ;0,1,2=121,3=90.000000
L 5.86083907 4.80613317 5.85708996 4.8055999 2 P 0 ;0,1,2=121,3=90.000000
L 5.85708996 4.8055999 5.85708996 4.8168 2 P 0 ;0,1,2=121,3=90.000000
L 5.85708996 4.83466654 5.8625062 4.8351997 2 P 0 ;0,1,2=121,3=90.000000
L 5.8625062 4.8351997 5.86708927 4.836 2 P 0 ;0,1,2=121,3=90.000000
L 5.86708927 4.836 5.87125659 4.83706644 2 P 0 ;0,1,2=121,3=90.000000
L 5.87125659 4.83706644 5.87583976 4.8384 2 P 0 ;0,1,2=121,3=90.000000
L 5.87583976 4.8384 5.88208996 4.84053337 2 P 0 ;0,1,2=121,3=90.000000
L 5.88208996 4.84053337 5.88208996 4.82986654 2 P 0 ;0,1,2=121,3=90.000000
A 6.08266004 4.5952 6.08266004 4.5952 6.07708996 4.5952 2 P 0 N
L 6.09208996 4.71986654 6.11708996 4.71986654 2 P 0 ;0,1,2=122,3=90.000000
L 6.11708996 4.71986654 6.11708996 4.72626663 2 P 0 ;0,1,2=122,3=90.000000
L 6.11708996 4.72626663 6.11583937 4.7284 2 P 0 ;0,1,2=122,3=90.000000
L 6.11583937 4.7284 6.11292333 4.7300001 2 P 0 ;0,1,2=122,3=90.000000
L 6.11292333 4.7300001 6.10958996 4.73053337 2 P 0 ;0,1,2=122,3=90.000000
L 6.10958996 4.73053337 6.10625659 4.7300001 2 P 0 ;0,1,2=122,3=90.000000
L 6.10625659 4.7300001 6.1037564 4.72866663 2 P 0 ;0,1,2=122,3=90.000000
L 6.1037564 4.72866663 6.10250591 4.72626663 2 P 0 ;0,1,2=122,3=90.000000
L 6.10250591 4.72626663 6.10250591 4.71986654 2 P 0 ;0,1,2=122,3=90.000000
L 6.09542254 4.7435999 6.09333967 4.74573327 2 P 0 ;0,1,2=122,3=90.000000
L 6.09333967 4.74573327 6.09208996 4.74813327 2 P 0 ;0,1,2=122,3=90.000000
L 6.09208996 4.74813327 6.09208996 4.75026663 2 P 0 ;0,1,2=122,3=90.000000
L 6.09208996 4.75026663 6.09333967 4.7524 2 P 0 ;0,1,2=122,3=90.000000
L 6.09333967 4.7524 6.09542254 4.7540001 2 P 0 ;0,1,2=122,3=90.000000
L 6.09542254 4.7540001 6.09834006 4.7548 2 P 0 ;0,1,2=122,3=90.000000
L 6.09834006 4.7548 6.1012561 4.75426673 2 P 0 ;0,1,2=122,3=90.000000
L 6.1012561 4.75426673 6.1037564 4.75293327 2 P 0 ;0,1,2=122,3=90.000000
L 6.1037564 4.75293327 6.10542343 4.75053327 2 P 0 ;0,1,2=122,3=90.000000
L 6.10542343 4.75053327 6.10625659 4.74733346 2 P 0 ;0,1,2=122,3=90.000000
L 6.10625659 4.74733346 6.10792293 4.74546663 2 P 0 ;0,1,2=122,3=90.000000
L 6.10792293 4.74546663 6.11083976 4.74466634 2 P 0 ;0,1,2=122,3=90.000000
L 6.11083976 4.74466634 6.1137565 4.7452001 2 P 0 ;0,1,2=122,3=90.000000
L 6.1137565 4.7452001 6.11583937 4.74653317 2 P 0 ;0,1,2=122,3=90.000000
L 6.11583937 4.74653317 6.11708996 4.7483999 2 P 0 ;0,1,2=122,3=90.000000
L 6.11708996 4.7483999 6.11708996 4.75026663 2 P 0 ;0,1,2=122,3=90.000000
L 6.11708996 4.75026663 6.11625679 4.75213337 2 P 0 ;0,1,2=122,3=90.000000
L 6.11625679 4.75213337 6.11417313 4.75373356 2 P 0 ;0,1,2=122,3=90.000000
L 6.11708996 4.7731997 6.09208996 4.7731997 2 P 0 ;0,1,2=122,3=90.000000
L 6.11708996 4.76706673 6.11708996 4.77933317 2 P 0 ;0,1,2=122,3=90.000000
L 6.1150063 4.80306663 6.11625679 4.80146644 2 P 0 ;0,1,2=122,3=90.000000
L 6.11625679 4.80146644 6.11708996 4.7996002 2 P 0 ;0,1,2=122,3=90.000000
L 6.11708996 4.7996002 6.11708996 4.79746683 2 P 0 ;0,1,2=122,3=90.000000
L 6.11708996 4.79746683 6.11583937 4.79506634 2 P 0 ;0,1,2=122,3=90.000000
L 6.11583937 4.79506634 6.1137565 4.7932001 2 P 0 ;0,1,2=122,3=90.000000
L 6.1137565 4.7932001 6.1112563 4.79186654 2 P 0 ;0,1,2=122,3=90.000000
L 6.1112563 4.79186654 6.10708976 4.79079961 2 P 0 ;0,1,2=122,3=90.000000
L 6.10708976 4.79079961 6.10333976 4.79053297 2 P 0 ;0,1,2=122,3=90.000000
L 6.10333976 4.79053297 6.09958986 4.79106673 2 P 0 ;0,1,2=122,3=90.000000
L 6.09958986 4.79106673 6.09708957 4.79186654 2 P 0 ;0,1,2=122,3=90.000000
L 6.09708957 4.79186654 6.09458937 4.79346663 2 P 0 ;0,1,2=122,3=90.000000
L 6.09458937 4.79346663 6.09292303 4.79533346 2 P 0 ;0,1,2=122,3=90.000000
L 6.09292303 4.79533346 6.09208996 4.7971997 2 P 0 ;0,1,2=122,3=90.000000
L 6.09208996 4.7971997 6.09208996 4.79906644 2 P 0 ;0,1,2=122,3=90.000000
L 6.09208996 4.79906644 6.09292303 4.80093327 2 P 0 ;0,1,2=122,3=90.000000
L 6.09292303 4.80093327 6.09417283 4.80253337 2 P 0 ;0,1,2=122,3=90.000000
L 6.09417283 4.80253337 6.09583907 4.80386693 2 P 0 ;0,1,2=122,3=90.000000
L 6.11292333 4.81613317 6.11542283 4.81773327 2 P 0 ;0,1,2=122,3=90.000000
L 6.11542283 4.81773327 6.11667333 4.8196 2 P 0 ;0,1,2=122,3=90.000000
L 6.11667333 4.8196 6.11708996 4.82173337 2 P 0 ;0,1,2=122,3=90.000000
L 6.11708996 4.82173337 6.11625679 4.8244 2 P 0 ;0,1,2=122,3=90.000000
L 6.11625679 4.8244 6.11417313 4.82626673 2 P 0 ;0,1,2=122,3=90.000000
L 6.11417313 4.82626673 6.11167362 4.8268 2 P 0 ;0,1,2=122,3=90.000000
L 6.11167362 4.8268 6.10917264 4.82653337 2 P 0 ;0,1,2=122,3=90.000000
L 6.10917264 4.82653337 6.10708976 4.82546644 2 P 0 ;0,1,2=122,3=90.000000
L 6.10708976 4.82546644 6.10292323 4.82013327 2 P 0 ;0,1,2=122,3=90.000000
L 6.10292323 4.82013327 6.1000064 4.81773327 2 P 0 ;0,1,2=122,3=90.000000
L 6.1000064 4.81773327 6.09583907 4.81613317 2 P 0 ;0,1,2=122,3=90.000000
L 6.09583907 4.81613317 6.09208996 4.8155999 2 P 0 ;0,1,2=122,3=90.000000
L 6.09208996 4.8155999 6.09208996 4.8268 2 P 0 ;0,1,2=122,3=90.000000
L 6.09208996 4.8484 6.11708996 4.8484 2 P 0 ;0,1,2=122,3=90.000000
L 6.11708996 4.8484 6.09917323 4.83853297 2 P 0 ;0,1,2=122,3=90.000000
L 6.09917323 4.83853297 6.09917323 4.85186693 2 P 0 ;0,1,2=122,3=90.000000
A 5.92266004 4.5952 5.92266004 4.5952 5.91708996 4.5952 2 P 0 N
L 5.93708996 4.70486654 5.96208996 4.70486654 2 P 0 ;0,1,2=123,3=90.000000
L 5.96208996 4.70486654 5.96208996 4.71126663 2 P 0 ;0,1,2=123,3=90.000000
L 5.96208996 4.71126663 5.96083937 4.7134 2 P 0 ;0,1,2=123,3=90.000000
L 5.96083937 4.7134 5.95792333 4.7150001 2 P 0 ;0,1,2=123,3=90.000000
L 5.95792333 4.7150001 5.95458996 4.71553337 2 P 0 ;0,1,2=123,3=90.000000
L 5.95458996 4.71553337 5.95125659 4.7150001 2 P 0 ;0,1,2=123,3=90.000000
L 5.95125659 4.7150001 5.9487564 4.71366663 2 P 0 ;0,1,2=123,3=90.000000
L 5.9487564 4.71366663 5.94750591 4.71126663 2 P 0 ;0,1,2=123,3=90.000000
L 5.94750591 4.71126663 5.94750591 4.70486654 2 P 0 ;0,1,2=123,3=90.000000
L 5.94042254 4.7285999 5.93833967 4.73073327 2 P 0 ;0,1,2=123,3=90.000000
L 5.93833967 4.73073327 5.93708996 4.73313327 2 P 0 ;0,1,2=123,3=90.000000
L 5.93708996 4.73313327 5.93708996 4.73526663 2 P 0 ;0,1,2=123,3=90.000000
L 5.93708996 4.73526663 5.93833967 4.7374 2 P 0 ;0,1,2=123,3=90.000000
L 5.93833967 4.7374 5.94042254 4.7390001 2 P 0 ;0,1,2=123,3=90.000000
L 5.94042254 4.7390001 5.94334006 4.7398 2 P 0 ;0,1,2=123,3=90.000000
L 5.94334006 4.7398 5.9462561 4.73926673 2 P 0 ;0,1,2=123,3=90.000000
L 5.9462561 4.73926673 5.9487564 4.73793327 2 P 0 ;0,1,2=123,3=90.000000
L 5.9487564 4.73793327 5.95042343 4.73553327 2 P 0 ;0,1,2=123,3=90.000000
L 5.95042343 4.73553327 5.95125659 4.73233346 2 P 0 ;0,1,2=123,3=90.000000
L 5.95125659 4.73233346 5.95292293 4.73046663 2 P 0 ;0,1,2=123,3=90.000000
L 5.95292293 4.73046663 5.95583976 4.72966634 2 P 0 ;0,1,2=123,3=90.000000
L 5.95583976 4.72966634 5.9587565 4.7302001 2 P 0 ;0,1,2=123,3=90.000000
L 5.9587565 4.7302001 5.96083937 4.73153317 2 P 0 ;0,1,2=123,3=90.000000
L 5.96083937 4.73153317 5.96208996 4.7333999 2 P 0 ;0,1,2=123,3=90.000000
L 5.96208996 4.7333999 5.96208996 4.73526663 2 P 0 ;0,1,2=123,3=90.000000
L 5.96208996 4.73526663 5.96125679 4.73713337 2 P 0 ;0,1,2=123,3=90.000000
L 5.96125679 4.73713337 5.95917313 4.73873356 2 P 0 ;0,1,2=123,3=90.000000
L 5.96208996 4.7581997 5.93708996 4.7581997 2 P 0 ;0,1,2=123,3=90.000000
L 5.96208996 4.75206673 5.96208996 4.76433317 2 P 0 ;0,1,2=123,3=90.000000
L 5.9600063 4.78806663 5.96125679 4.78646644 2 P 0 ;0,1,2=123,3=90.000000
L 5.96125679 4.78646644 5.96208996 4.7846002 2 P 0 ;0,1,2=123,3=90.000000
L 5.96208996 4.7846002 5.96208996 4.78246683 2 P 0 ;0,1,2=123,3=90.000000
L 5.96208996 4.78246683 5.96083937 4.78006634 2 P 0 ;0,1,2=123,3=90.000000
L 5.96083937 4.78006634 5.9587565 4.7782001 2 P 0 ;0,1,2=123,3=90.000000
L 5.9587565 4.7782001 5.9562563 4.77686654 2 P 0 ;0,1,2=123,3=90.000000
L 5.9562563 4.77686654 5.95208976 4.77579961 2 P 0 ;0,1,2=123,3=90.000000
L 5.95208976 4.77579961 5.94833976 4.77553297 2 P 0 ;0,1,2=123,3=90.000000
L 5.94833976 4.77553297 5.94458986 4.77606673 2 P 0 ;0,1,2=123,3=90.000000
L 5.94458986 4.77606673 5.94208957 4.77686654 2 P 0 ;0,1,2=123,3=90.000000
L 5.94208957 4.77686654 5.93958937 4.77846663 2 P 0 ;0,1,2=123,3=90.000000
L 5.93958937 4.77846663 5.93792303 4.78033346 2 P 0 ;0,1,2=123,3=90.000000
L 5.93792303 4.78033346 5.93708996 4.7821997 2 P 0 ;0,1,2=123,3=90.000000
L 5.93708996 4.7821997 5.93708996 4.78406644 2 P 0 ;0,1,2=123,3=90.000000
L 5.93708996 4.78406644 5.93792303 4.78593327 2 P 0 ;0,1,2=123,3=90.000000
L 5.93792303 4.78593327 5.93917283 4.78753337 2 P 0 ;0,1,2=123,3=90.000000
L 5.93917283 4.78753337 5.94083907 4.78886693 2 P 0 ;0,1,2=123,3=90.000000
L 5.94208957 4.80033327 5.93917283 4.80193297 2 P 0 ;0,1,2=123,3=90.000000
L 5.93917283 4.80193297 5.9375065 4.80406634 2 P 0 ;0,1,2=123,3=90.000000
L 5.9375065 4.80406634 5.93708996 4.80646683 2 P 0 ;0,1,2=123,3=90.000000
L 5.93708996 4.80646683 5.9375065 4.8086002 2 P 0 ;0,1,2=123,3=90.000000
L 5.9375065 4.8086002 5.93958937 4.81073356 2 P 0 ;0,1,2=123,3=90.000000
L 5.93958937 4.81073356 5.94208957 4.81206663 2 P 0 ;0,1,2=123,3=90.000000
L 5.94208957 4.81206663 5.94458986 4.81233317 2 P 0 ;0,1,2=123,3=90.000000
L 5.94458986 4.81233317 5.94750591 4.8118 2 P 0 ;0,1,2=123,3=90.000000
L 5.94750591 4.8118 5.94958957 4.80993327 2 P 0 ;0,1,2=123,3=90.000000
L 5.94958957 4.80993327 5.95042343 4.80806644 2 P 0 ;0,1,2=123,3=90.000000
L 5.95042343 4.80806644 5.95042343 4.80566654 2 P 0 ;0,1,2=123,3=90.000000
L 5.95042343 4.80806644 5.95167323 4.80966663 2 P 0 ;0,1,2=123,3=90.000000
L 5.95167323 4.80966663 5.9537561 4.8110001 2 P 0 ;0,1,2=123,3=90.000000
L 5.9537561 4.8110001 5.9562563 4.81153337 2 P 0 ;0,1,2=123,3=90.000000
L 5.9562563 4.81153337 5.9587565 4.8110001 2 P 0 ;0,1,2=123,3=90.000000
L 5.9587565 4.8110001 5.96083937 4.80966663 2 P 0 ;0,1,2=123,3=90.000000
L 5.96083937 4.80966663 5.96208996 4.80726663 2 P 0 ;0,1,2=123,3=90.000000
L 5.96208996 4.80726663 5.96167333 4.80486663 2 P 0 ;0,1,2=123,3=90.000000
L 5.96167333 4.80486663 5.9600063 4.80246663 2 P 0 ;0,1,2=123,3=90.000000
L 5.96208996 4.8301997 5.96125679 4.82806634 2 P 0 ;0,1,2=123,3=90.000000
L 5.96125679 4.82806634 5.95917313 4.82646663 2 P 0 ;0,1,2=123,3=90.000000
L 5.95917313 4.82646663 5.95667362 4.8253998 2 P 0 ;0,1,2=123,3=90.000000
L 5.95667362 4.8253998 5.95333947 4.8245999 2 P 0 ;0,1,2=123,3=90.000000
L 5.95333947 4.8245999 5.94958957 4.82433327 2 P 0 ;0,1,2=123,3=90.000000
L 5.94958957 4.82433327 5.94583957 4.8245999 2 P 0 ;0,1,2=123,3=90.000000
L 5.94583957 4.8245999 5.9425062 4.8253998 2 P 0 ;0,1,2=123,3=90.000000
L 5.9425062 4.8253998 5.940006 4.82646663 2 P 0 ;0,1,2=123,3=90.000000
L 5.940006 4.82646663 5.93792303 4.82806634 2 P 0 ;0,1,2=123,3=90.000000
L 5.93792303 4.82806634 5.93708996 4.8301997 2 P 0 ;0,1,2=123,3=90.000000
L 5.93708996 4.8301997 5.93792303 4.83233307 2 P 0 ;0,1,2=123,3=90.000000
L 5.93792303 4.83233307 5.940006 4.83393327 2 P 0 ;0,1,2=123,3=90.000000
L 5.940006 4.83393327 5.9425062 4.8350001 2 P 0 ;0,1,2=123,3=90.000000
L 5.9425062 4.8350001 5.94583957 4.8358 2 P 0 ;0,1,2=123,3=90.000000
L 5.94583957 4.8358 5.94958957 4.83606663 2 P 0 ;0,1,2=123,3=90.000000
L 5.94958957 4.83606663 5.95333947 4.8358 2 P 0 ;0,1,2=123,3=90.000000
L 5.95333947 4.8358 5.95667362 4.8350001 2 P 0 ;0,1,2=123,3=90.000000
L 5.95667362 4.8350001 5.95917313 4.83393327 2 P 0 ;0,1,2=123,3=90.000000
L 5.95917313 4.83393327 5.96125679 4.83233307 2 P 0 ;0,1,2=123,3=90.000000
L 5.96125679 4.83233307 5.96208996 4.8301997 2 P 0 ;0,1,2=123,3=90.000000
A 6.00266004 4.5952 6.00266004 4.5952 5.99708996 4.5952 2 P 0 Y
L 6.01708996 4.70986654 6.04208996 4.70986654 2 P 0 ;0,1,2=124,3=90.000000
L 6.04208996 4.70986654 6.04208996 4.71626663 2 P 0 ;0,1,2=124,3=90.000000
L 6.04208996 4.71626663 6.04083937 4.7184 2 P 0 ;0,1,2=124,3=90.000000
L 6.04083937 4.7184 6.03792333 4.7200001 2 P 0 ;0,1,2=124,3=90.000000
L 6.03792333 4.7200001 6.03458996 4.72053337 2 P 0 ;0,1,2=124,3=90.000000
L 6.03458996 4.72053337 6.03125659 4.7200001 2 P 0 ;0,1,2=124,3=90.000000
L 6.03125659 4.7200001 6.0287564 4.71866663 2 P 0 ;0,1,2=124,3=90.000000
L 6.0287564 4.71866663 6.02750591 4.71626663 2 P 0 ;0,1,2=124,3=90.000000
L 6.02750591 4.71626663 6.02750591 4.70986654 2 P 0 ;0,1,2=124,3=90.000000
L 6.02042254 4.7335999 6.01833967 4.73573327 2 P 0 ;0,1,2=124,3=90.000000
L 6.01833967 4.73573327 6.01708996 4.73813327 2 P 0 ;0,1,2=124,3=90.000000
L 6.01708996 4.73813327 6.01708996 4.74026663 2 P 0 ;0,1,2=124,3=90.000000
L 6.01708996 4.74026663 6.01833967 4.7424 2 P 0 ;0,1,2=124,3=90.000000
L 6.01833967 4.7424 6.02042254 4.7440001 2 P 0 ;0,1,2=124,3=90.000000
L 6.02042254 4.7440001 6.02334006 4.7448 2 P 0 ;0,1,2=124,3=90.000000
L 6.02334006 4.7448 6.0262561 4.74426673 2 P 0 ;0,1,2=124,3=90.000000
L 6.0262561 4.74426673 6.0287564 4.74293327 2 P 0 ;0,1,2=124,3=90.000000
L 6.0287564 4.74293327 6.03042343 4.74053327 2 P 0 ;0,1,2=124,3=90.000000
L 6.03042343 4.74053327 6.03125659 4.73733346 2 P 0 ;0,1,2=124,3=90.000000
L 6.03125659 4.73733346 6.03292293 4.73546663 2 P 0 ;0,1,2=124,3=90.000000
L 6.03292293 4.73546663 6.03583976 4.73466634 2 P 0 ;0,1,2=124,3=90.000000
L 6.03583976 4.73466634 6.0387565 4.7352001 2 P 0 ;0,1,2=124,3=90.000000
L 6.0387565 4.7352001 6.04083937 4.73653317 2 P 0 ;0,1,2=124,3=90.000000
L 6.04083937 4.73653317 6.04208996 4.7383999 2 P 0 ;0,1,2=124,3=90.000000
L 6.04208996 4.7383999 6.04208996 4.74026663 2 P 0 ;0,1,2=124,3=90.000000
L 6.04208996 4.74026663 6.04125679 4.74213337 2 P 0 ;0,1,2=124,3=90.000000
L 6.04125679 4.74213337 6.03917313 4.74373356 2 P 0 ;0,1,2=124,3=90.000000
L 6.04208996 4.7631997 6.01708996 4.7631997 2 P 0 ;0,1,2=124,3=90.000000
L 6.04208996 4.75706673 6.04208996 4.76933317 2 P 0 ;0,1,2=124,3=90.000000
L 6.0400063 4.79306663 6.04125679 4.79146644 2 P 0 ;0,1,2=124,3=90.000000
L 6.04125679 4.79146644 6.04208996 4.7896002 2 P 0 ;0,1,2=124,3=90.000000
L 6.04208996 4.7896002 6.04208996 4.78746683 2 P 0 ;0,1,2=124,3=90.000000
L 6.04208996 4.78746683 6.04083937 4.78506634 2 P 0 ;0,1,2=124,3=90.000000
L 6.04083937 4.78506634 6.0387565 4.7832001 2 P 0 ;0,1,2=124,3=90.000000
L 6.0387565 4.7832001 6.0362563 4.78186654 2 P 0 ;0,1,2=124,3=90.000000
L 6.0362563 4.78186654 6.03208976 4.78079961 2 P 0 ;0,1,2=124,3=90.000000
L 6.03208976 4.78079961 6.02833976 4.78053297 2 P 0 ;0,1,2=124,3=90.000000
L 6.02833976 4.78053297 6.02458986 4.78106673 2 P 0 ;0,1,2=124,3=90.000000
L 6.02458986 4.78106673 6.02208957 4.78186654 2 P 0 ;0,1,2=124,3=90.000000
L 6.02208957 4.78186654 6.01958937 4.78346663 2 P 0 ;0,1,2=124,3=90.000000
L 6.01958937 4.78346663 6.01792303 4.78533346 2 P 0 ;0,1,2=124,3=90.000000
L 6.01792303 4.78533346 6.01708996 4.7871997 2 P 0 ;0,1,2=124,3=90.000000
L 6.01708996 4.7871997 6.01708996 4.78906644 2 P 0 ;0,1,2=124,3=90.000000
L 6.01708996 4.78906644 6.01792303 4.79093327 2 P 0 ;0,1,2=124,3=90.000000
L 6.01792303 4.79093327 6.01917283 4.79253337 2 P 0 ;0,1,2=124,3=90.000000
L 6.01917283 4.79253337 6.02083907 4.79386693 2 P 0 ;0,1,2=124,3=90.000000
L 6.02208957 4.80533327 6.01917283 4.80693297 2 P 0 ;0,1,2=124,3=90.000000
L 6.01917283 4.80693297 6.0175065 4.80906634 2 P 0 ;0,1,2=124,3=90.000000
L 6.0175065 4.80906634 6.01708996 4.81146683 2 P 0 ;0,1,2=124,3=90.000000
L 6.01708996 4.81146683 6.0175065 4.8136002 2 P 0 ;0,1,2=124,3=90.000000
L 6.0175065 4.8136002 6.01958937 4.81573356 2 P 0 ;0,1,2=124,3=90.000000
L 6.01958937 4.81573356 6.02208957 4.81706663 2 P 0 ;0,1,2=124,3=90.000000
L 6.02208957 4.81706663 6.02458986 4.81733317 2 P 0 ;0,1,2=124,3=90.000000
L 6.02458986 4.81733317 6.02750591 4.8168 2 P 0 ;0,1,2=124,3=90.000000
L 6.02750591 4.8168 6.02958957 4.81493327 2 P 0 ;0,1,2=124,3=90.000000
L 6.02958957 4.81493327 6.03042343 4.81306644 2 P 0 ;0,1,2=124,3=90.000000
L 6.03042343 4.81306644 6.03042343 4.81066654 2 P 0 ;0,1,2=124,3=90.000000
L 6.03042343 4.81306644 6.03167323 4.81466663 2 P 0 ;0,1,2=124,3=90.000000
L 6.03167323 4.81466663 6.0337561 4.8160001 2 P 0 ;0,1,2=124,3=90.000000
L 6.0337561 4.8160001 6.0362563 4.81653337 2 P 0 ;0,1,2=124,3=90.000000
L 6.0362563 4.81653337 6.0387565 4.8160001 2 P 0 ;0,1,2=124,3=90.000000
L 6.0387565 4.8160001 6.04083937 4.81466663 2 P 0 ;0,1,2=124,3=90.000000
L 6.04083937 4.81466663 6.04208996 4.81226663 2 P 0 ;0,1,2=124,3=90.000000
L 6.04208996 4.81226663 6.04167333 4.80986663 2 P 0 ;0,1,2=124,3=90.000000
L 6.04167333 4.80986663 6.0400063 4.80746663 2 P 0 ;0,1,2=124,3=90.000000
L 6.01708996 4.8351997 6.04208996 4.8351997 2 P 0 ;0,1,2=124,3=90.000000
L 6.04208996 4.8351997 6.03709026 4.8319999 2 P 0 ;0,1,2=124,3=90.000000
L 6.01708996 4.8319999 6.01708996 4.83839951 2 P 0 ;0,1,2=124,3=90.000000
A 6.23766004 4.7202 6.23766004 4.7202 6.23208996 4.7202 2 P 0 N
L 6.46742343 4.7102 6.46742343 4.7352 2 P 0 ;0,1,2=125,3=0.000000
L 6.46742343 4.7352 6.46102333 4.7352 2 P 0 ;0,1,2=125,3=0.000000
L 6.46102333 4.7352 6.45888996 4.73394941 2 P 0 ;0,1,2=125,3=0.000000
L 6.45888996 4.73394941 6.45728986 4.73103337 2 P 0 ;0,1,2=125,3=0.000000
L 6.45728986 4.73103337 6.45675659 4.7277 2 P 0 ;0,1,2=125,3=0.000000
L 6.45675659 4.7277 6.45728986 4.72436663 2 P 0 ;0,1,2=125,3=0.000000
L 6.45728986 4.72436663 6.45862333 4.72186644 2 P 0 ;0,1,2=125,3=0.000000
L 6.45862333 4.72186644 6.46102333 4.72061594 2 P 0 ;0,1,2=125,3=0.000000
L 6.46102333 4.72061594 6.46742343 4.72061594 2 P 0 ;0,1,2=125,3=0.000000
L 6.44369006 4.71353258 6.44155669 4.7114497 2 P 0 ;0,1,2=125,3=0.000000
L 6.44155669 4.7114497 6.43915669 4.7102 2 P 0 ;0,1,2=125,3=0.000000
L 6.43915669 4.7102 6.43702333 4.7102 2 P 0 ;0,1,2=125,3=0.000000
L 6.43702333 4.7102 6.43488996 4.7114497 2 P 0 ;0,1,2=125,3=0.000000
L 6.43488996 4.7114497 6.43328986 4.71353258 2 P 0 ;0,1,2=125,3=0.000000
L 6.43328986 4.71353258 6.43248996 4.7164501 2 P 0 ;0,1,2=125,3=0.000000
L 6.43248996 4.7164501 6.43302323 4.71936614 2 P 0 ;0,1,2=125,3=0.000000
L 6.43302323 4.71936614 6.43435669 4.72186644 2 P 0 ;0,1,2=125,3=0.000000
L 6.43435669 4.72186644 6.43675669 4.72353346 2 P 0 ;0,1,2=125,3=0.000000
L 6.43675669 4.72353346 6.4399565 4.72436663 2 P 0 ;0,1,2=125,3=0.000000
L 6.4399565 4.72436663 6.44182333 4.72603297 2 P 0 ;0,1,2=125,3=0.000000
L 6.44182333 4.72603297 6.44262362 4.7289498 2 P 0 ;0,1,2=125,3=0.000000
L 6.44262362 4.7289498 6.44208986 4.73186654 2 P 0 ;0,1,2=125,3=0.000000
L 6.44208986 4.73186654 6.44075679 4.73394941 2 P 0 ;0,1,2=125,3=0.000000
L 6.44075679 4.73394941 6.43889006 4.7352 2 P 0 ;0,1,2=125,3=0.000000
L 6.43889006 4.7352 6.43702333 4.7352 2 P 0 ;0,1,2=125,3=0.000000
L 6.43702333 4.7352 6.43515659 4.73436683 2 P 0 ;0,1,2=125,3=0.000000
L 6.43515659 4.73436683 6.4335564 4.73228317 2 P 0 ;0,1,2=125,3=0.000000
L 6.41409026 4.7352 6.41409026 4.7102 2 P 0 ;0,1,2=125,3=0.000000
L 6.42022323 4.7352 6.40795679 4.7352 2 P 0 ;0,1,2=125,3=0.000000
L 6.38422333 4.73311634 6.38582352 4.73436683 2 P 0 ;0,1,2=125,3=0.000000
L 6.38582352 4.73436683 6.38768976 4.7352 2 P 0 ;0,1,2=125,3=0.000000
L 6.38768976 4.7352 6.38982313 4.7352 2 P 0 ;0,1,2=125,3=0.000000
L 6.38982313 4.7352 6.39222362 4.73394941 2 P 0 ;0,1,2=125,3=0.000000
L 6.39222362 4.73394941 6.39408986 4.73186654 2 P 0 ;0,1,2=125,3=0.000000
L 6.39408986 4.73186654 6.39542343 4.72936634 2 P 0 ;0,1,2=125,3=0.000000
L 6.39542343 4.72936634 6.39649035 4.7251998 2 P 0 ;0,1,2=125,3=0.000000
L 6.39649035 4.7251998 6.39675699 4.7214498 2 P 0 ;0,1,2=125,3=0.000000
L 6.39675699 4.7214498 6.39622323 4.7176999 2 P 0 ;0,1,2=125,3=0.000000
L 6.39622323 4.7176999 6.39542343 4.71519961 2 P 0 ;0,1,2=125,3=0.000000
L 6.39542343 4.71519961 6.39382333 4.71269941 2 P 0 ;0,1,2=125,3=0.000000
L 6.39382333 4.71269941 6.3919565 4.71103307 2 P 0 ;0,1,2=125,3=0.000000
L 6.3919565 4.71103307 6.39009026 4.7102 2 P 0 ;0,1,2=125,3=0.000000
L 6.39009026 4.7102 6.38822352 4.7102 2 P 0 ;0,1,2=125,3=0.000000
L 6.38822352 4.7102 6.38635669 4.71103307 2 P 0 ;0,1,2=125,3=0.000000
L 6.38635669 4.71103307 6.38475659 4.71228287 2 P 0 ;0,1,2=125,3=0.000000
L 6.38475659 4.71228287 6.38342303 4.71394911 2 P 0 ;0,1,2=125,3=0.000000
L 6.37115679 4.73103337 6.36955669 4.73353287 2 P 0 ;0,1,2=125,3=0.000000
L 6.36955669 4.73353287 6.36768996 4.73478337 2 P 0 ;0,1,2=125,3=0.000000
L 6.36768996 4.73478337 6.36555659 4.7352 2 P 0 ;0,1,2=125,3=0.000000
L 6.36555659 4.7352 6.36288996 4.73436683 2 P 0 ;0,1,2=125,3=0.000000
L 6.36288996 4.73436683 6.36102323 4.73228317 2 P 0 ;0,1,2=125,3=0.000000
L 6.36102323 4.73228317 6.36048996 4.72978366 2 P 0 ;0,1,2=125,3=0.000000
L 6.36048996 4.72978366 6.36075659 4.72728268 2 P 0 ;0,1,2=125,3=0.000000
L 6.36075659 4.72728268 6.36182352 4.7251998 2 P 0 ;0,1,2=125,3=0.000000
L 6.36182352 4.7251998 6.36715669 4.72103327 2 P 0 ;0,1,2=125,3=0.000000
L 6.36715669 4.72103327 6.36955669 4.71811644 2 P 0 ;0,1,2=125,3=0.000000
L 6.36955669 4.71811644 6.37115679 4.71394911 2 P 0 ;0,1,2=125,3=0.000000
L 6.37115679 4.71394911 6.37169006 4.7102 2 P 0 ;0,1,2=125,3=0.000000
L 6.37169006 4.7102 6.36048996 4.7102 2 P 0 ;0,1,2=125,3=0.000000
L 6.34795669 4.71519961 6.34635699 4.71228287 2 P 0 ;0,1,2=125,3=0.000000
L 6.34635699 4.71228287 6.34422362 4.71061654 2 P 0 ;0,1,2=125,3=0.000000
L 6.34422362 4.71061654 6.34182313 4.7102 2 P 0 ;0,1,2=125,3=0.000000
L 6.34182313 4.7102 6.33968976 4.71061654 2 P 0 ;0,1,2=125,3=0.000000
L 6.33968976 4.71061654 6.3375564 4.71269941 2 P 0 ;0,1,2=125,3=0.000000
L 6.3375564 4.71269941 6.33622333 4.71519961 2 P 0 ;0,1,2=125,3=0.000000
L 6.33622333 4.71519961 6.33595679 4.7176999 2 P 0 ;0,1,2=125,3=0.000000
L 6.33595679 4.7176999 6.33648996 4.72061594 2 P 0 ;0,1,2=125,3=0.000000
L 6.33648996 4.72061594 6.33835669 4.72269961 2 P 0 ;0,1,2=125,3=0.000000
L 6.33835669 4.72269961 6.34022352 4.72353346 2 P 0 ;0,1,2=125,3=0.000000
L 6.34022352 4.72353346 6.34262343 4.72353346 2 P 0 ;0,1,2=125,3=0.000000
L 6.34022352 4.72353346 6.33862333 4.72478327 2 P 0 ;0,1,2=125,3=0.000000
L 6.33862333 4.72478327 6.33728986 4.72686614 2 P 0 ;0,1,2=125,3=0.000000
L 6.33728986 4.72686614 6.33675659 4.72936634 2 P 0 ;0,1,2=125,3=0.000000
L 6.33675659 4.72936634 6.33728986 4.73186654 2 P 0 ;0,1,2=125,3=0.000000
L 6.33728986 4.73186654 6.33862333 4.73394941 2 P 0 ;0,1,2=125,3=0.000000
L 6.33862333 4.73394941 6.34102333 4.7352 2 P 0 ;0,1,2=125,3=0.000000
L 6.34102333 4.7352 6.34342333 4.73478337 2 P 0 ;0,1,2=125,3=0.000000
L 6.34342333 4.73478337 6.34582333 4.73311634 2 P 0 ;0,1,2=125,3=0.000000
A 6.23766004 4.6402 6.23766004 4.6402 6.23208996 4.6402 2 P 0 N
L 6.46742343 4.6302 6.46742343 4.6552 2 P 0 ;0,1,2=126,3=0.000000
L 6.46742343 4.6552 6.46102333 4.6552 2 P 0 ;0,1,2=126,3=0.000000
L 6.46102333 4.6552 6.45888996 4.65394941 2 P 0 ;0,1,2=126,3=0.000000
L 6.45888996 4.65394941 6.45728986 4.65103337 2 P 0 ;0,1,2=126,3=0.000000
L 6.45728986 4.65103337 6.45675659 4.6477 2 P 0 ;0,1,2=126,3=0.000000
L 6.45675659 4.6477 6.45728986 4.64436663 2 P 0 ;0,1,2=126,3=0.000000
L 6.45728986 4.64436663 6.45862333 4.64186644 2 P 0 ;0,1,2=126,3=0.000000
L 6.45862333 4.64186644 6.46102333 4.64061594 2 P 0 ;0,1,2=126,3=0.000000
L 6.46102333 4.64061594 6.46742343 4.64061594 2 P 0 ;0,1,2=126,3=0.000000
L 6.44369006 4.63353258 6.44155669 4.6314497 2 P 0 ;0,1,2=126,3=0.000000
L 6.44155669 4.6314497 6.43915669 4.6302 2 P 0 ;0,1,2=126,3=0.000000
L 6.43915669 4.6302 6.43702333 4.6302 2 P 0 ;0,1,2=126,3=0.000000
L 6.43702333 4.6302 6.43488996 4.6314497 2 P 0 ;0,1,2=126,3=0.000000
L 6.43488996 4.6314497 6.43328986 4.63353258 2 P 0 ;0,1,2=126,3=0.000000
L 6.43328986 4.63353258 6.43248996 4.6364501 2 P 0 ;0,1,2=126,3=0.000000
L 6.43248996 4.6364501 6.43302323 4.63936614 2 P 0 ;0,1,2=126,3=0.000000
L 6.43302323 4.63936614 6.43435669 4.64186644 2 P 0 ;0,1,2=126,3=0.000000
L 6.43435669 4.64186644 6.43675669 4.64353346 2 P 0 ;0,1,2=126,3=0.000000
L 6.43675669 4.64353346 6.4399565 4.64436663 2 P 0 ;0,1,2=126,3=0.000000
L 6.4399565 4.64436663 6.44182333 4.64603297 2 P 0 ;0,1,2=126,3=0.000000
L 6.44182333 4.64603297 6.44262362 4.6489498 2 P 0 ;0,1,2=126,3=0.000000
L 6.44262362 4.6489498 6.44208986 4.65186654 2 P 0 ;0,1,2=126,3=0.000000
L 6.44208986 4.65186654 6.44075679 4.65394941 2 P 0 ;0,1,2=126,3=0.000000
L 6.44075679 4.65394941 6.43889006 4.6552 2 P 0 ;0,1,2=126,3=0.000000
L 6.43889006 4.6552 6.43702333 4.6552 2 P 0 ;0,1,2=126,3=0.000000
L 6.43702333 4.6552 6.43515659 4.65436683 2 P 0 ;0,1,2=126,3=0.000000
L 6.43515659 4.65436683 6.4335564 4.65228317 2 P 0 ;0,1,2=126,3=0.000000
L 6.41409026 4.6552 6.41409026 4.6302 2 P 0 ;0,1,2=126,3=0.000000
L 6.42022323 4.6552 6.40795679 4.6552 2 P 0 ;0,1,2=126,3=0.000000
L 6.38422333 4.65311634 6.38582352 4.65436683 2 P 0 ;0,1,2=126,3=0.000000
L 6.38582352 4.65436683 6.38768976 4.6552 2 P 0 ;0,1,2=126,3=0.000000
L 6.38768976 4.6552 6.38982313 4.6552 2 P 0 ;0,1,2=126,3=0.000000
L 6.38982313 4.6552 6.39222362 4.65394941 2 P 0 ;0,1,2=126,3=0.000000
L 6.39222362 4.65394941 6.39408986 4.65186654 2 P 0 ;0,1,2=126,3=0.000000
L 6.39408986 4.65186654 6.39542343 4.64936634 2 P 0 ;0,1,2=126,3=0.000000
L 6.39542343 4.64936634 6.39649035 4.6451998 2 P 0 ;0,1,2=126,3=0.000000
L 6.39649035 4.6451998 6.39675699 4.6414498 2 P 0 ;0,1,2=126,3=0.000000
L 6.39675699 4.6414498 6.39622323 4.6376999 2 P 0 ;0,1,2=126,3=0.000000
L 6.39622323 4.6376999 6.39542343 4.63519961 2 P 0 ;0,1,2=126,3=0.000000
L 6.39542343 4.63519961 6.39382333 4.63269941 2 P 0 ;0,1,2=126,3=0.000000
L 6.39382333 4.63269941 6.3919565 4.63103307 2 P 0 ;0,1,2=126,3=0.000000
L 6.3919565 4.63103307 6.39009026 4.6302 2 P 0 ;0,1,2=126,3=0.000000
L 6.39009026 4.6302 6.38822352 4.6302 2 P 0 ;0,1,2=126,3=0.000000
L 6.38822352 4.6302 6.38635669 4.63103307 2 P 0 ;0,1,2=126,3=0.000000
L 6.38635669 4.63103307 6.38475659 4.63228287 2 P 0 ;0,1,2=126,3=0.000000
L 6.38475659 4.63228287 6.38342303 4.63394911 2 P 0 ;0,1,2=126,3=0.000000
L 6.36609026 4.6302 6.36609026 4.6552 2 P 0 ;0,1,2=126,3=0.000000
L 6.36609026 4.6552 6.36929006 4.6502003 2 P 0 ;0,1,2=126,3=0.000000
L 6.36929006 4.6302 6.36289045 4.6302 2 P 0 ;0,1,2=126,3=0.000000
L 6.34715679 4.64061594 6.34529006 4.64353346 2 P 0 ;0,1,2=126,3=0.000000
L 6.34529006 4.64353346 6.34368996 4.6451998 2 P 0 ;0,1,2=126,3=0.000000
L 6.34368996 4.6451998 6.34155659 4.64603297 2 P 0 ;0,1,2=126,3=0.000000
L 6.34155659 4.64603297 6.33968976 4.6451998 2 P 0 ;0,1,2=126,3=0.000000
L 6.33968976 4.6451998 6.33835669 4.64353346 2 P 0 ;0,1,2=126,3=0.000000
L 6.33835669 4.64353346 6.33728986 4.64103327 2 P 0 ;0,1,2=126,3=0.000000
L 6.33728986 4.64103327 6.33702323 4.63811644 2 P 0 ;0,1,2=126,3=0.000000
L 6.33702323 4.63811644 6.33728986 4.63561624 2 P 0 ;0,1,2=126,3=0.000000
L 6.33728986 4.63561624 6.33835669 4.63311604 2 P 0 ;0,1,2=126,3=0.000000
L 6.33835669 4.63311604 6.33995689 4.63103307 2 P 0 ;0,1,2=126,3=0.000000
L 6.33995689 4.63103307 6.34182313 4.6302 2 P 0 ;0,1,2=126,3=0.000000
L 6.34182313 4.6302 6.3439565 4.63103307 2 P 0 ;0,1,2=126,3=0.000000
L 6.3439565 4.63103307 6.34582333 4.63353258 2 P 0 ;0,1,2=126,3=0.000000
L 6.34582333 4.63353258 6.34689016 4.63728327 2 P 0 ;0,1,2=126,3=0.000000
L 6.34689016 4.63728327 6.34715679 4.6414498 2 P 0 ;0,1,2=126,3=0.000000
L 6.34715679 4.6414498 6.34662362 4.64686614 2 P 0 ;0,1,2=126,3=0.000000
L 6.34662362 4.64686614 6.34582333 4.64978366 2 P 0 ;0,1,2=126,3=0.000000
L 6.34582333 4.64978366 6.34449026 4.6526997 2 P 0 ;0,1,2=126,3=0.000000
L 6.34449026 4.6526997 6.34262343 4.65478337 2 P 0 ;0,1,2=126,3=0.000000
L 6.34262343 4.65478337 6.34075669 4.6552 2 P 0 ;0,1,2=126,3=0.000000
L 6.34075669 4.6552 6.33888996 4.65436683 2 P 0 ;0,1,2=126,3=0.000000
L 6.33888996 4.65436683 6.3375564 4.65228317 2 P 0 ;0,1,2=126,3=0.000000
A 6.23766004 4.8802 6.23766004 4.8802 6.23208996 4.8802 2 P 0 N
L 6.46742343 4.8702 6.46742343 4.8952 2 P 0 ;0,1,2=127,3=0.000000
L 6.46742343 4.8952 6.46102333 4.8952 2 P 0 ;0,1,2=127,3=0.000000
L 6.46102333 4.8952 6.45888996 4.89394941 2 P 0 ;0,1,2=127,3=0.000000
L 6.45888996 4.89394941 6.45728986 4.89103337 2 P 0 ;0,1,2=127,3=0.000000
L 6.45728986 4.89103337 6.45675659 4.8877 2 P 0 ;0,1,2=127,3=0.000000
L 6.45675659 4.8877 6.45728986 4.88436663 2 P 0 ;0,1,2=127,3=0.000000
L 6.45728986 4.88436663 6.45862333 4.88186644 2 P 0 ;0,1,2=127,3=0.000000
L 6.45862333 4.88186644 6.46102333 4.88061594 2 P 0 ;0,1,2=127,3=0.000000
L 6.46102333 4.88061594 6.46742343 4.88061594 2 P 0 ;0,1,2=127,3=0.000000
L 6.44369006 4.87353258 6.44155669 4.8714497 2 P 0 ;0,1,2=127,3=0.000000
L 6.44155669 4.8714497 6.43915669 4.8702 2 P 0 ;0,1,2=127,3=0.000000
L 6.43915669 4.8702 6.43702333 4.8702 2 P 0 ;0,1,2=127,3=0.000000
L 6.43702333 4.8702 6.43488996 4.8714497 2 P 0 ;0,1,2=127,3=0.000000
L 6.43488996 4.8714497 6.43328986 4.87353258 2 P 0 ;0,1,2=127,3=0.000000
L 6.43328986 4.87353258 6.43248996 4.8764501 2 P 0 ;0,1,2=127,3=0.000000
L 6.43248996 4.8764501 6.43302323 4.87936614 2 P 0 ;0,1,2=127,3=0.000000
L 6.43302323 4.87936614 6.43435669 4.88186644 2 P 0 ;0,1,2=127,3=0.000000
L 6.43435669 4.88186644 6.43675669 4.88353346 2 P 0 ;0,1,2=127,3=0.000000
L 6.43675669 4.88353346 6.4399565 4.88436663 2 P 0 ;0,1,2=127,3=0.000000
L 6.4399565 4.88436663 6.44182333 4.88603297 2 P 0 ;0,1,2=127,3=0.000000
L 6.44182333 4.88603297 6.44262362 4.8889498 2 P 0 ;0,1,2=127,3=0.000000
L 6.44262362 4.8889498 6.44208986 4.89186654 2 P 0 ;0,1,2=127,3=0.000000
L 6.44208986 4.89186654 6.44075679 4.89394941 2 P 0 ;0,1,2=127,3=0.000000
L 6.44075679 4.89394941 6.43889006 4.8952 2 P 0 ;0,1,2=127,3=0.000000
L 6.43889006 4.8952 6.43702333 4.8952 2 P 0 ;0,1,2=127,3=0.000000
L 6.43702333 4.8952 6.43515659 4.89436683 2 P 0 ;0,1,2=127,3=0.000000
L 6.43515659 4.89436683 6.4335564 4.89228317 2 P 0 ;0,1,2=127,3=0.000000
L 6.41409026 4.8952 6.41409026 4.8702 2 P 0 ;0,1,2=127,3=0.000000
L 6.42022323 4.8952 6.40795679 4.8952 2 P 0 ;0,1,2=127,3=0.000000
L 6.38422333 4.89311634 6.38582352 4.89436683 2 P 0 ;0,1,2=127,3=0.000000
L 6.38582352 4.89436683 6.38768976 4.8952 2 P 0 ;0,1,2=127,3=0.000000
L 6.38768976 4.8952 6.38982313 4.8952 2 P 0 ;0,1,2=127,3=0.000000
L 6.38982313 4.8952 6.39222362 4.89394941 2 P 0 ;0,1,2=127,3=0.000000
L 6.39222362 4.89394941 6.39408986 4.89186654 2 P 0 ;0,1,2=127,3=0.000000
L 6.39408986 4.89186654 6.39542343 4.88936634 2 P 0 ;0,1,2=127,3=0.000000
L 6.39542343 4.88936634 6.39649035 4.8851998 2 P 0 ;0,1,2=127,3=0.000000
L 6.39649035 4.8851998 6.39675699 4.8814498 2 P 0 ;0,1,2=127,3=0.000000
L 6.39675699 4.8814498 6.39622323 4.8776999 2 P 0 ;0,1,2=127,3=0.000000
L 6.39622323 4.8776999 6.39542343 4.87519961 2 P 0 ;0,1,2=127,3=0.000000
L 6.39542343 4.87519961 6.39382333 4.87269941 2 P 0 ;0,1,2=127,3=0.000000
L 6.39382333 4.87269941 6.3919565 4.87103307 2 P 0 ;0,1,2=127,3=0.000000
L 6.3919565 4.87103307 6.39009026 4.8702 2 P 0 ;0,1,2=127,3=0.000000
L 6.39009026 4.8702 6.38822352 4.8702 2 P 0 ;0,1,2=127,3=0.000000
L 6.38822352 4.8702 6.38635669 4.87103307 2 P 0 ;0,1,2=127,3=0.000000
L 6.38635669 4.87103307 6.38475659 4.87228287 2 P 0 ;0,1,2=127,3=0.000000
L 6.38475659 4.87228287 6.38342303 4.87394911 2 P 0 ;0,1,2=127,3=0.000000
L 6.36609026 4.8702 6.36609026 4.8952 2 P 0 ;0,1,2=127,3=0.000000
L 6.36609026 4.8952 6.36929006 4.8902003 2 P 0 ;0,1,2=127,3=0.000000
L 6.36929006 4.8702 6.36289045 4.8702 2 P 0 ;0,1,2=127,3=0.000000
L 6.34262343 4.8702 6.34209026 4.87561624 2 P 0 ;0,1,2=127,3=0.000000
L 6.34209026 4.87561624 6.34128996 4.88019931 2 P 0 ;0,1,2=127,3=0.000000
L 6.34128996 4.88019931 6.34022352 4.88436663 2 P 0 ;0,1,2=127,3=0.000000
L 6.34022352 4.88436663 6.33888996 4.8889498 2 P 0 ;0,1,2=127,3=0.000000
L 6.33888996 4.8889498 6.33675659 4.8952 2 P 0 ;0,1,2=127,3=0.000000
L 6.33675659 4.8952 6.34742343 4.8952 2 P 0 ;0,1,2=127,3=0.000000
A 6.23766004 4.8002 6.23766004 4.8002 6.23208996 4.8002 2 P 0 N
L 6.46742343 4.7902 6.46742343 4.8152 2 P 0 ;0,1,2=128,3=0.000000
L 6.46742343 4.8152 6.46102333 4.8152 2 P 0 ;0,1,2=128,3=0.000000
L 6.46102333 4.8152 6.45888996 4.81394941 2 P 0 ;0,1,2=128,3=0.000000
L 6.45888996 4.81394941 6.45728986 4.81103337 2 P 0 ;0,1,2=128,3=0.000000
L 6.45728986 4.81103337 6.45675659 4.8077 2 P 0 ;0,1,2=128,3=0.000000
L 6.45675659 4.8077 6.45728986 4.80436663 2 P 0 ;0,1,2=128,3=0.000000
L 6.45728986 4.80436663 6.45862333 4.80186644 2 P 0 ;0,1,2=128,3=0.000000
L 6.45862333 4.80186644 6.46102333 4.80061594 2 P 0 ;0,1,2=128,3=0.000000
L 6.46102333 4.80061594 6.46742343 4.80061594 2 P 0 ;0,1,2=128,3=0.000000
L 6.44369006 4.79353258 6.44155669 4.7914497 2 P 0 ;0,1,2=128,3=0.000000
L 6.44155669 4.7914497 6.43915669 4.7902 2 P 0 ;0,1,2=128,3=0.000000
L 6.43915669 4.7902 6.43702333 4.7902 2 P 0 ;0,1,2=128,3=0.000000
L 6.43702333 4.7902 6.43488996 4.7914497 2 P 0 ;0,1,2=128,3=0.000000
L 6.43488996 4.7914497 6.43328986 4.79353258 2 P 0 ;0,1,2=128,3=0.000000
L 6.43328986 4.79353258 6.43248996 4.7964501 2 P 0 ;0,1,2=128,3=0.000000
L 6.43248996 4.7964501 6.43302323 4.79936614 2 P 0 ;0,1,2=128,3=0.000000
L 6.43302323 4.79936614 6.43435669 4.80186644 2 P 0 ;0,1,2=128,3=0.000000
L 6.43435669 4.80186644 6.43675669 4.80353346 2 P 0 ;0,1,2=128,3=0.000000
L 6.43675669 4.80353346 6.4399565 4.80436663 2 P 0 ;0,1,2=128,3=0.000000
L 6.4399565 4.80436663 6.44182333 4.80603297 2 P 0 ;0,1,2=128,3=0.000000
L 6.44182333 4.80603297 6.44262362 4.8089498 2 P 0 ;0,1,2=128,3=0.000000
L 6.44262362 4.8089498 6.44208986 4.81186654 2 P 0 ;0,1,2=128,3=0.000000
L 6.44208986 4.81186654 6.44075679 4.81394941 2 P 0 ;0,1,2=128,3=0.000000
L 6.44075679 4.81394941 6.43889006 4.8152 2 P 0 ;0,1,2=128,3=0.000000
L 6.43889006 4.8152 6.43702333 4.8152 2 P 0 ;0,1,2=128,3=0.000000
L 6.43702333 4.8152 6.43515659 4.81436683 2 P 0 ;0,1,2=128,3=0.000000
L 6.43515659 4.81436683 6.4335564 4.81228317 2 P 0 ;0,1,2=128,3=0.000000
L 6.41409026 4.8152 6.41409026 4.7902 2 P 0 ;0,1,2=128,3=0.000000
L 6.42022323 4.8152 6.40795679 4.8152 2 P 0 ;0,1,2=128,3=0.000000
L 6.38422333 4.81311634 6.38582352 4.81436683 2 P 0 ;0,1,2=128,3=0.000000
L 6.38582352 4.81436683 6.38768976 4.8152 2 P 0 ;0,1,2=128,3=0.000000
L 6.38768976 4.8152 6.38982313 4.8152 2 P 0 ;0,1,2=128,3=0.000000
L 6.38982313 4.8152 6.39222362 4.81394941 2 P 0 ;0,1,2=128,3=0.000000
L 6.39222362 4.81394941 6.39408986 4.81186654 2 P 0 ;0,1,2=128,3=0.000000
L 6.39408986 4.81186654 6.39542343 4.80936634 2 P 0 ;0,1,2=128,3=0.000000
L 6.39542343 4.80936634 6.39649035 4.8051998 2 P 0 ;0,1,2=128,3=0.000000
L 6.39649035 4.8051998 6.39675699 4.8014498 2 P 0 ;0,1,2=128,3=0.000000
L 6.39675699 4.8014498 6.39622323 4.7976999 2 P 0 ;0,1,2=128,3=0.000000
L 6.39622323 4.7976999 6.39542343 4.79519961 2 P 0 ;0,1,2=128,3=0.000000
L 6.39542343 4.79519961 6.39382333 4.79269941 2 P 0 ;0,1,2=128,3=0.000000
L 6.39382333 4.79269941 6.3919565 4.79103307 2 P 0 ;0,1,2=128,3=0.000000
L 6.3919565 4.79103307 6.39009026 4.7902 2 P 0 ;0,1,2=128,3=0.000000
L 6.39009026 4.7902 6.38822352 4.7902 2 P 0 ;0,1,2=128,3=0.000000
L 6.38822352 4.7902 6.38635669 4.79103307 2 P 0 ;0,1,2=128,3=0.000000
L 6.38635669 4.79103307 6.38475659 4.79228287 2 P 0 ;0,1,2=128,3=0.000000
L 6.38475659 4.79228287 6.38342303 4.79394911 2 P 0 ;0,1,2=128,3=0.000000
L 6.36609026 4.7902 6.36609026 4.8152 2 P 0 ;0,1,2=128,3=0.000000
L 6.36609026 4.8152 6.36929006 4.8102003 2 P 0 ;0,1,2=128,3=0.000000
L 6.36929006 4.7902 6.36289045 4.7902 2 P 0 ;0,1,2=128,3=0.000000
L 6.34662362 4.79311604 6.34475679 4.79103307 2 P 0 ;0,1,2=128,3=0.000000
L 6.34475679 4.79103307 6.34262343 4.7902 2 P 0 ;0,1,2=128,3=0.000000
L 6.34262343 4.7902 6.34049006 4.79103307 2 P 0 ;0,1,2=128,3=0.000000
L 6.34049006 4.79103307 6.33862333 4.79353258 2 P 0 ;0,1,2=128,3=0.000000
L 6.33862333 4.79353258 6.33728986 4.79728327 2 P 0 ;0,1,2=128,3=0.000000
L 6.33728986 4.79728327 6.33675659 4.80103327 2 P 0 ;0,1,2=128,3=0.000000
L 6.33675659 4.80103327 6.33675659 4.80561634 2 P 0 ;0,1,2=128,3=0.000000
L 6.33675659 4.80561634 6.33728986 4.80936634 2 P 0 ;0,1,2=128,3=0.000000
L 6.33728986 4.80936634 6.33862333 4.8126997 2 P 0 ;0,1,2=128,3=0.000000
L 6.33862333 4.8126997 6.34022352 4.81436683 2 P 0 ;0,1,2=128,3=0.000000
L 6.34022352 4.81436683 6.34209026 4.8152 2 P 0 ;0,1,2=128,3=0.000000
L 6.34209026 4.8152 6.34422362 4.81436683 2 P 0 ;0,1,2=128,3=0.000000
L 6.34422362 4.81436683 6.34582333 4.8126997 2 P 0 ;0,1,2=128,3=0.000000
L 6.34582333 4.8126997 6.34689016 4.8102003 2 P 0 ;0,1,2=128,3=0.000000
L 6.34689016 4.8102003 6.34742343 4.80686614 2 P 0 ;0,1,2=128,3=0.000000
L 6.34742343 4.80686614 6.34689016 4.8039501 2 P 0 ;0,1,2=128,3=0.000000
L 6.34689016 4.8039501 6.34555669 4.80103327 2 P 0 ;0,1,2=128,3=0.000000
L 6.34555669 4.80103327 6.3439565 4.79936614 2 P 0 ;0,1,2=128,3=0.000000
L 6.3439565 4.79936614 6.34209026 4.79894961 2 P 0 ;0,1,2=128,3=0.000000
L 6.34209026 4.79894961 6.33995689 4.79978278 2 P 0 ;0,1,2=128,3=0.000000
L 6.33995689 4.79978278 6.33835669 4.80186644 2 P 0 ;0,1,2=128,3=0.000000
L 6.33835669 4.80186644 6.33675659 4.80561634 2 P 0 ;0,1,2=128,3=0.000000
A 6.70766004 4.7052 6.70766004 4.7052 6.70208996 4.7052 2 P 0 N
L 6.60042343 4.6952 6.60042343 4.7202 2 P 0 ;0,1,2=129,3=0.000000
L 6.60042343 4.7202 6.59402333 4.7202 2 P 0 ;0,1,2=129,3=0.000000
L 6.59402333 4.7202 6.59188996 4.71894941 2 P 0 ;0,1,2=129,3=0.000000
L 6.59188996 4.71894941 6.59028986 4.71603337 2 P 0 ;0,1,2=129,3=0.000000
L 6.59028986 4.71603337 6.58975659 4.7127 2 P 0 ;0,1,2=129,3=0.000000
L 6.58975659 4.7127 6.59028986 4.70936663 2 P 0 ;0,1,2=129,3=0.000000
L 6.59028986 4.70936663 6.59162333 4.70686644 2 P 0 ;0,1,2=129,3=0.000000
L 6.59162333 4.70686644 6.59402333 4.70561594 2 P 0 ;0,1,2=129,3=0.000000
L 6.59402333 4.70561594 6.60042343 4.70561594 2 P 0 ;0,1,2=129,3=0.000000
L 6.57669006 4.69853258 6.57455669 4.6964497 2 P 0 ;0,1,2=129,3=0.000000
L 6.57455669 4.6964497 6.57215669 4.6952 2 P 0 ;0,1,2=129,3=0.000000
L 6.57215669 4.6952 6.57002333 4.6952 2 P 0 ;0,1,2=129,3=0.000000
L 6.57002333 4.6952 6.56788996 4.6964497 2 P 0 ;0,1,2=129,3=0.000000
L 6.56788996 4.6964497 6.56628986 4.69853258 2 P 0 ;0,1,2=129,3=0.000000
L 6.56628986 4.69853258 6.56548996 4.7014501 2 P 0 ;0,1,2=129,3=0.000000
L 6.56548996 4.7014501 6.56602323 4.70436614 2 P 0 ;0,1,2=129,3=0.000000
L 6.56602323 4.70436614 6.56735669 4.70686644 2 P 0 ;0,1,2=129,3=0.000000
L 6.56735669 4.70686644 6.56975669 4.70853346 2 P 0 ;0,1,2=129,3=0.000000
L 6.56975669 4.70853346 6.5729565 4.70936663 2 P 0 ;0,1,2=129,3=0.000000
L 6.5729565 4.70936663 6.57482333 4.71103297 2 P 0 ;0,1,2=129,3=0.000000
L 6.57482333 4.71103297 6.57562362 4.7139498 2 P 0 ;0,1,2=129,3=0.000000
L 6.57562362 4.7139498 6.57508986 4.71686654 2 P 0 ;0,1,2=129,3=0.000000
L 6.57508986 4.71686654 6.57375679 4.71894941 2 P 0 ;0,1,2=129,3=0.000000
L 6.57375679 4.71894941 6.57189006 4.7202 2 P 0 ;0,1,2=129,3=0.000000
L 6.57189006 4.7202 6.57002333 4.7202 2 P 0 ;0,1,2=129,3=0.000000
L 6.57002333 4.7202 6.56815659 4.71936683 2 P 0 ;0,1,2=129,3=0.000000
L 6.56815659 4.71936683 6.5665564 4.71728317 2 P 0 ;0,1,2=129,3=0.000000
L 6.54709026 4.7202 6.54709026 4.6952 2 P 0 ;0,1,2=129,3=0.000000
L 6.55322323 4.7202 6.54095679 4.7202 2 P 0 ;0,1,2=129,3=0.000000
L 6.51722333 4.71811634 6.51882352 4.71936683 2 P 0 ;0,1,2=129,3=0.000000
L 6.51882352 4.71936683 6.52068976 4.7202 2 P 0 ;0,1,2=129,3=0.000000
L 6.52068976 4.7202 6.52282313 4.7202 2 P 0 ;0,1,2=129,3=0.000000
L 6.52282313 4.7202 6.52522362 4.71894941 2 P 0 ;0,1,2=129,3=0.000000
L 6.52522362 4.71894941 6.52708986 4.71686654 2 P 0 ;0,1,2=129,3=0.000000
L 6.52708986 4.71686654 6.52842343 4.71436634 2 P 0 ;0,1,2=129,3=0.000000
L 6.52842343 4.71436634 6.52949035 4.7101998 2 P 0 ;0,1,2=129,3=0.000000
L 6.52949035 4.7101998 6.52975699 4.7064498 2 P 0 ;0,1,2=129,3=0.000000
L 6.52975699 4.7064498 6.52922323 4.7026999 2 P 0 ;0,1,2=129,3=0.000000
L 6.52922323 4.7026999 6.52842343 4.70019961 2 P 0 ;0,1,2=129,3=0.000000
L 6.52842343 4.70019961 6.52682333 4.69769941 2 P 0 ;0,1,2=129,3=0.000000
L 6.52682333 4.69769941 6.5249565 4.69603307 2 P 0 ;0,1,2=129,3=0.000000
L 6.5249565 4.69603307 6.52309026 4.6952 2 P 0 ;0,1,2=129,3=0.000000
L 6.52309026 4.6952 6.52122352 4.6952 2 P 0 ;0,1,2=129,3=0.000000
L 6.52122352 4.6952 6.51935669 4.69603307 2 P 0 ;0,1,2=129,3=0.000000
L 6.51935669 4.69603307 6.51775659 4.69728287 2 P 0 ;0,1,2=129,3=0.000000
L 6.51775659 4.69728287 6.51642303 4.69894911 2 P 0 ;0,1,2=129,3=0.000000
L 6.49588996 4.6952 6.49588996 4.7202 2 P 0 ;0,1,2=129,3=0.000000
L 6.49588996 4.7202 6.50575699 4.70228327 2 P 0 ;0,1,2=129,3=0.000000
L 6.50575699 4.70228327 6.49242303 4.70228327 2 P 0 ;0,1,2=129,3=0.000000
A 6.70766004 4.6252 6.70766004 4.6252 6.70208996 4.6252 2 P 0 N
L 6.60042343 4.6152 6.60042343 4.6402 2 P 0 ;0,1,2=130,3=0.000000
L 6.60042343 4.6402 6.59402333 4.6402 2 P 0 ;0,1,2=130,3=0.000000
L 6.59402333 4.6402 6.59188996 4.63894941 2 P 0 ;0,1,2=130,3=0.000000
L 6.59188996 4.63894941 6.59028986 4.63603337 2 P 0 ;0,1,2=130,3=0.000000
L 6.59028986 4.63603337 6.58975659 4.6327 2 P 0 ;0,1,2=130,3=0.000000
L 6.58975659 4.6327 6.59028986 4.62936663 2 P 0 ;0,1,2=130,3=0.000000
L 6.59028986 4.62936663 6.59162333 4.62686644 2 P 0 ;0,1,2=130,3=0.000000
L 6.59162333 4.62686644 6.59402333 4.62561594 2 P 0 ;0,1,2=130,3=0.000000
L 6.59402333 4.62561594 6.60042343 4.62561594 2 P 0 ;0,1,2=130,3=0.000000
L 6.57669006 4.61853258 6.57455669 4.6164497 2 P 0 ;0,1,2=130,3=0.000000
L 6.57455669 4.6164497 6.57215669 4.6152 2 P 0 ;0,1,2=130,3=0.000000
L 6.57215669 4.6152 6.57002333 4.6152 2 P 0 ;0,1,2=130,3=0.000000
L 6.57002333 4.6152 6.56788996 4.6164497 2 P 0 ;0,1,2=130,3=0.000000
L 6.56788996 4.6164497 6.56628986 4.61853258 2 P 0 ;0,1,2=130,3=0.000000
L 6.56628986 4.61853258 6.56548996 4.6214501 2 P 0 ;0,1,2=130,3=0.000000
L 6.56548996 4.6214501 6.56602323 4.62436614 2 P 0 ;0,1,2=130,3=0.000000
L 6.56602323 4.62436614 6.56735669 4.62686644 2 P 0 ;0,1,2=130,3=0.000000
L 6.56735669 4.62686644 6.56975669 4.62853346 2 P 0 ;0,1,2=130,3=0.000000
L 6.56975669 4.62853346 6.5729565 4.62936663 2 P 0 ;0,1,2=130,3=0.000000
L 6.5729565 4.62936663 6.57482333 4.63103297 2 P 0 ;0,1,2=130,3=0.000000
L 6.57482333 4.63103297 6.57562362 4.6339498 2 P 0 ;0,1,2=130,3=0.000000
L 6.57562362 4.6339498 6.57508986 4.63686654 2 P 0 ;0,1,2=130,3=0.000000
L 6.57508986 4.63686654 6.57375679 4.63894941 2 P 0 ;0,1,2=130,3=0.000000
L 6.57375679 4.63894941 6.57189006 4.6402 2 P 0 ;0,1,2=130,3=0.000000
L 6.57189006 4.6402 6.57002333 4.6402 2 P 0 ;0,1,2=130,3=0.000000
L 6.57002333 4.6402 6.56815659 4.63936683 2 P 0 ;0,1,2=130,3=0.000000
L 6.56815659 4.63936683 6.5665564 4.63728317 2 P 0 ;0,1,2=130,3=0.000000
L 6.54709026 4.6402 6.54709026 4.6152 2 P 0 ;0,1,2=130,3=0.000000
L 6.55322323 4.6402 6.54095679 4.6402 2 P 0 ;0,1,2=130,3=0.000000
L 6.51722333 4.63811634 6.51882352 4.63936683 2 P 0 ;0,1,2=130,3=0.000000
L 6.51882352 4.63936683 6.52068976 4.6402 2 P 0 ;0,1,2=130,3=0.000000
L 6.52068976 4.6402 6.52282313 4.6402 2 P 0 ;0,1,2=130,3=0.000000
L 6.52282313 4.6402 6.52522362 4.63894941 2 P 0 ;0,1,2=130,3=0.000000
L 6.52522362 4.63894941 6.52708986 4.63686654 2 P 0 ;0,1,2=130,3=0.000000
L 6.52708986 4.63686654 6.52842343 4.63436634 2 P 0 ;0,1,2=130,3=0.000000
L 6.52842343 4.63436634 6.52949035 4.6301998 2 P 0 ;0,1,2=130,3=0.000000
L 6.52949035 4.6301998 6.52975699 4.6264498 2 P 0 ;0,1,2=130,3=0.000000
L 6.52975699 4.6264498 6.52922323 4.6226999 2 P 0 ;0,1,2=130,3=0.000000
L 6.52922323 4.6226999 6.52842343 4.62019961 2 P 0 ;0,1,2=130,3=0.000000
L 6.52842343 4.62019961 6.52682333 4.61769941 2 P 0 ;0,1,2=130,3=0.000000
L 6.52682333 4.61769941 6.5249565 4.61603307 2 P 0 ;0,1,2=130,3=0.000000
L 6.5249565 4.61603307 6.52309026 4.6152 2 P 0 ;0,1,2=130,3=0.000000
L 6.52309026 4.6152 6.52122352 4.6152 2 P 0 ;0,1,2=130,3=0.000000
L 6.52122352 4.6152 6.51935669 4.61603307 2 P 0 ;0,1,2=130,3=0.000000
L 6.51935669 4.61603307 6.51775659 4.61728287 2 P 0 ;0,1,2=130,3=0.000000
L 6.51775659 4.61728287 6.51642303 4.61894911 2 P 0 ;0,1,2=130,3=0.000000
L 6.50362362 4.61811604 6.50175679 4.61603307 2 P 0 ;0,1,2=130,3=0.000000
L 6.50175679 4.61603307 6.49962343 4.6152 2 P 0 ;0,1,2=130,3=0.000000
L 6.49962343 4.6152 6.49749006 4.61603307 2 P 0 ;0,1,2=130,3=0.000000
L 6.49749006 4.61603307 6.49562333 4.61853258 2 P 0 ;0,1,2=130,3=0.000000
L 6.49562333 4.61853258 6.49428986 4.62228327 2 P 0 ;0,1,2=130,3=0.000000
L 6.49428986 4.62228327 6.49375659 4.62603327 2 P 0 ;0,1,2=130,3=0.000000
L 6.49375659 4.62603327 6.49375659 4.63061634 2 P 0 ;0,1,2=130,3=0.000000
L 6.49375659 4.63061634 6.49428986 4.63436634 2 P 0 ;0,1,2=130,3=0.000000
L 6.49428986 4.63436634 6.49562333 4.6376997 2 P 0 ;0,1,2=130,3=0.000000
L 6.49562333 4.6376997 6.49722352 4.63936683 2 P 0 ;0,1,2=130,3=0.000000
L 6.49722352 4.63936683 6.49909026 4.6402 2 P 0 ;0,1,2=130,3=0.000000
L 6.49909026 4.6402 6.50122362 4.63936683 2 P 0 ;0,1,2=130,3=0.000000
L 6.50122362 4.63936683 6.50282333 4.6376997 2 P 0 ;0,1,2=130,3=0.000000
L 6.50282333 4.6376997 6.50389016 4.6352003 2 P 0 ;0,1,2=130,3=0.000000
L 6.50389016 4.6352003 6.50442343 4.63186614 2 P 0 ;0,1,2=130,3=0.000000
L 6.50442343 4.63186614 6.50389016 4.6289501 2 P 0 ;0,1,2=130,3=0.000000
L 6.50389016 4.6289501 6.50255669 4.62603327 2 P 0 ;0,1,2=130,3=0.000000
L 6.50255669 4.62603327 6.5009565 4.62436614 2 P 0 ;0,1,2=130,3=0.000000
L 6.5009565 4.62436614 6.49909026 4.62394961 2 P 0 ;0,1,2=130,3=0.000000
L 6.49909026 4.62394961 6.49695689 4.62478278 2 P 0 ;0,1,2=130,3=0.000000
L 6.49695689 4.62478278 6.49535669 4.62686644 2 P 0 ;0,1,2=130,3=0.000000
L 6.49535669 4.62686644 6.49375659 4.63061634 2 P 0 ;0,1,2=130,3=0.000000
A 6.87676004 4.73868002 6.87676004 4.73868002 6.87118996 4.73868002 2 P 0 N
L 7.10533346 4.73 7.10533346 4.755 2 P 0 ;0,1,2=131,3=0.000000
L 7.10533346 4.755 7.09893337 4.755 2 P 0 ;0,1,2=131,3=0.000000
L 7.09893337 4.755 7.0968 4.75374941 2 P 0 ;0,1,2=131,3=0.000000
L 7.0968 4.75374941 7.0951999 4.75083337 2 P 0 ;0,1,2=131,3=0.000000
L 7.0951999 4.75083337 7.09466663 4.7475 2 P 0 ;0,1,2=131,3=0.000000
L 7.09466663 4.7475 7.0951999 4.74416663 2 P 0 ;0,1,2=131,3=0.000000
L 7.0951999 4.74416663 7.09653337 4.74166644 2 P 0 ;0,1,2=131,3=0.000000
L 7.09653337 4.74166644 7.09893337 4.74041594 2 P 0 ;0,1,2=131,3=0.000000
L 7.09893337 4.74041594 7.10533346 4.74041594 2 P 0 ;0,1,2=131,3=0.000000
L 7.0816001 4.73333258 7.07946673 4.7312497 2 P 0 ;0,1,2=131,3=0.000000
L 7.07946673 4.7312497 7.07706673 4.73 2 P 0 ;0,1,2=131,3=0.000000
L 7.07706673 4.73 7.07493337 4.73 2 P 0 ;0,1,2=131,3=0.000000
L 7.07493337 4.73 7.0728 4.7312497 2 P 0 ;0,1,2=131,3=0.000000
L 7.0728 4.7312497 7.0711999 4.73333258 2 P 0 ;0,1,2=131,3=0.000000
L 7.0711999 4.73333258 7.0704 4.7362501 2 P 0 ;0,1,2=131,3=0.000000
L 7.0704 4.7362501 7.07093327 4.73916614 2 P 0 ;0,1,2=131,3=0.000000
L 7.07093327 4.73916614 7.07226673 4.74166644 2 P 0 ;0,1,2=131,3=0.000000
L 7.07226673 4.74166644 7.07466673 4.74333346 2 P 0 ;0,1,2=131,3=0.000000
L 7.07466673 4.74333346 7.07786654 4.74416663 2 P 0 ;0,1,2=131,3=0.000000
L 7.07786654 4.74416663 7.07973337 4.74583297 2 P 0 ;0,1,2=131,3=0.000000
L 7.07973337 4.74583297 7.08053366 4.7487498 2 P 0 ;0,1,2=131,3=0.000000
L 7.08053366 4.7487498 7.0799999 4.75166654 2 P 0 ;0,1,2=131,3=0.000000
L 7.0799999 4.75166654 7.07866683 4.75374941 2 P 0 ;0,1,2=131,3=0.000000
L 7.07866683 4.75374941 7.0768001 4.755 2 P 0 ;0,1,2=131,3=0.000000
L 7.0768001 4.755 7.07493337 4.755 2 P 0 ;0,1,2=131,3=0.000000
L 7.07493337 4.755 7.07306663 4.75416683 2 P 0 ;0,1,2=131,3=0.000000
L 7.07306663 4.75416683 7.07146644 4.75208317 2 P 0 ;0,1,2=131,3=0.000000
L 7.0520003 4.755 7.0520003 4.73 2 P 0 ;0,1,2=131,3=0.000000
L 7.05813327 4.755 7.04586683 4.755 2 P 0 ;0,1,2=131,3=0.000000
L 7.02213337 4.75291634 7.02373356 4.75416683 2 P 0 ;0,1,2=131,3=0.000000
L 7.02373356 4.75416683 7.0255998 4.755 2 P 0 ;0,1,2=131,3=0.000000
L 7.0255998 4.755 7.02773317 4.755 2 P 0 ;0,1,2=131,3=0.000000
L 7.02773317 4.755 7.03013366 4.75374941 2 P 0 ;0,1,2=131,3=0.000000
L 7.03013366 4.75374941 7.0319999 4.75166654 2 P 0 ;0,1,2=131,3=0.000000
L 7.0319999 4.75166654 7.03333346 4.74916634 2 P 0 ;0,1,2=131,3=0.000000
L 7.03333346 4.74916634 7.03440039 4.7449998 2 P 0 ;0,1,2=131,3=0.000000
L 7.03440039 4.7449998 7.03466703 4.7412498 2 P 0 ;0,1,2=131,3=0.000000
L 7.03466703 4.7412498 7.03413327 4.7374999 2 P 0 ;0,1,2=131,3=0.000000
L 7.03413327 4.7374999 7.03333346 4.73499961 2 P 0 ;0,1,2=131,3=0.000000
L 7.03333346 4.73499961 7.03173337 4.73249941 2 P 0 ;0,1,2=131,3=0.000000
L 7.03173337 4.73249941 7.02986654 4.73083307 2 P 0 ;0,1,2=131,3=0.000000
L 7.02986654 4.73083307 7.0280003 4.73 2 P 0 ;0,1,2=131,3=0.000000
L 7.0280003 4.73 7.02613356 4.73 2 P 0 ;0,1,2=131,3=0.000000
L 7.02613356 4.73 7.02426673 4.73083307 2 P 0 ;0,1,2=131,3=0.000000
L 7.02426673 4.73083307 7.02266663 4.73208287 2 P 0 ;0,1,2=131,3=0.000000
L 7.02266663 4.73208287 7.02133307 4.73374911 2 P 0 ;0,1,2=131,3=0.000000
L 7.0040003 4.73 7.0040003 4.755 2 P 0 ;0,1,2=131,3=0.000000
L 7.0040003 4.755 7.0072001 4.7500003 2 P 0 ;0,1,2=131,3=0.000000
L 7.0072001 4.73 7.00080049 4.73 2 P 0 ;0,1,2=131,3=0.000000
L 6.9800003 4.755 6.98213366 4.75416683 2 P 0 ;0,1,2=131,3=0.000000
L 6.98213366 4.75416683 6.98373337 4.75208317 2 P 0 ;0,1,2=131,3=0.000000
L 6.98373337 4.75208317 6.9848002 4.74958366 2 P 0 ;0,1,2=131,3=0.000000
L 6.9848002 4.74958366 6.9856001 4.74624951 2 P 0 ;0,1,2=131,3=0.000000
L 6.9856001 4.74624951 6.98586673 4.74249961 2 P 0 ;0,1,2=131,3=0.000000
L 6.98586673 4.74249961 6.9856001 4.73874961 2 P 0 ;0,1,2=131,3=0.000000
L 6.9856001 4.73874961 6.9848002 4.73541624 2 P 0 ;0,1,2=131,3=0.000000
L 6.9848002 4.73541624 6.98373337 4.73291604 2 P 0 ;0,1,2=131,3=0.000000
L 6.98373337 4.73291604 6.98213366 4.73083307 2 P 0 ;0,1,2=131,3=0.000000
L 6.98213366 4.73083307 6.9800003 4.73 2 P 0 ;0,1,2=131,3=0.000000
L 6.9800003 4.73 6.97786693 4.73083307 2 P 0 ;0,1,2=131,3=0.000000
L 6.97786693 4.73083307 6.97626673 4.73291604 2 P 0 ;0,1,2=131,3=0.000000
L 6.97626673 4.73291604 6.9751999 4.73541624 2 P 0 ;0,1,2=131,3=0.000000
L 6.9751999 4.73541624 6.9744 4.73874961 2 P 0 ;0,1,2=131,3=0.000000
L 6.9744 4.73874961 6.97413337 4.74249961 2 P 0 ;0,1,2=131,3=0.000000
L 6.97413337 4.74249961 6.9744 4.74624951 2 P 0 ;0,1,2=131,3=0.000000
L 6.9744 4.74624951 6.9751999 4.74958366 2 P 0 ;0,1,2=131,3=0.000000
L 6.9751999 4.74958366 6.97626673 4.75208317 2 P 0 ;0,1,2=131,3=0.000000
L 6.97626673 4.75208317 6.97786693 4.75416683 2 P 0 ;0,1,2=131,3=0.000000
L 6.97786693 4.75416683 6.9800003 4.755 2 P 0 ;0,1,2=131,3=0.000000
A 6.87676004 4.81705 6.87676004 4.81705 6.87118996 4.81705 2 P 0 N
L 7.08333346 4.81 7.08333346 4.835 2 P 0 ;0,1,2=132,3=0.000000
L 7.08333346 4.835 7.07693337 4.835 2 P 0 ;0,1,2=132,3=0.000000
L 7.07693337 4.835 7.0748 4.83374941 2 P 0 ;0,1,2=132,3=0.000000
L 7.0748 4.83374941 7.0731999 4.83083337 2 P 0 ;0,1,2=132,3=0.000000
L 7.0731999 4.83083337 7.07266663 4.8275 2 P 0 ;0,1,2=132,3=0.000000
L 7.07266663 4.8275 7.0731999 4.82416663 2 P 0 ;0,1,2=132,3=0.000000
L 7.0731999 4.82416663 7.07453337 4.82166644 2 P 0 ;0,1,2=132,3=0.000000
L 7.07453337 4.82166644 7.07693337 4.82041594 2 P 0 ;0,1,2=132,3=0.000000
L 7.07693337 4.82041594 7.08333346 4.82041594 2 P 0 ;0,1,2=132,3=0.000000
L 7.0596001 4.81333258 7.05746673 4.8112497 2 P 0 ;0,1,2=132,3=0.000000
L 7.05746673 4.8112497 7.05506673 4.81 2 P 0 ;0,1,2=132,3=0.000000
L 7.05506673 4.81 7.05293337 4.81 2 P 0 ;0,1,2=132,3=0.000000
L 7.05293337 4.81 7.0508 4.8112497 2 P 0 ;0,1,2=132,3=0.000000
L 7.0508 4.8112497 7.0491999 4.81333258 2 P 0 ;0,1,2=132,3=0.000000
L 7.0491999 4.81333258 7.0484 4.8162501 2 P 0 ;0,1,2=132,3=0.000000
L 7.0484 4.8162501 7.04893327 4.81916614 2 P 0 ;0,1,2=132,3=0.000000
L 7.04893327 4.81916614 7.05026673 4.82166644 2 P 0 ;0,1,2=132,3=0.000000
L 7.05026673 4.82166644 7.05266673 4.82333346 2 P 0 ;0,1,2=132,3=0.000000
L 7.05266673 4.82333346 7.05586654 4.82416663 2 P 0 ;0,1,2=132,3=0.000000
L 7.05586654 4.82416663 7.05773337 4.82583297 2 P 0 ;0,1,2=132,3=0.000000
L 7.05773337 4.82583297 7.05853366 4.8287498 2 P 0 ;0,1,2=132,3=0.000000
L 7.05853366 4.8287498 7.0579999 4.83166654 2 P 0 ;0,1,2=132,3=0.000000
L 7.0579999 4.83166654 7.05666683 4.83374941 2 P 0 ;0,1,2=132,3=0.000000
L 7.05666683 4.83374941 7.0548001 4.835 2 P 0 ;0,1,2=132,3=0.000000
L 7.0548001 4.835 7.05293337 4.835 2 P 0 ;0,1,2=132,3=0.000000
L 7.05293337 4.835 7.05106663 4.83416683 2 P 0 ;0,1,2=132,3=0.000000
L 7.05106663 4.83416683 7.04946644 4.83208317 2 P 0 ;0,1,2=132,3=0.000000
L 7.0300003 4.835 7.0300003 4.81 2 P 0 ;0,1,2=132,3=0.000000
L 7.03613327 4.835 7.02386683 4.835 2 P 0 ;0,1,2=132,3=0.000000
L 7.00013337 4.83291634 7.00173356 4.83416683 2 P 0 ;0,1,2=132,3=0.000000
L 7.00173356 4.83416683 7.0035998 4.835 2 P 0 ;0,1,2=132,3=0.000000
L 7.0035998 4.835 7.00573317 4.835 2 P 0 ;0,1,2=132,3=0.000000
L 7.00573317 4.835 7.00813366 4.83374941 2 P 0 ;0,1,2=132,3=0.000000
L 7.00813366 4.83374941 7.0099999 4.83166654 2 P 0 ;0,1,2=132,3=0.000000
L 7.0099999 4.83166654 7.01133346 4.82916634 2 P 0 ;0,1,2=132,3=0.000000
L 7.01133346 4.82916634 7.01240039 4.8249998 2 P 0 ;0,1,2=132,3=0.000000
L 7.01240039 4.8249998 7.01266703 4.8212498 2 P 0 ;0,1,2=132,3=0.000000
L 7.01266703 4.8212498 7.01213327 4.8174999 2 P 0 ;0,1,2=132,3=0.000000
L 7.01213327 4.8174999 7.01133346 4.81499961 2 P 0 ;0,1,2=132,3=0.000000
L 7.01133346 4.81499961 7.00973337 4.81249941 2 P 0 ;0,1,2=132,3=0.000000
L 7.00973337 4.81249941 7.00786654 4.81083307 2 P 0 ;0,1,2=132,3=0.000000
L 7.00786654 4.81083307 7.0060003 4.81 2 P 0 ;0,1,2=132,3=0.000000
L 7.0060003 4.81 7.00413356 4.81 2 P 0 ;0,1,2=132,3=0.000000
L 7.00413356 4.81 7.00226673 4.81083307 2 P 0 ;0,1,2=132,3=0.000000
L 7.00226673 4.81083307 7.00066663 4.81208287 2 P 0 ;0,1,2=132,3=0.000000
L 7.00066663 4.81208287 6.99933307 4.81374911 2 P 0 ;0,1,2=132,3=0.000000
L 6.98253346 4.81 6.9820003 4.81541624 2 P 0 ;0,1,2=132,3=0.000000
L 6.9820003 4.81541624 6.9812 4.81999931 2 P 0 ;0,1,2=132,3=0.000000
L 6.9812 4.81999931 6.98013356 4.82416663 2 P 0 ;0,1,2=132,3=0.000000
L 6.98013356 4.82416663 6.9788 4.8287498 2 P 0 ;0,1,2=132,3=0.000000
L 6.9788 4.8287498 6.97666663 4.835 2 P 0 ;0,1,2=132,3=0.000000
L 6.97666663 4.835 6.98733346 4.835 2 P 0 ;0,1,2=132,3=0.000000
A 11.37336004 2.96 11.37336004 2.96 11.36778996 2.96 2 P 0 N
L 11.57613337 2.99791634 11.57773356 2.99916683 2 P 0 ;0,1,2=133,3=0.000000
L 11.57773356 2.99916683 11.5795998 3 2 P 0 ;0,1,2=133,3=0.000000
L 11.5795998 3 11.58173317 3 2 P 0 ;0,1,2=133,3=0.000000
L 11.58173317 3 11.58413366 2.99874941 2 P 0 ;0,1,2=133,3=0.000000
L 11.58413366 2.99874941 11.5859999 2.99666654 2 P 0 ;0,1,2=133,3=0.000000
L 11.5859999 2.99666654 11.58733346 2.99416634 2 P 0 ;0,1,2=133,3=0.000000
L 11.58733346 2.99416634 11.58840039 2.9899998 2 P 0 ;0,1,2=133,3=0.000000
L 11.58840039 2.9899998 11.58866703 2.9862498 2 P 0 ;0,1,2=133,3=0.000000
L 11.58866703 2.9862498 11.58813327 2.9824999 2 P 0 ;0,1,2=133,3=0.000000
L 11.58813327 2.9824999 11.58733346 2.97999961 2 P 0 ;0,1,2=133,3=0.000000
L 11.58733346 2.97999961 11.58573337 2.97749941 2 P 0 ;0,1,2=133,3=0.000000
L 11.58573337 2.97749941 11.58386654 2.97583307 2 P 0 ;0,1,2=133,3=0.000000
L 11.58386654 2.97583307 11.5820003 2.975 2 P 0 ;0,1,2=133,3=0.000000
L 11.5820003 2.975 11.58013356 2.975 2 P 0 ;0,1,2=133,3=0.000000
L 11.58013356 2.975 11.57826673 2.97583307 2 P 0 ;0,1,2=133,3=0.000000
L 11.57826673 2.97583307 11.57666663 2.97708287 2 P 0 ;0,1,2=133,3=0.000000
L 11.57666663 2.97708287 11.57533307 2.97874911 2 P 0 ;0,1,2=133,3=0.000000
L 11.56306683 2.99583337 11.56146673 2.99833287 2 P 0 ;0,1,2=133,3=0.000000
L 11.56146673 2.99833287 11.5596 2.99958337 2 P 0 ;0,1,2=133,3=0.000000
L 11.5596 2.99958337 11.55746663 3 2 P 0 ;0,1,2=133,3=0.000000
L 11.55746663 3 11.5548 2.99916683 2 P 0 ;0,1,2=133,3=0.000000
L 11.5548 2.99916683 11.55293327 2.99708317 2 P 0 ;0,1,2=133,3=0.000000
L 11.55293327 2.99708317 11.5524 2.99458366 2 P 0 ;0,1,2=133,3=0.000000
L 11.5524 2.99458366 11.55266663 2.99208268 2 P 0 ;0,1,2=133,3=0.000000
L 11.55266663 2.99208268 11.55373356 2.9899998 2 P 0 ;0,1,2=133,3=0.000000
L 11.55373356 2.9899998 11.55906673 2.98583327 2 P 0 ;0,1,2=133,3=0.000000
L 11.55906673 2.98583327 11.56146673 2.98291644 2 P 0 ;0,1,2=133,3=0.000000
L 11.56146673 2.98291644 11.56306683 2.97874911 2 P 0 ;0,1,2=133,3=0.000000
L 11.56306683 2.97874911 11.5636001 2.975 2 P 0 ;0,1,2=133,3=0.000000
L 11.5636001 2.975 11.5524 2.975 2 P 0 ;0,1,2=133,3=0.000000
L 11.53906683 2.99583337 11.53746673 2.99833287 2 P 0 ;0,1,2=133,3=0.000000
L 11.53746673 2.99833287 11.5356 2.99958337 2 P 0 ;0,1,2=133,3=0.000000
L 11.5356 2.99958337 11.53346663 3 2 P 0 ;0,1,2=133,3=0.000000
L 11.53346663 3 11.5308 2.99916683 2 P 0 ;0,1,2=133,3=0.000000
L 11.5308 2.99916683 11.52893327 2.99708317 2 P 0 ;0,1,2=133,3=0.000000
L 11.52893327 2.99708317 11.5284 2.99458366 2 P 0 ;0,1,2=133,3=0.000000
L 11.5284 2.99458366 11.52866663 2.99208268 2 P 0 ;0,1,2=133,3=0.000000
L 11.52866663 2.99208268 11.52973356 2.9899998 2 P 0 ;0,1,2=133,3=0.000000
L 11.52973356 2.9899998 11.53506673 2.98583327 2 P 0 ;0,1,2=133,3=0.000000
L 11.53506673 2.98583327 11.53746673 2.98291644 2 P 0 ;0,1,2=133,3=0.000000
L 11.53746673 2.98291644 11.53906683 2.97874911 2 P 0 ;0,1,2=133,3=0.000000
L 11.53906683 2.97874911 11.5396001 2.975 2 P 0 ;0,1,2=133,3=0.000000
L 11.5396001 2.975 11.5284 2.975 2 P 0 ;0,1,2=133,3=0.000000
L 11.51586673 2.97999961 11.51426703 2.97708287 2 P 0 ;0,1,2=133,3=0.000000
L 11.51426703 2.97708287 11.51213366 2.97541654 2 P 0 ;0,1,2=133,3=0.000000
L 11.51213366 2.97541654 11.50973317 2.975 2 P 0 ;0,1,2=133,3=0.000000
L 11.50973317 2.975 11.5075998 2.97541654 2 P 0 ;0,1,2=133,3=0.000000
L 11.5075998 2.97541654 11.50546644 2.97749941 2 P 0 ;0,1,2=133,3=0.000000
L 11.50546644 2.97749941 11.50413337 2.97999961 2 P 0 ;0,1,2=133,3=0.000000
L 11.50413337 2.97999961 11.50386683 2.9824999 2 P 0 ;0,1,2=133,3=0.000000
L 11.50386683 2.9824999 11.5044 2.98541594 2 P 0 ;0,1,2=133,3=0.000000
L 11.5044 2.98541594 11.50626673 2.98749961 2 P 0 ;0,1,2=133,3=0.000000
L 11.50626673 2.98749961 11.50813356 2.98833346 2 P 0 ;0,1,2=133,3=0.000000
L 11.50813356 2.98833346 11.51053346 2.98833346 2 P 0 ;0,1,2=133,3=0.000000
L 11.50813356 2.98833346 11.50653337 2.98958327 2 P 0 ;0,1,2=133,3=0.000000
L 11.50653337 2.98958327 11.5051999 2.99166614 2 P 0 ;0,1,2=133,3=0.000000
L 11.5051999 2.99166614 11.50466663 2.99416634 2 P 0 ;0,1,2=133,3=0.000000
L 11.50466663 2.99416634 11.5051999 2.99666654 2 P 0 ;0,1,2=133,3=0.000000
L 11.5051999 2.99666654 11.50653337 2.99874941 2 P 0 ;0,1,2=133,3=0.000000
L 11.50653337 2.99874941 11.50893337 3 2 P 0 ;0,1,2=133,3=0.000000
L 11.50893337 3 11.51133337 2.99958337 2 P 0 ;0,1,2=133,3=0.000000
L 11.51133337 2.99958337 11.51373337 2.99791634 2 P 0 ;0,1,2=133,3=0.000000
L 11.49186673 2.97874911 11.49026703 2.97666624 2 P 0 ;0,1,2=133,3=0.000000
L 11.49026703 2.97666624 11.4884003 2.97541654 2 P 0 ;0,1,2=133,3=0.000000
L 11.4884003 2.97541654 11.4860003 2.975 2 P 0 ;0,1,2=133,3=0.000000
L 11.4860003 2.975 11.4835998 2.97583307 2 P 0 ;0,1,2=133,3=0.000000
L 11.4835998 2.97583307 11.48173356 2.97749941 2 P 0 ;0,1,2=133,3=0.000000
L 11.48173356 2.97749941 11.4804 2.98041624 2 P 0 ;0,1,2=133,3=0.000000
L 11.4804 2.98041624 11.48013337 2.98374961 2 P 0 ;0,1,2=133,3=0.000000
L 11.48013337 2.98374961 11.48066663 2.98708297 2 P 0 ;0,1,2=133,3=0.000000
L 11.48066663 2.98708297 11.4820002 2.98916663 2 P 0 ;0,1,2=133,3=0.000000
L 11.4820002 2.98916663 11.48386693 2.99083297 2 P 0 ;0,1,2=133,3=0.000000
L 11.48386693 2.99083297 11.48573317 2.99124951 2 P 0 ;0,1,2=133,3=0.000000
L 11.48573317 2.99124951 11.4876 2.99083297 2 P 0 ;0,1,2=133,3=0.000000
L 11.4876 2.99083297 11.4899999 2.98916663 2 P 0 ;0,1,2=133,3=0.000000
L 11.4899999 2.98916663 11.4892001 3 2 P 0 ;0,1,2=133,3=0.000000
L 11.4892001 3 11.4820002 3 2 P 0 ;0,1,2=133,3=0.000000
A 11.37336004 3.12 11.37336004 3.12 11.36778996 3.12 2 P 0 N
L 11.57561339 3.12854636 11.57721358 3.12979685 2 P 0 ;0,1,2=134,3=0.000000
L 11.57721358 3.12979685 11.57907982 3.13063002 2 P 0 ;0,1,2=134,3=0.000000
L 11.57907982 3.13063002 11.58121319 3.13063002 2 P 0 ;0,1,2=134,3=0.000000
L 11.58121319 3.13063002 11.58361368 3.12937943 2 P 0 ;0,1,2=134,3=0.000000
L 11.58361368 3.12937943 11.58547992 3.12729656 2 P 0 ;0,1,2=134,3=0.000000
L 11.58547992 3.12729656 11.58681348 3.12479636 2 P 0 ;0,1,2=134,3=0.000000
L 11.58681348 3.12479636 11.58788041 3.12062982 2 P 0 ;0,1,2=134,3=0.000000
L 11.58788041 3.12062982 11.58814705 3.11687982 2 P 0 ;0,1,2=134,3=0.000000
L 11.58814705 3.11687982 11.58761329 3.11312992 2 P 0 ;0,1,2=134,3=0.000000
L 11.58761329 3.11312992 11.58681348 3.11062963 2 P 0 ;0,1,2=134,3=0.000000
L 11.58681348 3.11062963 11.58521339 3.10812943 2 P 0 ;0,1,2=134,3=0.000000
L 11.58521339 3.10812943 11.58334656 3.10646309 2 P 0 ;0,1,2=134,3=0.000000
L 11.58334656 3.10646309 11.58148032 3.10563002 2 P 0 ;0,1,2=134,3=0.000000
L 11.58148032 3.10563002 11.57961358 3.10563002 2 P 0 ;0,1,2=134,3=0.000000
L 11.57961358 3.10563002 11.57774675 3.10646309 2 P 0 ;0,1,2=134,3=0.000000
L 11.57774675 3.10646309 11.57614665 3.10771289 2 P 0 ;0,1,2=134,3=0.000000
L 11.57614665 3.10771289 11.57481309 3.10937913 2 P 0 ;0,1,2=134,3=0.000000
L 11.56254685 3.12646339 11.56094675 3.12896289 2 P 0 ;0,1,2=134,3=0.000000
L 11.56094675 3.12896289 11.55908002 3.13021339 2 P 0 ;0,1,2=134,3=0.000000
L 11.55908002 3.13021339 11.55694665 3.13063002 2 P 0 ;0,1,2=134,3=0.000000
L 11.55694665 3.13063002 11.55428002 3.12979685 2 P 0 ;0,1,2=134,3=0.000000
L 11.55428002 3.12979685 11.55241329 3.12771319 2 P 0 ;0,1,2=134,3=0.000000
L 11.55241329 3.12771319 11.55188002 3.12521368 2 P 0 ;0,1,2=134,3=0.000000
L 11.55188002 3.12521368 11.55214665 3.1227127 2 P 0 ;0,1,2=134,3=0.000000
L 11.55214665 3.1227127 11.55321358 3.12062982 2 P 0 ;0,1,2=134,3=0.000000
L 11.55321358 3.12062982 11.55854675 3.11646329 2 P 0 ;0,1,2=134,3=0.000000
L 11.55854675 3.11646329 11.56094675 3.11354646 2 P 0 ;0,1,2=134,3=0.000000
L 11.56094675 3.11354646 11.56254685 3.10937913 2 P 0 ;0,1,2=134,3=0.000000
L 11.56254685 3.10937913 11.56308012 3.10563002 2 P 0 ;0,1,2=134,3=0.000000
L 11.56308012 3.10563002 11.55188002 3.10563002 2 P 0 ;0,1,2=134,3=0.000000
L 11.53854685 3.12646339 11.53694675 3.12896289 2 P 0 ;0,1,2=134,3=0.000000
L 11.53694675 3.12896289 11.53508002 3.13021339 2 P 0 ;0,1,2=134,3=0.000000
L 11.53508002 3.13021339 11.53294665 3.13063002 2 P 0 ;0,1,2=134,3=0.000000
L 11.53294665 3.13063002 11.53028002 3.12979685 2 P 0 ;0,1,2=134,3=0.000000
L 11.53028002 3.12979685 11.52841329 3.12771319 2 P 0 ;0,1,2=134,3=0.000000
L 11.52841329 3.12771319 11.52788002 3.12521368 2 P 0 ;0,1,2=134,3=0.000000
L 11.52788002 3.12521368 11.52814665 3.1227127 2 P 0 ;0,1,2=134,3=0.000000
L 11.52814665 3.1227127 11.52921358 3.12062982 2 P 0 ;0,1,2=134,3=0.000000
L 11.52921358 3.12062982 11.53454675 3.11646329 2 P 0 ;0,1,2=134,3=0.000000
L 11.53454675 3.11646329 11.53694675 3.11354646 2 P 0 ;0,1,2=134,3=0.000000
L 11.53694675 3.11354646 11.53854685 3.10937913 2 P 0 ;0,1,2=134,3=0.000000
L 11.53854685 3.10937913 11.53908012 3.10563002 2 P 0 ;0,1,2=134,3=0.000000
L 11.53908012 3.10563002 11.52788002 3.10563002 2 P 0 ;0,1,2=134,3=0.000000
L 11.51534675 3.11062963 11.51374705 3.10771289 2 P 0 ;0,1,2=134,3=0.000000
L 11.51374705 3.10771289 11.51161368 3.10604656 2 P 0 ;0,1,2=134,3=0.000000
L 11.51161368 3.10604656 11.50921319 3.10563002 2 P 0 ;0,1,2=134,3=0.000000
L 11.50921319 3.10563002 11.50707982 3.10604656 2 P 0 ;0,1,2=134,3=0.000000
L 11.50707982 3.10604656 11.50494646 3.10812943 2 P 0 ;0,1,2=134,3=0.000000
L 11.50494646 3.10812943 11.50361339 3.11062963 2 P 0 ;0,1,2=134,3=0.000000
L 11.50361339 3.11062963 11.50334685 3.11312992 2 P 0 ;0,1,2=134,3=0.000000
L 11.50334685 3.11312992 11.50388002 3.11604596 2 P 0 ;0,1,2=134,3=0.000000
L 11.50388002 3.11604596 11.50574675 3.11812963 2 P 0 ;0,1,2=134,3=0.000000
L 11.50574675 3.11812963 11.50761358 3.11896348 2 P 0 ;0,1,2=134,3=0.000000
L 11.50761358 3.11896348 11.51001348 3.11896348 2 P 0 ;0,1,2=134,3=0.000000
L 11.50761358 3.11896348 11.50601339 3.12021329 2 P 0 ;0,1,2=134,3=0.000000
L 11.50601339 3.12021329 11.50467992 3.12229616 2 P 0 ;0,1,2=134,3=0.000000
L 11.50467992 3.12229616 11.50414665 3.12479636 2 P 0 ;0,1,2=134,3=0.000000
L 11.50414665 3.12479636 11.50467992 3.12729656 2 P 0 ;0,1,2=134,3=0.000000
L 11.50467992 3.12729656 11.50601339 3.12937943 2 P 0 ;0,1,2=134,3=0.000000
L 11.50601339 3.12937943 11.50841339 3.13063002 2 P 0 ;0,1,2=134,3=0.000000
L 11.50841339 3.13063002 11.51081339 3.13021339 2 P 0 ;0,1,2=134,3=0.000000
L 11.51081339 3.13021339 11.51321339 3.12854636 2 P 0 ;0,1,2=134,3=0.000000
L 11.48228002 3.10563002 11.48228002 3.13063002 2 P 0 ;0,1,2=134,3=0.000000
L 11.48228002 3.13063002 11.49214705 3.11271329 2 P 0 ;0,1,2=134,3=0.000000
L 11.49214705 3.11271329 11.47881309 3.11271329 2 P 0 ;0,1,2=134,3=0.000000
A 11.37336004 3.04 11.37336004 3.04 11.36778996 3.04 2 P 0 N
L 11.57561339 3.04854636 11.57721358 3.04979685 2 P 0 ;0,1,2=135,3=0.000000
L 11.57721358 3.04979685 11.57907982 3.05063002 2 P 0 ;0,1,2=135,3=0.000000
L 11.57907982 3.05063002 11.58121319 3.05063002 2 P 0 ;0,1,2=135,3=0.000000
L 11.58121319 3.05063002 11.58361368 3.04937943 2 P 0 ;0,1,2=135,3=0.000000
L 11.58361368 3.04937943 11.58547992 3.04729656 2 P 0 ;0,1,2=135,3=0.000000
L 11.58547992 3.04729656 11.58681348 3.04479636 2 P 0 ;0,1,2=135,3=0.000000
L 11.58681348 3.04479636 11.58788041 3.04062982 2 P 0 ;0,1,2=135,3=0.000000
L 11.58788041 3.04062982 11.58814705 3.03687982 2 P 0 ;0,1,2=135,3=0.000000
L 11.58814705 3.03687982 11.58761329 3.03312992 2 P 0 ;0,1,2=135,3=0.000000
L 11.58761329 3.03312992 11.58681348 3.03062963 2 P 0 ;0,1,2=135,3=0.000000
L 11.58681348 3.03062963 11.58521339 3.02812943 2 P 0 ;0,1,2=135,3=0.000000
L 11.58521339 3.02812943 11.58334656 3.02646309 2 P 0 ;0,1,2=135,3=0.000000
L 11.58334656 3.02646309 11.58148032 3.02563002 2 P 0 ;0,1,2=135,3=0.000000
L 11.58148032 3.02563002 11.57961358 3.02563002 2 P 0 ;0,1,2=135,3=0.000000
L 11.57961358 3.02563002 11.57774675 3.02646309 2 P 0 ;0,1,2=135,3=0.000000
L 11.57774675 3.02646309 11.57614665 3.02771289 2 P 0 ;0,1,2=135,3=0.000000
L 11.57614665 3.02771289 11.57481309 3.02937913 2 P 0 ;0,1,2=135,3=0.000000
L 11.56254685 3.04646339 11.56094675 3.04896289 2 P 0 ;0,1,2=135,3=0.000000
L 11.56094675 3.04896289 11.55908002 3.05021339 2 P 0 ;0,1,2=135,3=0.000000
L 11.55908002 3.05021339 11.55694665 3.05063002 2 P 0 ;0,1,2=135,3=0.000000
L 11.55694665 3.05063002 11.55428002 3.04979685 2 P 0 ;0,1,2=135,3=0.000000
L 11.55428002 3.04979685 11.55241329 3.04771319 2 P 0 ;0,1,2=135,3=0.000000
L 11.55241329 3.04771319 11.55188002 3.04521368 2 P 0 ;0,1,2=135,3=0.000000
L 11.55188002 3.04521368 11.55214665 3.0427127 2 P 0 ;0,1,2=135,3=0.000000
L 11.55214665 3.0427127 11.55321358 3.04062982 2 P 0 ;0,1,2=135,3=0.000000
L 11.55321358 3.04062982 11.55854675 3.03646329 2 P 0 ;0,1,2=135,3=0.000000
L 11.55854675 3.03646329 11.56094675 3.03354646 2 P 0 ;0,1,2=135,3=0.000000
L 11.56094675 3.03354646 11.56254685 3.02937913 2 P 0 ;0,1,2=135,3=0.000000
L 11.56254685 3.02937913 11.56308012 3.02563002 2 P 0 ;0,1,2=135,3=0.000000
L 11.56308012 3.02563002 11.55188002 3.02563002 2 P 0 ;0,1,2=135,3=0.000000
L 11.53854685 3.04646339 11.53694675 3.04896289 2 P 0 ;0,1,2=135,3=0.000000
L 11.53694675 3.04896289 11.53508002 3.05021339 2 P 0 ;0,1,2=135,3=0.000000
L 11.53508002 3.05021339 11.53294665 3.05063002 2 P 0 ;0,1,2=135,3=0.000000
L 11.53294665 3.05063002 11.53028002 3.04979685 2 P 0 ;0,1,2=135,3=0.000000
L 11.53028002 3.04979685 11.52841329 3.04771319 2 P 0 ;0,1,2=135,3=0.000000
L 11.52841329 3.04771319 11.52788002 3.04521368 2 P 0 ;0,1,2=135,3=0.000000
L 11.52788002 3.04521368 11.52814665 3.0427127 2 P 0 ;0,1,2=135,3=0.000000
L 11.52814665 3.0427127 11.52921358 3.04062982 2 P 0 ;0,1,2=135,3=0.000000
L 11.52921358 3.04062982 11.53454675 3.03646329 2 P 0 ;0,1,2=135,3=0.000000
L 11.53454675 3.03646329 11.53694675 3.03354646 2 P 0 ;0,1,2=135,3=0.000000
L 11.53694675 3.03354646 11.53854685 3.02937913 2 P 0 ;0,1,2=135,3=0.000000
L 11.53854685 3.02937913 11.53908012 3.02563002 2 P 0 ;0,1,2=135,3=0.000000
L 11.53908012 3.02563002 11.52788002 3.02563002 2 P 0 ;0,1,2=135,3=0.000000
L 11.51534675 3.03062963 11.51374705 3.02771289 2 P 0 ;0,1,2=135,3=0.000000
L 11.51374705 3.02771289 11.51161368 3.02604656 2 P 0 ;0,1,2=135,3=0.000000
L 11.51161368 3.02604656 11.50921319 3.02563002 2 P 0 ;0,1,2=135,3=0.000000
L 11.50921319 3.02563002 11.50707982 3.02604656 2 P 0 ;0,1,2=135,3=0.000000
L 11.50707982 3.02604656 11.50494646 3.02812943 2 P 0 ;0,1,2=135,3=0.000000
L 11.50494646 3.02812943 11.50361339 3.03062963 2 P 0 ;0,1,2=135,3=0.000000
L 11.50361339 3.03062963 11.50334685 3.03312992 2 P 0 ;0,1,2=135,3=0.000000
L 11.50334685 3.03312992 11.50388002 3.03604596 2 P 0 ;0,1,2=135,3=0.000000
L 11.50388002 3.03604596 11.50574675 3.03812963 2 P 0 ;0,1,2=135,3=0.000000
L 11.50574675 3.03812963 11.50761358 3.03896348 2 P 0 ;0,1,2=135,3=0.000000
L 11.50761358 3.03896348 11.51001348 3.03896348 2 P 0 ;0,1,2=135,3=0.000000
L 11.50761358 3.03896348 11.50601339 3.04021329 2 P 0 ;0,1,2=135,3=0.000000
L 11.50601339 3.04021329 11.50467992 3.04229616 2 P 0 ;0,1,2=135,3=0.000000
L 11.50467992 3.04229616 11.50414665 3.04479636 2 P 0 ;0,1,2=135,3=0.000000
L 11.50414665 3.04479636 11.50467992 3.04729656 2 P 0 ;0,1,2=135,3=0.000000
L 11.50467992 3.04729656 11.50601339 3.04937943 2 P 0 ;0,1,2=135,3=0.000000
L 11.50601339 3.04937943 11.50841339 3.05063002 2 P 0 ;0,1,2=135,3=0.000000
L 11.50841339 3.05063002 11.51081339 3.05021339 2 P 0 ;0,1,2=135,3=0.000000
L 11.51081339 3.05021339 11.51321339 3.04854636 2 P 0 ;0,1,2=135,3=0.000000
L 11.49134675 3.03062963 11.48974705 3.02771289 2 P 0 ;0,1,2=135,3=0.000000
L 11.48974705 3.02771289 11.48761368 3.02604656 2 P 0 ;0,1,2=135,3=0.000000
L 11.48761368 3.02604656 11.48521319 3.02563002 2 P 0 ;0,1,2=135,3=0.000000
L 11.48521319 3.02563002 11.48307982 3.02604656 2 P 0 ;0,1,2=135,3=0.000000
L 11.48307982 3.02604656 11.48094646 3.02812943 2 P 0 ;0,1,2=135,3=0.000000
L 11.48094646 3.02812943 11.47961339 3.03062963 2 P 0 ;0,1,2=135,3=0.000000
L 11.47961339 3.03062963 11.47934685 3.03312992 2 P 0 ;0,1,2=135,3=0.000000
L 11.47934685 3.03312992 11.47988002 3.03604596 2 P 0 ;0,1,2=135,3=0.000000
L 11.47988002 3.03604596 11.48174675 3.03812963 2 P 0 ;0,1,2=135,3=0.000000
L 11.48174675 3.03812963 11.48361358 3.03896348 2 P 0 ;0,1,2=135,3=0.000000
L 11.48361358 3.03896348 11.48601348 3.03896348 2 P 0 ;0,1,2=135,3=0.000000
L 11.48361358 3.03896348 11.48201339 3.04021329 2 P 0 ;0,1,2=135,3=0.000000
L 11.48201339 3.04021329 11.48067992 3.04229616 2 P 0 ;0,1,2=135,3=0.000000
L 11.48067992 3.04229616 11.48014665 3.04479636 2 P 0 ;0,1,2=135,3=0.000000
L 11.48014665 3.04479636 11.48067992 3.04729656 2 P 0 ;0,1,2=135,3=0.000000
L 11.48067992 3.04729656 11.48201339 3.04937943 2 P 0 ;0,1,2=135,3=0.000000
L 11.48201339 3.04937943 11.48441339 3.05063002 2 P 0 ;0,1,2=135,3=0.000000
L 11.48441339 3.05063002 11.48681339 3.05021339 2 P 0 ;0,1,2=135,3=0.000000
L 11.48681339 3.05021339 11.48921339 3.04854636 2 P 0 ;0,1,2=135,3=0.000000
A 11.37336004 3.2 11.37336004 3.2 11.36778996 3.2 2 P 0 N
L 11.57561339 3.20854636 11.57721358 3.20979685 2 P 0 ;0,1,2=136,3=0.000000
L 11.57721358 3.20979685 11.57907982 3.21063002 2 P 0 ;0,1,2=136,3=0.000000
L 11.57907982 3.21063002 11.58121319 3.21063002 2 P 0 ;0,1,2=136,3=0.000000
L 11.58121319 3.21063002 11.58361368 3.20937943 2 P 0 ;0,1,2=136,3=0.000000
L 11.58361368 3.20937943 11.58547992 3.20729656 2 P 0 ;0,1,2=136,3=0.000000
L 11.58547992 3.20729656 11.58681348 3.20479636 2 P 0 ;0,1,2=136,3=0.000000
L 11.58681348 3.20479636 11.58788041 3.20062982 2 P 0 ;0,1,2=136,3=0.000000
L 11.58788041 3.20062982 11.58814705 3.19687982 2 P 0 ;0,1,2=136,3=0.000000
L 11.58814705 3.19687982 11.58761329 3.19312992 2 P 0 ;0,1,2=136,3=0.000000
L 11.58761329 3.19312992 11.58681348 3.19062963 2 P 0 ;0,1,2=136,3=0.000000
L 11.58681348 3.19062963 11.58521339 3.18812943 2 P 0 ;0,1,2=136,3=0.000000
L 11.58521339 3.18812943 11.58334656 3.18646309 2 P 0 ;0,1,2=136,3=0.000000
L 11.58334656 3.18646309 11.58148032 3.18563002 2 P 0 ;0,1,2=136,3=0.000000
L 11.58148032 3.18563002 11.57961358 3.18563002 2 P 0 ;0,1,2=136,3=0.000000
L 11.57961358 3.18563002 11.57774675 3.18646309 2 P 0 ;0,1,2=136,3=0.000000
L 11.57774675 3.18646309 11.57614665 3.18771289 2 P 0 ;0,1,2=136,3=0.000000
L 11.57614665 3.18771289 11.57481309 3.18937913 2 P 0 ;0,1,2=136,3=0.000000
L 11.56254685 3.20646339 11.56094675 3.20896289 2 P 0 ;0,1,2=136,3=0.000000
L 11.56094675 3.20896289 11.55908002 3.21021339 2 P 0 ;0,1,2=136,3=0.000000
L 11.55908002 3.21021339 11.55694665 3.21063002 2 P 0 ;0,1,2=136,3=0.000000
L 11.55694665 3.21063002 11.55428002 3.20979685 2 P 0 ;0,1,2=136,3=0.000000
L 11.55428002 3.20979685 11.55241329 3.20771319 2 P 0 ;0,1,2=136,3=0.000000
L 11.55241329 3.20771319 11.55188002 3.20521368 2 P 0 ;0,1,2=136,3=0.000000
L 11.55188002 3.20521368 11.55214665 3.2027127 2 P 0 ;0,1,2=136,3=0.000000
L 11.55214665 3.2027127 11.55321358 3.20062982 2 P 0 ;0,1,2=136,3=0.000000
L 11.55321358 3.20062982 11.55854675 3.19646329 2 P 0 ;0,1,2=136,3=0.000000
L 11.55854675 3.19646329 11.56094675 3.19354646 2 P 0 ;0,1,2=136,3=0.000000
L 11.56094675 3.19354646 11.56254685 3.18937913 2 P 0 ;0,1,2=136,3=0.000000
L 11.56254685 3.18937913 11.56308012 3.18563002 2 P 0 ;0,1,2=136,3=0.000000
L 11.56308012 3.18563002 11.55188002 3.18563002 2 P 0 ;0,1,2=136,3=0.000000
L 11.53854685 3.20646339 11.53694675 3.20896289 2 P 0 ;0,1,2=136,3=0.000000
L 11.53694675 3.20896289 11.53508002 3.21021339 2 P 0 ;0,1,2=136,3=0.000000
L 11.53508002 3.21021339 11.53294665 3.21063002 2 P 0 ;0,1,2=136,3=0.000000
L 11.53294665 3.21063002 11.53028002 3.20979685 2 P 0 ;0,1,2=136,3=0.000000
L 11.53028002 3.20979685 11.52841329 3.20771319 2 P 0 ;0,1,2=136,3=0.000000
L 11.52841329 3.20771319 11.52788002 3.20521368 2 P 0 ;0,1,2=136,3=0.000000
L 11.52788002 3.20521368 11.52814665 3.2027127 2 P 0 ;0,1,2=136,3=0.000000
L 11.52814665 3.2027127 11.52921358 3.20062982 2 P 0 ;0,1,2=136,3=0.000000
L 11.52921358 3.20062982 11.53454675 3.19646329 2 P 0 ;0,1,2=136,3=0.000000
L 11.53454675 3.19646329 11.53694675 3.19354646 2 P 0 ;0,1,2=136,3=0.000000
L 11.53694675 3.19354646 11.53854685 3.18937913 2 P 0 ;0,1,2=136,3=0.000000
L 11.53854685 3.18937913 11.53908012 3.18563002 2 P 0 ;0,1,2=136,3=0.000000
L 11.53908012 3.18563002 11.52788002 3.18563002 2 P 0 ;0,1,2=136,3=0.000000
L 11.51534675 3.19062963 11.51374705 3.18771289 2 P 0 ;0,1,2=136,3=0.000000
L 11.51374705 3.18771289 11.51161368 3.18604656 2 P 0 ;0,1,2=136,3=0.000000
L 11.51161368 3.18604656 11.50921319 3.18563002 2 P 0 ;0,1,2=136,3=0.000000
L 11.50921319 3.18563002 11.50707982 3.18604656 2 P 0 ;0,1,2=136,3=0.000000
L 11.50707982 3.18604656 11.50494646 3.18812943 2 P 0 ;0,1,2=136,3=0.000000
L 11.50494646 3.18812943 11.50361339 3.19062963 2 P 0 ;0,1,2=136,3=0.000000
L 11.50361339 3.19062963 11.50334685 3.19312992 2 P 0 ;0,1,2=136,3=0.000000
L 11.50334685 3.19312992 11.50388002 3.19604596 2 P 0 ;0,1,2=136,3=0.000000
L 11.50388002 3.19604596 11.50574675 3.19812963 2 P 0 ;0,1,2=136,3=0.000000
L 11.50574675 3.19812963 11.50761358 3.19896348 2 P 0 ;0,1,2=136,3=0.000000
L 11.50761358 3.19896348 11.51001348 3.19896348 2 P 0 ;0,1,2=136,3=0.000000
L 11.50761358 3.19896348 11.50601339 3.20021329 2 P 0 ;0,1,2=136,3=0.000000
L 11.50601339 3.20021329 11.50467992 3.20229616 2 P 0 ;0,1,2=136,3=0.000000
L 11.50467992 3.20229616 11.50414665 3.20479636 2 P 0 ;0,1,2=136,3=0.000000
L 11.50414665 3.20479636 11.50467992 3.20729656 2 P 0 ;0,1,2=136,3=0.000000
L 11.50467992 3.20729656 11.50601339 3.20937943 2 P 0 ;0,1,2=136,3=0.000000
L 11.50601339 3.20937943 11.50841339 3.21063002 2 P 0 ;0,1,2=136,3=0.000000
L 11.50841339 3.21063002 11.51081339 3.21021339 2 P 0 ;0,1,2=136,3=0.000000
L 11.51081339 3.21021339 11.51321339 3.20854636 2 P 0 ;0,1,2=136,3=0.000000
L 11.49054685 3.20646339 11.48894675 3.20896289 2 P 0 ;0,1,2=136,3=0.000000
L 11.48894675 3.20896289 11.48708002 3.21021339 2 P 0 ;0,1,2=136,3=0.000000
L 11.48708002 3.21021339 11.48494665 3.21063002 2 P 0 ;0,1,2=136,3=0.000000
L 11.48494665 3.21063002 11.48228002 3.20979685 2 P 0 ;0,1,2=136,3=0.000000
L 11.48228002 3.20979685 11.48041329 3.20771319 2 P 0 ;0,1,2=136,3=0.000000
L 11.48041329 3.20771319 11.47988002 3.20521368 2 P 0 ;0,1,2=136,3=0.000000
L 11.47988002 3.20521368 11.48014665 3.2027127 2 P 0 ;0,1,2=136,3=0.000000
L 11.48014665 3.2027127 11.48121358 3.20062982 2 P 0 ;0,1,2=136,3=0.000000
L 11.48121358 3.20062982 11.48654675 3.19646329 2 P 0 ;0,1,2=136,3=0.000000
L 11.48654675 3.19646329 11.48894675 3.19354646 2 P 0 ;0,1,2=136,3=0.000000
L 11.48894675 3.19354646 11.49054685 3.18937913 2 P 0 ;0,1,2=136,3=0.000000
L 11.49054685 3.18937913 11.49108012 3.18563002 2 P 0 ;0,1,2=136,3=0.000000
L 11.49108012 3.18563002 11.47988002 3.18563002 2 P 0 ;0,1,2=136,3=0.000000
A 11.37336004 3.28 11.37336004 3.28 11.36778996 3.28 2 P 0 N
L 11.57561339 3.28854636 11.57721358 3.28979685 2 P 0 ;0,1,2=137,3=0.000000
L 11.57721358 3.28979685 11.57907982 3.29063002 2 P 0 ;0,1,2=137,3=0.000000
L 11.57907982 3.29063002 11.58121319 3.29063002 2 P 0 ;0,1,2=137,3=0.000000
L 11.58121319 3.29063002 11.58361368 3.28937943 2 P 0 ;0,1,2=137,3=0.000000
L 11.58361368 3.28937943 11.58547992 3.28729656 2 P 0 ;0,1,2=137,3=0.000000
L 11.58547992 3.28729656 11.58681348 3.28479636 2 P 0 ;0,1,2=137,3=0.000000
L 11.58681348 3.28479636 11.58788041 3.28062982 2 P 0 ;0,1,2=137,3=0.000000
L 11.58788041 3.28062982 11.58814705 3.27687982 2 P 0 ;0,1,2=137,3=0.000000
L 11.58814705 3.27687982 11.58761329 3.27312992 2 P 0 ;0,1,2=137,3=0.000000
L 11.58761329 3.27312992 11.58681348 3.27062963 2 P 0 ;0,1,2=137,3=0.000000
L 11.58681348 3.27062963 11.58521339 3.26812943 2 P 0 ;0,1,2=137,3=0.000000
L 11.58521339 3.26812943 11.58334656 3.26646309 2 P 0 ;0,1,2=137,3=0.000000
L 11.58334656 3.26646309 11.58148032 3.26563002 2 P 0 ;0,1,2=137,3=0.000000
L 11.58148032 3.26563002 11.57961358 3.26563002 2 P 0 ;0,1,2=137,3=0.000000
L 11.57961358 3.26563002 11.57774675 3.26646309 2 P 0 ;0,1,2=137,3=0.000000
L 11.57774675 3.26646309 11.57614665 3.26771289 2 P 0 ;0,1,2=137,3=0.000000
L 11.57614665 3.26771289 11.57481309 3.26937913 2 P 0 ;0,1,2=137,3=0.000000
L 11.56254685 3.28646339 11.56094675 3.28896289 2 P 0 ;0,1,2=137,3=0.000000
L 11.56094675 3.28896289 11.55908002 3.29021339 2 P 0 ;0,1,2=137,3=0.000000
L 11.55908002 3.29021339 11.55694665 3.29063002 2 P 0 ;0,1,2=137,3=0.000000
L 11.55694665 3.29063002 11.55428002 3.28979685 2 P 0 ;0,1,2=137,3=0.000000
L 11.55428002 3.28979685 11.55241329 3.28771319 2 P 0 ;0,1,2=137,3=0.000000
L 11.55241329 3.28771319 11.55188002 3.28521368 2 P 0 ;0,1,2=137,3=0.000000
L 11.55188002 3.28521368 11.55214665 3.2827127 2 P 0 ;0,1,2=137,3=0.000000
L 11.55214665 3.2827127 11.55321358 3.28062982 2 P 0 ;0,1,2=137,3=0.000000
L 11.55321358 3.28062982 11.55854675 3.27646329 2 P 0 ;0,1,2=137,3=0.000000
L 11.55854675 3.27646329 11.56094675 3.27354646 2 P 0 ;0,1,2=137,3=0.000000
L 11.56094675 3.27354646 11.56254685 3.26937913 2 P 0 ;0,1,2=137,3=0.000000
L 11.56254685 3.26937913 11.56308012 3.26563002 2 P 0 ;0,1,2=137,3=0.000000
L 11.56308012 3.26563002 11.55188002 3.26563002 2 P 0 ;0,1,2=137,3=0.000000
L 11.53854685 3.28646339 11.53694675 3.28896289 2 P 0 ;0,1,2=137,3=0.000000
L 11.53694675 3.28896289 11.53508002 3.29021339 2 P 0 ;0,1,2=137,3=0.000000
L 11.53508002 3.29021339 11.53294665 3.29063002 2 P 0 ;0,1,2=137,3=0.000000
L 11.53294665 3.29063002 11.53028002 3.28979685 2 P 0 ;0,1,2=137,3=0.000000
L 11.53028002 3.28979685 11.52841329 3.28771319 2 P 0 ;0,1,2=137,3=0.000000
L 11.52841329 3.28771319 11.52788002 3.28521368 2 P 0 ;0,1,2=137,3=0.000000
L 11.52788002 3.28521368 11.52814665 3.2827127 2 P 0 ;0,1,2=137,3=0.000000
L 11.52814665 3.2827127 11.52921358 3.28062982 2 P 0 ;0,1,2=137,3=0.000000
L 11.52921358 3.28062982 11.53454675 3.27646329 2 P 0 ;0,1,2=137,3=0.000000
L 11.53454675 3.27646329 11.53694675 3.27354646 2 P 0 ;0,1,2=137,3=0.000000
L 11.53694675 3.27354646 11.53854685 3.26937913 2 P 0 ;0,1,2=137,3=0.000000
L 11.53854685 3.26937913 11.53908012 3.26563002 2 P 0 ;0,1,2=137,3=0.000000
L 11.53908012 3.26563002 11.52788002 3.26563002 2 P 0 ;0,1,2=137,3=0.000000
L 11.51534675 3.27062963 11.51374705 3.26771289 2 P 0 ;0,1,2=137,3=0.000000
L 11.51374705 3.26771289 11.51161368 3.26604656 2 P 0 ;0,1,2=137,3=0.000000
L 11.51161368 3.26604656 11.50921319 3.26563002 2 P 0 ;0,1,2=137,3=0.000000
L 11.50921319 3.26563002 11.50707982 3.26604656 2 P 0 ;0,1,2=137,3=0.000000
L 11.50707982 3.26604656 11.50494646 3.26812943 2 P 0 ;0,1,2=137,3=0.000000
L 11.50494646 3.26812943 11.50361339 3.27062963 2 P 0 ;0,1,2=137,3=0.000000
L 11.50361339 3.27062963 11.50334685 3.27312992 2 P 0 ;0,1,2=137,3=0.000000
L 11.50334685 3.27312992 11.50388002 3.27604596 2 P 0 ;0,1,2=137,3=0.000000
L 11.50388002 3.27604596 11.50574675 3.27812963 2 P 0 ;0,1,2=137,3=0.000000
L 11.50574675 3.27812963 11.50761358 3.27896348 2 P 0 ;0,1,2=137,3=0.000000
L 11.50761358 3.27896348 11.51001348 3.27896348 2 P 0 ;0,1,2=137,3=0.000000
L 11.50761358 3.27896348 11.50601339 3.28021329 2 P 0 ;0,1,2=137,3=0.000000
L 11.50601339 3.28021329 11.50467992 3.28229616 2 P 0 ;0,1,2=137,3=0.000000
L 11.50467992 3.28229616 11.50414665 3.28479636 2 P 0 ;0,1,2=137,3=0.000000
L 11.50414665 3.28479636 11.50467992 3.28729656 2 P 0 ;0,1,2=137,3=0.000000
L 11.50467992 3.28729656 11.50601339 3.28937943 2 P 0 ;0,1,2=137,3=0.000000
L 11.50601339 3.28937943 11.50841339 3.29063002 2 P 0 ;0,1,2=137,3=0.000000
L 11.50841339 3.29063002 11.51081339 3.29021339 2 P 0 ;0,1,2=137,3=0.000000
L 11.51081339 3.29021339 11.51321339 3.28854636 2 P 0 ;0,1,2=137,3=0.000000
L 11.48548032 3.26563002 11.48548032 3.29063002 2 P 0 ;0,1,2=137,3=0.000000
L 11.48548032 3.29063002 11.48868012 3.28563032 2 P 0 ;0,1,2=137,3=0.000000
L 11.48868012 3.26563002 11.48228051 3.26563002 2 P 0 ;0,1,2=137,3=0.000000
A 5.36943002 3.12 5.36943002 3.12 5.36386004 3.12 2 P 0 N
L 5.24168337 3.13354636 5.24328356 3.13479685 2 P 0 ;0,1,2=138,3=0.000000
L 5.24328356 3.13479685 5.2451498 3.13563002 2 P 0 ;0,1,2=138,3=0.000000
L 5.2451498 3.13563002 5.24728317 3.13563002 2 P 0 ;0,1,2=138,3=0.000000
L 5.24728317 3.13563002 5.24968366 3.13437943 2 P 0 ;0,1,2=138,3=0.000000
L 5.24968366 3.13437943 5.2515499 3.13229656 2 P 0 ;0,1,2=138,3=0.000000
L 5.2515499 3.13229656 5.25288346 3.12979636 2 P 0 ;0,1,2=138,3=0.000000
L 5.25288346 3.12979636 5.25395039 3.12562982 2 P 0 ;0,1,2=138,3=0.000000
L 5.25395039 3.12562982 5.25421703 3.12187982 2 P 0 ;0,1,2=138,3=0.000000
L 5.25421703 3.12187982 5.25368327 3.11812992 2 P 0 ;0,1,2=138,3=0.000000
L 5.25368327 3.11812992 5.25288346 3.11562963 2 P 0 ;0,1,2=138,3=0.000000
L 5.25288346 3.11562963 5.25128337 3.11312943 2 P 0 ;0,1,2=138,3=0.000000
L 5.25128337 3.11312943 5.24941654 3.11146309 2 P 0 ;0,1,2=138,3=0.000000
L 5.24941654 3.11146309 5.2475503 3.11063002 2 P 0 ;0,1,2=138,3=0.000000
L 5.2475503 3.11063002 5.24568356 3.11063002 2 P 0 ;0,1,2=138,3=0.000000
L 5.24568356 3.11063002 5.24381673 3.11146309 2 P 0 ;0,1,2=138,3=0.000000
L 5.24381673 3.11146309 5.24221663 3.11271289 2 P 0 ;0,1,2=138,3=0.000000
L 5.24221663 3.11271289 5.24088307 3.11437913 2 P 0 ;0,1,2=138,3=0.000000
L 5.2235503 3.11063002 5.2235503 3.13563002 2 P 0 ;0,1,2=138,3=0.000000
L 5.2235503 3.13563002 5.2267501 3.13063032 2 P 0 ;0,1,2=138,3=0.000000
L 5.2267501 3.11063002 5.22035049 3.11063002 2 P 0 ;0,1,2=138,3=0.000000
L 5.20408366 3.11354606 5.20221683 3.11146309 2 P 0 ;0,1,2=138,3=0.000000
L 5.20221683 3.11146309 5.20008346 3.11063002 2 P 0 ;0,1,2=138,3=0.000000
L 5.20008346 3.11063002 5.1979501 3.11146309 2 P 0 ;0,1,2=138,3=0.000000
L 5.1979501 3.11146309 5.19608337 3.1139626 2 P 0 ;0,1,2=138,3=0.000000
L 5.19608337 3.1139626 5.1947499 3.11771329 2 P 0 ;0,1,2=138,3=0.000000
L 5.1947499 3.11771329 5.19421663 3.12146329 2 P 0 ;0,1,2=138,3=0.000000
L 5.19421663 3.12146329 5.19421663 3.12604636 2 P 0 ;0,1,2=138,3=0.000000
L 5.19421663 3.12604636 5.1947499 3.12979636 2 P 0 ;0,1,2=138,3=0.000000
L 5.1947499 3.12979636 5.19608337 3.13312972 2 P 0 ;0,1,2=138,3=0.000000
L 5.19608337 3.13312972 5.19768356 3.13479685 2 P 0 ;0,1,2=138,3=0.000000
L 5.19768356 3.13479685 5.1995503 3.13563002 2 P 0 ;0,1,2=138,3=0.000000
L 5.1995503 3.13563002 5.20168366 3.13479685 2 P 0 ;0,1,2=138,3=0.000000
L 5.20168366 3.13479685 5.20328337 3.13312972 2 P 0 ;0,1,2=138,3=0.000000
L 5.20328337 3.13312972 5.2043502 3.13063032 2 P 0 ;0,1,2=138,3=0.000000
L 5.2043502 3.13063032 5.20488346 3.12729616 2 P 0 ;0,1,2=138,3=0.000000
L 5.20488346 3.12729616 5.2043502 3.12438012 2 P 0 ;0,1,2=138,3=0.000000
L 5.2043502 3.12438012 5.20301673 3.12146329 2 P 0 ;0,1,2=138,3=0.000000
L 5.20301673 3.12146329 5.20141654 3.11979616 2 P 0 ;0,1,2=138,3=0.000000
L 5.20141654 3.11979616 5.1995503 3.11937963 2 P 0 ;0,1,2=138,3=0.000000
L 5.1995503 3.11937963 5.19741693 3.1202128 2 P 0 ;0,1,2=138,3=0.000000
L 5.19741693 3.1202128 5.19581673 3.12229646 2 P 0 ;0,1,2=138,3=0.000000
L 5.19581673 3.12229646 5.19421663 3.12604636 2 P 0 ;0,1,2=138,3=0.000000
L 5.18008366 3.11354606 5.17821683 3.11146309 2 P 0 ;0,1,2=138,3=0.000000
L 5.17821683 3.11146309 5.17608346 3.11063002 2 P 0 ;0,1,2=138,3=0.000000
L 5.17608346 3.11063002 5.1739501 3.11146309 2 P 0 ;0,1,2=138,3=0.000000
L 5.1739501 3.11146309 5.17208337 3.1139626 2 P 0 ;0,1,2=138,3=0.000000
L 5.17208337 3.1139626 5.1707499 3.11771329 2 P 0 ;0,1,2=138,3=0.000000
L 5.1707499 3.11771329 5.17021663 3.12146329 2 P 0 ;0,1,2=138,3=0.000000
L 5.17021663 3.12146329 5.17021663 3.12604636 2 P 0 ;0,1,2=138,3=0.000000
L 5.17021663 3.12604636 5.1707499 3.12979636 2 P 0 ;0,1,2=138,3=0.000000
L 5.1707499 3.12979636 5.17208337 3.13312972 2 P 0 ;0,1,2=138,3=0.000000
L 5.17208337 3.13312972 5.17368356 3.13479685 2 P 0 ;0,1,2=138,3=0.000000
L 5.17368356 3.13479685 5.1755503 3.13563002 2 P 0 ;0,1,2=138,3=0.000000
L 5.1755503 3.13563002 5.17768366 3.13479685 2 P 0 ;0,1,2=138,3=0.000000
L 5.17768366 3.13479685 5.17928337 3.13312972 2 P 0 ;0,1,2=138,3=0.000000
L 5.17928337 3.13312972 5.1803502 3.13063032 2 P 0 ;0,1,2=138,3=0.000000
L 5.1803502 3.13063032 5.18088346 3.12729616 2 P 0 ;0,1,2=138,3=0.000000
L 5.18088346 3.12729616 5.1803502 3.12438012 2 P 0 ;0,1,2=138,3=0.000000
L 5.1803502 3.12438012 5.17901673 3.12146329 2 P 0 ;0,1,2=138,3=0.000000
L 5.17901673 3.12146329 5.17741654 3.11979616 2 P 0 ;0,1,2=138,3=0.000000
L 5.17741654 3.11979616 5.1755503 3.11937963 2 P 0 ;0,1,2=138,3=0.000000
L 5.1755503 3.11937963 5.17341693 3.1202128 2 P 0 ;0,1,2=138,3=0.000000
L 5.17341693 3.1202128 5.17181673 3.12229646 2 P 0 ;0,1,2=138,3=0.000000
L 5.17181673 3.12229646 5.17021663 3.12604636 2 P 0 ;0,1,2=138,3=0.000000
L 5.15741673 3.11562963 5.15581703 3.11271289 2 P 0 ;0,1,2=138,3=0.000000
L 5.15581703 3.11271289 5.15368366 3.11104656 2 P 0 ;0,1,2=138,3=0.000000
L 5.15368366 3.11104656 5.15128317 3.11063002 2 P 0 ;0,1,2=138,3=0.000000
L 5.15128317 3.11063002 5.1491498 3.11104656 2 P 0 ;0,1,2=138,3=0.000000
L 5.1491498 3.11104656 5.14701644 3.11312943 2 P 0 ;0,1,2=138,3=0.000000
L 5.14701644 3.11312943 5.14568337 3.11562963 2 P 0 ;0,1,2=138,3=0.000000
L 5.14568337 3.11562963 5.14541683 3.11812992 2 P 0 ;0,1,2=138,3=0.000000
L 5.14541683 3.11812992 5.14595 3.12104596 2 P 0 ;0,1,2=138,3=0.000000
L 5.14595 3.12104596 5.14781673 3.12312963 2 P 0 ;0,1,2=138,3=0.000000
L 5.14781673 3.12312963 5.14968356 3.12396348 2 P 0 ;0,1,2=138,3=0.000000
L 5.14968356 3.12396348 5.15208346 3.12396348 2 P 0 ;0,1,2=138,3=0.000000
L 5.14968356 3.12396348 5.14808337 3.12521329 2 P 0 ;0,1,2=138,3=0.000000
L 5.14808337 3.12521329 5.1467499 3.12729616 2 P 0 ;0,1,2=138,3=0.000000
L 5.1467499 3.12729616 5.14621663 3.12979636 2 P 0 ;0,1,2=138,3=0.000000
L 5.14621663 3.12979636 5.1467499 3.13229656 2 P 0 ;0,1,2=138,3=0.000000
L 5.1467499 3.13229656 5.14808337 3.13437943 2 P 0 ;0,1,2=138,3=0.000000
L 5.14808337 3.13437943 5.15048337 3.13563002 2 P 0 ;0,1,2=138,3=0.000000
L 5.15048337 3.13563002 5.15288337 3.13521339 2 P 0 ;0,1,2=138,3=0.000000
L 5.15288337 3.13521339 5.15528337 3.13354636 2 P 0 ;0,1,2=138,3=0.000000
A 5.36943002 3.04 5.36943002 3.04 5.36386004 3.04 2 P 0 N
L 5.24168337 3.05354636 5.24328356 3.05479685 2 P 0 ;0,1,2=139,3=0.000000
L 5.24328356 3.05479685 5.2451498 3.05563002 2 P 0 ;0,1,2=139,3=0.000000
L 5.2451498 3.05563002 5.24728317 3.05563002 2 P 0 ;0,1,2=139,3=0.000000
L 5.24728317 3.05563002 5.24968366 3.05437943 2 P 0 ;0,1,2=139,3=0.000000
L 5.24968366 3.05437943 5.2515499 3.05229656 2 P 0 ;0,1,2=139,3=0.000000
L 5.2515499 3.05229656 5.25288346 3.04979636 2 P 0 ;0,1,2=139,3=0.000000
L 5.25288346 3.04979636 5.25395039 3.04562982 2 P 0 ;0,1,2=139,3=0.000000
L 5.25395039 3.04562982 5.25421703 3.04187982 2 P 0 ;0,1,2=139,3=0.000000
L 5.25421703 3.04187982 5.25368327 3.03812992 2 P 0 ;0,1,2=139,3=0.000000
L 5.25368327 3.03812992 5.25288346 3.03562963 2 P 0 ;0,1,2=139,3=0.000000
L 5.25288346 3.03562963 5.25128337 3.03312943 2 P 0 ;0,1,2=139,3=0.000000
L 5.25128337 3.03312943 5.24941654 3.03146309 2 P 0 ;0,1,2=139,3=0.000000
L 5.24941654 3.03146309 5.2475503 3.03063002 2 P 0 ;0,1,2=139,3=0.000000
L 5.2475503 3.03063002 5.24568356 3.03063002 2 P 0 ;0,1,2=139,3=0.000000
L 5.24568356 3.03063002 5.24381673 3.03146309 2 P 0 ;0,1,2=139,3=0.000000
L 5.24381673 3.03146309 5.24221663 3.03271289 2 P 0 ;0,1,2=139,3=0.000000
L 5.24221663 3.03271289 5.24088307 3.03437913 2 P 0 ;0,1,2=139,3=0.000000
L 5.2235503 3.03063002 5.2235503 3.05563002 2 P 0 ;0,1,2=139,3=0.000000
L 5.2235503 3.05563002 5.2267501 3.05063032 2 P 0 ;0,1,2=139,3=0.000000
L 5.2267501 3.03063002 5.22035049 3.03063002 2 P 0 ;0,1,2=139,3=0.000000
L 5.20408366 3.03354606 5.20221683 3.03146309 2 P 0 ;0,1,2=139,3=0.000000
L 5.20221683 3.03146309 5.20008346 3.03063002 2 P 0 ;0,1,2=139,3=0.000000
L 5.20008346 3.03063002 5.1979501 3.03146309 2 P 0 ;0,1,2=139,3=0.000000
L 5.1979501 3.03146309 5.19608337 3.0339626 2 P 0 ;0,1,2=139,3=0.000000
L 5.19608337 3.0339626 5.1947499 3.03771329 2 P 0 ;0,1,2=139,3=0.000000
L 5.1947499 3.03771329 5.19421663 3.04146329 2 P 0 ;0,1,2=139,3=0.000000
L 5.19421663 3.04146329 5.19421663 3.04604636 2 P 0 ;0,1,2=139,3=0.000000
L 5.19421663 3.04604636 5.1947499 3.04979636 2 P 0 ;0,1,2=139,3=0.000000
L 5.1947499 3.04979636 5.19608337 3.05312972 2 P 0 ;0,1,2=139,3=0.000000
L 5.19608337 3.05312972 5.19768356 3.05479685 2 P 0 ;0,1,2=139,3=0.000000
L 5.19768356 3.05479685 5.1995503 3.05563002 2 P 0 ;0,1,2=139,3=0.000000
L 5.1995503 3.05563002 5.20168366 3.05479685 2 P 0 ;0,1,2=139,3=0.000000
L 5.20168366 3.05479685 5.20328337 3.05312972 2 P 0 ;0,1,2=139,3=0.000000
L 5.20328337 3.05312972 5.2043502 3.05063032 2 P 0 ;0,1,2=139,3=0.000000
L 5.2043502 3.05063032 5.20488346 3.04729616 2 P 0 ;0,1,2=139,3=0.000000
L 5.20488346 3.04729616 5.2043502 3.04438012 2 P 0 ;0,1,2=139,3=0.000000
L 5.2043502 3.04438012 5.20301673 3.04146329 2 P 0 ;0,1,2=139,3=0.000000
L 5.20301673 3.04146329 5.20141654 3.03979616 2 P 0 ;0,1,2=139,3=0.000000
L 5.20141654 3.03979616 5.1995503 3.03937963 2 P 0 ;0,1,2=139,3=0.000000
L 5.1995503 3.03937963 5.19741693 3.0402128 2 P 0 ;0,1,2=139,3=0.000000
L 5.19741693 3.0402128 5.19581673 3.04229646 2 P 0 ;0,1,2=139,3=0.000000
L 5.19581673 3.04229646 5.19421663 3.04604636 2 P 0 ;0,1,2=139,3=0.000000
L 5.18008366 3.03354606 5.17821683 3.03146309 2 P 0 ;0,1,2=139,3=0.000000
L 5.17821683 3.03146309 5.17608346 3.03063002 2 P 0 ;0,1,2=139,3=0.000000
L 5.17608346 3.03063002 5.1739501 3.03146309 2 P 0 ;0,1,2=139,3=0.000000
L 5.1739501 3.03146309 5.17208337 3.0339626 2 P 0 ;0,1,2=139,3=0.000000
L 5.17208337 3.0339626 5.1707499 3.03771329 2 P 0 ;0,1,2=139,3=0.000000
L 5.1707499 3.03771329 5.17021663 3.04146329 2 P 0 ;0,1,2=139,3=0.000000
L 5.17021663 3.04146329 5.17021663 3.04604636 2 P 0 ;0,1,2=139,3=0.000000
L 5.17021663 3.04604636 5.1707499 3.04979636 2 P 0 ;0,1,2=139,3=0.000000
L 5.1707499 3.04979636 5.17208337 3.05312972 2 P 0 ;0,1,2=139,3=0.000000
L 5.17208337 3.05312972 5.17368356 3.05479685 2 P 0 ;0,1,2=139,3=0.000000
L 5.17368356 3.05479685 5.1755503 3.05563002 2 P 0 ;0,1,2=139,3=0.000000
L 5.1755503 3.05563002 5.17768366 3.05479685 2 P 0 ;0,1,2=139,3=0.000000
L 5.17768366 3.05479685 5.17928337 3.05312972 2 P 0 ;0,1,2=139,3=0.000000
L 5.17928337 3.05312972 5.1803502 3.05063032 2 P 0 ;0,1,2=139,3=0.000000
L 5.1803502 3.05063032 5.18088346 3.04729616 2 P 0 ;0,1,2=139,3=0.000000
L 5.18088346 3.04729616 5.1803502 3.04438012 2 P 0 ;0,1,2=139,3=0.000000
L 5.1803502 3.04438012 5.17901673 3.04146329 2 P 0 ;0,1,2=139,3=0.000000
L 5.17901673 3.04146329 5.17741654 3.03979616 2 P 0 ;0,1,2=139,3=0.000000
L 5.17741654 3.03979616 5.1755503 3.03937963 2 P 0 ;0,1,2=139,3=0.000000
L 5.1755503 3.03937963 5.17341693 3.0402128 2 P 0 ;0,1,2=139,3=0.000000
L 5.17341693 3.0402128 5.17181673 3.04229646 2 P 0 ;0,1,2=139,3=0.000000
L 5.17181673 3.04229646 5.17021663 3.04604636 2 P 0 ;0,1,2=139,3=0.000000
L 5.15661683 3.05146339 5.15501673 3.05396289 2 P 0 ;0,1,2=139,3=0.000000
L 5.15501673 3.05396289 5.15315 3.05521339 2 P 0 ;0,1,2=139,3=0.000000
L 5.15315 3.05521339 5.15101663 3.05563002 2 P 0 ;0,1,2=139,3=0.000000
L 5.15101663 3.05563002 5.14835 3.05479685 2 P 0 ;0,1,2=139,3=0.000000
L 5.14835 3.05479685 5.14648327 3.05271319 2 P 0 ;0,1,2=139,3=0.000000
L 5.14648327 3.05271319 5.14595 3.05021368 2 P 0 ;0,1,2=139,3=0.000000
L 5.14595 3.05021368 5.14621663 3.0477127 2 P 0 ;0,1,2=139,3=0.000000
L 5.14621663 3.0477127 5.14728356 3.04562982 2 P 0 ;0,1,2=139,3=0.000000
L 5.14728356 3.04562982 5.15261673 3.04146329 2 P 0 ;0,1,2=139,3=0.000000
L 5.15261673 3.04146329 5.15501673 3.03854646 2 P 0 ;0,1,2=139,3=0.000000
L 5.15501673 3.03854646 5.15661683 3.03437913 2 P 0 ;0,1,2=139,3=0.000000
L 5.15661683 3.03437913 5.1571501 3.03063002 2 P 0 ;0,1,2=139,3=0.000000
L 5.1571501 3.03063002 5.14595 3.03063002 2 P 0 ;0,1,2=139,3=0.000000
A 5.36943002 3.28 5.36943002 3.28 5.36386004 3.28 2 P 0 N
L 5.24168337 3.29354636 5.24328356 3.29479685 2 P 0 ;0,1,2=140,3=0.000000
L 5.24328356 3.29479685 5.2451498 3.29563002 2 P 0 ;0,1,2=140,3=0.000000
L 5.2451498 3.29563002 5.24728317 3.29563002 2 P 0 ;0,1,2=140,3=0.000000
L 5.24728317 3.29563002 5.24968366 3.29437943 2 P 0 ;0,1,2=140,3=0.000000
L 5.24968366 3.29437943 5.2515499 3.29229656 2 P 0 ;0,1,2=140,3=0.000000
L 5.2515499 3.29229656 5.25288346 3.28979636 2 P 0 ;0,1,2=140,3=0.000000
L 5.25288346 3.28979636 5.25395039 3.28562982 2 P 0 ;0,1,2=140,3=0.000000
L 5.25395039 3.28562982 5.25421703 3.28187982 2 P 0 ;0,1,2=140,3=0.000000
L 5.25421703 3.28187982 5.25368327 3.27812992 2 P 0 ;0,1,2=140,3=0.000000
L 5.25368327 3.27812992 5.25288346 3.27562963 2 P 0 ;0,1,2=140,3=0.000000
L 5.25288346 3.27562963 5.25128337 3.27312943 2 P 0 ;0,1,2=140,3=0.000000
L 5.25128337 3.27312943 5.24941654 3.27146309 2 P 0 ;0,1,2=140,3=0.000000
L 5.24941654 3.27146309 5.2475503 3.27063002 2 P 0 ;0,1,2=140,3=0.000000
L 5.2475503 3.27063002 5.24568356 3.27063002 2 P 0 ;0,1,2=140,3=0.000000
L 5.24568356 3.27063002 5.24381673 3.27146309 2 P 0 ;0,1,2=140,3=0.000000
L 5.24381673 3.27146309 5.24221663 3.27271289 2 P 0 ;0,1,2=140,3=0.000000
L 5.24221663 3.27271289 5.24088307 3.27437913 2 P 0 ;0,1,2=140,3=0.000000
L 5.2235503 3.27063002 5.2235503 3.29563002 2 P 0 ;0,1,2=140,3=0.000000
L 5.2235503 3.29563002 5.2267501 3.29063032 2 P 0 ;0,1,2=140,3=0.000000
L 5.2267501 3.27063002 5.22035049 3.27063002 2 P 0 ;0,1,2=140,3=0.000000
L 5.20408366 3.27354606 5.20221683 3.27146309 2 P 0 ;0,1,2=140,3=0.000000
L 5.20221683 3.27146309 5.20008346 3.27063002 2 P 0 ;0,1,2=140,3=0.000000
L 5.20008346 3.27063002 5.1979501 3.27146309 2 P 0 ;0,1,2=140,3=0.000000
L 5.1979501 3.27146309 5.19608337 3.2739626 2 P 0 ;0,1,2=140,3=0.000000
L 5.19608337 3.2739626 5.1947499 3.27771329 2 P 0 ;0,1,2=140,3=0.000000
L 5.1947499 3.27771329 5.19421663 3.28146329 2 P 0 ;0,1,2=140,3=0.000000
L 5.19421663 3.28146329 5.19421663 3.28604636 2 P 0 ;0,1,2=140,3=0.000000
L 5.19421663 3.28604636 5.1947499 3.28979636 2 P 0 ;0,1,2=140,3=0.000000
L 5.1947499 3.28979636 5.19608337 3.29312972 2 P 0 ;0,1,2=140,3=0.000000
L 5.19608337 3.29312972 5.19768356 3.29479685 2 P 0 ;0,1,2=140,3=0.000000
L 5.19768356 3.29479685 5.1995503 3.29563002 2 P 0 ;0,1,2=140,3=0.000000
L 5.1995503 3.29563002 5.20168366 3.29479685 2 P 0 ;0,1,2=140,3=0.000000
L 5.20168366 3.29479685 5.20328337 3.29312972 2 P 0 ;0,1,2=140,3=0.000000
L 5.20328337 3.29312972 5.2043502 3.29063032 2 P 0 ;0,1,2=140,3=0.000000
L 5.2043502 3.29063032 5.20488346 3.28729616 2 P 0 ;0,1,2=140,3=0.000000
L 5.20488346 3.28729616 5.2043502 3.28438012 2 P 0 ;0,1,2=140,3=0.000000
L 5.2043502 3.28438012 5.20301673 3.28146329 2 P 0 ;0,1,2=140,3=0.000000
L 5.20301673 3.28146329 5.20141654 3.27979616 2 P 0 ;0,1,2=140,3=0.000000
L 5.20141654 3.27979616 5.1995503 3.27937963 2 P 0 ;0,1,2=140,3=0.000000
L 5.1995503 3.27937963 5.19741693 3.2802128 2 P 0 ;0,1,2=140,3=0.000000
L 5.19741693 3.2802128 5.19581673 3.28229646 2 P 0 ;0,1,2=140,3=0.000000
L 5.19581673 3.28229646 5.19421663 3.28604636 2 P 0 ;0,1,2=140,3=0.000000
L 5.18008366 3.27354606 5.17821683 3.27146309 2 P 0 ;0,1,2=140,3=0.000000
L 5.17821683 3.27146309 5.17608346 3.27063002 2 P 0 ;0,1,2=140,3=0.000000
L 5.17608346 3.27063002 5.1739501 3.27146309 2 P 0 ;0,1,2=140,3=0.000000
L 5.1739501 3.27146309 5.17208337 3.2739626 2 P 0 ;0,1,2=140,3=0.000000
L 5.17208337 3.2739626 5.1707499 3.27771329 2 P 0 ;0,1,2=140,3=0.000000
L 5.1707499 3.27771329 5.17021663 3.28146329 2 P 0 ;0,1,2=140,3=0.000000
L 5.17021663 3.28146329 5.17021663 3.28604636 2 P 0 ;0,1,2=140,3=0.000000
L 5.17021663 3.28604636 5.1707499 3.28979636 2 P 0 ;0,1,2=140,3=0.000000
L 5.1707499 3.28979636 5.17208337 3.29312972 2 P 0 ;0,1,2=140,3=0.000000
L 5.17208337 3.29312972 5.17368356 3.29479685 2 P 0 ;0,1,2=140,3=0.000000
L 5.17368356 3.29479685 5.1755503 3.29563002 2 P 0 ;0,1,2=140,3=0.000000
L 5.1755503 3.29563002 5.17768366 3.29479685 2 P 0 ;0,1,2=140,3=0.000000
L 5.17768366 3.29479685 5.17928337 3.29312972 2 P 0 ;0,1,2=140,3=0.000000
L 5.17928337 3.29312972 5.1803502 3.29063032 2 P 0 ;0,1,2=140,3=0.000000
L 5.1803502 3.29063032 5.18088346 3.28729616 2 P 0 ;0,1,2=140,3=0.000000
L 5.18088346 3.28729616 5.1803502 3.28438012 2 P 0 ;0,1,2=140,3=0.000000
L 5.1803502 3.28438012 5.17901673 3.28146329 2 P 0 ;0,1,2=140,3=0.000000
L 5.17901673 3.28146329 5.17741654 3.27979616 2 P 0 ;0,1,2=140,3=0.000000
L 5.17741654 3.27979616 5.1755503 3.27937963 2 P 0 ;0,1,2=140,3=0.000000
L 5.1755503 3.27937963 5.17341693 3.2802128 2 P 0 ;0,1,2=140,3=0.000000
L 5.17341693 3.2802128 5.17181673 3.28229646 2 P 0 ;0,1,2=140,3=0.000000
L 5.17181673 3.28229646 5.17021663 3.28604636 2 P 0 ;0,1,2=140,3=0.000000
L 5.1515503 3.27063002 5.1515503 3.29563002 2 P 0 ;0,1,2=140,3=0.000000
L 5.1515503 3.29563002 5.1547501 3.29063032 2 P 0 ;0,1,2=140,3=0.000000
L 5.1547501 3.27063002 5.14835049 3.27063002 2 P 0 ;0,1,2=140,3=0.000000
A 5.36943002 3.2 5.36943002 3.2 5.36386004 3.2 2 P 0 N
L 5.24168337 3.21354636 5.24328356 3.21479685 2 P 0 ;0,1,2=141,3=0.000000
L 5.24328356 3.21479685 5.2451498 3.21563002 2 P 0 ;0,1,2=141,3=0.000000
L 5.2451498 3.21563002 5.24728317 3.21563002 2 P 0 ;0,1,2=141,3=0.000000
L 5.24728317 3.21563002 5.24968366 3.21437943 2 P 0 ;0,1,2=141,3=0.000000
L 5.24968366 3.21437943 5.2515499 3.21229656 2 P 0 ;0,1,2=141,3=0.000000
L 5.2515499 3.21229656 5.25288346 3.20979636 2 P 0 ;0,1,2=141,3=0.000000
L 5.25288346 3.20979636 5.25395039 3.20562982 2 P 0 ;0,1,2=141,3=0.000000
L 5.25395039 3.20562982 5.25421703 3.20187982 2 P 0 ;0,1,2=141,3=0.000000
L 5.25421703 3.20187982 5.25368327 3.19812992 2 P 0 ;0,1,2=141,3=0.000000
L 5.25368327 3.19812992 5.25288346 3.19562963 2 P 0 ;0,1,2=141,3=0.000000
L 5.25288346 3.19562963 5.25128337 3.19312943 2 P 0 ;0,1,2=141,3=0.000000
L 5.25128337 3.19312943 5.24941654 3.19146309 2 P 0 ;0,1,2=141,3=0.000000
L 5.24941654 3.19146309 5.2475503 3.19063002 2 P 0 ;0,1,2=141,3=0.000000
L 5.2475503 3.19063002 5.24568356 3.19063002 2 P 0 ;0,1,2=141,3=0.000000
L 5.24568356 3.19063002 5.24381673 3.19146309 2 P 0 ;0,1,2=141,3=0.000000
L 5.24381673 3.19146309 5.24221663 3.19271289 2 P 0 ;0,1,2=141,3=0.000000
L 5.24221663 3.19271289 5.24088307 3.19437913 2 P 0 ;0,1,2=141,3=0.000000
L 5.2235503 3.19063002 5.2235503 3.21563002 2 P 0 ;0,1,2=141,3=0.000000
L 5.2235503 3.21563002 5.2267501 3.21063032 2 P 0 ;0,1,2=141,3=0.000000
L 5.2267501 3.19063002 5.22035049 3.19063002 2 P 0 ;0,1,2=141,3=0.000000
L 5.20408366 3.19354606 5.20221683 3.19146309 2 P 0 ;0,1,2=141,3=0.000000
L 5.20221683 3.19146309 5.20008346 3.19063002 2 P 0 ;0,1,2=141,3=0.000000
L 5.20008346 3.19063002 5.1979501 3.19146309 2 P 0 ;0,1,2=141,3=0.000000
L 5.1979501 3.19146309 5.19608337 3.1939626 2 P 0 ;0,1,2=141,3=0.000000
L 5.19608337 3.1939626 5.1947499 3.19771329 2 P 0 ;0,1,2=141,3=0.000000
L 5.1947499 3.19771329 5.19421663 3.20146329 2 P 0 ;0,1,2=141,3=0.000000
L 5.19421663 3.20146329 5.19421663 3.20604636 2 P 0 ;0,1,2=141,3=0.000000
L 5.19421663 3.20604636 5.1947499 3.20979636 2 P 0 ;0,1,2=141,3=0.000000
L 5.1947499 3.20979636 5.19608337 3.21312972 2 P 0 ;0,1,2=141,3=0.000000
L 5.19608337 3.21312972 5.19768356 3.21479685 2 P 0 ;0,1,2=141,3=0.000000
L 5.19768356 3.21479685 5.1995503 3.21563002 2 P 0 ;0,1,2=141,3=0.000000
L 5.1995503 3.21563002 5.20168366 3.21479685 2 P 0 ;0,1,2=141,3=0.000000
L 5.20168366 3.21479685 5.20328337 3.21312972 2 P 0 ;0,1,2=141,3=0.000000
L 5.20328337 3.21312972 5.2043502 3.21063032 2 P 0 ;0,1,2=141,3=0.000000
L 5.2043502 3.21063032 5.20488346 3.20729616 2 P 0 ;0,1,2=141,3=0.000000
L 5.20488346 3.20729616 5.2043502 3.20438012 2 P 0 ;0,1,2=141,3=0.000000
L 5.2043502 3.20438012 5.20301673 3.20146329 2 P 0 ;0,1,2=141,3=0.000000
L 5.20301673 3.20146329 5.20141654 3.19979616 2 P 0 ;0,1,2=141,3=0.000000
L 5.20141654 3.19979616 5.1995503 3.19937963 2 P 0 ;0,1,2=141,3=0.000000
L 5.1995503 3.19937963 5.19741693 3.2002128 2 P 0 ;0,1,2=141,3=0.000000
L 5.19741693 3.2002128 5.19581673 3.20229646 2 P 0 ;0,1,2=141,3=0.000000
L 5.19581673 3.20229646 5.19421663 3.20604636 2 P 0 ;0,1,2=141,3=0.000000
L 5.18141673 3.19562963 5.17981703 3.19271289 2 P 0 ;0,1,2=141,3=0.000000
L 5.17981703 3.19271289 5.17768366 3.19104656 2 P 0 ;0,1,2=141,3=0.000000
L 5.17768366 3.19104656 5.17528317 3.19063002 2 P 0 ;0,1,2=141,3=0.000000
L 5.17528317 3.19063002 5.1731498 3.19104656 2 P 0 ;0,1,2=141,3=0.000000
L 5.1731498 3.19104656 5.17101644 3.19312943 2 P 0 ;0,1,2=141,3=0.000000
L 5.17101644 3.19312943 5.16968337 3.19562963 2 P 0 ;0,1,2=141,3=0.000000
L 5.16968337 3.19562963 5.16941683 3.19812992 2 P 0 ;0,1,2=141,3=0.000000
L 5.16941683 3.19812992 5.16995 3.20104596 2 P 0 ;0,1,2=141,3=0.000000
L 5.16995 3.20104596 5.17181673 3.20312963 2 P 0 ;0,1,2=141,3=0.000000
L 5.17181673 3.20312963 5.17368356 3.20396348 2 P 0 ;0,1,2=141,3=0.000000
L 5.17368356 3.20396348 5.17608346 3.20396348 2 P 0 ;0,1,2=141,3=0.000000
L 5.17368356 3.20396348 5.17208337 3.20521329 2 P 0 ;0,1,2=141,3=0.000000
L 5.17208337 3.20521329 5.1707499 3.20729616 2 P 0 ;0,1,2=141,3=0.000000
L 5.1707499 3.20729616 5.17021663 3.20979636 2 P 0 ;0,1,2=141,3=0.000000
L 5.17021663 3.20979636 5.1707499 3.21229656 2 P 0 ;0,1,2=141,3=0.000000
L 5.1707499 3.21229656 5.17208337 3.21437943 2 P 0 ;0,1,2=141,3=0.000000
L 5.17208337 3.21437943 5.17448337 3.21563002 2 P 0 ;0,1,2=141,3=0.000000
L 5.17448337 3.21563002 5.17688337 3.21521339 2 P 0 ;0,1,2=141,3=0.000000
L 5.17688337 3.21521339 5.17928337 3.21354636 2 P 0 ;0,1,2=141,3=0.000000
L 5.1515503 3.21563002 5.15368366 3.21479685 2 P 0 ;0,1,2=141,3=0.000000
L 5.15368366 3.21479685 5.15528337 3.21271319 2 P 0 ;0,1,2=141,3=0.000000
L 5.15528337 3.21271319 5.1563502 3.21021368 2 P 0 ;0,1,2=141,3=0.000000
L 5.1563502 3.21021368 5.1571501 3.20687953 2 P 0 ;0,1,2=141,3=0.000000
L 5.1571501 3.20687953 5.15741673 3.20312963 2 P 0 ;0,1,2=141,3=0.000000
L 5.15741673 3.20312963 5.1571501 3.19937963 2 P 0 ;0,1,2=141,3=0.000000
L 5.1571501 3.19937963 5.1563502 3.19604626 2 P 0 ;0,1,2=141,3=0.000000
L 5.1563502 3.19604626 5.15528337 3.19354606 2 P 0 ;0,1,2=141,3=0.000000
L 5.15528337 3.19354606 5.15368366 3.19146309 2 P 0 ;0,1,2=141,3=0.000000
L 5.15368366 3.19146309 5.1515503 3.19063002 2 P 0 ;0,1,2=141,3=0.000000
L 5.1515503 3.19063002 5.14941693 3.19146309 2 P 0 ;0,1,2=141,3=0.000000
L 5.14941693 3.19146309 5.14781673 3.19354606 2 P 0 ;0,1,2=141,3=0.000000
L 5.14781673 3.19354606 5.1467499 3.19604626 2 P 0 ;0,1,2=141,3=0.000000
L 5.1467499 3.19604626 5.14595 3.19937963 2 P 0 ;0,1,2=141,3=0.000000
L 5.14595 3.19937963 5.14568337 3.20312963 2 P 0 ;0,1,2=141,3=0.000000
L 5.14568337 3.20312963 5.14595 3.20687953 2 P 0 ;0,1,2=141,3=0.000000
L 5.14595 3.20687953 5.1467499 3.21021368 2 P 0 ;0,1,2=141,3=0.000000
L 5.1467499 3.21021368 5.14781673 3.21271319 2 P 0 ;0,1,2=141,3=0.000000
L 5.14781673 3.21271319 5.14941693 3.21479685 2 P 0 ;0,1,2=141,3=0.000000
L 5.14941693 3.21479685 5.1515503 3.21563002 2 P 0 ;0,1,2=141,3=0.000000
A 5.36943002 2.96 5.36943002 2.96 5.36386004 2.96 2 P 0 N
L 5.24168337 2.97354636 5.24328356 2.97479685 2 P 0 ;0,1,2=142,3=0.000000
L 5.24328356 2.97479685 5.2451498 2.97563002 2 P 0 ;0,1,2=142,3=0.000000
L 5.2451498 2.97563002 5.24728317 2.97563002 2 P 0 ;0,1,2=142,3=0.000000
L 5.24728317 2.97563002 5.24968366 2.97437943 2 P 0 ;0,1,2=142,3=0.000000
L 5.24968366 2.97437943 5.2515499 2.97229656 2 P 0 ;0,1,2=142,3=0.000000
L 5.2515499 2.97229656 5.25288346 2.96979636 2 P 0 ;0,1,2=142,3=0.000000
L 5.25288346 2.96979636 5.25395039 2.96562982 2 P 0 ;0,1,2=142,3=0.000000
L 5.25395039 2.96562982 5.25421703 2.96187982 2 P 0 ;0,1,2=142,3=0.000000
L 5.25421703 2.96187982 5.25368327 2.95812992 2 P 0 ;0,1,2=142,3=0.000000
L 5.25368327 2.95812992 5.25288346 2.95562963 2 P 0 ;0,1,2=142,3=0.000000
L 5.25288346 2.95562963 5.25128337 2.95312943 2 P 0 ;0,1,2=142,3=0.000000
L 5.25128337 2.95312943 5.24941654 2.95146309 2 P 0 ;0,1,2=142,3=0.000000
L 5.24941654 2.95146309 5.2475503 2.95063002 2 P 0 ;0,1,2=142,3=0.000000
L 5.2475503 2.95063002 5.24568356 2.95063002 2 P 0 ;0,1,2=142,3=0.000000
L 5.24568356 2.95063002 5.24381673 2.95146309 2 P 0 ;0,1,2=142,3=0.000000
L 5.24381673 2.95146309 5.24221663 2.95271289 2 P 0 ;0,1,2=142,3=0.000000
L 5.24221663 2.95271289 5.24088307 2.95437913 2 P 0 ;0,1,2=142,3=0.000000
L 5.2235503 2.95063002 5.2235503 2.97563002 2 P 0 ;0,1,2=142,3=0.000000
L 5.2235503 2.97563002 5.2267501 2.97063032 2 P 0 ;0,1,2=142,3=0.000000
L 5.2267501 2.95063002 5.22035049 2.95063002 2 P 0 ;0,1,2=142,3=0.000000
L 5.20408366 2.95354606 5.20221683 2.95146309 2 P 0 ;0,1,2=142,3=0.000000
L 5.20221683 2.95146309 5.20008346 2.95063002 2 P 0 ;0,1,2=142,3=0.000000
L 5.20008346 2.95063002 5.1979501 2.95146309 2 P 0 ;0,1,2=142,3=0.000000
L 5.1979501 2.95146309 5.19608337 2.9539626 2 P 0 ;0,1,2=142,3=0.000000
L 5.19608337 2.9539626 5.1947499 2.95771329 2 P 0 ;0,1,2=142,3=0.000000
L 5.1947499 2.95771329 5.19421663 2.96146329 2 P 0 ;0,1,2=142,3=0.000000
L 5.19421663 2.96146329 5.19421663 2.96604636 2 P 0 ;0,1,2=142,3=0.000000
L 5.19421663 2.96604636 5.1947499 2.96979636 2 P 0 ;0,1,2=142,3=0.000000
L 5.1947499 2.96979636 5.19608337 2.97312972 2 P 0 ;0,1,2=142,3=0.000000
L 5.19608337 2.97312972 5.19768356 2.97479685 2 P 0 ;0,1,2=142,3=0.000000
L 5.19768356 2.97479685 5.1995503 2.97563002 2 P 0 ;0,1,2=142,3=0.000000
L 5.1995503 2.97563002 5.20168366 2.97479685 2 P 0 ;0,1,2=142,3=0.000000
L 5.20168366 2.97479685 5.20328337 2.97312972 2 P 0 ;0,1,2=142,3=0.000000
L 5.20328337 2.97312972 5.2043502 2.97063032 2 P 0 ;0,1,2=142,3=0.000000
L 5.2043502 2.97063032 5.20488346 2.96729616 2 P 0 ;0,1,2=142,3=0.000000
L 5.20488346 2.96729616 5.2043502 2.96438012 2 P 0 ;0,1,2=142,3=0.000000
L 5.2043502 2.96438012 5.20301673 2.96146329 2 P 0 ;0,1,2=142,3=0.000000
L 5.20301673 2.96146329 5.20141654 2.95979616 2 P 0 ;0,1,2=142,3=0.000000
L 5.20141654 2.95979616 5.1995503 2.95937963 2 P 0 ;0,1,2=142,3=0.000000
L 5.1995503 2.95937963 5.19741693 2.9602128 2 P 0 ;0,1,2=142,3=0.000000
L 5.19741693 2.9602128 5.19581673 2.96229646 2 P 0 ;0,1,2=142,3=0.000000
L 5.19581673 2.96229646 5.19421663 2.96604636 2 P 0 ;0,1,2=142,3=0.000000
L 5.18061683 2.97146339 5.17901673 2.97396289 2 P 0 ;0,1,2=142,3=0.000000
L 5.17901673 2.97396289 5.17715 2.97521339 2 P 0 ;0,1,2=142,3=0.000000
L 5.17715 2.97521339 5.17501663 2.97563002 2 P 0 ;0,1,2=142,3=0.000000
L 5.17501663 2.97563002 5.17235 2.97479685 2 P 0 ;0,1,2=142,3=0.000000
L 5.17235 2.97479685 5.17048327 2.97271319 2 P 0 ;0,1,2=142,3=0.000000
L 5.17048327 2.97271319 5.16995 2.97021368 2 P 0 ;0,1,2=142,3=0.000000
L 5.16995 2.97021368 5.17021663 2.9677127 2 P 0 ;0,1,2=142,3=0.000000
L 5.17021663 2.9677127 5.17128356 2.96562982 2 P 0 ;0,1,2=142,3=0.000000
L 5.17128356 2.96562982 5.17661673 2.96146329 2 P 0 ;0,1,2=142,3=0.000000
L 5.17661673 2.96146329 5.17901673 2.95854646 2 P 0 ;0,1,2=142,3=0.000000
L 5.17901673 2.95854646 5.18061683 2.95437913 2 P 0 ;0,1,2=142,3=0.000000
L 5.18061683 2.95437913 5.1811501 2.95063002 2 P 0 ;0,1,2=142,3=0.000000
L 5.1811501 2.95063002 5.16995 2.95063002 2 P 0 ;0,1,2=142,3=0.000000
L 5.15608366 2.95354606 5.15421683 2.95146309 2 P 0 ;0,1,2=142,3=0.000000
L 5.15421683 2.95146309 5.15208346 2.95063002 2 P 0 ;0,1,2=142,3=0.000000
L 5.15208346 2.95063002 5.1499501 2.95146309 2 P 0 ;0,1,2=142,3=0.000000
L 5.1499501 2.95146309 5.14808337 2.9539626 2 P 0 ;0,1,2=142,3=0.000000
L 5.14808337 2.9539626 5.1467499 2.95771329 2 P 0 ;0,1,2=142,3=0.000000
L 5.1467499 2.95771329 5.14621663 2.96146329 2 P 0 ;0,1,2=142,3=0.000000
L 5.14621663 2.96146329 5.14621663 2.96604636 2 P 0 ;0,1,2=142,3=0.000000
L 5.14621663 2.96604636 5.1467499 2.96979636 2 P 0 ;0,1,2=142,3=0.000000
L 5.1467499 2.96979636 5.14808337 2.97312972 2 P 0 ;0,1,2=142,3=0.000000
L 5.14808337 2.97312972 5.14968356 2.97479685 2 P 0 ;0,1,2=142,3=0.000000
L 5.14968356 2.97479685 5.1515503 2.97563002 2 P 0 ;0,1,2=142,3=0.000000
L 5.1515503 2.97563002 5.15368366 2.97479685 2 P 0 ;0,1,2=142,3=0.000000
L 5.15368366 2.97479685 5.15528337 2.97312972 2 P 0 ;0,1,2=142,3=0.000000
L 5.15528337 2.97312972 5.1563502 2.97063032 2 P 0 ;0,1,2=142,3=0.000000
L 5.1563502 2.97063032 5.15688346 2.96729616 2 P 0 ;0,1,2=142,3=0.000000
L 5.15688346 2.96729616 5.1563502 2.96438012 2 P 0 ;0,1,2=142,3=0.000000
L 5.1563502 2.96438012 5.15501673 2.96146329 2 P 0 ;0,1,2=142,3=0.000000
L 5.15501673 2.96146329 5.15341654 2.95979616 2 P 0 ;0,1,2=142,3=0.000000
L 5.15341654 2.95979616 5.1515503 2.95937963 2 P 0 ;0,1,2=142,3=0.000000
L 5.1515503 2.95937963 5.14941693 2.9602128 2 P 0 ;0,1,2=142,3=0.000000
L 5.14941693 2.9602128 5.14781673 2.96229646 2 P 0 ;0,1,2=142,3=0.000000
L 5.14781673 2.96229646 5.14621663 2.96604636 2 P 0 ;0,1,2=142,3=0.000000
A 5.32826004 1.8768 5.32826004 1.8768 5.32575 1.8768 1 P 0 N
L 5.61613337 1.89291634 5.61773356 1.89416683 2 P 0 ;0,1,2=143,3=0.000000
L 5.61773356 1.89416683 5.6195998 1.895 2 P 0 ;0,1,2=143,3=0.000000
L 5.6195998 1.895 5.62173317 1.895 2 P 0 ;0,1,2=143,3=0.000000
L 5.62173317 1.895 5.62413366 1.89374941 2 P 0 ;0,1,2=143,3=0.000000
L 5.62413366 1.89374941 5.6259999 1.89166654 2 P 0 ;0,1,2=143,3=0.000000
L 5.6259999 1.89166654 5.62733346 1.88916634 2 P 0 ;0,1,2=143,3=0.000000
L 5.62733346 1.88916634 5.62840039 1.8849998 2 P 0 ;0,1,2=143,3=0.000000
L 5.62840039 1.8849998 5.62866703 1.8812498 2 P 0 ;0,1,2=143,3=0.000000
L 5.62866703 1.8812498 5.62813327 1.8774999 2 P 0 ;0,1,2=143,3=0.000000
L 5.62813327 1.8774999 5.62733346 1.87499961 2 P 0 ;0,1,2=143,3=0.000000
L 5.62733346 1.87499961 5.62573337 1.87249941 2 P 0 ;0,1,2=143,3=0.000000
L 5.62573337 1.87249941 5.62386654 1.87083307 2 P 0 ;0,1,2=143,3=0.000000
L 5.62386654 1.87083307 5.6220003 1.87 2 P 0 ;0,1,2=143,3=0.000000
L 5.6220003 1.87 5.62013356 1.87 2 P 0 ;0,1,2=143,3=0.000000
L 5.62013356 1.87 5.61826673 1.87083307 2 P 0 ;0,1,2=143,3=0.000000
L 5.61826673 1.87083307 5.61666663 1.87208287 2 P 0 ;0,1,2=143,3=0.000000
L 5.61666663 1.87208287 5.61533307 1.87374911 2 P 0 ;0,1,2=143,3=0.000000
L 5.5948 1.87 5.5948 1.895 2 P 0 ;0,1,2=143,3=0.000000
L 5.5948 1.895 5.60466703 1.87708327 2 P 0 ;0,1,2=143,3=0.000000
L 5.60466703 1.87708327 5.59133307 1.87708327 2 P 0 ;0,1,2=143,3=0.000000
L 5.57906683 1.89083337 5.57746673 1.89333287 2 P 0 ;0,1,2=143,3=0.000000
L 5.57746673 1.89333287 5.5756 1.89458337 2 P 0 ;0,1,2=143,3=0.000000
L 5.5756 1.89458337 5.57346663 1.895 2 P 0 ;0,1,2=143,3=0.000000
L 5.57346663 1.895 5.5708 1.89416683 2 P 0 ;0,1,2=143,3=0.000000
L 5.5708 1.89416683 5.56893327 1.89208317 2 P 0 ;0,1,2=143,3=0.000000
L 5.56893327 1.89208317 5.5684 1.88958366 2 P 0 ;0,1,2=143,3=0.000000
L 5.5684 1.88958366 5.56866663 1.88708268 2 P 0 ;0,1,2=143,3=0.000000
L 5.56866663 1.88708268 5.56973356 1.8849998 2 P 0 ;0,1,2=143,3=0.000000
L 5.56973356 1.8849998 5.57506673 1.88083327 2 P 0 ;0,1,2=143,3=0.000000
L 5.57506673 1.88083327 5.57746673 1.87791644 2 P 0 ;0,1,2=143,3=0.000000
L 5.57746673 1.87791644 5.57906683 1.87374911 2 P 0 ;0,1,2=143,3=0.000000
L 5.57906683 1.87374911 5.5796001 1.87 2 P 0 ;0,1,2=143,3=0.000000
L 5.5796001 1.87 5.5684 1.87 2 P 0 ;0,1,2=143,3=0.000000
L 5.55586673 1.87499961 5.55426703 1.87208287 2 P 0 ;0,1,2=143,3=0.000000
L 5.55426703 1.87208287 5.55213366 1.87041654 2 P 0 ;0,1,2=143,3=0.000000
L 5.55213366 1.87041654 5.54973317 1.87 2 P 0 ;0,1,2=143,3=0.000000
L 5.54973317 1.87 5.5475998 1.87041654 2 P 0 ;0,1,2=143,3=0.000000
L 5.5475998 1.87041654 5.54546644 1.87249941 2 P 0 ;0,1,2=143,3=0.000000
L 5.54546644 1.87249941 5.54413337 1.87499961 2 P 0 ;0,1,2=143,3=0.000000
L 5.54413337 1.87499961 5.54386683 1.8774999 2 P 0 ;0,1,2=143,3=0.000000
L 5.54386683 1.8774999 5.5444 1.88041594 2 P 0 ;0,1,2=143,3=0.000000
L 5.5444 1.88041594 5.54626673 1.88249961 2 P 0 ;0,1,2=143,3=0.000000
L 5.54626673 1.88249961 5.54813356 1.88333346 2 P 0 ;0,1,2=143,3=0.000000
L 5.54813356 1.88333346 5.55053346 1.88333346 2 P 0 ;0,1,2=143,3=0.000000
L 5.54813356 1.88333346 5.54653337 1.88458327 2 P 0 ;0,1,2=143,3=0.000000
L 5.54653337 1.88458327 5.5451999 1.88666614 2 P 0 ;0,1,2=143,3=0.000000
L 5.5451999 1.88666614 5.54466663 1.88916634 2 P 0 ;0,1,2=143,3=0.000000
L 5.54466663 1.88916634 5.5451999 1.89166654 2 P 0 ;0,1,2=143,3=0.000000
L 5.5451999 1.89166654 5.54653337 1.89374941 2 P 0 ;0,1,2=143,3=0.000000
L 5.54653337 1.89374941 5.54893337 1.895 2 P 0 ;0,1,2=143,3=0.000000
L 5.54893337 1.895 5.55133337 1.89458337 2 P 0 ;0,1,2=143,3=0.000000
L 5.55133337 1.89458337 5.55373337 1.89291634 2 P 0 ;0,1,2=143,3=0.000000
A 5.32826004 1.9218 5.32826004 1.9218 5.32575 1.9218 1 P 0 N
L 5.61613337 1.92791634 5.61773356 1.92916683 2 P 0 ;0,1,2=144,3=0.000000
L 5.61773356 1.92916683 5.6195998 1.93 2 P 0 ;0,1,2=144,3=0.000000
L 5.6195998 1.93 5.62173317 1.93 2 P 0 ;0,1,2=144,3=0.000000
L 5.62173317 1.93 5.62413366 1.92874941 2 P 0 ;0,1,2=144,3=0.000000
L 5.62413366 1.92874941 5.6259999 1.92666654 2 P 0 ;0,1,2=144,3=0.000000
L 5.6259999 1.92666654 5.62733346 1.92416634 2 P 0 ;0,1,2=144,3=0.000000
L 5.62733346 1.92416634 5.62840039 1.9199998 2 P 0 ;0,1,2=144,3=0.000000
L 5.62840039 1.9199998 5.62866703 1.9162498 2 P 0 ;0,1,2=144,3=0.000000
L 5.62866703 1.9162498 5.62813327 1.9124999 2 P 0 ;0,1,2=144,3=0.000000
L 5.62813327 1.9124999 5.62733346 1.90999961 2 P 0 ;0,1,2=144,3=0.000000
L 5.62733346 1.90999961 5.62573337 1.90749941 2 P 0 ;0,1,2=144,3=0.000000
L 5.62573337 1.90749941 5.62386654 1.90583307 2 P 0 ;0,1,2=144,3=0.000000
L 5.62386654 1.90583307 5.6220003 1.905 2 P 0 ;0,1,2=144,3=0.000000
L 5.6220003 1.905 5.62013356 1.905 2 P 0 ;0,1,2=144,3=0.000000
L 5.62013356 1.905 5.61826673 1.90583307 2 P 0 ;0,1,2=144,3=0.000000
L 5.61826673 1.90583307 5.61666663 1.90708287 2 P 0 ;0,1,2=144,3=0.000000
L 5.61666663 1.90708287 5.61533307 1.90874911 2 P 0 ;0,1,2=144,3=0.000000
L 5.5948 1.905 5.5948 1.93 2 P 0 ;0,1,2=144,3=0.000000
L 5.5948 1.93 5.60466703 1.91208327 2 P 0 ;0,1,2=144,3=0.000000
L 5.60466703 1.91208327 5.59133307 1.91208327 2 P 0 ;0,1,2=144,3=0.000000
L 5.57906683 1.92583337 5.57746673 1.92833287 2 P 0 ;0,1,2=144,3=0.000000
L 5.57746673 1.92833287 5.5756 1.92958337 2 P 0 ;0,1,2=144,3=0.000000
L 5.5756 1.92958337 5.57346663 1.93 2 P 0 ;0,1,2=144,3=0.000000
L 5.57346663 1.93 5.5708 1.92916683 2 P 0 ;0,1,2=144,3=0.000000
L 5.5708 1.92916683 5.56893327 1.92708317 2 P 0 ;0,1,2=144,3=0.000000
L 5.56893327 1.92708317 5.5684 1.92458366 2 P 0 ;0,1,2=144,3=0.000000
L 5.5684 1.92458366 5.56866663 1.92208268 2 P 0 ;0,1,2=144,3=0.000000
L 5.56866663 1.92208268 5.56973356 1.9199998 2 P 0 ;0,1,2=144,3=0.000000
L 5.56973356 1.9199998 5.57506673 1.91583327 2 P 0 ;0,1,2=144,3=0.000000
L 5.57506673 1.91583327 5.57746673 1.91291644 2 P 0 ;0,1,2=144,3=0.000000
L 5.57746673 1.91291644 5.57906683 1.90874911 2 P 0 ;0,1,2=144,3=0.000000
L 5.57906683 1.90874911 5.5796001 1.905 2 P 0 ;0,1,2=144,3=0.000000
L 5.5796001 1.905 5.5684 1.905 2 P 0 ;0,1,2=144,3=0.000000
L 5.55506683 1.92583337 5.55346673 1.92833287 2 P 0 ;0,1,2=144,3=0.000000
L 5.55346673 1.92833287 5.5516 1.92958337 2 P 0 ;0,1,2=144,3=0.000000
L 5.5516 1.92958337 5.54946663 1.93 2 P 0 ;0,1,2=144,3=0.000000
L 5.54946663 1.93 5.5468 1.92916683 2 P 0 ;0,1,2=144,3=0.000000
L 5.5468 1.92916683 5.54493327 1.92708317 2 P 0 ;0,1,2=144,3=0.000000
L 5.54493327 1.92708317 5.5444 1.92458366 2 P 0 ;0,1,2=144,3=0.000000
L 5.5444 1.92458366 5.54466663 1.92208268 2 P 0 ;0,1,2=144,3=0.000000
L 5.54466663 1.92208268 5.54573356 1.9199998 2 P 0 ;0,1,2=144,3=0.000000
L 5.54573356 1.9199998 5.55106673 1.91583327 2 P 0 ;0,1,2=144,3=0.000000
L 5.55106673 1.91583327 5.55346673 1.91291644 2 P 0 ;0,1,2=144,3=0.000000
L 5.55346673 1.91291644 5.55506683 1.90874911 2 P 0 ;0,1,2=144,3=0.000000
L 5.55506683 1.90874911 5.5556001 1.905 2 P 0 ;0,1,2=144,3=0.000000
L 5.5556001 1.905 5.5444 1.905 2 P 0 ;0,1,2=144,3=0.000000
A 5.32826004 2.1529 5.32826004 2.1529 5.32575 2.1529 1 P 0 N
L 5.62113337 2.16291634 5.62273356 2.16416683 2 P 0 ;0,1,2=145,3=0.000000
L 5.62273356 2.16416683 5.6245998 2.165 2 P 0 ;0,1,2=145,3=0.000000
L 5.6245998 2.165 5.62673317 2.165 2 P 0 ;0,1,2=145,3=0.000000
L 5.62673317 2.165 5.62913366 2.16374941 2 P 0 ;0,1,2=145,3=0.000000
L 5.62913366 2.16374941 5.6309999 2.16166654 2 P 0 ;0,1,2=145,3=0.000000
L 5.6309999 2.16166654 5.63233346 2.15916634 2 P 0 ;0,1,2=145,3=0.000000
L 5.63233346 2.15916634 5.63340039 2.1549998 2 P 0 ;0,1,2=145,3=0.000000
L 5.63340039 2.1549998 5.63366703 2.1512498 2 P 0 ;0,1,2=145,3=0.000000
L 5.63366703 2.1512498 5.63313327 2.1474999 2 P 0 ;0,1,2=145,3=0.000000
L 5.63313327 2.1474999 5.63233346 2.14499961 2 P 0 ;0,1,2=145,3=0.000000
L 5.63233346 2.14499961 5.63073337 2.14249941 2 P 0 ;0,1,2=145,3=0.000000
L 5.63073337 2.14249941 5.62886654 2.14083307 2 P 0 ;0,1,2=145,3=0.000000
L 5.62886654 2.14083307 5.6270003 2.14 2 P 0 ;0,1,2=145,3=0.000000
L 5.6270003 2.14 5.62513356 2.14 2 P 0 ;0,1,2=145,3=0.000000
L 5.62513356 2.14 5.62326673 2.14083307 2 P 0 ;0,1,2=145,3=0.000000
L 5.62326673 2.14083307 5.62166663 2.14208287 2 P 0 ;0,1,2=145,3=0.000000
L 5.62166663 2.14208287 5.62033307 2.14374911 2 P 0 ;0,1,2=145,3=0.000000
L 5.5998 2.14 5.5998 2.165 2 P 0 ;0,1,2=145,3=0.000000
L 5.5998 2.165 5.60966703 2.14708327 2 P 0 ;0,1,2=145,3=0.000000
L 5.60966703 2.14708327 5.59633307 2.14708327 2 P 0 ;0,1,2=145,3=0.000000
L 5.58486673 2.14499961 5.58326703 2.14208287 2 P 0 ;0,1,2=145,3=0.000000
L 5.58326703 2.14208287 5.58113366 2.14041654 2 P 0 ;0,1,2=145,3=0.000000
L 5.58113366 2.14041654 5.57873317 2.14 2 P 0 ;0,1,2=145,3=0.000000
L 5.57873317 2.14 5.5765998 2.14041654 2 P 0 ;0,1,2=145,3=0.000000
L 5.5765998 2.14041654 5.57446644 2.14249941 2 P 0 ;0,1,2=145,3=0.000000
L 5.57446644 2.14249941 5.57313337 2.14499961 2 P 0 ;0,1,2=145,3=0.000000
L 5.57313337 2.14499961 5.57286683 2.1474999 2 P 0 ;0,1,2=145,3=0.000000
L 5.57286683 2.1474999 5.5734 2.15041594 2 P 0 ;0,1,2=145,3=0.000000
L 5.5734 2.15041594 5.57526673 2.15249961 2 P 0 ;0,1,2=145,3=0.000000
L 5.57526673 2.15249961 5.57713356 2.15333346 2 P 0 ;0,1,2=145,3=0.000000
L 5.57713356 2.15333346 5.57953346 2.15333346 2 P 0 ;0,1,2=145,3=0.000000
L 5.57713356 2.15333346 5.57553337 2.15458327 2 P 0 ;0,1,2=145,3=0.000000
L 5.57553337 2.15458327 5.5741999 2.15666614 2 P 0 ;0,1,2=145,3=0.000000
L 5.5741999 2.15666614 5.57366663 2.15916634 2 P 0 ;0,1,2=145,3=0.000000
L 5.57366663 2.15916634 5.5741999 2.16166654 2 P 0 ;0,1,2=145,3=0.000000
L 5.5741999 2.16166654 5.57553337 2.16374941 2 P 0 ;0,1,2=145,3=0.000000
L 5.57553337 2.16374941 5.57793337 2.165 2 P 0 ;0,1,2=145,3=0.000000
L 5.57793337 2.165 5.58033337 2.16458337 2 P 0 ;0,1,2=145,3=0.000000
L 5.58033337 2.16458337 5.58273337 2.16291634 2 P 0 ;0,1,2=145,3=0.000000
L 5.5550003 2.165 5.55713366 2.16416683 2 P 0 ;0,1,2=145,3=0.000000
L 5.55713366 2.16416683 5.55873337 2.16208317 2 P 0 ;0,1,2=145,3=0.000000
L 5.55873337 2.16208317 5.5598002 2.15958366 2 P 0 ;0,1,2=145,3=0.000000
L 5.5598002 2.15958366 5.5606001 2.15624951 2 P 0 ;0,1,2=145,3=0.000000
L 5.5606001 2.15624951 5.56086673 2.15249961 2 P 0 ;0,1,2=145,3=0.000000
L 5.56086673 2.15249961 5.5606001 2.14874961 2 P 0 ;0,1,2=145,3=0.000000
L 5.5606001 2.14874961 5.5598002 2.14541624 2 P 0 ;0,1,2=145,3=0.000000
L 5.5598002 2.14541624 5.55873337 2.14291604 2 P 0 ;0,1,2=145,3=0.000000
L 5.55873337 2.14291604 5.55713366 2.14083307 2 P 0 ;0,1,2=145,3=0.000000
L 5.55713366 2.14083307 5.5550003 2.14 2 P 0 ;0,1,2=145,3=0.000000
L 5.5550003 2.14 5.55286693 2.14083307 2 P 0 ;0,1,2=145,3=0.000000
L 5.55286693 2.14083307 5.55126673 2.14291604 2 P 0 ;0,1,2=145,3=0.000000
L 5.55126673 2.14291604 5.5501999 2.14541624 2 P 0 ;0,1,2=145,3=0.000000
L 5.5501999 2.14541624 5.5494 2.14874961 2 P 0 ;0,1,2=145,3=0.000000
L 5.5494 2.14874961 5.54913337 2.15249961 2 P 0 ;0,1,2=145,3=0.000000
L 5.54913337 2.15249961 5.5494 2.15624951 2 P 0 ;0,1,2=145,3=0.000000
L 5.5494 2.15624951 5.5501999 2.15958366 2 P 0 ;0,1,2=145,3=0.000000
L 5.5501999 2.15958366 5.55126673 2.16208317 2 P 0 ;0,1,2=145,3=0.000000
L 5.55126673 2.16208317 5.55286693 2.16416683 2 P 0 ;0,1,2=145,3=0.000000
L 5.55286693 2.16416683 5.5550003 2.165 2 P 0 ;0,1,2=145,3=0.000000
A 5.32826004 2.0572 5.32826004 2.0572 5.32575 2.0572 1 P 0 N
L 5.62113337 2.06791634 5.62273356 2.06916683 2 P 0 ;0,1,2=146,3=0.000000
L 5.62273356 2.06916683 5.6245998 2.07 2 P 0 ;0,1,2=146,3=0.000000
L 5.6245998 2.07 5.62673317 2.07 2 P 0 ;0,1,2=146,3=0.000000
L 5.62673317 2.07 5.62913366 2.06874941 2 P 0 ;0,1,2=146,3=0.000000
L 5.62913366 2.06874941 5.6309999 2.06666654 2 P 0 ;0,1,2=146,3=0.000000
L 5.6309999 2.06666654 5.63233346 2.06416634 2 P 0 ;0,1,2=146,3=0.000000
L 5.63233346 2.06416634 5.63340039 2.0599998 2 P 0 ;0,1,2=146,3=0.000000
L 5.63340039 2.0599998 5.63366703 2.0562498 2 P 0 ;0,1,2=146,3=0.000000
L 5.63366703 2.0562498 5.63313327 2.0524999 2 P 0 ;0,1,2=146,3=0.000000
L 5.63313327 2.0524999 5.63233346 2.04999961 2 P 0 ;0,1,2=146,3=0.000000
L 5.63233346 2.04999961 5.63073337 2.04749941 2 P 0 ;0,1,2=146,3=0.000000
L 5.63073337 2.04749941 5.62886654 2.04583307 2 P 0 ;0,1,2=146,3=0.000000
L 5.62886654 2.04583307 5.6270003 2.045 2 P 0 ;0,1,2=146,3=0.000000
L 5.6270003 2.045 5.62513356 2.045 2 P 0 ;0,1,2=146,3=0.000000
L 5.62513356 2.045 5.62326673 2.04583307 2 P 0 ;0,1,2=146,3=0.000000
L 5.62326673 2.04583307 5.62166663 2.04708287 2 P 0 ;0,1,2=146,3=0.000000
L 5.62166663 2.04708287 5.62033307 2.04874911 2 P 0 ;0,1,2=146,3=0.000000
L 5.60886673 2.04874911 5.60726703 2.04666624 2 P 0 ;0,1,2=146,3=0.000000
L 5.60726703 2.04666624 5.6054003 2.04541654 2 P 0 ;0,1,2=146,3=0.000000
L 5.6054003 2.04541654 5.6030003 2.045 2 P 0 ;0,1,2=146,3=0.000000
L 5.6030003 2.045 5.6005998 2.04583307 2 P 0 ;0,1,2=146,3=0.000000
L 5.6005998 2.04583307 5.59873356 2.04749941 2 P 0 ;0,1,2=146,3=0.000000
L 5.59873356 2.04749941 5.5974 2.05041624 2 P 0 ;0,1,2=146,3=0.000000
L 5.5974 2.05041624 5.59713337 2.05374961 2 P 0 ;0,1,2=146,3=0.000000
L 5.59713337 2.05374961 5.59766663 2.05708297 2 P 0 ;0,1,2=146,3=0.000000
L 5.59766663 2.05708297 5.5990002 2.05916663 2 P 0 ;0,1,2=146,3=0.000000
L 5.5990002 2.05916663 5.60086693 2.06083297 2 P 0 ;0,1,2=146,3=0.000000
L 5.60086693 2.06083297 5.60273317 2.06124951 2 P 0 ;0,1,2=146,3=0.000000
L 5.60273317 2.06124951 5.6046 2.06083297 2 P 0 ;0,1,2=146,3=0.000000
L 5.6046 2.06083297 5.6069999 2.05916663 2 P 0 ;0,1,2=146,3=0.000000
L 5.6069999 2.05916663 5.6062001 2.07 2 P 0 ;0,1,2=146,3=0.000000
L 5.6062001 2.07 5.5990002 2.07 2 P 0 ;0,1,2=146,3=0.000000
A 5.32826004 2.0122 5.32826004 2.0122 5.32575 2.0122 1 P 0 N
L 5.62113337 2.03291634 5.62273356 2.03416683 2 P 0 ;0,1,2=147,3=0.000000
L 5.62273356 2.03416683 5.6245998 2.035 2 P 0 ;0,1,2=147,3=0.000000
L 5.6245998 2.035 5.62673317 2.035 2 P 0 ;0,1,2=147,3=0.000000
L 5.62673317 2.035 5.62913366 2.03374941 2 P 0 ;0,1,2=147,3=0.000000
L 5.62913366 2.03374941 5.6309999 2.03166654 2 P 0 ;0,1,2=147,3=0.000000
L 5.6309999 2.03166654 5.63233346 2.02916634 2 P 0 ;0,1,2=147,3=0.000000
L 5.63233346 2.02916634 5.63340039 2.0249998 2 P 0 ;0,1,2=147,3=0.000000
L 5.63340039 2.0249998 5.63366703 2.0212498 2 P 0 ;0,1,2=147,3=0.000000
L 5.63366703 2.0212498 5.63313327 2.0174999 2 P 0 ;0,1,2=147,3=0.000000
L 5.63313327 2.0174999 5.63233346 2.01499961 2 P 0 ;0,1,2=147,3=0.000000
L 5.63233346 2.01499961 5.63073337 2.01249941 2 P 0 ;0,1,2=147,3=0.000000
L 5.63073337 2.01249941 5.62886654 2.01083307 2 P 0 ;0,1,2=147,3=0.000000
L 5.62886654 2.01083307 5.6270003 2.01 2 P 0 ;0,1,2=147,3=0.000000
L 5.6270003 2.01 5.62513356 2.01 2 P 0 ;0,1,2=147,3=0.000000
L 5.62513356 2.01 5.62326673 2.01083307 2 P 0 ;0,1,2=147,3=0.000000
L 5.62326673 2.01083307 5.62166663 2.01208287 2 P 0 ;0,1,2=147,3=0.000000
L 5.62166663 2.01208287 5.62033307 2.01374911 2 P 0 ;0,1,2=147,3=0.000000
L 5.60806683 2.02041594 5.6062001 2.02333346 2 P 0 ;0,1,2=147,3=0.000000
L 5.6062001 2.02333346 5.6046 2.0249998 2 P 0 ;0,1,2=147,3=0.000000
L 5.6046 2.0249998 5.60246663 2.02583297 2 P 0 ;0,1,2=147,3=0.000000
L 5.60246663 2.02583297 5.6005998 2.0249998 2 P 0 ;0,1,2=147,3=0.000000
L 5.6005998 2.0249998 5.59926673 2.02333346 2 P 0 ;0,1,2=147,3=0.000000
L 5.59926673 2.02333346 5.5981999 2.02083327 2 P 0 ;0,1,2=147,3=0.000000
L 5.5981999 2.02083327 5.59793327 2.01791644 2 P 0 ;0,1,2=147,3=0.000000
L 5.59793327 2.01791644 5.5981999 2.01541624 2 P 0 ;0,1,2=147,3=0.000000
L 5.5981999 2.01541624 5.59926673 2.01291604 2 P 0 ;0,1,2=147,3=0.000000
L 5.59926673 2.01291604 5.60086693 2.01083307 2 P 0 ;0,1,2=147,3=0.000000
L 5.60086693 2.01083307 5.60273317 2.01 2 P 0 ;0,1,2=147,3=0.000000
L 5.60273317 2.01 5.60486654 2.01083307 2 P 0 ;0,1,2=147,3=0.000000
L 5.60486654 2.01083307 5.60673337 2.01333258 2 P 0 ;0,1,2=147,3=0.000000
L 5.60673337 2.01333258 5.6078002 2.01708327 2 P 0 ;0,1,2=147,3=0.000000
L 5.6078002 2.01708327 5.60806683 2.0212498 2 P 0 ;0,1,2=147,3=0.000000
L 5.60806683 2.0212498 5.60753366 2.02666614 2 P 0 ;0,1,2=147,3=0.000000
L 5.60753366 2.02666614 5.60673337 2.02958366 2 P 0 ;0,1,2=147,3=0.000000
L 5.60673337 2.02958366 5.6054003 2.0324997 2 P 0 ;0,1,2=147,3=0.000000
L 5.6054003 2.0324997 5.60353346 2.03458337 2 P 0 ;0,1,2=147,3=0.000000
L 5.60353346 2.03458337 5.60166673 2.035 2 P 0 ;0,1,2=147,3=0.000000
L 5.60166673 2.035 5.5998 2.03416683 2 P 0 ;0,1,2=147,3=0.000000
L 5.5998 2.03416683 5.59846644 2.03208317 2 P 0 ;0,1,2=147,3=0.000000
A 5.32826004 2.3333 5.32826004 2.3333 5.32575 2.3333 1 P 0 N
L 5.62113337 2.33791634 5.62273356 2.33916683 2 P 0 ;0,1,2=148,3=0.000000
L 5.62273356 2.33916683 5.6245998 2.34 2 P 0 ;0,1,2=148,3=0.000000
L 5.6245998 2.34 5.62673317 2.34 2 P 0 ;0,1,2=148,3=0.000000
L 5.62673317 2.34 5.62913366 2.33874941 2 P 0 ;0,1,2=148,3=0.000000
L 5.62913366 2.33874941 5.6309999 2.33666654 2 P 0 ;0,1,2=148,3=0.000000
L 5.6309999 2.33666654 5.63233346 2.33416634 2 P 0 ;0,1,2=148,3=0.000000
L 5.63233346 2.33416634 5.63340039 2.3299998 2 P 0 ;0,1,2=148,3=0.000000
L 5.63340039 2.3299998 5.63366703 2.3262498 2 P 0 ;0,1,2=148,3=0.000000
L 5.63366703 2.3262498 5.63313327 2.3224999 2 P 0 ;0,1,2=148,3=0.000000
L 5.63313327 2.3224999 5.63233346 2.31999961 2 P 0 ;0,1,2=148,3=0.000000
L 5.63233346 2.31999961 5.63073337 2.31749941 2 P 0 ;0,1,2=148,3=0.000000
L 5.63073337 2.31749941 5.62886654 2.31583307 2 P 0 ;0,1,2=148,3=0.000000
L 5.62886654 2.31583307 5.6270003 2.315 2 P 0 ;0,1,2=148,3=0.000000
L 5.6270003 2.315 5.62513356 2.315 2 P 0 ;0,1,2=148,3=0.000000
L 5.62513356 2.315 5.62326673 2.31583307 2 P 0 ;0,1,2=148,3=0.000000
L 5.62326673 2.31583307 5.62166663 2.31708287 2 P 0 ;0,1,2=148,3=0.000000
L 5.62166663 2.31708287 5.62033307 2.31874911 2 P 0 ;0,1,2=148,3=0.000000
L 5.5998 2.315 5.5998 2.34 2 P 0 ;0,1,2=148,3=0.000000
L 5.5998 2.34 5.60966703 2.32208327 2 P 0 ;0,1,2=148,3=0.000000
L 5.60966703 2.32208327 5.59633307 2.32208327 2 P 0 ;0,1,2=148,3=0.000000
L 5.58406683 2.33583337 5.58246673 2.33833287 2 P 0 ;0,1,2=148,3=0.000000
L 5.58246673 2.33833287 5.5806 2.33958337 2 P 0 ;0,1,2=148,3=0.000000
L 5.5806 2.33958337 5.57846663 2.34 2 P 0 ;0,1,2=148,3=0.000000
L 5.57846663 2.34 5.5758 2.33916683 2 P 0 ;0,1,2=148,3=0.000000
L 5.5758 2.33916683 5.57393327 2.33708317 2 P 0 ;0,1,2=148,3=0.000000
L 5.57393327 2.33708317 5.5734 2.33458366 2 P 0 ;0,1,2=148,3=0.000000
L 5.5734 2.33458366 5.57366663 2.33208268 2 P 0 ;0,1,2=148,3=0.000000
L 5.57366663 2.33208268 5.57473356 2.3299998 2 P 0 ;0,1,2=148,3=0.000000
L 5.57473356 2.3299998 5.58006673 2.32583327 2 P 0 ;0,1,2=148,3=0.000000
L 5.58006673 2.32583327 5.58246673 2.32291644 2 P 0 ;0,1,2=148,3=0.000000
L 5.58246673 2.32291644 5.58406683 2.31874911 2 P 0 ;0,1,2=148,3=0.000000
L 5.58406683 2.31874911 5.5846001 2.315 2 P 0 ;0,1,2=148,3=0.000000
L 5.5846001 2.315 5.5734 2.315 2 P 0 ;0,1,2=148,3=0.000000
L 5.55553346 2.315 5.5550003 2.32041624 2 P 0 ;0,1,2=148,3=0.000000
L 5.5550003 2.32041624 5.5542 2.32499931 2 P 0 ;0,1,2=148,3=0.000000
L 5.5542 2.32499931 5.55313356 2.32916663 2 P 0 ;0,1,2=148,3=0.000000
L 5.55313356 2.32916663 5.5518 2.3337498 2 P 0 ;0,1,2=148,3=0.000000
L 5.5518 2.3337498 5.54966663 2.34 2 P 0 ;0,1,2=148,3=0.000000
L 5.54966663 2.34 5.56033346 2.34 2 P 0 ;0,1,2=148,3=0.000000
A 5.32826004 2.2883 5.32826004 2.2883 5.32575 2.2883 1 P 0 N
L 5.62113337 2.30291634 5.62273356 2.30416683 2 P 0 ;0,1,2=149,3=0.000000
L 5.62273356 2.30416683 5.6245998 2.305 2 P 0 ;0,1,2=149,3=0.000000
L 5.6245998 2.305 5.62673317 2.305 2 P 0 ;0,1,2=149,3=0.000000
L 5.62673317 2.305 5.62913366 2.30374941 2 P 0 ;0,1,2=149,3=0.000000
L 5.62913366 2.30374941 5.6309999 2.30166654 2 P 0 ;0,1,2=149,3=0.000000
L 5.6309999 2.30166654 5.63233346 2.29916634 2 P 0 ;0,1,2=149,3=0.000000
L 5.63233346 2.29916634 5.63340039 2.2949998 2 P 0 ;0,1,2=149,3=0.000000
L 5.63340039 2.2949998 5.63366703 2.2912498 2 P 0 ;0,1,2=149,3=0.000000
L 5.63366703 2.2912498 5.63313327 2.2874999 2 P 0 ;0,1,2=149,3=0.000000
L 5.63313327 2.2874999 5.63233346 2.28499961 2 P 0 ;0,1,2=149,3=0.000000
L 5.63233346 2.28499961 5.63073337 2.28249941 2 P 0 ;0,1,2=149,3=0.000000
L 5.63073337 2.28249941 5.62886654 2.28083307 2 P 0 ;0,1,2=149,3=0.000000
L 5.62886654 2.28083307 5.6270003 2.28 2 P 0 ;0,1,2=149,3=0.000000
L 5.6270003 2.28 5.62513356 2.28 2 P 0 ;0,1,2=149,3=0.000000
L 5.62513356 2.28 5.62326673 2.28083307 2 P 0 ;0,1,2=149,3=0.000000
L 5.62326673 2.28083307 5.62166663 2.28208287 2 P 0 ;0,1,2=149,3=0.000000
L 5.62166663 2.28208287 5.62033307 2.28374911 2 P 0 ;0,1,2=149,3=0.000000
L 5.5998 2.28 5.5998 2.305 2 P 0 ;0,1,2=149,3=0.000000
L 5.5998 2.305 5.60966703 2.28708327 2 P 0 ;0,1,2=149,3=0.000000
L 5.60966703 2.28708327 5.59633307 2.28708327 2 P 0 ;0,1,2=149,3=0.000000
L 5.58406683 2.30083337 5.58246673 2.30333287 2 P 0 ;0,1,2=149,3=0.000000
L 5.58246673 2.30333287 5.5806 2.30458337 2 P 0 ;0,1,2=149,3=0.000000
L 5.5806 2.30458337 5.57846663 2.305 2 P 0 ;0,1,2=149,3=0.000000
L 5.57846663 2.305 5.5758 2.30416683 2 P 0 ;0,1,2=149,3=0.000000
L 5.5758 2.30416683 5.57393327 2.30208317 2 P 0 ;0,1,2=149,3=0.000000
L 5.57393327 2.30208317 5.5734 2.29958366 2 P 0 ;0,1,2=149,3=0.000000
L 5.5734 2.29958366 5.57366663 2.29708268 2 P 0 ;0,1,2=149,3=0.000000
L 5.57366663 2.29708268 5.57473356 2.2949998 2 P 0 ;0,1,2=149,3=0.000000
L 5.57473356 2.2949998 5.58006673 2.29083327 2 P 0 ;0,1,2=149,3=0.000000
L 5.58006673 2.29083327 5.58246673 2.28791644 2 P 0 ;0,1,2=149,3=0.000000
L 5.58246673 2.28791644 5.58406683 2.28374911 2 P 0 ;0,1,2=149,3=0.000000
L 5.58406683 2.28374911 5.5846001 2.28 2 P 0 ;0,1,2=149,3=0.000000
L 5.5846001 2.28 5.5734 2.28 2 P 0 ;0,1,2=149,3=0.000000
L 5.5550003 2.28 5.55313356 2.28041654 2 P 0 ;0,1,2=149,3=0.000000
L 5.55313356 2.28041654 5.5510002 2.28166624 2 P 0 ;0,1,2=149,3=0.000000
L 5.5510002 2.28166624 5.54966663 2.28374911 2 P 0 ;0,1,2=149,3=0.000000
L 5.54966663 2.28374911 5.54913337 2.28666673 2 P 0 ;0,1,2=149,3=0.000000
L 5.54913337 2.28666673 5.54966663 2.28958278 2 P 0 ;0,1,2=149,3=0.000000
L 5.54966663 2.28958278 5.55126673 2.29208297 2 P 0 ;0,1,2=149,3=0.000000
L 5.55126673 2.29208297 5.55366673 2.29333346 2 P 0 ;0,1,2=149,3=0.000000
L 5.55366673 2.29333346 5.55633337 2.29333346 2 P 0 ;0,1,2=149,3=0.000000
L 5.55633337 2.29333346 5.55793346 2.29416663 2 P 0 ;0,1,2=149,3=0.000000
L 5.55793346 2.29416663 5.55926703 2.29624951 2 P 0 ;0,1,2=149,3=0.000000
L 5.55926703 2.29624951 5.5598002 2.29916634 2 P 0 ;0,1,2=149,3=0.000000
L 5.5598002 2.29916634 5.5589999 2.30208317 2 P 0 ;0,1,2=149,3=0.000000
L 5.5589999 2.30208317 5.55713366 2.30416683 2 P 0 ;0,1,2=149,3=0.000000
L 5.55713366 2.30416683 5.5550003 2.305 2 P 0 ;0,1,2=149,3=0.000000
L 5.5550003 2.305 5.55286693 2.30416683 2 P 0 ;0,1,2=149,3=0.000000
L 5.55286693 2.30416683 5.5510002 2.30208317 2 P 0 ;0,1,2=149,3=0.000000
L 5.5510002 2.30208317 5.5501999 2.29916634 2 P 0 ;0,1,2=149,3=0.000000
L 5.5501999 2.29916634 5.55073356 2.29624951 2 P 0 ;0,1,2=149,3=0.000000
L 5.55073356 2.29624951 5.55206663 2.29416663 2 P 0 ;0,1,2=149,3=0.000000
L 5.55206663 2.29416663 5.55366673 2.29333346 2 P 0 ;0,1,2=149,3=0.000000
L 5.55366673 2.29333346 5.55633337 2.29333346 2 P 0 ;0,1,2=149,3=0.000000
L 5.55633337 2.29333346 5.55873337 2.29208297 2 P 0 ;0,1,2=149,3=0.000000
L 5.55873337 2.29208297 5.56033346 2.28958278 2 P 0 ;0,1,2=149,3=0.000000
L 5.56033346 2.28958278 5.56086673 2.28666673 2 P 0 ;0,1,2=149,3=0.000000
L 5.56086673 2.28666673 5.56033346 2.28374911 2 P 0 ;0,1,2=149,3=0.000000
L 5.56033346 2.28374911 5.5589999 2.28166624 2 P 0 ;0,1,2=149,3=0.000000
L 5.5589999 2.28166624 5.55686654 2.28041654 2 P 0 ;0,1,2=149,3=0.000000
L 5.55686654 2.28041654 5.5550003 2.28 2 P 0 ;0,1,2=149,3=0.000000
A 5.32826004 2.1979 5.32826004 2.1979 5.32575 2.1979 1 P 0 N
L 5.62113337 2.19791634 5.62273356 2.19916683 2 P 0 ;0,1,2=150,3=0.000000
L 5.62273356 2.19916683 5.6245998 2.2 2 P 0 ;0,1,2=150,3=0.000000
L 5.6245998 2.2 5.62673317 2.2 2 P 0 ;0,1,2=150,3=0.000000
L 5.62673317 2.2 5.62913366 2.19874941 2 P 0 ;0,1,2=150,3=0.000000
L 5.62913366 2.19874941 5.6309999 2.19666654 2 P 0 ;0,1,2=150,3=0.000000
L 5.6309999 2.19666654 5.63233346 2.19416634 2 P 0 ;0,1,2=150,3=0.000000
L 5.63233346 2.19416634 5.63340039 2.1899998 2 P 0 ;0,1,2=150,3=0.000000
L 5.63340039 2.1899998 5.63366703 2.1862498 2 P 0 ;0,1,2=150,3=0.000000
L 5.63366703 2.1862498 5.63313327 2.1824999 2 P 0 ;0,1,2=150,3=0.000000
L 5.63313327 2.1824999 5.63233346 2.17999961 2 P 0 ;0,1,2=150,3=0.000000
L 5.63233346 2.17999961 5.63073337 2.17749941 2 P 0 ;0,1,2=150,3=0.000000
L 5.63073337 2.17749941 5.62886654 2.17583307 2 P 0 ;0,1,2=150,3=0.000000
L 5.62886654 2.17583307 5.6270003 2.175 2 P 0 ;0,1,2=150,3=0.000000
L 5.6270003 2.175 5.62513356 2.175 2 P 0 ;0,1,2=150,3=0.000000
L 5.62513356 2.175 5.62326673 2.17583307 2 P 0 ;0,1,2=150,3=0.000000
L 5.62326673 2.17583307 5.62166663 2.17708287 2 P 0 ;0,1,2=150,3=0.000000
L 5.62166663 2.17708287 5.62033307 2.17874911 2 P 0 ;0,1,2=150,3=0.000000
L 5.5998 2.175 5.5998 2.2 2 P 0 ;0,1,2=150,3=0.000000
L 5.5998 2.2 5.60966703 2.18208327 2 P 0 ;0,1,2=150,3=0.000000
L 5.60966703 2.18208327 5.59633307 2.18208327 2 P 0 ;0,1,2=150,3=0.000000
L 5.58406683 2.19583337 5.58246673 2.19833287 2 P 0 ;0,1,2=150,3=0.000000
L 5.58246673 2.19833287 5.5806 2.19958337 2 P 0 ;0,1,2=150,3=0.000000
L 5.5806 2.19958337 5.57846663 2.2 2 P 0 ;0,1,2=150,3=0.000000
L 5.57846663 2.2 5.5758 2.19916683 2 P 0 ;0,1,2=150,3=0.000000
L 5.5758 2.19916683 5.57393327 2.19708317 2 P 0 ;0,1,2=150,3=0.000000
L 5.57393327 2.19708317 5.5734 2.19458366 2 P 0 ;0,1,2=150,3=0.000000
L 5.5734 2.19458366 5.57366663 2.19208268 2 P 0 ;0,1,2=150,3=0.000000
L 5.57366663 2.19208268 5.57473356 2.1899998 2 P 0 ;0,1,2=150,3=0.000000
L 5.57473356 2.1899998 5.58006673 2.18583327 2 P 0 ;0,1,2=150,3=0.000000
L 5.58006673 2.18583327 5.58246673 2.18291644 2 P 0 ;0,1,2=150,3=0.000000
L 5.58246673 2.18291644 5.58406683 2.17874911 2 P 0 ;0,1,2=150,3=0.000000
L 5.58406683 2.17874911 5.5846001 2.175 2 P 0 ;0,1,2=150,3=0.000000
L 5.5846001 2.175 5.5734 2.175 2 P 0 ;0,1,2=150,3=0.000000
L 5.55953366 2.17791604 5.55766683 2.17583307 2 P 0 ;0,1,2=150,3=0.000000
L 5.55766683 2.17583307 5.55553346 2.175 2 P 0 ;0,1,2=150,3=0.000000
L 5.55553346 2.175 5.5534001 2.17583307 2 P 0 ;0,1,2=150,3=0.000000
L 5.5534001 2.17583307 5.55153337 2.17833258 2 P 0 ;0,1,2=150,3=0.000000
L 5.55153337 2.17833258 5.5501999 2.18208327 2 P 0 ;0,1,2=150,3=0.000000
L 5.5501999 2.18208327 5.54966663 2.18583327 2 P 0 ;0,1,2=150,3=0.000000
L 5.54966663 2.18583327 5.54966663 2.19041634 2 P 0 ;0,1,2=150,3=0.000000
L 5.54966663 2.19041634 5.5501999 2.19416634 2 P 0 ;0,1,2=150,3=0.000000
L 5.5501999 2.19416634 5.55153337 2.1974997 2 P 0 ;0,1,2=150,3=0.000000
L 5.55153337 2.1974997 5.55313356 2.19916683 2 P 0 ;0,1,2=150,3=0.000000
L 5.55313356 2.19916683 5.5550003 2.2 2 P 0 ;0,1,2=150,3=0.000000
L 5.5550003 2.2 5.55713366 2.19916683 2 P 0 ;0,1,2=150,3=0.000000
L 5.55713366 2.19916683 5.55873337 2.1974997 2 P 0 ;0,1,2=150,3=0.000000
L 5.55873337 2.1974997 5.5598002 2.1950003 2 P 0 ;0,1,2=150,3=0.000000
L 5.5598002 2.1950003 5.56033346 2.19166614 2 P 0 ;0,1,2=150,3=0.000000
L 5.56033346 2.19166614 5.5598002 2.1887501 2 P 0 ;0,1,2=150,3=0.000000
L 5.5598002 2.1887501 5.55846673 2.18583327 2 P 0 ;0,1,2=150,3=0.000000
L 5.55846673 2.18583327 5.55686654 2.18416614 2 P 0 ;0,1,2=150,3=0.000000
L 5.55686654 2.18416614 5.5550003 2.18374961 2 P 0 ;0,1,2=150,3=0.000000
L 5.5550003 2.18374961 5.55286693 2.18458278 2 P 0 ;0,1,2=150,3=0.000000
L 5.55286693 2.18458278 5.55126673 2.18666644 2 P 0 ;0,1,2=150,3=0.000000
L 5.55126673 2.18666644 5.54966663 2.19041634 2 P 0 ;0,1,2=150,3=0.000000
A 5.32826004 2.4687 5.32826004 2.4687 5.32575 2.4687 1 P 0 N
L 5.62113337 2.47291634 5.62273356 2.47416683 2 P 0 ;0,1,2=151,3=0.000000
L 5.62273356 2.47416683 5.6245998 2.475 2 P 0 ;0,1,2=151,3=0.000000
L 5.6245998 2.475 5.62673317 2.475 2 P 0 ;0,1,2=151,3=0.000000
L 5.62673317 2.475 5.62913366 2.47374941 2 P 0 ;0,1,2=151,3=0.000000
L 5.62913366 2.47374941 5.6309999 2.47166654 2 P 0 ;0,1,2=151,3=0.000000
L 5.6309999 2.47166654 5.63233346 2.46916634 2 P 0 ;0,1,2=151,3=0.000000
L 5.63233346 2.46916634 5.63340039 2.4649998 2 P 0 ;0,1,2=151,3=0.000000
L 5.63340039 2.4649998 5.63366703 2.4612498 2 P 0 ;0,1,2=151,3=0.000000
L 5.63366703 2.4612498 5.63313327 2.4574999 2 P 0 ;0,1,2=151,3=0.000000
L 5.63313327 2.4574999 5.63233346 2.45499961 2 P 0 ;0,1,2=151,3=0.000000
L 5.63233346 2.45499961 5.63073337 2.45249941 2 P 0 ;0,1,2=151,3=0.000000
L 5.63073337 2.45249941 5.62886654 2.45083307 2 P 0 ;0,1,2=151,3=0.000000
L 5.62886654 2.45083307 5.6270003 2.45 2 P 0 ;0,1,2=151,3=0.000000
L 5.6270003 2.45 5.62513356 2.45 2 P 0 ;0,1,2=151,3=0.000000
L 5.62513356 2.45 5.62326673 2.45083307 2 P 0 ;0,1,2=151,3=0.000000
L 5.62326673 2.45083307 5.62166663 2.45208287 2 P 0 ;0,1,2=151,3=0.000000
L 5.62166663 2.45208287 5.62033307 2.45374911 2 P 0 ;0,1,2=151,3=0.000000
L 5.5998 2.45 5.5998 2.475 2 P 0 ;0,1,2=151,3=0.000000
L 5.5998 2.475 5.60966703 2.45708327 2 P 0 ;0,1,2=151,3=0.000000
L 5.60966703 2.45708327 5.59633307 2.45708327 2 P 0 ;0,1,2=151,3=0.000000
L 5.58486673 2.45499961 5.58326703 2.45208287 2 P 0 ;0,1,2=151,3=0.000000
L 5.58326703 2.45208287 5.58113366 2.45041654 2 P 0 ;0,1,2=151,3=0.000000
L 5.58113366 2.45041654 5.57873317 2.45 2 P 0 ;0,1,2=151,3=0.000000
L 5.57873317 2.45 5.5765998 2.45041654 2 P 0 ;0,1,2=151,3=0.000000
L 5.5765998 2.45041654 5.57446644 2.45249941 2 P 0 ;0,1,2=151,3=0.000000
L 5.57446644 2.45249941 5.57313337 2.45499961 2 P 0 ;0,1,2=151,3=0.000000
L 5.57313337 2.45499961 5.57286683 2.4574999 2 P 0 ;0,1,2=151,3=0.000000
L 5.57286683 2.4574999 5.5734 2.46041594 2 P 0 ;0,1,2=151,3=0.000000
L 5.5734 2.46041594 5.57526673 2.46249961 2 P 0 ;0,1,2=151,3=0.000000
L 5.57526673 2.46249961 5.57713356 2.46333346 2 P 0 ;0,1,2=151,3=0.000000
L 5.57713356 2.46333346 5.57953346 2.46333346 2 P 0 ;0,1,2=151,3=0.000000
L 5.57713356 2.46333346 5.57553337 2.46458327 2 P 0 ;0,1,2=151,3=0.000000
L 5.57553337 2.46458327 5.5741999 2.46666614 2 P 0 ;0,1,2=151,3=0.000000
L 5.5741999 2.46666614 5.57366663 2.46916634 2 P 0 ;0,1,2=151,3=0.000000
L 5.57366663 2.46916634 5.5741999 2.47166654 2 P 0 ;0,1,2=151,3=0.000000
L 5.5741999 2.47166654 5.57553337 2.47374941 2 P 0 ;0,1,2=151,3=0.000000
L 5.57553337 2.47374941 5.57793337 2.475 2 P 0 ;0,1,2=151,3=0.000000
L 5.57793337 2.475 5.58033337 2.47458337 2 P 0 ;0,1,2=151,3=0.000000
L 5.58033337 2.47458337 5.58273337 2.47291634 2 P 0 ;0,1,2=151,3=0.000000
L 5.56086673 2.45499961 5.55926703 2.45208287 2 P 0 ;0,1,2=151,3=0.000000
L 5.55926703 2.45208287 5.55713366 2.45041654 2 P 0 ;0,1,2=151,3=0.000000
L 5.55713366 2.45041654 5.55473317 2.45 2 P 0 ;0,1,2=151,3=0.000000
L 5.55473317 2.45 5.5525998 2.45041654 2 P 0 ;0,1,2=151,3=0.000000
L 5.5525998 2.45041654 5.55046644 2.45249941 2 P 0 ;0,1,2=151,3=0.000000
L 5.55046644 2.45249941 5.54913337 2.45499961 2 P 0 ;0,1,2=151,3=0.000000
L 5.54913337 2.45499961 5.54886683 2.4574999 2 P 0 ;0,1,2=151,3=0.000000
L 5.54886683 2.4574999 5.5494 2.46041594 2 P 0 ;0,1,2=151,3=0.000000
L 5.5494 2.46041594 5.55126673 2.46249961 2 P 0 ;0,1,2=151,3=0.000000
L 5.55126673 2.46249961 5.55313356 2.46333346 2 P 0 ;0,1,2=151,3=0.000000
L 5.55313356 2.46333346 5.55553346 2.46333346 2 P 0 ;0,1,2=151,3=0.000000
L 5.55313356 2.46333346 5.55153337 2.46458327 2 P 0 ;0,1,2=151,3=0.000000
L 5.55153337 2.46458327 5.5501999 2.46666614 2 P 0 ;0,1,2=151,3=0.000000
L 5.5501999 2.46666614 5.54966663 2.46916634 2 P 0 ;0,1,2=151,3=0.000000
L 5.54966663 2.46916634 5.5501999 2.47166654 2 P 0 ;0,1,2=151,3=0.000000
L 5.5501999 2.47166654 5.55153337 2.47374941 2 P 0 ;0,1,2=151,3=0.000000
L 5.55153337 2.47374941 5.55393337 2.475 2 P 0 ;0,1,2=151,3=0.000000
L 5.55393337 2.475 5.55633337 2.47458337 2 P 0 ;0,1,2=151,3=0.000000
L 5.55633337 2.47458337 5.55873337 2.47291634 2 P 0 ;0,1,2=151,3=0.000000
A 5.32826004 2.4237 5.32826004 2.4237 5.32575 2.4237 1 P 0 N
L 5.62113337 2.43791634 5.62273356 2.43916683 2 P 0 ;0,1,2=152,3=0.000000
L 5.62273356 2.43916683 5.6245998 2.44 2 P 0 ;0,1,2=152,3=0.000000
L 5.6245998 2.44 5.62673317 2.44 2 P 0 ;0,1,2=152,3=0.000000
L 5.62673317 2.44 5.62913366 2.43874941 2 P 0 ;0,1,2=152,3=0.000000
L 5.62913366 2.43874941 5.6309999 2.43666654 2 P 0 ;0,1,2=152,3=0.000000
L 5.6309999 2.43666654 5.63233346 2.43416634 2 P 0 ;0,1,2=152,3=0.000000
L 5.63233346 2.43416634 5.63340039 2.4299998 2 P 0 ;0,1,2=152,3=0.000000
L 5.63340039 2.4299998 5.63366703 2.4262498 2 P 0 ;0,1,2=152,3=0.000000
L 5.63366703 2.4262498 5.63313327 2.4224999 2 P 0 ;0,1,2=152,3=0.000000
L 5.63313327 2.4224999 5.63233346 2.41999961 2 P 0 ;0,1,2=152,3=0.000000
L 5.63233346 2.41999961 5.63073337 2.41749941 2 P 0 ;0,1,2=152,3=0.000000
L 5.63073337 2.41749941 5.62886654 2.41583307 2 P 0 ;0,1,2=152,3=0.000000
L 5.62886654 2.41583307 5.6270003 2.415 2 P 0 ;0,1,2=152,3=0.000000
L 5.6270003 2.415 5.62513356 2.415 2 P 0 ;0,1,2=152,3=0.000000
L 5.62513356 2.415 5.62326673 2.41583307 2 P 0 ;0,1,2=152,3=0.000000
L 5.62326673 2.41583307 5.62166663 2.41708287 2 P 0 ;0,1,2=152,3=0.000000
L 5.62166663 2.41708287 5.62033307 2.41874911 2 P 0 ;0,1,2=152,3=0.000000
L 5.5998 2.415 5.5998 2.44 2 P 0 ;0,1,2=152,3=0.000000
L 5.5998 2.44 5.60966703 2.42208327 2 P 0 ;0,1,2=152,3=0.000000
L 5.60966703 2.42208327 5.59633307 2.42208327 2 P 0 ;0,1,2=152,3=0.000000
L 5.58486673 2.41999961 5.58326703 2.41708287 2 P 0 ;0,1,2=152,3=0.000000
L 5.58326703 2.41708287 5.58113366 2.41541654 2 P 0 ;0,1,2=152,3=0.000000
L 5.58113366 2.41541654 5.57873317 2.415 2 P 0 ;0,1,2=152,3=0.000000
L 5.57873317 2.415 5.5765998 2.41541654 2 P 0 ;0,1,2=152,3=0.000000
L 5.5765998 2.41541654 5.57446644 2.41749941 2 P 0 ;0,1,2=152,3=0.000000
L 5.57446644 2.41749941 5.57313337 2.41999961 2 P 0 ;0,1,2=152,3=0.000000
L 5.57313337 2.41999961 5.57286683 2.4224999 2 P 0 ;0,1,2=152,3=0.000000
L 5.57286683 2.4224999 5.5734 2.42541594 2 P 0 ;0,1,2=152,3=0.000000
L 5.5734 2.42541594 5.57526673 2.42749961 2 P 0 ;0,1,2=152,3=0.000000
L 5.57526673 2.42749961 5.57713356 2.42833346 2 P 0 ;0,1,2=152,3=0.000000
L 5.57713356 2.42833346 5.57953346 2.42833346 2 P 0 ;0,1,2=152,3=0.000000
L 5.57713356 2.42833346 5.57553337 2.42958327 2 P 0 ;0,1,2=152,3=0.000000
L 5.57553337 2.42958327 5.5741999 2.43166614 2 P 0 ;0,1,2=152,3=0.000000
L 5.5741999 2.43166614 5.57366663 2.43416634 2 P 0 ;0,1,2=152,3=0.000000
L 5.57366663 2.43416634 5.5741999 2.43666654 2 P 0 ;0,1,2=152,3=0.000000
L 5.5741999 2.43666654 5.57553337 2.43874941 2 P 0 ;0,1,2=152,3=0.000000
L 5.57553337 2.43874941 5.57793337 2.44 2 P 0 ;0,1,2=152,3=0.000000
L 5.57793337 2.44 5.58033337 2.43958337 2 P 0 ;0,1,2=152,3=0.000000
L 5.58033337 2.43958337 5.58273337 2.43791634 2 P 0 ;0,1,2=152,3=0.000000
L 5.5518 2.415 5.5518 2.44 2 P 0 ;0,1,2=152,3=0.000000
L 5.5518 2.44 5.56166703 2.42208327 2 P 0 ;0,1,2=152,3=0.000000
L 5.56166703 2.42208327 5.54833307 2.42208327 2 P 0 ;0,1,2=152,3=0.000000
A 5.32826004 2.6079 5.32826004 2.6079 5.32575 2.6079 1 P 0 N
L 5.62113337 2.61291634 5.62273356 2.61416683 2 P 0 ;0,1,2=153,3=0.000000
L 5.62273356 2.61416683 5.6245998 2.615 2 P 0 ;0,1,2=153,3=0.000000
L 5.6245998 2.615 5.62673317 2.615 2 P 0 ;0,1,2=153,3=0.000000
L 5.62673317 2.615 5.62913366 2.61374941 2 P 0 ;0,1,2=153,3=0.000000
L 5.62913366 2.61374941 5.6309999 2.61166654 2 P 0 ;0,1,2=153,3=0.000000
L 5.6309999 2.61166654 5.63233346 2.60916634 2 P 0 ;0,1,2=153,3=0.000000
L 5.63233346 2.60916634 5.63340039 2.6049998 2 P 0 ;0,1,2=153,3=0.000000
L 5.63340039 2.6049998 5.63366703 2.6012498 2 P 0 ;0,1,2=153,3=0.000000
L 5.63366703 2.6012498 5.63313327 2.5974999 2 P 0 ;0,1,2=153,3=0.000000
L 5.63313327 2.5974999 5.63233346 2.59499961 2 P 0 ;0,1,2=153,3=0.000000
L 5.63233346 2.59499961 5.63073337 2.59249941 2 P 0 ;0,1,2=153,3=0.000000
L 5.63073337 2.59249941 5.62886654 2.59083307 2 P 0 ;0,1,2=153,3=0.000000
L 5.62886654 2.59083307 5.6270003 2.59 2 P 0 ;0,1,2=153,3=0.000000
L 5.6270003 2.59 5.62513356 2.59 2 P 0 ;0,1,2=153,3=0.000000
L 5.62513356 2.59 5.62326673 2.59083307 2 P 0 ;0,1,2=153,3=0.000000
L 5.62326673 2.59083307 5.62166663 2.59208287 2 P 0 ;0,1,2=153,3=0.000000
L 5.62166663 2.59208287 5.62033307 2.59374911 2 P 0 ;0,1,2=153,3=0.000000
L 5.5998 2.59 5.5998 2.615 2 P 0 ;0,1,2=153,3=0.000000
L 5.5998 2.615 5.60966703 2.59708327 2 P 0 ;0,1,2=153,3=0.000000
L 5.60966703 2.59708327 5.59633307 2.59708327 2 P 0 ;0,1,2=153,3=0.000000
L 5.58486673 2.59499961 5.58326703 2.59208287 2 P 0 ;0,1,2=153,3=0.000000
L 5.58326703 2.59208287 5.58113366 2.59041654 2 P 0 ;0,1,2=153,3=0.000000
L 5.58113366 2.59041654 5.57873317 2.59 2 P 0 ;0,1,2=153,3=0.000000
L 5.57873317 2.59 5.5765998 2.59041654 2 P 0 ;0,1,2=153,3=0.000000
L 5.5765998 2.59041654 5.57446644 2.59249941 2 P 0 ;0,1,2=153,3=0.000000
L 5.57446644 2.59249941 5.57313337 2.59499961 2 P 0 ;0,1,2=153,3=0.000000
L 5.57313337 2.59499961 5.57286683 2.5974999 2 P 0 ;0,1,2=153,3=0.000000
L 5.57286683 2.5974999 5.5734 2.60041594 2 P 0 ;0,1,2=153,3=0.000000
L 5.5734 2.60041594 5.57526673 2.60249961 2 P 0 ;0,1,2=153,3=0.000000
L 5.57526673 2.60249961 5.57713356 2.60333346 2 P 0 ;0,1,2=153,3=0.000000
L 5.57713356 2.60333346 5.57953346 2.60333346 2 P 0 ;0,1,2=153,3=0.000000
L 5.57713356 2.60333346 5.57553337 2.60458327 2 P 0 ;0,1,2=153,3=0.000000
L 5.57553337 2.60458327 5.5741999 2.60666614 2 P 0 ;0,1,2=153,3=0.000000
L 5.5741999 2.60666614 5.57366663 2.60916634 2 P 0 ;0,1,2=153,3=0.000000
L 5.57366663 2.60916634 5.5741999 2.61166654 2 P 0 ;0,1,2=153,3=0.000000
L 5.5741999 2.61166654 5.57553337 2.61374941 2 P 0 ;0,1,2=153,3=0.000000
L 5.57553337 2.61374941 5.57793337 2.615 2 P 0 ;0,1,2=153,3=0.000000
L 5.57793337 2.615 5.58033337 2.61458337 2 P 0 ;0,1,2=153,3=0.000000
L 5.58033337 2.61458337 5.58273337 2.61291634 2 P 0 ;0,1,2=153,3=0.000000
L 5.55953366 2.59291604 5.55766683 2.59083307 2 P 0 ;0,1,2=153,3=0.000000
L 5.55766683 2.59083307 5.55553346 2.59 2 P 0 ;0,1,2=153,3=0.000000
L 5.55553346 2.59 5.5534001 2.59083307 2 P 0 ;0,1,2=153,3=0.000000
L 5.5534001 2.59083307 5.55153337 2.59333258 2 P 0 ;0,1,2=153,3=0.000000
L 5.55153337 2.59333258 5.5501999 2.59708327 2 P 0 ;0,1,2=153,3=0.000000
L 5.5501999 2.59708327 5.54966663 2.60083327 2 P 0 ;0,1,2=153,3=0.000000
L 5.54966663 2.60083327 5.54966663 2.60541634 2 P 0 ;0,1,2=153,3=0.000000
L 5.54966663 2.60541634 5.5501999 2.60916634 2 P 0 ;0,1,2=153,3=0.000000
L 5.5501999 2.60916634 5.55153337 2.6124997 2 P 0 ;0,1,2=153,3=0.000000
L 5.55153337 2.6124997 5.55313356 2.61416683 2 P 0 ;0,1,2=153,3=0.000000
L 5.55313356 2.61416683 5.5550003 2.615 2 P 0 ;0,1,2=153,3=0.000000
L 5.5550003 2.615 5.55713366 2.61416683 2 P 0 ;0,1,2=153,3=0.000000
L 5.55713366 2.61416683 5.55873337 2.6124997 2 P 0 ;0,1,2=153,3=0.000000
L 5.55873337 2.6124997 5.5598002 2.6100003 2 P 0 ;0,1,2=153,3=0.000000
L 5.5598002 2.6100003 5.56033346 2.60666614 2 P 0 ;0,1,2=153,3=0.000000
L 5.56033346 2.60666614 5.5598002 2.6037501 2 P 0 ;0,1,2=153,3=0.000000
L 5.5598002 2.6037501 5.55846673 2.60083327 2 P 0 ;0,1,2=153,3=0.000000
L 5.55846673 2.60083327 5.55686654 2.59916614 2 P 0 ;0,1,2=153,3=0.000000
L 5.55686654 2.59916614 5.5550003 2.59874961 2 P 0 ;0,1,2=153,3=0.000000
L 5.5550003 2.59874961 5.55286693 2.59958278 2 P 0 ;0,1,2=153,3=0.000000
L 5.55286693 2.59958278 5.55126673 2.60166644 2 P 0 ;0,1,2=153,3=0.000000
L 5.55126673 2.60166644 5.54966663 2.60541634 2 P 0 ;0,1,2=153,3=0.000000
A 5.32826004 2.5629 5.32826004 2.5629 5.32575 2.5629 1 P 0 N
L 5.62113337 2.57791634 5.62273356 2.57916683 2 P 0 ;0,1,2=154,3=0.000000
L 5.62273356 2.57916683 5.6245998 2.58 2 P 0 ;0,1,2=154,3=0.000000
L 5.6245998 2.58 5.62673317 2.58 2 P 0 ;0,1,2=154,3=0.000000
L 5.62673317 2.58 5.62913366 2.57874941 2 P 0 ;0,1,2=154,3=0.000000
L 5.62913366 2.57874941 5.6309999 2.57666654 2 P 0 ;0,1,2=154,3=0.000000
L 5.6309999 2.57666654 5.63233346 2.57416634 2 P 0 ;0,1,2=154,3=0.000000
L 5.63233346 2.57416634 5.63340039 2.5699998 2 P 0 ;0,1,2=154,3=0.000000
L 5.63340039 2.5699998 5.63366703 2.5662498 2 P 0 ;0,1,2=154,3=0.000000
L 5.63366703 2.5662498 5.63313327 2.5624999 2 P 0 ;0,1,2=154,3=0.000000
L 5.63313327 2.5624999 5.63233346 2.55999961 2 P 0 ;0,1,2=154,3=0.000000
L 5.63233346 2.55999961 5.63073337 2.55749941 2 P 0 ;0,1,2=154,3=0.000000
L 5.63073337 2.55749941 5.62886654 2.55583307 2 P 0 ;0,1,2=154,3=0.000000
L 5.62886654 2.55583307 5.6270003 2.555 2 P 0 ;0,1,2=154,3=0.000000
L 5.6270003 2.555 5.62513356 2.555 2 P 0 ;0,1,2=154,3=0.000000
L 5.62513356 2.555 5.62326673 2.55583307 2 P 0 ;0,1,2=154,3=0.000000
L 5.62326673 2.55583307 5.62166663 2.55708287 2 P 0 ;0,1,2=154,3=0.000000
L 5.62166663 2.55708287 5.62033307 2.55874911 2 P 0 ;0,1,2=154,3=0.000000
L 5.5998 2.555 5.5998 2.58 2 P 0 ;0,1,2=154,3=0.000000
L 5.5998 2.58 5.60966703 2.56208327 2 P 0 ;0,1,2=154,3=0.000000
L 5.60966703 2.56208327 5.59633307 2.56208327 2 P 0 ;0,1,2=154,3=0.000000
L 5.5758 2.555 5.5758 2.58 2 P 0 ;0,1,2=154,3=0.000000
L 5.5758 2.58 5.58566703 2.56208327 2 P 0 ;0,1,2=154,3=0.000000
L 5.58566703 2.56208327 5.57233307 2.56208327 2 P 0 ;0,1,2=154,3=0.000000
L 5.5550003 2.58 5.55713366 2.57916683 2 P 0 ;0,1,2=154,3=0.000000
L 5.55713366 2.57916683 5.55873337 2.57708317 2 P 0 ;0,1,2=154,3=0.000000
L 5.55873337 2.57708317 5.5598002 2.57458366 2 P 0 ;0,1,2=154,3=0.000000
L 5.5598002 2.57458366 5.5606001 2.57124951 2 P 0 ;0,1,2=154,3=0.000000
L 5.5606001 2.57124951 5.56086673 2.56749961 2 P 0 ;0,1,2=154,3=0.000000
L 5.56086673 2.56749961 5.5606001 2.56374961 2 P 0 ;0,1,2=154,3=0.000000
L 5.5606001 2.56374961 5.5598002 2.56041624 2 P 0 ;0,1,2=154,3=0.000000
L 5.5598002 2.56041624 5.55873337 2.55791604 2 P 0 ;0,1,2=154,3=0.000000
L 5.55873337 2.55791604 5.55713366 2.55583307 2 P 0 ;0,1,2=154,3=0.000000
L 5.55713366 2.55583307 5.5550003 2.555 2 P 0 ;0,1,2=154,3=0.000000
L 5.5550003 2.555 5.55286693 2.55583307 2 P 0 ;0,1,2=154,3=0.000000
L 5.55286693 2.55583307 5.55126673 2.55791604 2 P 0 ;0,1,2=154,3=0.000000
L 5.55126673 2.55791604 5.5501999 2.56041624 2 P 0 ;0,1,2=154,3=0.000000
L 5.5501999 2.56041624 5.5494 2.56374961 2 P 0 ;0,1,2=154,3=0.000000
L 5.5494 2.56374961 5.54913337 2.56749961 2 P 0 ;0,1,2=154,3=0.000000
L 5.54913337 2.56749961 5.5494 2.57124951 2 P 0 ;0,1,2=154,3=0.000000
L 5.5494 2.57124951 5.5501999 2.57458366 2 P 0 ;0,1,2=154,3=0.000000
L 5.5501999 2.57458366 5.55126673 2.57708317 2 P 0 ;0,1,2=154,3=0.000000
L 5.55126673 2.57708317 5.55286693 2.57916683 2 P 0 ;0,1,2=154,3=0.000000
L 5.55286693 2.57916683 5.5550003 2.58 2 P 0 ;0,1,2=154,3=0.000000
A 5.48308996 1.9894 5.48308996 1.9894 5.48058002 1.9894 1 P 0 N
L 5.71613337 2.00291634 5.71773356 2.00416683 2 P 0 ;0,1,2=155,3=0.000000
L 5.71773356 2.00416683 5.7195998 2.005 2 P 0 ;0,1,2=155,3=0.000000
L 5.7195998 2.005 5.72173317 2.005 2 P 0 ;0,1,2=155,3=0.000000
L 5.72173317 2.005 5.72413366 2.00374941 2 P 0 ;0,1,2=155,3=0.000000
L 5.72413366 2.00374941 5.7259999 2.00166654 2 P 0 ;0,1,2=155,3=0.000000
L 5.7259999 2.00166654 5.72733346 1.99916634 2 P 0 ;0,1,2=155,3=0.000000
L 5.72733346 1.99916634 5.72840039 1.9949998 2 P 0 ;0,1,2=155,3=0.000000
L 5.72840039 1.9949998 5.72866703 1.9912498 2 P 0 ;0,1,2=155,3=0.000000
L 5.72866703 1.9912498 5.72813327 1.9874999 2 P 0 ;0,1,2=155,3=0.000000
L 5.72813327 1.9874999 5.72733346 1.98499961 2 P 0 ;0,1,2=155,3=0.000000
L 5.72733346 1.98499961 5.72573337 1.98249941 2 P 0 ;0,1,2=155,3=0.000000
L 5.72573337 1.98249941 5.72386654 1.98083307 2 P 0 ;0,1,2=155,3=0.000000
L 5.72386654 1.98083307 5.7220003 1.98 2 P 0 ;0,1,2=155,3=0.000000
L 5.7220003 1.98 5.72013356 1.98 2 P 0 ;0,1,2=155,3=0.000000
L 5.72013356 1.98 5.71826673 1.98083307 2 P 0 ;0,1,2=155,3=0.000000
L 5.71826673 1.98083307 5.71666663 1.98208287 2 P 0 ;0,1,2=155,3=0.000000
L 5.71666663 1.98208287 5.71533307 1.98374911 2 P 0 ;0,1,2=155,3=0.000000
L 5.6948 1.98 5.6948 2.005 2 P 0 ;0,1,2=155,3=0.000000
L 5.6948 2.005 5.70466703 1.98708327 2 P 0 ;0,1,2=155,3=0.000000
L 5.70466703 1.98708327 5.69133307 1.98708327 2 P 0 ;0,1,2=155,3=0.000000
L 5.67906683 2.00083337 5.67746673 2.00333287 2 P 0 ;0,1,2=155,3=0.000000
L 5.67746673 2.00333287 5.6756 2.00458337 2 P 0 ;0,1,2=155,3=0.000000
L 5.6756 2.00458337 5.67346663 2.005 2 P 0 ;0,1,2=155,3=0.000000
L 5.67346663 2.005 5.6708 2.00416683 2 P 0 ;0,1,2=155,3=0.000000
L 5.6708 2.00416683 5.66893327 2.00208317 2 P 0 ;0,1,2=155,3=0.000000
L 5.66893327 2.00208317 5.6684 1.99958366 2 P 0 ;0,1,2=155,3=0.000000
L 5.6684 1.99958366 5.66866663 1.99708268 2 P 0 ;0,1,2=155,3=0.000000
L 5.66866663 1.99708268 5.66973356 1.9949998 2 P 0 ;0,1,2=155,3=0.000000
L 5.66973356 1.9949998 5.67506673 1.99083327 2 P 0 ;0,1,2=155,3=0.000000
L 5.67506673 1.99083327 5.67746673 1.98791644 2 P 0 ;0,1,2=155,3=0.000000
L 5.67746673 1.98791644 5.67906683 1.98374911 2 P 0 ;0,1,2=155,3=0.000000
L 5.67906683 1.98374911 5.6796001 1.98 2 P 0 ;0,1,2=155,3=0.000000
L 5.6796001 1.98 5.6684 1.98 2 P 0 ;0,1,2=155,3=0.000000
L 5.6500003 1.98 5.6500003 2.005 2 P 0 ;0,1,2=155,3=0.000000
L 5.6500003 2.005 5.6532001 2.0000003 2 P 0 ;0,1,2=155,3=0.000000
L 5.6532001 1.98 5.64680049 1.98 2 P 0 ;0,1,2=155,3=0.000000
A 5.48308996 2.0853 5.48308996 2.0853 5.48058002 2.0853 1 P 0 N
L 5.71613337 2.10791634 5.71773356 2.10916683 2 P 0 ;0,1,2=156,3=0.000000
L 5.71773356 2.10916683 5.7195998 2.11 2 P 0 ;0,1,2=156,3=0.000000
L 5.7195998 2.11 5.72173317 2.11 2 P 0 ;0,1,2=156,3=0.000000
L 5.72173317 2.11 5.72413366 2.10874941 2 P 0 ;0,1,2=156,3=0.000000
L 5.72413366 2.10874941 5.7259999 2.10666654 2 P 0 ;0,1,2=156,3=0.000000
L 5.7259999 2.10666654 5.72733346 2.10416634 2 P 0 ;0,1,2=156,3=0.000000
L 5.72733346 2.10416634 5.72840039 2.0999998 2 P 0 ;0,1,2=156,3=0.000000
L 5.72840039 2.0999998 5.72866703 2.0962498 2 P 0 ;0,1,2=156,3=0.000000
L 5.72866703 2.0962498 5.72813327 2.0924999 2 P 0 ;0,1,2=156,3=0.000000
L 5.72813327 2.0924999 5.72733346 2.08999961 2 P 0 ;0,1,2=156,3=0.000000
L 5.72733346 2.08999961 5.72573337 2.08749941 2 P 0 ;0,1,2=156,3=0.000000
L 5.72573337 2.08749941 5.72386654 2.08583307 2 P 0 ;0,1,2=156,3=0.000000
L 5.72386654 2.08583307 5.7220003 2.085 2 P 0 ;0,1,2=156,3=0.000000
L 5.7220003 2.085 5.72013356 2.085 2 P 0 ;0,1,2=156,3=0.000000
L 5.72013356 2.085 5.71826673 2.08583307 2 P 0 ;0,1,2=156,3=0.000000
L 5.71826673 2.08583307 5.71666663 2.08708287 2 P 0 ;0,1,2=156,3=0.000000
L 5.71666663 2.08708287 5.71533307 2.08874911 2 P 0 ;0,1,2=156,3=0.000000
L 5.6948 2.085 5.6948 2.11 2 P 0 ;0,1,2=156,3=0.000000
L 5.6948 2.11 5.70466703 2.09208327 2 P 0 ;0,1,2=156,3=0.000000
L 5.70466703 2.09208327 5.69133307 2.09208327 2 P 0 ;0,1,2=156,3=0.000000
L 5.67906683 2.10583337 5.67746673 2.10833287 2 P 0 ;0,1,2=156,3=0.000000
L 5.67746673 2.10833287 5.6756 2.10958337 2 P 0 ;0,1,2=156,3=0.000000
L 5.6756 2.10958337 5.67346663 2.11 2 P 0 ;0,1,2=156,3=0.000000
L 5.67346663 2.11 5.6708 2.10916683 2 P 0 ;0,1,2=156,3=0.000000
L 5.6708 2.10916683 5.66893327 2.10708317 2 P 0 ;0,1,2=156,3=0.000000
L 5.66893327 2.10708317 5.6684 2.10458366 2 P 0 ;0,1,2=156,3=0.000000
L 5.6684 2.10458366 5.66866663 2.10208268 2 P 0 ;0,1,2=156,3=0.000000
L 5.66866663 2.10208268 5.66973356 2.0999998 2 P 0 ;0,1,2=156,3=0.000000
L 5.66973356 2.0999998 5.67506673 2.09583327 2 P 0 ;0,1,2=156,3=0.000000
L 5.67506673 2.09583327 5.67746673 2.09291644 2 P 0 ;0,1,2=156,3=0.000000
L 5.67746673 2.09291644 5.67906683 2.08874911 2 P 0 ;0,1,2=156,3=0.000000
L 5.67906683 2.08874911 5.6796001 2.085 2 P 0 ;0,1,2=156,3=0.000000
L 5.6796001 2.085 5.6684 2.085 2 P 0 ;0,1,2=156,3=0.000000
L 5.6468 2.085 5.6468 2.11 2 P 0 ;0,1,2=156,3=0.000000
L 5.6468 2.11 5.65666703 2.09208327 2 P 0 ;0,1,2=156,3=0.000000
L 5.65666703 2.09208327 5.64333307 2.09208327 2 P 0 ;0,1,2=156,3=0.000000
A 5.48308996 2.1303 5.48308996 2.1303 5.48058002 2.1303 1 P 0 N
L 5.71613337 2.14291634 5.71773356 2.14416683 2 P 0 ;0,1,2=157,3=0.000000
L 5.71773356 2.14416683 5.7195998 2.145 2 P 0 ;0,1,2=157,3=0.000000
L 5.7195998 2.145 5.72173317 2.145 2 P 0 ;0,1,2=157,3=0.000000
L 5.72173317 2.145 5.72413366 2.14374941 2 P 0 ;0,1,2=157,3=0.000000
L 5.72413366 2.14374941 5.7259999 2.14166654 2 P 0 ;0,1,2=157,3=0.000000
L 5.7259999 2.14166654 5.72733346 2.13916634 2 P 0 ;0,1,2=157,3=0.000000
L 5.72733346 2.13916634 5.72840039 2.1349998 2 P 0 ;0,1,2=157,3=0.000000
L 5.72840039 2.1349998 5.72866703 2.1312498 2 P 0 ;0,1,2=157,3=0.000000
L 5.72866703 2.1312498 5.72813327 2.1274999 2 P 0 ;0,1,2=157,3=0.000000
L 5.72813327 2.1274999 5.72733346 2.12499961 2 P 0 ;0,1,2=157,3=0.000000
L 5.72733346 2.12499961 5.72573337 2.12249941 2 P 0 ;0,1,2=157,3=0.000000
L 5.72573337 2.12249941 5.72386654 2.12083307 2 P 0 ;0,1,2=157,3=0.000000
L 5.72386654 2.12083307 5.7220003 2.12 2 P 0 ;0,1,2=157,3=0.000000
L 5.7220003 2.12 5.72013356 2.12 2 P 0 ;0,1,2=157,3=0.000000
L 5.72013356 2.12 5.71826673 2.12083307 2 P 0 ;0,1,2=157,3=0.000000
L 5.71826673 2.12083307 5.71666663 2.12208287 2 P 0 ;0,1,2=157,3=0.000000
L 5.71666663 2.12208287 5.71533307 2.12374911 2 P 0 ;0,1,2=157,3=0.000000
L 5.6948 2.12 5.6948 2.145 2 P 0 ;0,1,2=157,3=0.000000
L 5.6948 2.145 5.70466703 2.12708327 2 P 0 ;0,1,2=157,3=0.000000
L 5.70466703 2.12708327 5.69133307 2.12708327 2 P 0 ;0,1,2=157,3=0.000000
A 5.48308996 1.9444 5.48308996 1.9444 5.48058002 1.9444 1 P 0 N
L 5.71613337 1.96791634 5.71773356 1.96916683 2 P 0 ;0,1,2=158,3=0.000000
L 5.71773356 1.96916683 5.7195998 1.97 2 P 0 ;0,1,2=158,3=0.000000
L 5.7195998 1.97 5.72173317 1.97 2 P 0 ;0,1,2=158,3=0.000000
L 5.72173317 1.97 5.72413366 1.96874941 2 P 0 ;0,1,2=158,3=0.000000
L 5.72413366 1.96874941 5.7259999 1.96666654 2 P 0 ;0,1,2=158,3=0.000000
L 5.7259999 1.96666654 5.72733346 1.96416634 2 P 0 ;0,1,2=158,3=0.000000
L 5.72733346 1.96416634 5.72840039 1.9599998 2 P 0 ;0,1,2=158,3=0.000000
L 5.72840039 1.9599998 5.72866703 1.9562498 2 P 0 ;0,1,2=158,3=0.000000
L 5.72866703 1.9562498 5.72813327 1.9524999 2 P 0 ;0,1,2=158,3=0.000000
L 5.72813327 1.9524999 5.72733346 1.94999961 2 P 0 ;0,1,2=158,3=0.000000
L 5.72733346 1.94999961 5.72573337 1.94749941 2 P 0 ;0,1,2=158,3=0.000000
L 5.72573337 1.94749941 5.72386654 1.94583307 2 P 0 ;0,1,2=158,3=0.000000
L 5.72386654 1.94583307 5.7220003 1.945 2 P 0 ;0,1,2=158,3=0.000000
L 5.7220003 1.945 5.72013356 1.945 2 P 0 ;0,1,2=158,3=0.000000
L 5.72013356 1.945 5.71826673 1.94583307 2 P 0 ;0,1,2=158,3=0.000000
L 5.71826673 1.94583307 5.71666663 1.94708287 2 P 0 ;0,1,2=158,3=0.000000
L 5.71666663 1.94708287 5.71533307 1.94874911 2 P 0 ;0,1,2=158,3=0.000000
L 5.70386673 1.94999961 5.70226703 1.94708287 2 P 0 ;0,1,2=158,3=0.000000
L 5.70226703 1.94708287 5.70013366 1.94541654 2 P 0 ;0,1,2=158,3=0.000000
L 5.70013366 1.94541654 5.69773317 1.945 2 P 0 ;0,1,2=158,3=0.000000
L 5.69773317 1.945 5.6955998 1.94541654 2 P 0 ;0,1,2=158,3=0.000000
L 5.6955998 1.94541654 5.69346644 1.94749941 2 P 0 ;0,1,2=158,3=0.000000
L 5.69346644 1.94749941 5.69213337 1.94999961 2 P 0 ;0,1,2=158,3=0.000000
L 5.69213337 1.94999961 5.69186683 1.9524999 2 P 0 ;0,1,2=158,3=0.000000
L 5.69186683 1.9524999 5.6924 1.95541594 2 P 0 ;0,1,2=158,3=0.000000
L 5.6924 1.95541594 5.69426673 1.95749961 2 P 0 ;0,1,2=158,3=0.000000
L 5.69426673 1.95749961 5.69613356 1.95833346 2 P 0 ;0,1,2=158,3=0.000000
L 5.69613356 1.95833346 5.69853346 1.95833346 2 P 0 ;0,1,2=158,3=0.000000
L 5.69613356 1.95833346 5.69453337 1.95958327 2 P 0 ;0,1,2=158,3=0.000000
L 5.69453337 1.95958327 5.6931999 1.96166614 2 P 0 ;0,1,2=158,3=0.000000
L 5.6931999 1.96166614 5.69266663 1.96416634 2 P 0 ;0,1,2=158,3=0.000000
L 5.69266663 1.96416634 5.6931999 1.96666654 2 P 0 ;0,1,2=158,3=0.000000
L 5.6931999 1.96666654 5.69453337 1.96874941 2 P 0 ;0,1,2=158,3=0.000000
L 5.69453337 1.96874941 5.69693337 1.97 2 P 0 ;0,1,2=158,3=0.000000
L 5.69693337 1.97 5.69933337 1.96958337 2 P 0 ;0,1,2=158,3=0.000000
L 5.69933337 1.96958337 5.70173337 1.96791634 2 P 0 ;0,1,2=158,3=0.000000
A 5.48308996 2.2657 5.48308996 2.2657 5.48058002 2.2657 1 P 0 N
L 5.71613337 2.26791634 5.71773356 2.26916683 2 P 0 ;0,1,2=159,3=0.000000
L 5.71773356 2.26916683 5.7195998 2.27 2 P 0 ;0,1,2=159,3=0.000000
L 5.7195998 2.27 5.72173317 2.27 2 P 0 ;0,1,2=159,3=0.000000
L 5.72173317 2.27 5.72413366 2.26874941 2 P 0 ;0,1,2=159,3=0.000000
L 5.72413366 2.26874941 5.7259999 2.26666654 2 P 0 ;0,1,2=159,3=0.000000
L 5.7259999 2.26666654 5.72733346 2.26416634 2 P 0 ;0,1,2=159,3=0.000000
L 5.72733346 2.26416634 5.72840039 2.2599998 2 P 0 ;0,1,2=159,3=0.000000
L 5.72840039 2.2599998 5.72866703 2.2562498 2 P 0 ;0,1,2=159,3=0.000000
L 5.72866703 2.2562498 5.72813327 2.2524999 2 P 0 ;0,1,2=159,3=0.000000
L 5.72813327 2.2524999 5.72733346 2.24999961 2 P 0 ;0,1,2=159,3=0.000000
L 5.72733346 2.24999961 5.72573337 2.24749941 2 P 0 ;0,1,2=159,3=0.000000
L 5.72573337 2.24749941 5.72386654 2.24583307 2 P 0 ;0,1,2=159,3=0.000000
L 5.72386654 2.24583307 5.7220003 2.245 2 P 0 ;0,1,2=159,3=0.000000
L 5.7220003 2.245 5.72013356 2.245 2 P 0 ;0,1,2=159,3=0.000000
L 5.72013356 2.245 5.71826673 2.24583307 2 P 0 ;0,1,2=159,3=0.000000
L 5.71826673 2.24583307 5.71666663 2.24708287 2 P 0 ;0,1,2=159,3=0.000000
L 5.71666663 2.24708287 5.71533307 2.24874911 2 P 0 ;0,1,2=159,3=0.000000
L 5.6948 2.245 5.6948 2.27 2 P 0 ;0,1,2=159,3=0.000000
L 5.6948 2.27 5.70466703 2.25208327 2 P 0 ;0,1,2=159,3=0.000000
L 5.70466703 2.25208327 5.69133307 2.25208327 2 P 0 ;0,1,2=159,3=0.000000
L 5.67906683 2.26583337 5.67746673 2.26833287 2 P 0 ;0,1,2=159,3=0.000000
L 5.67746673 2.26833287 5.6756 2.26958337 2 P 0 ;0,1,2=159,3=0.000000
L 5.6756 2.26958337 5.67346663 2.27 2 P 0 ;0,1,2=159,3=0.000000
L 5.67346663 2.27 5.6708 2.26916683 2 P 0 ;0,1,2=159,3=0.000000
L 5.6708 2.26916683 5.66893327 2.26708317 2 P 0 ;0,1,2=159,3=0.000000
L 5.66893327 2.26708317 5.6684 2.26458366 2 P 0 ;0,1,2=159,3=0.000000
L 5.6684 2.26458366 5.66866663 2.26208268 2 P 0 ;0,1,2=159,3=0.000000
L 5.66866663 2.26208268 5.66973356 2.2599998 2 P 0 ;0,1,2=159,3=0.000000
L 5.66973356 2.2599998 5.67506673 2.25583327 2 P 0 ;0,1,2=159,3=0.000000
L 5.67506673 2.25583327 5.67746673 2.25291644 2 P 0 ;0,1,2=159,3=0.000000
L 5.67746673 2.25291644 5.67906683 2.24874911 2 P 0 ;0,1,2=159,3=0.000000
L 5.67906683 2.24874911 5.6796001 2.245 2 P 0 ;0,1,2=159,3=0.000000
L 5.6796001 2.245 5.6684 2.245 2 P 0 ;0,1,2=159,3=0.000000
L 5.65586673 2.24874911 5.65426703 2.24666624 2 P 0 ;0,1,2=159,3=0.000000
L 5.65426703 2.24666624 5.6524003 2.24541654 2 P 0 ;0,1,2=159,3=0.000000
L 5.6524003 2.24541654 5.6500003 2.245 2 P 0 ;0,1,2=159,3=0.000000
L 5.6500003 2.245 5.6475998 2.24583307 2 P 0 ;0,1,2=159,3=0.000000
L 5.6475998 2.24583307 5.64573356 2.24749941 2 P 0 ;0,1,2=159,3=0.000000
L 5.64573356 2.24749941 5.6444 2.25041624 2 P 0 ;0,1,2=159,3=0.000000
L 5.6444 2.25041624 5.64413337 2.25374961 2 P 0 ;0,1,2=159,3=0.000000
L 5.64413337 2.25374961 5.64466663 2.25708297 2 P 0 ;0,1,2=159,3=0.000000
L 5.64466663 2.25708297 5.6460002 2.25916663 2 P 0 ;0,1,2=159,3=0.000000
L 5.6460002 2.25916663 5.64786693 2.26083297 2 P 0 ;0,1,2=159,3=0.000000
L 5.64786693 2.26083297 5.64973317 2.26124951 2 P 0 ;0,1,2=159,3=0.000000
L 5.64973317 2.26124951 5.6516 2.26083297 2 P 0 ;0,1,2=159,3=0.000000
L 5.6516 2.26083297 5.6539999 2.25916663 2 P 0 ;0,1,2=159,3=0.000000
L 5.6539999 2.25916663 5.6532001 2.27 2 P 0 ;0,1,2=159,3=0.000000
L 5.6532001 2.27 5.6460002 2.27 2 P 0 ;0,1,2=159,3=0.000000
A 5.48308996 2.2207 5.48308996 2.2207 5.48058002 2.2207 1 P 0 N
L 5.71613337 2.23291634 5.71773356 2.23416683 2 P 0 ;0,1,2=160,3=0.000000
L 5.71773356 2.23416683 5.7195998 2.235 2 P 0 ;0,1,2=160,3=0.000000
L 5.7195998 2.235 5.72173317 2.235 2 P 0 ;0,1,2=160,3=0.000000
L 5.72173317 2.235 5.72413366 2.23374941 2 P 0 ;0,1,2=160,3=0.000000
L 5.72413366 2.23374941 5.7259999 2.23166654 2 P 0 ;0,1,2=160,3=0.000000
L 5.7259999 2.23166654 5.72733346 2.22916634 2 P 0 ;0,1,2=160,3=0.000000
L 5.72733346 2.22916634 5.72840039 2.2249998 2 P 0 ;0,1,2=160,3=0.000000
L 5.72840039 2.2249998 5.72866703 2.2212498 2 P 0 ;0,1,2=160,3=0.000000
L 5.72866703 2.2212498 5.72813327 2.2174999 2 P 0 ;0,1,2=160,3=0.000000
L 5.72813327 2.2174999 5.72733346 2.21499961 2 P 0 ;0,1,2=160,3=0.000000
L 5.72733346 2.21499961 5.72573337 2.21249941 2 P 0 ;0,1,2=160,3=0.000000
L 5.72573337 2.21249941 5.72386654 2.21083307 2 P 0 ;0,1,2=160,3=0.000000
L 5.72386654 2.21083307 5.7220003 2.21 2 P 0 ;0,1,2=160,3=0.000000
L 5.7220003 2.21 5.72013356 2.21 2 P 0 ;0,1,2=160,3=0.000000
L 5.72013356 2.21 5.71826673 2.21083307 2 P 0 ;0,1,2=160,3=0.000000
L 5.71826673 2.21083307 5.71666663 2.21208287 2 P 0 ;0,1,2=160,3=0.000000
L 5.71666663 2.21208287 5.71533307 2.21374911 2 P 0 ;0,1,2=160,3=0.000000
L 5.6948 2.21 5.6948 2.235 2 P 0 ;0,1,2=160,3=0.000000
L 5.6948 2.235 5.70466703 2.21708327 2 P 0 ;0,1,2=160,3=0.000000
L 5.70466703 2.21708327 5.69133307 2.21708327 2 P 0 ;0,1,2=160,3=0.000000
L 5.67906683 2.23083337 5.67746673 2.23333287 2 P 0 ;0,1,2=160,3=0.000000
L 5.67746673 2.23333287 5.6756 2.23458337 2 P 0 ;0,1,2=160,3=0.000000
L 5.6756 2.23458337 5.67346663 2.235 2 P 0 ;0,1,2=160,3=0.000000
L 5.67346663 2.235 5.6708 2.23416683 2 P 0 ;0,1,2=160,3=0.000000
L 5.6708 2.23416683 5.66893327 2.23208317 2 P 0 ;0,1,2=160,3=0.000000
L 5.66893327 2.23208317 5.6684 2.22958366 2 P 0 ;0,1,2=160,3=0.000000
L 5.6684 2.22958366 5.66866663 2.22708268 2 P 0 ;0,1,2=160,3=0.000000
L 5.66866663 2.22708268 5.66973356 2.2249998 2 P 0 ;0,1,2=160,3=0.000000
L 5.66973356 2.2249998 5.67506673 2.22083327 2 P 0 ;0,1,2=160,3=0.000000
L 5.67506673 2.22083327 5.67746673 2.21791644 2 P 0 ;0,1,2=160,3=0.000000
L 5.67746673 2.21791644 5.67906683 2.21374911 2 P 0 ;0,1,2=160,3=0.000000
L 5.67906683 2.21374911 5.6796001 2.21 2 P 0 ;0,1,2=160,3=0.000000
L 5.6796001 2.21 5.6684 2.21 2 P 0 ;0,1,2=160,3=0.000000
L 5.65506683 2.22041594 5.6532001 2.22333346 2 P 0 ;0,1,2=160,3=0.000000
L 5.6532001 2.22333346 5.6516 2.2249998 2 P 0 ;0,1,2=160,3=0.000000
L 5.6516 2.2249998 5.64946663 2.22583297 2 P 0 ;0,1,2=160,3=0.000000
L 5.64946663 2.22583297 5.6475998 2.2249998 2 P 0 ;0,1,2=160,3=0.000000
L 5.6475998 2.2249998 5.64626673 2.22333346 2 P 0 ;0,1,2=160,3=0.000000
L 5.64626673 2.22333346 5.6451999 2.22083327 2 P 0 ;0,1,2=160,3=0.000000
L 5.6451999 2.22083327 5.64493327 2.21791644 2 P 0 ;0,1,2=160,3=0.000000
L 5.64493327 2.21791644 5.6451999 2.21541624 2 P 0 ;0,1,2=160,3=0.000000
L 5.6451999 2.21541624 5.64626673 2.21291604 2 P 0 ;0,1,2=160,3=0.000000
L 5.64626673 2.21291604 5.64786693 2.21083307 2 P 0 ;0,1,2=160,3=0.000000
L 5.64786693 2.21083307 5.64973317 2.21 2 P 0 ;0,1,2=160,3=0.000000
L 5.64973317 2.21 5.65186654 2.21083307 2 P 0 ;0,1,2=160,3=0.000000
L 5.65186654 2.21083307 5.65373337 2.21333258 2 P 0 ;0,1,2=160,3=0.000000
L 5.65373337 2.21333258 5.6548002 2.21708327 2 P 0 ;0,1,2=160,3=0.000000
L 5.6548002 2.21708327 5.65506683 2.2212498 2 P 0 ;0,1,2=160,3=0.000000
L 5.65506683 2.2212498 5.65453366 2.22666614 2 P 0 ;0,1,2=160,3=0.000000
L 5.65453366 2.22666614 5.65373337 2.22958366 2 P 0 ;0,1,2=160,3=0.000000
L 5.65373337 2.22958366 5.6524003 2.2324997 2 P 0 ;0,1,2=160,3=0.000000
L 5.6524003 2.2324997 5.65053346 2.23458337 2 P 0 ;0,1,2=160,3=0.000000
L 5.65053346 2.23458337 5.64866673 2.235 2 P 0 ;0,1,2=160,3=0.000000
L 5.64866673 2.235 5.6468 2.23416683 2 P 0 ;0,1,2=160,3=0.000000
L 5.6468 2.23416683 5.64546644 2.23208317 2 P 0 ;0,1,2=160,3=0.000000
A 5.48308996 2.4011 5.48308996 2.4011 5.48058002 2.4011 1 P 0 N
L 5.71113337 2.40291634 5.71273356 2.40416683 2 P 0 ;0,1,2=161,3=0.000000
L 5.71273356 2.40416683 5.7145998 2.405 2 P 0 ;0,1,2=161,3=0.000000
L 5.7145998 2.405 5.71673317 2.405 2 P 0 ;0,1,2=161,3=0.000000
L 5.71673317 2.405 5.71913366 2.40374941 2 P 0 ;0,1,2=161,3=0.000000
L 5.71913366 2.40374941 5.7209999 2.40166654 2 P 0 ;0,1,2=161,3=0.000000
L 5.7209999 2.40166654 5.72233346 2.39916634 2 P 0 ;0,1,2=161,3=0.000000
L 5.72233346 2.39916634 5.72340039 2.3949998 2 P 0 ;0,1,2=161,3=0.000000
L 5.72340039 2.3949998 5.72366703 2.3912498 2 P 0 ;0,1,2=161,3=0.000000
L 5.72366703 2.3912498 5.72313327 2.3874999 2 P 0 ;0,1,2=161,3=0.000000
L 5.72313327 2.3874999 5.72233346 2.38499961 2 P 0 ;0,1,2=161,3=0.000000
L 5.72233346 2.38499961 5.72073337 2.38249941 2 P 0 ;0,1,2=161,3=0.000000
L 5.72073337 2.38249941 5.71886654 2.38083307 2 P 0 ;0,1,2=161,3=0.000000
L 5.71886654 2.38083307 5.7170003 2.38 2 P 0 ;0,1,2=161,3=0.000000
L 5.7170003 2.38 5.71513356 2.38 2 P 0 ;0,1,2=161,3=0.000000
L 5.71513356 2.38 5.71326673 2.38083307 2 P 0 ;0,1,2=161,3=0.000000
L 5.71326673 2.38083307 5.71166663 2.38208287 2 P 0 ;0,1,2=161,3=0.000000
L 5.71166663 2.38208287 5.71033307 2.38374911 2 P 0 ;0,1,2=161,3=0.000000
L 5.6898 2.38 5.6898 2.405 2 P 0 ;0,1,2=161,3=0.000000
L 5.6898 2.405 5.69966703 2.38708327 2 P 0 ;0,1,2=161,3=0.000000
L 5.69966703 2.38708327 5.68633307 2.38708327 2 P 0 ;0,1,2=161,3=0.000000
L 5.67486673 2.38499961 5.67326703 2.38208287 2 P 0 ;0,1,2=161,3=0.000000
L 5.67326703 2.38208287 5.67113366 2.38041654 2 P 0 ;0,1,2=161,3=0.000000
L 5.67113366 2.38041654 5.66873317 2.38 2 P 0 ;0,1,2=161,3=0.000000
L 5.66873317 2.38 5.6665998 2.38041654 2 P 0 ;0,1,2=161,3=0.000000
L 5.6665998 2.38041654 5.66446644 2.38249941 2 P 0 ;0,1,2=161,3=0.000000
L 5.66446644 2.38249941 5.66313337 2.38499961 2 P 0 ;0,1,2=161,3=0.000000
L 5.66313337 2.38499961 5.66286683 2.3874999 2 P 0 ;0,1,2=161,3=0.000000
L 5.66286683 2.3874999 5.6634 2.39041594 2 P 0 ;0,1,2=161,3=0.000000
L 5.6634 2.39041594 5.66526673 2.39249961 2 P 0 ;0,1,2=161,3=0.000000
L 5.66526673 2.39249961 5.66713356 2.39333346 2 P 0 ;0,1,2=161,3=0.000000
L 5.66713356 2.39333346 5.66953346 2.39333346 2 P 0 ;0,1,2=161,3=0.000000
L 5.66713356 2.39333346 5.66553337 2.39458327 2 P 0 ;0,1,2=161,3=0.000000
L 5.66553337 2.39458327 5.6641999 2.39666614 2 P 0 ;0,1,2=161,3=0.000000
L 5.6641999 2.39666614 5.66366663 2.39916634 2 P 0 ;0,1,2=161,3=0.000000
L 5.66366663 2.39916634 5.6641999 2.40166654 2 P 0 ;0,1,2=161,3=0.000000
L 5.6641999 2.40166654 5.66553337 2.40374941 2 P 0 ;0,1,2=161,3=0.000000
L 5.66553337 2.40374941 5.66793337 2.405 2 P 0 ;0,1,2=161,3=0.000000
L 5.66793337 2.405 5.67033337 2.40458337 2 P 0 ;0,1,2=161,3=0.000000
L 5.67033337 2.40458337 5.67273337 2.40291634 2 P 0 ;0,1,2=161,3=0.000000
L 5.6450003 2.38 5.6450003 2.405 2 P 0 ;0,1,2=161,3=0.000000
L 5.6450003 2.405 5.6482001 2.4000003 2 P 0 ;0,1,2=161,3=0.000000
L 5.6482001 2.38 5.64180049 2.38 2 P 0 ;0,1,2=161,3=0.000000
A 5.48308996 2.3561 5.48308996 2.3561 5.48058002 2.3561 1 P 0 N
L 5.71113337 2.36791634 5.71273356 2.36916683 2 P 0 ;0,1,2=162,3=0.000000
L 5.71273356 2.36916683 5.7145998 2.37 2 P 0 ;0,1,2=162,3=0.000000
L 5.7145998 2.37 5.71673317 2.37 2 P 0 ;0,1,2=162,3=0.000000
L 5.71673317 2.37 5.71913366 2.36874941 2 P 0 ;0,1,2=162,3=0.000000
L 5.71913366 2.36874941 5.7209999 2.36666654 2 P 0 ;0,1,2=162,3=0.000000
L 5.7209999 2.36666654 5.72233346 2.36416634 2 P 0 ;0,1,2=162,3=0.000000
L 5.72233346 2.36416634 5.72340039 2.3599998 2 P 0 ;0,1,2=162,3=0.000000
L 5.72340039 2.3599998 5.72366703 2.3562498 2 P 0 ;0,1,2=162,3=0.000000
L 5.72366703 2.3562498 5.72313327 2.3524999 2 P 0 ;0,1,2=162,3=0.000000
L 5.72313327 2.3524999 5.72233346 2.34999961 2 P 0 ;0,1,2=162,3=0.000000
L 5.72233346 2.34999961 5.72073337 2.34749941 2 P 0 ;0,1,2=162,3=0.000000
L 5.72073337 2.34749941 5.71886654 2.34583307 2 P 0 ;0,1,2=162,3=0.000000
L 5.71886654 2.34583307 5.7170003 2.345 2 P 0 ;0,1,2=162,3=0.000000
L 5.7170003 2.345 5.71513356 2.345 2 P 0 ;0,1,2=162,3=0.000000
L 5.71513356 2.345 5.71326673 2.34583307 2 P 0 ;0,1,2=162,3=0.000000
L 5.71326673 2.34583307 5.71166663 2.34708287 2 P 0 ;0,1,2=162,3=0.000000
L 5.71166663 2.34708287 5.71033307 2.34874911 2 P 0 ;0,1,2=162,3=0.000000
L 5.6898 2.345 5.6898 2.37 2 P 0 ;0,1,2=162,3=0.000000
L 5.6898 2.37 5.69966703 2.35208327 2 P 0 ;0,1,2=162,3=0.000000
L 5.69966703 2.35208327 5.68633307 2.35208327 2 P 0 ;0,1,2=162,3=0.000000
L 5.67486673 2.34999961 5.67326703 2.34708287 2 P 0 ;0,1,2=162,3=0.000000
L 5.67326703 2.34708287 5.67113366 2.34541654 2 P 0 ;0,1,2=162,3=0.000000
L 5.67113366 2.34541654 5.66873317 2.345 2 P 0 ;0,1,2=162,3=0.000000
L 5.66873317 2.345 5.6665998 2.34541654 2 P 0 ;0,1,2=162,3=0.000000
L 5.6665998 2.34541654 5.66446644 2.34749941 2 P 0 ;0,1,2=162,3=0.000000
L 5.66446644 2.34749941 5.66313337 2.34999961 2 P 0 ;0,1,2=162,3=0.000000
L 5.66313337 2.34999961 5.66286683 2.3524999 2 P 0 ;0,1,2=162,3=0.000000
L 5.66286683 2.3524999 5.6634 2.35541594 2 P 0 ;0,1,2=162,3=0.000000
L 5.6634 2.35541594 5.66526673 2.35749961 2 P 0 ;0,1,2=162,3=0.000000
L 5.66526673 2.35749961 5.66713356 2.35833346 2 P 0 ;0,1,2=162,3=0.000000
L 5.66713356 2.35833346 5.66953346 2.35833346 2 P 0 ;0,1,2=162,3=0.000000
L 5.66713356 2.35833346 5.66553337 2.35958327 2 P 0 ;0,1,2=162,3=0.000000
L 5.66553337 2.35958327 5.6641999 2.36166614 2 P 0 ;0,1,2=162,3=0.000000
L 5.6641999 2.36166614 5.66366663 2.36416634 2 P 0 ;0,1,2=162,3=0.000000
L 5.66366663 2.36416634 5.6641999 2.36666654 2 P 0 ;0,1,2=162,3=0.000000
L 5.6641999 2.36666654 5.66553337 2.36874941 2 P 0 ;0,1,2=162,3=0.000000
L 5.66553337 2.36874941 5.66793337 2.37 2 P 0 ;0,1,2=162,3=0.000000
L 5.66793337 2.37 5.67033337 2.36958337 2 P 0 ;0,1,2=162,3=0.000000
L 5.67033337 2.36958337 5.67273337 2.36791634 2 P 0 ;0,1,2=162,3=0.000000
L 5.65006683 2.36583337 5.64846673 2.36833287 2 P 0 ;0,1,2=162,3=0.000000
L 5.64846673 2.36833287 5.6466 2.36958337 2 P 0 ;0,1,2=162,3=0.000000
L 5.6466 2.36958337 5.64446663 2.37 2 P 0 ;0,1,2=162,3=0.000000
L 5.64446663 2.37 5.6418 2.36916683 2 P 0 ;0,1,2=162,3=0.000000
L 5.6418 2.36916683 5.63993327 2.36708317 2 P 0 ;0,1,2=162,3=0.000000
L 5.63993327 2.36708317 5.6394 2.36458366 2 P 0 ;0,1,2=162,3=0.000000
L 5.6394 2.36458366 5.63966663 2.36208268 2 P 0 ;0,1,2=162,3=0.000000
L 5.63966663 2.36208268 5.64073356 2.3599998 2 P 0 ;0,1,2=162,3=0.000000
L 5.64073356 2.3599998 5.64606673 2.35583327 2 P 0 ;0,1,2=162,3=0.000000
L 5.64606673 2.35583327 5.64846673 2.35291644 2 P 0 ;0,1,2=162,3=0.000000
L 5.64846673 2.35291644 5.65006683 2.34874911 2 P 0 ;0,1,2=162,3=0.000000
L 5.65006683 2.34874911 5.6506001 2.345 2 P 0 ;0,1,2=162,3=0.000000
L 5.6506001 2.345 5.6394 2.345 2 P 0 ;0,1,2=162,3=0.000000
A 5.48308996 2.5403 5.48308996 2.5403 5.48058002 2.5403 1 P 0 N
L 5.71113337 2.54291634 5.71273356 2.54416683 2 P 0 ;0,1,2=163,3=0.000000
L 5.71273356 2.54416683 5.7145998 2.545 2 P 0 ;0,1,2=163,3=0.000000
L 5.7145998 2.545 5.71673317 2.545 2 P 0 ;0,1,2=163,3=0.000000
L 5.71673317 2.545 5.71913366 2.54374941 2 P 0 ;0,1,2=163,3=0.000000
L 5.71913366 2.54374941 5.7209999 2.54166654 2 P 0 ;0,1,2=163,3=0.000000
L 5.7209999 2.54166654 5.72233346 2.53916634 2 P 0 ;0,1,2=163,3=0.000000
L 5.72233346 2.53916634 5.72340039 2.5349998 2 P 0 ;0,1,2=163,3=0.000000
L 5.72340039 2.5349998 5.72366703 2.5312498 2 P 0 ;0,1,2=163,3=0.000000
L 5.72366703 2.5312498 5.72313327 2.5274999 2 P 0 ;0,1,2=163,3=0.000000
L 5.72313327 2.5274999 5.72233346 2.52499961 2 P 0 ;0,1,2=163,3=0.000000
L 5.72233346 2.52499961 5.72073337 2.52249941 2 P 0 ;0,1,2=163,3=0.000000
L 5.72073337 2.52249941 5.71886654 2.52083307 2 P 0 ;0,1,2=163,3=0.000000
L 5.71886654 2.52083307 5.7170003 2.52 2 P 0 ;0,1,2=163,3=0.000000
L 5.7170003 2.52 5.71513356 2.52 2 P 0 ;0,1,2=163,3=0.000000
L 5.71513356 2.52 5.71326673 2.52083307 2 P 0 ;0,1,2=163,3=0.000000
L 5.71326673 2.52083307 5.71166663 2.52208287 2 P 0 ;0,1,2=163,3=0.000000
L 5.71166663 2.52208287 5.71033307 2.52374911 2 P 0 ;0,1,2=163,3=0.000000
L 5.6898 2.52 5.6898 2.545 2 P 0 ;0,1,2=163,3=0.000000
L 5.6898 2.545 5.69966703 2.52708327 2 P 0 ;0,1,2=163,3=0.000000
L 5.69966703 2.52708327 5.68633307 2.52708327 2 P 0 ;0,1,2=163,3=0.000000
L 5.67486673 2.52499961 5.67326703 2.52208287 2 P 0 ;0,1,2=163,3=0.000000
L 5.67326703 2.52208287 5.67113366 2.52041654 2 P 0 ;0,1,2=163,3=0.000000
L 5.67113366 2.52041654 5.66873317 2.52 2 P 0 ;0,1,2=163,3=0.000000
L 5.66873317 2.52 5.6665998 2.52041654 2 P 0 ;0,1,2=163,3=0.000000
L 5.6665998 2.52041654 5.66446644 2.52249941 2 P 0 ;0,1,2=163,3=0.000000
L 5.66446644 2.52249941 5.66313337 2.52499961 2 P 0 ;0,1,2=163,3=0.000000
L 5.66313337 2.52499961 5.66286683 2.5274999 2 P 0 ;0,1,2=163,3=0.000000
L 5.66286683 2.5274999 5.6634 2.53041594 2 P 0 ;0,1,2=163,3=0.000000
L 5.6634 2.53041594 5.66526673 2.53249961 2 P 0 ;0,1,2=163,3=0.000000
L 5.66526673 2.53249961 5.66713356 2.53333346 2 P 0 ;0,1,2=163,3=0.000000
L 5.66713356 2.53333346 5.66953346 2.53333346 2 P 0 ;0,1,2=163,3=0.000000
L 5.66713356 2.53333346 5.66553337 2.53458327 2 P 0 ;0,1,2=163,3=0.000000
L 5.66553337 2.53458327 5.6641999 2.53666614 2 P 0 ;0,1,2=163,3=0.000000
L 5.6641999 2.53666614 5.66366663 2.53916634 2 P 0 ;0,1,2=163,3=0.000000
L 5.66366663 2.53916634 5.6641999 2.54166654 2 P 0 ;0,1,2=163,3=0.000000
L 5.6641999 2.54166654 5.66553337 2.54374941 2 P 0 ;0,1,2=163,3=0.000000
L 5.66553337 2.54374941 5.66793337 2.545 2 P 0 ;0,1,2=163,3=0.000000
L 5.66793337 2.545 5.67033337 2.54458337 2 P 0 ;0,1,2=163,3=0.000000
L 5.67033337 2.54458337 5.67273337 2.54291634 2 P 0 ;0,1,2=163,3=0.000000
L 5.65086673 2.52374911 5.64926703 2.52166624 2 P 0 ;0,1,2=163,3=0.000000
L 5.64926703 2.52166624 5.6474003 2.52041654 2 P 0 ;0,1,2=163,3=0.000000
L 5.6474003 2.52041654 5.6450003 2.52 2 P 0 ;0,1,2=163,3=0.000000
L 5.6450003 2.52 5.6425998 2.52083307 2 P 0 ;0,1,2=163,3=0.000000
L 5.6425998 2.52083307 5.64073356 2.52249941 2 P 0 ;0,1,2=163,3=0.000000
L 5.64073356 2.52249941 5.6394 2.52541624 2 P 0 ;0,1,2=163,3=0.000000
L 5.6394 2.52541624 5.63913337 2.52874961 2 P 0 ;0,1,2=163,3=0.000000
L 5.63913337 2.52874961 5.63966663 2.53208297 2 P 0 ;0,1,2=163,3=0.000000
L 5.63966663 2.53208297 5.6410002 2.53416663 2 P 0 ;0,1,2=163,3=0.000000
L 5.6410002 2.53416663 5.64286693 2.53583297 2 P 0 ;0,1,2=163,3=0.000000
L 5.64286693 2.53583297 5.64473317 2.53624951 2 P 0 ;0,1,2=163,3=0.000000
L 5.64473317 2.53624951 5.6466 2.53583297 2 P 0 ;0,1,2=163,3=0.000000
L 5.6466 2.53583297 5.6489999 2.53416663 2 P 0 ;0,1,2=163,3=0.000000
L 5.6489999 2.53416663 5.6482001 2.545 2 P 0 ;0,1,2=163,3=0.000000
L 5.6482001 2.545 5.6410002 2.545 2 P 0 ;0,1,2=163,3=0.000000
A 5.48308996 2.4953 5.48308996 2.4953 5.48058002 2.4953 1 P 0 N
L 5.71113337 2.50791634 5.71273356 2.50916683 2 P 0 ;0,1,2=164,3=0.000000
L 5.71273356 2.50916683 5.7145998 2.51 2 P 0 ;0,1,2=164,3=0.000000
L 5.7145998 2.51 5.71673317 2.51 2 P 0 ;0,1,2=164,3=0.000000
L 5.71673317 2.51 5.71913366 2.50874941 2 P 0 ;0,1,2=164,3=0.000000
L 5.71913366 2.50874941 5.7209999 2.50666654 2 P 0 ;0,1,2=164,3=0.000000
L 5.7209999 2.50666654 5.72233346 2.50416634 2 P 0 ;0,1,2=164,3=0.000000
L 5.72233346 2.50416634 5.72340039 2.4999998 2 P 0 ;0,1,2=164,3=0.000000
L 5.72340039 2.4999998 5.72366703 2.4962498 2 P 0 ;0,1,2=164,3=0.000000
L 5.72366703 2.4962498 5.72313327 2.4924999 2 P 0 ;0,1,2=164,3=0.000000
L 5.72313327 2.4924999 5.72233346 2.48999961 2 P 0 ;0,1,2=164,3=0.000000
L 5.72233346 2.48999961 5.72073337 2.48749941 2 P 0 ;0,1,2=164,3=0.000000
L 5.72073337 2.48749941 5.71886654 2.48583307 2 P 0 ;0,1,2=164,3=0.000000
L 5.71886654 2.48583307 5.7170003 2.485 2 P 0 ;0,1,2=164,3=0.000000
L 5.7170003 2.485 5.71513356 2.485 2 P 0 ;0,1,2=164,3=0.000000
L 5.71513356 2.485 5.71326673 2.48583307 2 P 0 ;0,1,2=164,3=0.000000
L 5.71326673 2.48583307 5.71166663 2.48708287 2 P 0 ;0,1,2=164,3=0.000000
L 5.71166663 2.48708287 5.71033307 2.48874911 2 P 0 ;0,1,2=164,3=0.000000
L 5.6898 2.485 5.6898 2.51 2 P 0 ;0,1,2=164,3=0.000000
L 5.6898 2.51 5.69966703 2.49208327 2 P 0 ;0,1,2=164,3=0.000000
L 5.69966703 2.49208327 5.68633307 2.49208327 2 P 0 ;0,1,2=164,3=0.000000
L 5.67486673 2.48999961 5.67326703 2.48708287 2 P 0 ;0,1,2=164,3=0.000000
L 5.67326703 2.48708287 5.67113366 2.48541654 2 P 0 ;0,1,2=164,3=0.000000
L 5.67113366 2.48541654 5.66873317 2.485 2 P 0 ;0,1,2=164,3=0.000000
L 5.66873317 2.485 5.6665998 2.48541654 2 P 0 ;0,1,2=164,3=0.000000
L 5.6665998 2.48541654 5.66446644 2.48749941 2 P 0 ;0,1,2=164,3=0.000000
L 5.66446644 2.48749941 5.66313337 2.48999961 2 P 0 ;0,1,2=164,3=0.000000
L 5.66313337 2.48999961 5.66286683 2.4924999 2 P 0 ;0,1,2=164,3=0.000000
L 5.66286683 2.4924999 5.6634 2.49541594 2 P 0 ;0,1,2=164,3=0.000000
L 5.6634 2.49541594 5.66526673 2.49749961 2 P 0 ;0,1,2=164,3=0.000000
L 5.66526673 2.49749961 5.66713356 2.49833346 2 P 0 ;0,1,2=164,3=0.000000
L 5.66713356 2.49833346 5.66953346 2.49833346 2 P 0 ;0,1,2=164,3=0.000000
L 5.66713356 2.49833346 5.66553337 2.49958327 2 P 0 ;0,1,2=164,3=0.000000
L 5.66553337 2.49958327 5.6641999 2.50166614 2 P 0 ;0,1,2=164,3=0.000000
L 5.6641999 2.50166614 5.66366663 2.50416634 2 P 0 ;0,1,2=164,3=0.000000
L 5.66366663 2.50416634 5.6641999 2.50666654 2 P 0 ;0,1,2=164,3=0.000000
L 5.6641999 2.50666654 5.66553337 2.50874941 2 P 0 ;0,1,2=164,3=0.000000
L 5.66553337 2.50874941 5.66793337 2.51 2 P 0 ;0,1,2=164,3=0.000000
L 5.66793337 2.51 5.67033337 2.50958337 2 P 0 ;0,1,2=164,3=0.000000
L 5.67033337 2.50958337 5.67273337 2.50791634 2 P 0 ;0,1,2=164,3=0.000000
L 5.65006683 2.49541594 5.6482001 2.49833346 2 P 0 ;0,1,2=164,3=0.000000
L 5.6482001 2.49833346 5.6466 2.4999998 2 P 0 ;0,1,2=164,3=0.000000
L 5.6466 2.4999998 5.64446663 2.50083297 2 P 0 ;0,1,2=164,3=0.000000
L 5.64446663 2.50083297 5.6425998 2.4999998 2 P 0 ;0,1,2=164,3=0.000000
L 5.6425998 2.4999998 5.64126673 2.49833346 2 P 0 ;0,1,2=164,3=0.000000
L 5.64126673 2.49833346 5.6401999 2.49583327 2 P 0 ;0,1,2=164,3=0.000000
L 5.6401999 2.49583327 5.63993327 2.49291644 2 P 0 ;0,1,2=164,3=0.000000
L 5.63993327 2.49291644 5.6401999 2.49041624 2 P 0 ;0,1,2=164,3=0.000000
L 5.6401999 2.49041624 5.64126673 2.48791604 2 P 0 ;0,1,2=164,3=0.000000
L 5.64126673 2.48791604 5.64286693 2.48583307 2 P 0 ;0,1,2=164,3=0.000000
L 5.64286693 2.48583307 5.64473317 2.485 2 P 0 ;0,1,2=164,3=0.000000
L 5.64473317 2.485 5.64686654 2.48583307 2 P 0 ;0,1,2=164,3=0.000000
L 5.64686654 2.48583307 5.64873337 2.48833258 2 P 0 ;0,1,2=164,3=0.000000
L 5.64873337 2.48833258 5.6498002 2.49208327 2 P 0 ;0,1,2=164,3=0.000000
L 5.6498002 2.49208327 5.65006683 2.4962498 2 P 0 ;0,1,2=164,3=0.000000
L 5.65006683 2.4962498 5.64953366 2.50166614 2 P 0 ;0,1,2=164,3=0.000000
L 5.64953366 2.50166614 5.64873337 2.50458366 2 P 0 ;0,1,2=164,3=0.000000
L 5.64873337 2.50458366 5.6474003 2.5074997 2 P 0 ;0,1,2=164,3=0.000000
L 5.6474003 2.5074997 5.64553346 2.50958337 2 P 0 ;0,1,2=164,3=0.000000
L 5.64553346 2.50958337 5.64366673 2.51 2 P 0 ;0,1,2=164,3=0.000000
L 5.64366673 2.51 5.6418 2.50916683 2 P 0 ;0,1,2=164,3=0.000000
L 5.6418 2.50916683 5.64046644 2.50708317 2 P 0 ;0,1,2=164,3=0.000000
A 5.48308996 2.6305 5.48308996 2.6305 5.48058002 2.6305 1 P 0 N
L 5.71613337 2.65291634 5.71773356 2.65416683 2 P 0 ;0,1,2=165,3=0.000000
L 5.71773356 2.65416683 5.7195998 2.655 2 P 0 ;0,1,2=165,3=0.000000
L 5.7195998 2.655 5.72173317 2.655 2 P 0 ;0,1,2=165,3=0.000000
L 5.72173317 2.655 5.72413366 2.65374941 2 P 0 ;0,1,2=165,3=0.000000
L 5.72413366 2.65374941 5.7259999 2.65166654 2 P 0 ;0,1,2=165,3=0.000000
L 5.7259999 2.65166654 5.72733346 2.64916634 2 P 0 ;0,1,2=165,3=0.000000
L 5.72733346 2.64916634 5.72840039 2.6449998 2 P 0 ;0,1,2=165,3=0.000000
L 5.72840039 2.6449998 5.72866703 2.6412498 2 P 0 ;0,1,2=165,3=0.000000
L 5.72866703 2.6412498 5.72813327 2.6374999 2 P 0 ;0,1,2=165,3=0.000000
L 5.72813327 2.6374999 5.72733346 2.63499961 2 P 0 ;0,1,2=165,3=0.000000
L 5.72733346 2.63499961 5.72573337 2.63249941 2 P 0 ;0,1,2=165,3=0.000000
L 5.72573337 2.63249941 5.72386654 2.63083307 2 P 0 ;0,1,2=165,3=0.000000
L 5.72386654 2.63083307 5.7220003 2.63 2 P 0 ;0,1,2=165,3=0.000000
L 5.7220003 2.63 5.72013356 2.63 2 P 0 ;0,1,2=165,3=0.000000
L 5.72013356 2.63 5.71826673 2.63083307 2 P 0 ;0,1,2=165,3=0.000000
L 5.71826673 2.63083307 5.71666663 2.63208287 2 P 0 ;0,1,2=165,3=0.000000
L 5.71666663 2.63208287 5.71533307 2.63374911 2 P 0 ;0,1,2=165,3=0.000000
L 5.6948 2.63 5.6948 2.655 2 P 0 ;0,1,2=165,3=0.000000
L 5.6948 2.655 5.70466703 2.63708327 2 P 0 ;0,1,2=165,3=0.000000
L 5.70466703 2.63708327 5.69133307 2.63708327 2 P 0 ;0,1,2=165,3=0.000000
L 5.67986673 2.63499961 5.67826703 2.63208287 2 P 0 ;0,1,2=165,3=0.000000
L 5.67826703 2.63208287 5.67613366 2.63041654 2 P 0 ;0,1,2=165,3=0.000000
L 5.67613366 2.63041654 5.67373317 2.63 2 P 0 ;0,1,2=165,3=0.000000
L 5.67373317 2.63 5.6715998 2.63041654 2 P 0 ;0,1,2=165,3=0.000000
L 5.6715998 2.63041654 5.66946644 2.63249941 2 P 0 ;0,1,2=165,3=0.000000
L 5.66946644 2.63249941 5.66813337 2.63499961 2 P 0 ;0,1,2=165,3=0.000000
L 5.66813337 2.63499961 5.66786683 2.6374999 2 P 0 ;0,1,2=165,3=0.000000
L 5.66786683 2.6374999 5.6684 2.64041594 2 P 0 ;0,1,2=165,3=0.000000
L 5.6684 2.64041594 5.67026673 2.64249961 2 P 0 ;0,1,2=165,3=0.000000
L 5.67026673 2.64249961 5.67213356 2.64333346 2 P 0 ;0,1,2=165,3=0.000000
L 5.67213356 2.64333346 5.67453346 2.64333346 2 P 0 ;0,1,2=165,3=0.000000
L 5.67213356 2.64333346 5.67053337 2.64458327 2 P 0 ;0,1,2=165,3=0.000000
L 5.67053337 2.64458327 5.6691999 2.64666614 2 P 0 ;0,1,2=165,3=0.000000
L 5.6691999 2.64666614 5.66866663 2.64916634 2 P 0 ;0,1,2=165,3=0.000000
L 5.66866663 2.64916634 5.6691999 2.65166654 2 P 0 ;0,1,2=165,3=0.000000
L 5.6691999 2.65166654 5.67053337 2.65374941 2 P 0 ;0,1,2=165,3=0.000000
L 5.67053337 2.65374941 5.67293337 2.655 2 P 0 ;0,1,2=165,3=0.000000
L 5.67293337 2.655 5.67533337 2.65458337 2 P 0 ;0,1,2=165,3=0.000000
L 5.67533337 2.65458337 5.67773337 2.65291634 2 P 0 ;0,1,2=165,3=0.000000
L 5.6500003 2.63 5.64813356 2.63041654 2 P 0 ;0,1,2=165,3=0.000000
L 5.64813356 2.63041654 5.6460002 2.63166624 2 P 0 ;0,1,2=165,3=0.000000
L 5.6460002 2.63166624 5.64466663 2.63374911 2 P 0 ;0,1,2=165,3=0.000000
L 5.64466663 2.63374911 5.64413337 2.63666673 2 P 0 ;0,1,2=165,3=0.000000
L 5.64413337 2.63666673 5.64466663 2.63958278 2 P 0 ;0,1,2=165,3=0.000000
L 5.64466663 2.63958278 5.64626673 2.64208297 2 P 0 ;0,1,2=165,3=0.000000
L 5.64626673 2.64208297 5.64866673 2.64333346 2 P 0 ;0,1,2=165,3=0.000000
L 5.64866673 2.64333346 5.65133337 2.64333346 2 P 0 ;0,1,2=165,3=0.000000
L 5.65133337 2.64333346 5.65293346 2.64416663 2 P 0 ;0,1,2=165,3=0.000000
L 5.65293346 2.64416663 5.65426703 2.64624951 2 P 0 ;0,1,2=165,3=0.000000
L 5.65426703 2.64624951 5.6548002 2.64916634 2 P 0 ;0,1,2=165,3=0.000000
L 5.6548002 2.64916634 5.6539999 2.65208317 2 P 0 ;0,1,2=165,3=0.000000
L 5.6539999 2.65208317 5.65213366 2.65416683 2 P 0 ;0,1,2=165,3=0.000000
L 5.65213366 2.65416683 5.6500003 2.655 2 P 0 ;0,1,2=165,3=0.000000
L 5.6500003 2.655 5.64786693 2.65416683 2 P 0 ;0,1,2=165,3=0.000000
L 5.64786693 2.65416683 5.6460002 2.65208317 2 P 0 ;0,1,2=165,3=0.000000
L 5.6460002 2.65208317 5.6451999 2.64916634 2 P 0 ;0,1,2=165,3=0.000000
L 5.6451999 2.64916634 5.64573356 2.64624951 2 P 0 ;0,1,2=165,3=0.000000
L 5.64573356 2.64624951 5.64706663 2.64416663 2 P 0 ;0,1,2=165,3=0.000000
L 5.64706663 2.64416663 5.64866673 2.64333346 2 P 0 ;0,1,2=165,3=0.000000
L 5.64866673 2.64333346 5.65133337 2.64333346 2 P 0 ;0,1,2=165,3=0.000000
L 5.65133337 2.64333346 5.65373337 2.64208297 2 P 0 ;0,1,2=165,3=0.000000
L 5.65373337 2.64208297 5.65533346 2.63958278 2 P 0 ;0,1,2=165,3=0.000000
L 5.65533346 2.63958278 5.65586673 2.63666673 2 P 0 ;0,1,2=165,3=0.000000
L 5.65586673 2.63666673 5.65533346 2.63374911 2 P 0 ;0,1,2=165,3=0.000000
L 5.65533346 2.63374911 5.6539999 2.63166624 2 P 0 ;0,1,2=165,3=0.000000
L 5.6539999 2.63166624 5.65186654 2.63041654 2 P 0 ;0,1,2=165,3=0.000000
L 5.65186654 2.63041654 5.6500003 2.63 2 P 0 ;0,1,2=165,3=0.000000
A 5.48308996 2.6755 5.48308996 2.6755 5.48058002 2.6755 1 P 0 N
L 5.71613337 2.68791634 5.71773356 2.68916683 2 P 0 ;0,1,2=166,3=0.000000
L 5.71773356 2.68916683 5.7195998 2.69 2 P 0 ;0,1,2=166,3=0.000000
L 5.7195998 2.69 5.72173317 2.69 2 P 0 ;0,1,2=166,3=0.000000
L 5.72173317 2.69 5.72413366 2.68874941 2 P 0 ;0,1,2=166,3=0.000000
L 5.72413366 2.68874941 5.7259999 2.68666654 2 P 0 ;0,1,2=166,3=0.000000
L 5.7259999 2.68666654 5.72733346 2.68416634 2 P 0 ;0,1,2=166,3=0.000000
L 5.72733346 2.68416634 5.72840039 2.6799998 2 P 0 ;0,1,2=166,3=0.000000
L 5.72840039 2.6799998 5.72866703 2.6762498 2 P 0 ;0,1,2=166,3=0.000000
L 5.72866703 2.6762498 5.72813327 2.6724999 2 P 0 ;0,1,2=166,3=0.000000
L 5.72813327 2.6724999 5.72733346 2.66999961 2 P 0 ;0,1,2=166,3=0.000000
L 5.72733346 2.66999961 5.72573337 2.66749941 2 P 0 ;0,1,2=166,3=0.000000
L 5.72573337 2.66749941 5.72386654 2.66583307 2 P 0 ;0,1,2=166,3=0.000000
L 5.72386654 2.66583307 5.7220003 2.665 2 P 0 ;0,1,2=166,3=0.000000
L 5.7220003 2.665 5.72013356 2.665 2 P 0 ;0,1,2=166,3=0.000000
L 5.72013356 2.665 5.71826673 2.66583307 2 P 0 ;0,1,2=166,3=0.000000
L 5.71826673 2.66583307 5.71666663 2.66708287 2 P 0 ;0,1,2=166,3=0.000000
L 5.71666663 2.66708287 5.71533307 2.66874911 2 P 0 ;0,1,2=166,3=0.000000
L 5.6948 2.665 5.6948 2.69 2 P 0 ;0,1,2=166,3=0.000000
L 5.6948 2.69 5.70466703 2.67208327 2 P 0 ;0,1,2=166,3=0.000000
L 5.70466703 2.67208327 5.69133307 2.67208327 2 P 0 ;0,1,2=166,3=0.000000
L 5.67986673 2.66999961 5.67826703 2.66708287 2 P 0 ;0,1,2=166,3=0.000000
L 5.67826703 2.66708287 5.67613366 2.66541654 2 P 0 ;0,1,2=166,3=0.000000
L 5.67613366 2.66541654 5.67373317 2.665 2 P 0 ;0,1,2=166,3=0.000000
L 5.67373317 2.665 5.6715998 2.66541654 2 P 0 ;0,1,2=166,3=0.000000
L 5.6715998 2.66541654 5.66946644 2.66749941 2 P 0 ;0,1,2=166,3=0.000000
L 5.66946644 2.66749941 5.66813337 2.66999961 2 P 0 ;0,1,2=166,3=0.000000
L 5.66813337 2.66999961 5.66786683 2.6724999 2 P 0 ;0,1,2=166,3=0.000000
L 5.66786683 2.6724999 5.6684 2.67541594 2 P 0 ;0,1,2=166,3=0.000000
L 5.6684 2.67541594 5.67026673 2.67749961 2 P 0 ;0,1,2=166,3=0.000000
L 5.67026673 2.67749961 5.67213356 2.67833346 2 P 0 ;0,1,2=166,3=0.000000
L 5.67213356 2.67833346 5.67453346 2.67833346 2 P 0 ;0,1,2=166,3=0.000000
L 5.67213356 2.67833346 5.67053337 2.67958327 2 P 0 ;0,1,2=166,3=0.000000
L 5.67053337 2.67958327 5.6691999 2.68166614 2 P 0 ;0,1,2=166,3=0.000000
L 5.6691999 2.68166614 5.66866663 2.68416634 2 P 0 ;0,1,2=166,3=0.000000
L 5.66866663 2.68416634 5.6691999 2.68666654 2 P 0 ;0,1,2=166,3=0.000000
L 5.6691999 2.68666654 5.67053337 2.68874941 2 P 0 ;0,1,2=166,3=0.000000
L 5.67053337 2.68874941 5.67293337 2.69 2 P 0 ;0,1,2=166,3=0.000000
L 5.67293337 2.69 5.67533337 2.68958337 2 P 0 ;0,1,2=166,3=0.000000
L 5.67533337 2.68958337 5.67773337 2.68791634 2 P 0 ;0,1,2=166,3=0.000000
L 5.65053346 2.665 5.6500003 2.67041624 2 P 0 ;0,1,2=166,3=0.000000
L 5.6500003 2.67041624 5.6492 2.67499931 2 P 0 ;0,1,2=166,3=0.000000
L 5.6492 2.67499931 5.64813356 2.67916663 2 P 0 ;0,1,2=166,3=0.000000
L 5.64813356 2.67916663 5.6468 2.6837498 2 P 0 ;0,1,2=166,3=0.000000
L 5.6468 2.6837498 5.64466663 2.69 2 P 0 ;0,1,2=166,3=0.000000
L 5.64466663 2.69 5.65533346 2.69 2 P 0 ;0,1,2=166,3=0.000000
A 5.48308996 1.6693 5.48308996 1.6693 5.48058002 1.6693 1 P 0 N
L 5.71613337 1.68791634 5.71773356 1.68916683 2 P 0 ;0,1,2=167,3=0.000000
L 5.71773356 1.68916683 5.7195998 1.69 2 P 0 ;0,1,2=167,3=0.000000
L 5.7195998 1.69 5.72173317 1.69 2 P 0 ;0,1,2=167,3=0.000000
L 5.72173317 1.69 5.72413366 1.68874941 2 P 0 ;0,1,2=167,3=0.000000
L 5.72413366 1.68874941 5.7259999 1.68666654 2 P 0 ;0,1,2=167,3=0.000000
L 5.7259999 1.68666654 5.72733346 1.68416634 2 P 0 ;0,1,2=167,3=0.000000
L 5.72733346 1.68416634 5.72840039 1.6799998 2 P 0 ;0,1,2=167,3=0.000000
L 5.72840039 1.6799998 5.72866703 1.6762498 2 P 0 ;0,1,2=167,3=0.000000
L 5.72866703 1.6762498 5.72813327 1.6724999 2 P 0 ;0,1,2=167,3=0.000000
L 5.72813327 1.6724999 5.72733346 1.66999961 2 P 0 ;0,1,2=167,3=0.000000
L 5.72733346 1.66999961 5.72573337 1.66749941 2 P 0 ;0,1,2=167,3=0.000000
L 5.72573337 1.66749941 5.72386654 1.66583307 2 P 0 ;0,1,2=167,3=0.000000
L 5.72386654 1.66583307 5.7220003 1.665 2 P 0 ;0,1,2=167,3=0.000000
L 5.7220003 1.665 5.72013356 1.665 2 P 0 ;0,1,2=167,3=0.000000
L 5.72013356 1.665 5.71826673 1.66583307 2 P 0 ;0,1,2=167,3=0.000000
L 5.71826673 1.66583307 5.71666663 1.66708287 2 P 0 ;0,1,2=167,3=0.000000
L 5.71666663 1.66708287 5.71533307 1.66874911 2 P 0 ;0,1,2=167,3=0.000000
L 5.70306683 1.68583337 5.70146673 1.68833287 2 P 0 ;0,1,2=167,3=0.000000
L 5.70146673 1.68833287 5.6996 1.68958337 2 P 0 ;0,1,2=167,3=0.000000
L 5.6996 1.68958337 5.69746663 1.69 2 P 0 ;0,1,2=167,3=0.000000
L 5.69746663 1.69 5.6948 1.68916683 2 P 0 ;0,1,2=167,3=0.000000
L 5.6948 1.68916683 5.69293327 1.68708317 2 P 0 ;0,1,2=167,3=0.000000
L 5.69293327 1.68708317 5.6924 1.68458366 2 P 0 ;0,1,2=167,3=0.000000
L 5.6924 1.68458366 5.69266663 1.68208268 2 P 0 ;0,1,2=167,3=0.000000
L 5.69266663 1.68208268 5.69373356 1.6799998 2 P 0 ;0,1,2=167,3=0.000000
L 5.69373356 1.6799998 5.69906673 1.67583327 2 P 0 ;0,1,2=167,3=0.000000
L 5.69906673 1.67583327 5.70146673 1.67291644 2 P 0 ;0,1,2=167,3=0.000000
L 5.70146673 1.67291644 5.70306683 1.66874911 2 P 0 ;0,1,2=167,3=0.000000
L 5.70306683 1.66874911 5.7036001 1.665 2 P 0 ;0,1,2=167,3=0.000000
L 5.7036001 1.665 5.6924 1.665 2 P 0 ;0,1,2=167,3=0.000000
L 5.67906683 1.68583337 5.67746673 1.68833287 2 P 0 ;0,1,2=167,3=0.000000
L 5.67746673 1.68833287 5.6756 1.68958337 2 P 0 ;0,1,2=167,3=0.000000
L 5.6756 1.68958337 5.67346663 1.69 2 P 0 ;0,1,2=167,3=0.000000
L 5.67346663 1.69 5.6708 1.68916683 2 P 0 ;0,1,2=167,3=0.000000
L 5.6708 1.68916683 5.66893327 1.68708317 2 P 0 ;0,1,2=167,3=0.000000
L 5.66893327 1.68708317 5.6684 1.68458366 2 P 0 ;0,1,2=167,3=0.000000
L 5.6684 1.68458366 5.66866663 1.68208268 2 P 0 ;0,1,2=167,3=0.000000
L 5.66866663 1.68208268 5.66973356 1.6799998 2 P 0 ;0,1,2=167,3=0.000000
L 5.66973356 1.6799998 5.67506673 1.67583327 2 P 0 ;0,1,2=167,3=0.000000
L 5.67506673 1.67583327 5.67746673 1.67291644 2 P 0 ;0,1,2=167,3=0.000000
L 5.67746673 1.67291644 5.67906683 1.66874911 2 P 0 ;0,1,2=167,3=0.000000
L 5.67906683 1.66874911 5.6796001 1.665 2 P 0 ;0,1,2=167,3=0.000000
L 5.6796001 1.665 5.6684 1.665 2 P 0 ;0,1,2=167,3=0.000000
L 5.65586673 1.66999961 5.65426703 1.66708287 2 P 0 ;0,1,2=167,3=0.000000
L 5.65426703 1.66708287 5.65213366 1.66541654 2 P 0 ;0,1,2=167,3=0.000000
L 5.65213366 1.66541654 5.64973317 1.665 2 P 0 ;0,1,2=167,3=0.000000
L 5.64973317 1.665 5.6475998 1.66541654 2 P 0 ;0,1,2=167,3=0.000000
L 5.6475998 1.66541654 5.64546644 1.66749941 2 P 0 ;0,1,2=167,3=0.000000
L 5.64546644 1.66749941 5.64413337 1.66999961 2 P 0 ;0,1,2=167,3=0.000000
L 5.64413337 1.66999961 5.64386683 1.6724999 2 P 0 ;0,1,2=167,3=0.000000
L 5.64386683 1.6724999 5.6444 1.67541594 2 P 0 ;0,1,2=167,3=0.000000
L 5.6444 1.67541594 5.64626673 1.67749961 2 P 0 ;0,1,2=167,3=0.000000
L 5.64626673 1.67749961 5.64813356 1.67833346 2 P 0 ;0,1,2=167,3=0.000000
L 5.64813356 1.67833346 5.65053346 1.67833346 2 P 0 ;0,1,2=167,3=0.000000
L 5.64813356 1.67833346 5.64653337 1.67958327 2 P 0 ;0,1,2=167,3=0.000000
L 5.64653337 1.67958327 5.6451999 1.68166614 2 P 0 ;0,1,2=167,3=0.000000
L 5.6451999 1.68166614 5.64466663 1.68416634 2 P 0 ;0,1,2=167,3=0.000000
L 5.64466663 1.68416634 5.6451999 1.68666654 2 P 0 ;0,1,2=167,3=0.000000
L 5.6451999 1.68666654 5.64653337 1.68874941 2 P 0 ;0,1,2=167,3=0.000000
L 5.64653337 1.68874941 5.64893337 1.69 2 P 0 ;0,1,2=167,3=0.000000
L 5.64893337 1.69 5.65133337 1.68958337 2 P 0 ;0,1,2=167,3=0.000000
L 5.65133337 1.68958337 5.65373337 1.68791634 2 P 0 ;0,1,2=167,3=0.000000
L 5.62653346 1.665 5.6260003 1.67041624 2 P 0 ;0,1,2=167,3=0.000000
L 5.6260003 1.67041624 5.6252 1.67499931 2 P 0 ;0,1,2=167,3=0.000000
L 5.6252 1.67499931 5.62413356 1.67916663 2 P 0 ;0,1,2=167,3=0.000000
L 5.62413356 1.67916663 5.6228 1.6837498 2 P 0 ;0,1,2=167,3=0.000000
L 5.6228 1.6837498 5.62066663 1.69 2 P 0 ;0,1,2=167,3=0.000000
L 5.62066663 1.69 5.63133346 1.69 2 P 0 ;0,1,2=167,3=0.000000
A 5.32826004 1.6008 5.32826004 1.6008 5.32575 1.6008 1 P 0 N
L 5.61113337 1.60791634 5.61273356 1.60916683 2 P 0 ;0,1,2=168,3=0.000000
L 5.61273356 1.60916683 5.6145998 1.61 2 P 0 ;0,1,2=168,3=0.000000
L 5.6145998 1.61 5.61673317 1.61 2 P 0 ;0,1,2=168,3=0.000000
L 5.61673317 1.61 5.61913366 1.60874941 2 P 0 ;0,1,2=168,3=0.000000
L 5.61913366 1.60874941 5.6209999 1.60666654 2 P 0 ;0,1,2=168,3=0.000000
L 5.6209999 1.60666654 5.62233346 1.60416634 2 P 0 ;0,1,2=168,3=0.000000
L 5.62233346 1.60416634 5.62340039 1.5999998 2 P 0 ;0,1,2=168,3=0.000000
L 5.62340039 1.5999998 5.62366703 1.5962498 2 P 0 ;0,1,2=168,3=0.000000
L 5.62366703 1.5962498 5.62313327 1.5924999 2 P 0 ;0,1,2=168,3=0.000000
L 5.62313327 1.5924999 5.62233346 1.58999961 2 P 0 ;0,1,2=168,3=0.000000
L 5.62233346 1.58999961 5.62073337 1.58749941 2 P 0 ;0,1,2=168,3=0.000000
L 5.62073337 1.58749941 5.61886654 1.58583307 2 P 0 ;0,1,2=168,3=0.000000
L 5.61886654 1.58583307 5.6170003 1.585 2 P 0 ;0,1,2=168,3=0.000000
L 5.6170003 1.585 5.61513356 1.585 2 P 0 ;0,1,2=168,3=0.000000
L 5.61513356 1.585 5.61326673 1.58583307 2 P 0 ;0,1,2=168,3=0.000000
L 5.61326673 1.58583307 5.61166663 1.58708287 2 P 0 ;0,1,2=168,3=0.000000
L 5.61166663 1.58708287 5.61033307 1.58874911 2 P 0 ;0,1,2=168,3=0.000000
L 5.5930003 1.585 5.5930003 1.61 2 P 0 ;0,1,2=168,3=0.000000
L 5.5930003 1.61 5.5962001 1.6050003 2 P 0 ;0,1,2=168,3=0.000000
L 5.5962001 1.585 5.58980049 1.585 2 P 0 ;0,1,2=168,3=0.000000
A 5.32826004 1.7821 5.32826004 1.7821 5.32575 1.7821 1 P 0 N
L 5.61113337 1.79291634 5.61273356 1.79416683 2 P 0 ;0,1,2=169,3=0.000000
L 5.61273356 1.79416683 5.6145998 1.795 2 P 0 ;0,1,2=169,3=0.000000
L 5.6145998 1.795 5.61673317 1.795 2 P 0 ;0,1,2=169,3=0.000000
L 5.61673317 1.795 5.61913366 1.79374941 2 P 0 ;0,1,2=169,3=0.000000
L 5.61913366 1.79374941 5.6209999 1.79166654 2 P 0 ;0,1,2=169,3=0.000000
L 5.6209999 1.79166654 5.62233346 1.78916634 2 P 0 ;0,1,2=169,3=0.000000
L 5.62233346 1.78916634 5.62340039 1.7849998 2 P 0 ;0,1,2=169,3=0.000000
L 5.62340039 1.7849998 5.62366703 1.7812498 2 P 0 ;0,1,2=169,3=0.000000
L 5.62366703 1.7812498 5.62313327 1.7774999 2 P 0 ;0,1,2=169,3=0.000000
L 5.62313327 1.7774999 5.62233346 1.77499961 2 P 0 ;0,1,2=169,3=0.000000
L 5.62233346 1.77499961 5.62073337 1.77249941 2 P 0 ;0,1,2=169,3=0.000000
L 5.62073337 1.77249941 5.61886654 1.77083307 2 P 0 ;0,1,2=169,3=0.000000
L 5.61886654 1.77083307 5.6170003 1.77 2 P 0 ;0,1,2=169,3=0.000000
L 5.6170003 1.77 5.61513356 1.77 2 P 0 ;0,1,2=169,3=0.000000
L 5.61513356 1.77 5.61326673 1.77083307 2 P 0 ;0,1,2=169,3=0.000000
L 5.61326673 1.77083307 5.61166663 1.77208287 2 P 0 ;0,1,2=169,3=0.000000
L 5.61166663 1.77208287 5.61033307 1.77374911 2 P 0 ;0,1,2=169,3=0.000000
L 5.59806683 1.79083337 5.59646673 1.79333287 2 P 0 ;0,1,2=169,3=0.000000
L 5.59646673 1.79333287 5.5946 1.79458337 2 P 0 ;0,1,2=169,3=0.000000
L 5.5946 1.79458337 5.59246663 1.795 2 P 0 ;0,1,2=169,3=0.000000
L 5.59246663 1.795 5.5898 1.79416683 2 P 0 ;0,1,2=169,3=0.000000
L 5.5898 1.79416683 5.58793327 1.79208317 2 P 0 ;0,1,2=169,3=0.000000
L 5.58793327 1.79208317 5.5874 1.78958366 2 P 0 ;0,1,2=169,3=0.000000
L 5.5874 1.78958366 5.58766663 1.78708268 2 P 0 ;0,1,2=169,3=0.000000
L 5.58766663 1.78708268 5.58873356 1.7849998 2 P 0 ;0,1,2=169,3=0.000000
L 5.58873356 1.7849998 5.59406673 1.78083327 2 P 0 ;0,1,2=169,3=0.000000
L 5.59406673 1.78083327 5.59646673 1.77791644 2 P 0 ;0,1,2=169,3=0.000000
L 5.59646673 1.77791644 5.59806683 1.77374911 2 P 0 ;0,1,2=169,3=0.000000
L 5.59806683 1.77374911 5.5986001 1.77 2 P 0 ;0,1,2=169,3=0.000000
L 5.5986001 1.77 5.5874 1.77 2 P 0 ;0,1,2=169,3=0.000000
A 11.44143996 2.575 11.44143996 2.575 11.43893002 2.575 1 P 0 N
L 11.65613337 2.58291634 11.65773356 2.58416683 2 P 0 ;0,1,2=170,3=0.000000
L 11.65773356 2.58416683 11.6595998 2.585 2 P 0 ;0,1,2=170,3=0.000000
L 11.6595998 2.585 11.66173317 2.585 2 P 0 ;0,1,2=170,3=0.000000
L 11.66173317 2.585 11.66413366 2.58374941 2 P 0 ;0,1,2=170,3=0.000000
L 11.66413366 2.58374941 11.6659999 2.58166654 2 P 0 ;0,1,2=170,3=0.000000
L 11.6659999 2.58166654 11.66733346 2.57916634 2 P 0 ;0,1,2=170,3=0.000000
L 11.66733346 2.57916634 11.66840039 2.5749998 2 P 0 ;0,1,2=170,3=0.000000
L 11.66840039 2.5749998 11.66866703 2.5712498 2 P 0 ;0,1,2=170,3=0.000000
L 11.66866703 2.5712498 11.66813327 2.5674999 2 P 0 ;0,1,2=170,3=0.000000
L 11.66813327 2.5674999 11.66733346 2.56499961 2 P 0 ;0,1,2=170,3=0.000000
L 11.66733346 2.56499961 11.66573337 2.56249941 2 P 0 ;0,1,2=170,3=0.000000
L 11.66573337 2.56249941 11.66386654 2.56083307 2 P 0 ;0,1,2=170,3=0.000000
L 11.66386654 2.56083307 11.6620003 2.56 2 P 0 ;0,1,2=170,3=0.000000
L 11.6620003 2.56 11.66013356 2.56 2 P 0 ;0,1,2=170,3=0.000000
L 11.66013356 2.56 11.65826673 2.56083307 2 P 0 ;0,1,2=170,3=0.000000
L 11.65826673 2.56083307 11.65666663 2.56208287 2 P 0 ;0,1,2=170,3=0.000000
L 11.65666663 2.56208287 11.65533307 2.56374911 2 P 0 ;0,1,2=170,3=0.000000
L 11.64306683 2.58083337 11.64146673 2.58333287 2 P 0 ;0,1,2=170,3=0.000000
L 11.64146673 2.58333287 11.6396 2.58458337 2 P 0 ;0,1,2=170,3=0.000000
L 11.6396 2.58458337 11.63746663 2.585 2 P 0 ;0,1,2=170,3=0.000000
L 11.63746663 2.585 11.6348 2.58416683 2 P 0 ;0,1,2=170,3=0.000000
L 11.6348 2.58416683 11.63293327 2.58208317 2 P 0 ;0,1,2=170,3=0.000000
L 11.63293327 2.58208317 11.6324 2.57958366 2 P 0 ;0,1,2=170,3=0.000000
L 11.6324 2.57958366 11.63266663 2.57708268 2 P 0 ;0,1,2=170,3=0.000000
L 11.63266663 2.57708268 11.63373356 2.5749998 2 P 0 ;0,1,2=170,3=0.000000
L 11.63373356 2.5749998 11.63906673 2.57083327 2 P 0 ;0,1,2=170,3=0.000000
L 11.63906673 2.57083327 11.64146673 2.56791644 2 P 0 ;0,1,2=170,3=0.000000
L 11.64146673 2.56791644 11.64306683 2.56374911 2 P 0 ;0,1,2=170,3=0.000000
L 11.64306683 2.56374911 11.6436001 2.56 2 P 0 ;0,1,2=170,3=0.000000
L 11.6436001 2.56 11.6324 2.56 2 P 0 ;0,1,2=170,3=0.000000
L 11.6140003 2.56 11.6140003 2.585 2 P 0 ;0,1,2=170,3=0.000000
L 11.6140003 2.585 11.6172001 2.5800003 2 P 0 ;0,1,2=170,3=0.000000
L 11.6172001 2.56 11.61080049 2.56 2 P 0 ;0,1,2=170,3=0.000000
L 11.59453366 2.56291604 11.59266683 2.56083307 2 P 0 ;0,1,2=170,3=0.000000
L 11.59266683 2.56083307 11.59053346 2.56 2 P 0 ;0,1,2=170,3=0.000000
L 11.59053346 2.56 11.5884001 2.56083307 2 P 0 ;0,1,2=170,3=0.000000
L 11.5884001 2.56083307 11.58653337 2.56333258 2 P 0 ;0,1,2=170,3=0.000000
L 11.58653337 2.56333258 11.5851999 2.56708327 2 P 0 ;0,1,2=170,3=0.000000
L 11.5851999 2.56708327 11.58466663 2.57083327 2 P 0 ;0,1,2=170,3=0.000000
L 11.58466663 2.57083327 11.58466663 2.57541634 2 P 0 ;0,1,2=170,3=0.000000
L 11.58466663 2.57541634 11.5851999 2.57916634 2 P 0 ;0,1,2=170,3=0.000000
L 11.5851999 2.57916634 11.58653337 2.5824997 2 P 0 ;0,1,2=170,3=0.000000
L 11.58653337 2.5824997 11.58813356 2.58416683 2 P 0 ;0,1,2=170,3=0.000000
L 11.58813356 2.58416683 11.5900003 2.585 2 P 0 ;0,1,2=170,3=0.000000
L 11.5900003 2.585 11.59213366 2.58416683 2 P 0 ;0,1,2=170,3=0.000000
L 11.59213366 2.58416683 11.59373337 2.5824997 2 P 0 ;0,1,2=170,3=0.000000
L 11.59373337 2.5824997 11.5948002 2.5800003 2 P 0 ;0,1,2=170,3=0.000000
L 11.5948002 2.5800003 11.59533346 2.57666614 2 P 0 ;0,1,2=170,3=0.000000
L 11.59533346 2.57666614 11.5948002 2.5737501 2 P 0 ;0,1,2=170,3=0.000000
L 11.5948002 2.5737501 11.59346673 2.57083327 2 P 0 ;0,1,2=170,3=0.000000
L 11.59346673 2.57083327 11.59186654 2.56916614 2 P 0 ;0,1,2=170,3=0.000000
L 11.59186654 2.56916614 11.5900003 2.56874961 2 P 0 ;0,1,2=170,3=0.000000
L 11.5900003 2.56874961 11.58786693 2.56958278 2 P 0 ;0,1,2=170,3=0.000000
L 11.58786693 2.56958278 11.58626673 2.57166644 2 P 0 ;0,1,2=170,3=0.000000
L 11.58626673 2.57166644 11.58466663 2.57541634 2 P 0 ;0,1,2=170,3=0.000000
L 11.5660003 2.56 11.56413356 2.56041654 2 P 0 ;0,1,2=170,3=0.000000
L 11.56413356 2.56041654 11.5620002 2.56166624 2 P 0 ;0,1,2=170,3=0.000000
L 11.5620002 2.56166624 11.56066663 2.56374911 2 P 0 ;0,1,2=170,3=0.000000
L 11.56066663 2.56374911 11.56013337 2.56666673 2 P 0 ;0,1,2=170,3=0.000000
L 11.56013337 2.56666673 11.56066663 2.56958278 2 P 0 ;0,1,2=170,3=0.000000
L 11.56066663 2.56958278 11.56226673 2.57208297 2 P 0 ;0,1,2=170,3=0.000000
L 11.56226673 2.57208297 11.56466673 2.57333346 2 P 0 ;0,1,2=170,3=0.000000
L 11.56466673 2.57333346 11.56733337 2.57333346 2 P 0 ;0,1,2=170,3=0.000000
L 11.56733337 2.57333346 11.56893346 2.57416663 2 P 0 ;0,1,2=170,3=0.000000
L 11.56893346 2.57416663 11.57026703 2.57624951 2 P 0 ;0,1,2=170,3=0.000000
L 11.57026703 2.57624951 11.5708002 2.57916634 2 P 0 ;0,1,2=170,3=0.000000
L 11.5708002 2.57916634 11.5699999 2.58208317 2 P 0 ;0,1,2=170,3=0.000000
L 11.5699999 2.58208317 11.56813366 2.58416683 2 P 0 ;0,1,2=170,3=0.000000
L 11.56813366 2.58416683 11.5660003 2.585 2 P 0 ;0,1,2=170,3=0.000000
L 11.5660003 2.585 11.56386693 2.58416683 2 P 0 ;0,1,2=170,3=0.000000
L 11.56386693 2.58416683 11.5620002 2.58208317 2 P 0 ;0,1,2=170,3=0.000000
L 11.5620002 2.58208317 11.5611999 2.57916634 2 P 0 ;0,1,2=170,3=0.000000
L 11.5611999 2.57916634 11.56173356 2.57624951 2 P 0 ;0,1,2=170,3=0.000000
L 11.56173356 2.57624951 11.56306663 2.57416663 2 P 0 ;0,1,2=170,3=0.000000
L 11.56306663 2.57416663 11.56466673 2.57333346 2 P 0 ;0,1,2=170,3=0.000000
L 11.56466673 2.57333346 11.56733337 2.57333346 2 P 0 ;0,1,2=170,3=0.000000
L 11.56733337 2.57333346 11.56973337 2.57208297 2 P 0 ;0,1,2=170,3=0.000000
L 11.56973337 2.57208297 11.57133346 2.56958278 2 P 0 ;0,1,2=170,3=0.000000
L 11.57133346 2.56958278 11.57186673 2.56666673 2 P 0 ;0,1,2=170,3=0.000000
L 11.57186673 2.56666673 11.57133346 2.56374911 2 P 0 ;0,1,2=170,3=0.000000
L 11.57133346 2.56374911 11.5699999 2.56166624 2 P 0 ;0,1,2=170,3=0.000000
L 11.5699999 2.56166624 11.56786654 2.56041654 2 P 0 ;0,1,2=170,3=0.000000
L 11.56786654 2.56041654 11.5660003 2.56 2 P 0 ;0,1,2=170,3=0.000000
A 11.44143996 2.53 11.44143996 2.53 11.43893002 2.53 1 P 0 N
L 11.65613337 2.54291634 11.65773356 2.54416683 2 P 0 ;0,1,2=171,3=0.000000
L 11.65773356 2.54416683 11.6595998 2.545 2 P 0 ;0,1,2=171,3=0.000000
L 11.6595998 2.545 11.66173317 2.545 2 P 0 ;0,1,2=171,3=0.000000
L 11.66173317 2.545 11.66413366 2.54374941 2 P 0 ;0,1,2=171,3=0.000000
L 11.66413366 2.54374941 11.6659999 2.54166654 2 P 0 ;0,1,2=171,3=0.000000
L 11.6659999 2.54166654 11.66733346 2.53916634 2 P 0 ;0,1,2=171,3=0.000000
L 11.66733346 2.53916634 11.66840039 2.5349998 2 P 0 ;0,1,2=171,3=0.000000
L 11.66840039 2.5349998 11.66866703 2.5312498 2 P 0 ;0,1,2=171,3=0.000000
L 11.66866703 2.5312498 11.66813327 2.5274999 2 P 0 ;0,1,2=171,3=0.000000
L 11.66813327 2.5274999 11.66733346 2.52499961 2 P 0 ;0,1,2=171,3=0.000000
L 11.66733346 2.52499961 11.66573337 2.52249941 2 P 0 ;0,1,2=171,3=0.000000
L 11.66573337 2.52249941 11.66386654 2.52083307 2 P 0 ;0,1,2=171,3=0.000000
L 11.66386654 2.52083307 11.6620003 2.52 2 P 0 ;0,1,2=171,3=0.000000
L 11.6620003 2.52 11.66013356 2.52 2 P 0 ;0,1,2=171,3=0.000000
L 11.66013356 2.52 11.65826673 2.52083307 2 P 0 ;0,1,2=171,3=0.000000
L 11.65826673 2.52083307 11.65666663 2.52208287 2 P 0 ;0,1,2=171,3=0.000000
L 11.65666663 2.52208287 11.65533307 2.52374911 2 P 0 ;0,1,2=171,3=0.000000
L 11.64306683 2.54083337 11.64146673 2.54333287 2 P 0 ;0,1,2=171,3=0.000000
L 11.64146673 2.54333287 11.6396 2.54458337 2 P 0 ;0,1,2=171,3=0.000000
L 11.6396 2.54458337 11.63746663 2.545 2 P 0 ;0,1,2=171,3=0.000000
L 11.63746663 2.545 11.6348 2.54416683 2 P 0 ;0,1,2=171,3=0.000000
L 11.6348 2.54416683 11.63293327 2.54208317 2 P 0 ;0,1,2=171,3=0.000000
L 11.63293327 2.54208317 11.6324 2.53958366 2 P 0 ;0,1,2=171,3=0.000000
L 11.6324 2.53958366 11.63266663 2.53708268 2 P 0 ;0,1,2=171,3=0.000000
L 11.63266663 2.53708268 11.63373356 2.5349998 2 P 0 ;0,1,2=171,3=0.000000
L 11.63373356 2.5349998 11.63906673 2.53083327 2 P 0 ;0,1,2=171,3=0.000000
L 11.63906673 2.53083327 11.64146673 2.52791644 2 P 0 ;0,1,2=171,3=0.000000
L 11.64146673 2.52791644 11.64306683 2.52374911 2 P 0 ;0,1,2=171,3=0.000000
L 11.64306683 2.52374911 11.6436001 2.52 2 P 0 ;0,1,2=171,3=0.000000
L 11.6436001 2.52 11.6324 2.52 2 P 0 ;0,1,2=171,3=0.000000
L 11.6140003 2.52 11.6140003 2.545 2 P 0 ;0,1,2=171,3=0.000000
L 11.6140003 2.545 11.6172001 2.5400003 2 P 0 ;0,1,2=171,3=0.000000
L 11.6172001 2.52 11.61080049 2.52 2 P 0 ;0,1,2=171,3=0.000000
L 11.59453366 2.52291604 11.59266683 2.52083307 2 P 0 ;0,1,2=171,3=0.000000
L 11.59266683 2.52083307 11.59053346 2.52 2 P 0 ;0,1,2=171,3=0.000000
L 11.59053346 2.52 11.5884001 2.52083307 2 P 0 ;0,1,2=171,3=0.000000
L 11.5884001 2.52083307 11.58653337 2.52333258 2 P 0 ;0,1,2=171,3=0.000000
L 11.58653337 2.52333258 11.5851999 2.52708327 2 P 0 ;0,1,2=171,3=0.000000
L 11.5851999 2.52708327 11.58466663 2.53083327 2 P 0 ;0,1,2=171,3=0.000000
L 11.58466663 2.53083327 11.58466663 2.53541634 2 P 0 ;0,1,2=171,3=0.000000
L 11.58466663 2.53541634 11.5851999 2.53916634 2 P 0 ;0,1,2=171,3=0.000000
L 11.5851999 2.53916634 11.58653337 2.5424997 2 P 0 ;0,1,2=171,3=0.000000
L 11.58653337 2.5424997 11.58813356 2.54416683 2 P 0 ;0,1,2=171,3=0.000000
L 11.58813356 2.54416683 11.5900003 2.545 2 P 0 ;0,1,2=171,3=0.000000
L 11.5900003 2.545 11.59213366 2.54416683 2 P 0 ;0,1,2=171,3=0.000000
L 11.59213366 2.54416683 11.59373337 2.5424997 2 P 0 ;0,1,2=171,3=0.000000
L 11.59373337 2.5424997 11.5948002 2.5400003 2 P 0 ;0,1,2=171,3=0.000000
L 11.5948002 2.5400003 11.59533346 2.53666614 2 P 0 ;0,1,2=171,3=0.000000
L 11.59533346 2.53666614 11.5948002 2.5337501 2 P 0 ;0,1,2=171,3=0.000000
L 11.5948002 2.5337501 11.59346673 2.53083327 2 P 0 ;0,1,2=171,3=0.000000
L 11.59346673 2.53083327 11.59186654 2.52916614 2 P 0 ;0,1,2=171,3=0.000000
L 11.59186654 2.52916614 11.5900003 2.52874961 2 P 0 ;0,1,2=171,3=0.000000
L 11.5900003 2.52874961 11.58786693 2.52958278 2 P 0 ;0,1,2=171,3=0.000000
L 11.58786693 2.52958278 11.58626673 2.53166644 2 P 0 ;0,1,2=171,3=0.000000
L 11.58626673 2.53166644 11.58466663 2.53541634 2 P 0 ;0,1,2=171,3=0.000000
L 11.57053366 2.52291604 11.56866683 2.52083307 2 P 0 ;0,1,2=171,3=0.000000
L 11.56866683 2.52083307 11.56653346 2.52 2 P 0 ;0,1,2=171,3=0.000000
L 11.56653346 2.52 11.5644001 2.52083307 2 P 0 ;0,1,2=171,3=0.000000
L 11.5644001 2.52083307 11.56253337 2.52333258 2 P 0 ;0,1,2=171,3=0.000000
L 11.56253337 2.52333258 11.5611999 2.52708327 2 P 0 ;0,1,2=171,3=0.000000
L 11.5611999 2.52708327 11.56066663 2.53083327 2 P 0 ;0,1,2=171,3=0.000000
L 11.56066663 2.53083327 11.56066663 2.53541634 2 P 0 ;0,1,2=171,3=0.000000
L 11.56066663 2.53541634 11.5611999 2.53916634 2 P 0 ;0,1,2=171,3=0.000000
L 11.5611999 2.53916634 11.56253337 2.5424997 2 P 0 ;0,1,2=171,3=0.000000
L 11.56253337 2.5424997 11.56413356 2.54416683 2 P 0 ;0,1,2=171,3=0.000000
L 11.56413356 2.54416683 11.5660003 2.545 2 P 0 ;0,1,2=171,3=0.000000
L 11.5660003 2.545 11.56813366 2.54416683 2 P 0 ;0,1,2=171,3=0.000000
L 11.56813366 2.54416683 11.56973337 2.5424997 2 P 0 ;0,1,2=171,3=0.000000
L 11.56973337 2.5424997 11.5708002 2.5400003 2 P 0 ;0,1,2=171,3=0.000000
L 11.5708002 2.5400003 11.57133346 2.53666614 2 P 0 ;0,1,2=171,3=0.000000
L 11.57133346 2.53666614 11.5708002 2.5337501 2 P 0 ;0,1,2=171,3=0.000000
L 11.5708002 2.5337501 11.56946673 2.53083327 2 P 0 ;0,1,2=171,3=0.000000
L 11.56946673 2.53083327 11.56786654 2.52916614 2 P 0 ;0,1,2=171,3=0.000000
L 11.56786654 2.52916614 11.5660003 2.52874961 2 P 0 ;0,1,2=171,3=0.000000
L 11.5660003 2.52874961 11.56386693 2.52958278 2 P 0 ;0,1,2=171,3=0.000000
L 11.56386693 2.52958278 11.56226673 2.53166644 2 P 0 ;0,1,2=171,3=0.000000
L 11.56226673 2.53166644 11.56066663 2.53541634 2 P 0 ;0,1,2=171,3=0.000000
A 11.64143996 2.655 11.64143996 2.655 11.63893002 2.655 1 P 0 N
L 11.89144341 2.66429636 11.8930436 2.66554685 2 P 0 ;0,1,2=172,3=0.000000
L 11.8930436 2.66554685 11.89490984 2.66638002 2 P 0 ;0,1,2=172,3=0.000000
L 11.89490984 2.66638002 11.89704321 2.66638002 2 P 0 ;0,1,2=172,3=0.000000
L 11.89704321 2.66638002 11.8994437 2.66512943 2 P 0 ;0,1,2=172,3=0.000000
L 11.8994437 2.66512943 11.90130994 2.66304656 2 P 0 ;0,1,2=172,3=0.000000
L 11.90130994 2.66304656 11.9026435 2.66054636 2 P 0 ;0,1,2=172,3=0.000000
L 11.9026435 2.66054636 11.90371043 2.65637982 2 P 0 ;0,1,2=172,3=0.000000
L 11.90371043 2.65637982 11.90397707 2.65262982 2 P 0 ;0,1,2=172,3=0.000000
L 11.90397707 2.65262982 11.90344331 2.64887992 2 P 0 ;0,1,2=172,3=0.000000
L 11.90344331 2.64887992 11.9026435 2.64637963 2 P 0 ;0,1,2=172,3=0.000000
L 11.9026435 2.64637963 11.90104341 2.64387943 2 P 0 ;0,1,2=172,3=0.000000
L 11.90104341 2.64387943 11.89917657 2.64221309 2 P 0 ;0,1,2=172,3=0.000000
L 11.89917657 2.64221309 11.89731033 2.64138002 2 P 0 ;0,1,2=172,3=0.000000
L 11.89731033 2.64138002 11.8954436 2.64138002 2 P 0 ;0,1,2=172,3=0.000000
L 11.8954436 2.64138002 11.89357677 2.64221309 2 P 0 ;0,1,2=172,3=0.000000
L 11.89357677 2.64221309 11.89197667 2.64346289 2 P 0 ;0,1,2=172,3=0.000000
L 11.89197667 2.64346289 11.89064311 2.64512913 2 P 0 ;0,1,2=172,3=0.000000
L 11.87837687 2.66221339 11.87677677 2.66471289 2 P 0 ;0,1,2=172,3=0.000000
L 11.87677677 2.66471289 11.87491004 2.66596339 2 P 0 ;0,1,2=172,3=0.000000
L 11.87491004 2.66596339 11.87277667 2.66638002 2 P 0 ;0,1,2=172,3=0.000000
L 11.87277667 2.66638002 11.87011004 2.66554685 2 P 0 ;0,1,2=172,3=0.000000
L 11.87011004 2.66554685 11.86824331 2.66346319 2 P 0 ;0,1,2=172,3=0.000000
L 11.86824331 2.66346319 11.86771004 2.66096368 2 P 0 ;0,1,2=172,3=0.000000
L 11.86771004 2.66096368 11.86797667 2.6584627 2 P 0 ;0,1,2=172,3=0.000000
L 11.86797667 2.6584627 11.8690436 2.65637982 2 P 0 ;0,1,2=172,3=0.000000
L 11.8690436 2.65637982 11.87437677 2.65221329 2 P 0 ;0,1,2=172,3=0.000000
L 11.87437677 2.65221329 11.87677677 2.64929646 2 P 0 ;0,1,2=172,3=0.000000
L 11.87677677 2.64929646 11.87837687 2.64512913 2 P 0 ;0,1,2=172,3=0.000000
L 11.87837687 2.64512913 11.87891014 2.64138002 2 P 0 ;0,1,2=172,3=0.000000
L 11.87891014 2.64138002 11.86771004 2.64138002 2 P 0 ;0,1,2=172,3=0.000000
L 11.85437687 2.66221339 11.85277677 2.66471289 2 P 0 ;0,1,2=172,3=0.000000
L 11.85277677 2.66471289 11.85091004 2.66596339 2 P 0 ;0,1,2=172,3=0.000000
L 11.85091004 2.66596339 11.84877667 2.66638002 2 P 0 ;0,1,2=172,3=0.000000
L 11.84877667 2.66638002 11.84611004 2.66554685 2 P 0 ;0,1,2=172,3=0.000000
L 11.84611004 2.66554685 11.84424331 2.66346319 2 P 0 ;0,1,2=172,3=0.000000
L 11.84424331 2.66346319 11.84371004 2.66096368 2 P 0 ;0,1,2=172,3=0.000000
L 11.84371004 2.66096368 11.84397667 2.6584627 2 P 0 ;0,1,2=172,3=0.000000
L 11.84397667 2.6584627 11.8450436 2.65637982 2 P 0 ;0,1,2=172,3=0.000000
L 11.8450436 2.65637982 11.85037677 2.65221329 2 P 0 ;0,1,2=172,3=0.000000
L 11.85037677 2.65221329 11.85277677 2.64929646 2 P 0 ;0,1,2=172,3=0.000000
L 11.85277677 2.64929646 11.85437687 2.64512913 2 P 0 ;0,1,2=172,3=0.000000
L 11.85437687 2.64512913 11.85491014 2.64138002 2 P 0 ;0,1,2=172,3=0.000000
L 11.85491014 2.64138002 11.84371004 2.64138002 2 P 0 ;0,1,2=172,3=0.000000
L 11.82531033 2.66638002 11.8274437 2.66554685 2 P 0 ;0,1,2=172,3=0.000000
L 11.8274437 2.66554685 11.82904341 2.66346319 2 P 0 ;0,1,2=172,3=0.000000
L 11.82904341 2.66346319 11.83011024 2.66096368 2 P 0 ;0,1,2=172,3=0.000000
L 11.83011024 2.66096368 11.83091014 2.65762953 2 P 0 ;0,1,2=172,3=0.000000
L 11.83091014 2.65762953 11.83117677 2.65387963 2 P 0 ;0,1,2=172,3=0.000000
L 11.83117677 2.65387963 11.83091014 2.65012963 2 P 0 ;0,1,2=172,3=0.000000
L 11.83091014 2.65012963 11.83011024 2.64679626 2 P 0 ;0,1,2=172,3=0.000000
L 11.83011024 2.64679626 11.82904341 2.64429606 2 P 0 ;0,1,2=172,3=0.000000
L 11.82904341 2.64429606 11.8274437 2.64221309 2 P 0 ;0,1,2=172,3=0.000000
L 11.8274437 2.64221309 11.82531033 2.64138002 2 P 0 ;0,1,2=172,3=0.000000
L 11.82531033 2.64138002 11.82317697 2.64221309 2 P 0 ;0,1,2=172,3=0.000000
L 11.82317697 2.64221309 11.82157677 2.64429606 2 P 0 ;0,1,2=172,3=0.000000
L 11.82157677 2.64429606 11.82050994 2.64679626 2 P 0 ;0,1,2=172,3=0.000000
L 11.82050994 2.64679626 11.81971004 2.65012963 2 P 0 ;0,1,2=172,3=0.000000
L 11.81971004 2.65012963 11.81944341 2.65387963 2 P 0 ;0,1,2=172,3=0.000000
L 11.81944341 2.65387963 11.81971004 2.65762953 2 P 0 ;0,1,2=172,3=0.000000
L 11.81971004 2.65762953 11.82050994 2.66096368 2 P 0 ;0,1,2=172,3=0.000000
L 11.82050994 2.66096368 11.82157677 2.66346319 2 P 0 ;0,1,2=172,3=0.000000
L 11.82157677 2.66346319 11.82317697 2.66554685 2 P 0 ;0,1,2=172,3=0.000000
L 11.82317697 2.66554685 11.82531033 2.66638002 2 P 0 ;0,1,2=172,3=0.000000
L 11.80131033 2.66638002 11.8034437 2.66554685 2 P 0 ;0,1,2=172,3=0.000000
L 11.8034437 2.66554685 11.80504341 2.66346319 2 P 0 ;0,1,2=172,3=0.000000
L 11.80504341 2.66346319 11.80611024 2.66096368 2 P 0 ;0,1,2=172,3=0.000000
L 11.80611024 2.66096368 11.80691014 2.65762953 2 P 0 ;0,1,2=172,3=0.000000
L 11.80691014 2.65762953 11.80717677 2.65387963 2 P 0 ;0,1,2=172,3=0.000000
L 11.80717677 2.65387963 11.80691014 2.65012963 2 P 0 ;0,1,2=172,3=0.000000
L 11.80691014 2.65012963 11.80611024 2.64679626 2 P 0 ;0,1,2=172,3=0.000000
L 11.80611024 2.64679626 11.80504341 2.64429606 2 P 0 ;0,1,2=172,3=0.000000
L 11.80504341 2.64429606 11.8034437 2.64221309 2 P 0 ;0,1,2=172,3=0.000000
L 11.8034437 2.64221309 11.80131033 2.64138002 2 P 0 ;0,1,2=172,3=0.000000
L 11.80131033 2.64138002 11.79917697 2.64221309 2 P 0 ;0,1,2=172,3=0.000000
L 11.79917697 2.64221309 11.79757677 2.64429606 2 P 0 ;0,1,2=172,3=0.000000
L 11.79757677 2.64429606 11.79650994 2.64679626 2 P 0 ;0,1,2=172,3=0.000000
L 11.79650994 2.64679626 11.79571004 2.65012963 2 P 0 ;0,1,2=172,3=0.000000
L 11.79571004 2.65012963 11.79544341 2.65387963 2 P 0 ;0,1,2=172,3=0.000000
L 11.79544341 2.65387963 11.79571004 2.65762953 2 P 0 ;0,1,2=172,3=0.000000
L 11.79571004 2.65762953 11.79650994 2.66096368 2 P 0 ;0,1,2=172,3=0.000000
L 11.79650994 2.66096368 11.79757677 2.66346319 2 P 0 ;0,1,2=172,3=0.000000
L 11.79757677 2.66346319 11.79917697 2.66554685 2 P 0 ;0,1,2=172,3=0.000000
L 11.79917697 2.66554685 11.80131033 2.66638002 2 P 0 ;0,1,2=172,3=0.000000
A 11.64143996 2.61 11.64143996 2.61 11.63893002 2.61 1 P 0 N
L 11.89144341 2.61929636 11.8930436 2.62054685 2 P 0 ;0,1,2=173,3=0.000000
L 11.8930436 2.62054685 11.89490984 2.62138002 2 P 0 ;0,1,2=173,3=0.000000
L 11.89490984 2.62138002 11.89704321 2.62138002 2 P 0 ;0,1,2=173,3=0.000000
L 11.89704321 2.62138002 11.8994437 2.62012943 2 P 0 ;0,1,2=173,3=0.000000
L 11.8994437 2.62012943 11.90130994 2.61804656 2 P 0 ;0,1,2=173,3=0.000000
L 11.90130994 2.61804656 11.9026435 2.61554636 2 P 0 ;0,1,2=173,3=0.000000
L 11.9026435 2.61554636 11.90371043 2.61137982 2 P 0 ;0,1,2=173,3=0.000000
L 11.90371043 2.61137982 11.90397707 2.60762982 2 P 0 ;0,1,2=173,3=0.000000
L 11.90397707 2.60762982 11.90344331 2.60387992 2 P 0 ;0,1,2=173,3=0.000000
L 11.90344331 2.60387992 11.9026435 2.60137963 2 P 0 ;0,1,2=173,3=0.000000
L 11.9026435 2.60137963 11.90104341 2.59887943 2 P 0 ;0,1,2=173,3=0.000000
L 11.90104341 2.59887943 11.89917657 2.59721309 2 P 0 ;0,1,2=173,3=0.000000
L 11.89917657 2.59721309 11.89731033 2.59638002 2 P 0 ;0,1,2=173,3=0.000000
L 11.89731033 2.59638002 11.8954436 2.59638002 2 P 0 ;0,1,2=173,3=0.000000
L 11.8954436 2.59638002 11.89357677 2.59721309 2 P 0 ;0,1,2=173,3=0.000000
L 11.89357677 2.59721309 11.89197667 2.59846289 2 P 0 ;0,1,2=173,3=0.000000
L 11.89197667 2.59846289 11.89064311 2.60012913 2 P 0 ;0,1,2=173,3=0.000000
L 11.87837687 2.61721339 11.87677677 2.61971289 2 P 0 ;0,1,2=173,3=0.000000
L 11.87677677 2.61971289 11.87491004 2.62096339 2 P 0 ;0,1,2=173,3=0.000000
L 11.87491004 2.62096339 11.87277667 2.62138002 2 P 0 ;0,1,2=173,3=0.000000
L 11.87277667 2.62138002 11.87011004 2.62054685 2 P 0 ;0,1,2=173,3=0.000000
L 11.87011004 2.62054685 11.86824331 2.61846319 2 P 0 ;0,1,2=173,3=0.000000
L 11.86824331 2.61846319 11.86771004 2.61596368 2 P 0 ;0,1,2=173,3=0.000000
L 11.86771004 2.61596368 11.86797667 2.6134627 2 P 0 ;0,1,2=173,3=0.000000
L 11.86797667 2.6134627 11.8690436 2.61137982 2 P 0 ;0,1,2=173,3=0.000000
L 11.8690436 2.61137982 11.87437677 2.60721329 2 P 0 ;0,1,2=173,3=0.000000
L 11.87437677 2.60721329 11.87677677 2.60429646 2 P 0 ;0,1,2=173,3=0.000000
L 11.87677677 2.60429646 11.87837687 2.60012913 2 P 0 ;0,1,2=173,3=0.000000
L 11.87837687 2.60012913 11.87891014 2.59638002 2 P 0 ;0,1,2=173,3=0.000000
L 11.87891014 2.59638002 11.86771004 2.59638002 2 P 0 ;0,1,2=173,3=0.000000
L 11.85437687 2.61721339 11.85277677 2.61971289 2 P 0 ;0,1,2=173,3=0.000000
L 11.85277677 2.61971289 11.85091004 2.62096339 2 P 0 ;0,1,2=173,3=0.000000
L 11.85091004 2.62096339 11.84877667 2.62138002 2 P 0 ;0,1,2=173,3=0.000000
L 11.84877667 2.62138002 11.84611004 2.62054685 2 P 0 ;0,1,2=173,3=0.000000
L 11.84611004 2.62054685 11.84424331 2.61846319 2 P 0 ;0,1,2=173,3=0.000000
L 11.84424331 2.61846319 11.84371004 2.61596368 2 P 0 ;0,1,2=173,3=0.000000
L 11.84371004 2.61596368 11.84397667 2.6134627 2 P 0 ;0,1,2=173,3=0.000000
L 11.84397667 2.6134627 11.8450436 2.61137982 2 P 0 ;0,1,2=173,3=0.000000
L 11.8450436 2.61137982 11.85037677 2.60721329 2 P 0 ;0,1,2=173,3=0.000000
L 11.85037677 2.60721329 11.85277677 2.60429646 2 P 0 ;0,1,2=173,3=0.000000
L 11.85277677 2.60429646 11.85437687 2.60012913 2 P 0 ;0,1,2=173,3=0.000000
L 11.85437687 2.60012913 11.85491014 2.59638002 2 P 0 ;0,1,2=173,3=0.000000
L 11.85491014 2.59638002 11.84371004 2.59638002 2 P 0 ;0,1,2=173,3=0.000000
L 11.82531033 2.62138002 11.8274437 2.62054685 2 P 0 ;0,1,2=173,3=0.000000
L 11.8274437 2.62054685 11.82904341 2.61846319 2 P 0 ;0,1,2=173,3=0.000000
L 11.82904341 2.61846319 11.83011024 2.61596368 2 P 0 ;0,1,2=173,3=0.000000
L 11.83011024 2.61596368 11.83091014 2.61262953 2 P 0 ;0,1,2=173,3=0.000000
L 11.83091014 2.61262953 11.83117677 2.60887963 2 P 0 ;0,1,2=173,3=0.000000
L 11.83117677 2.60887963 11.83091014 2.60512963 2 P 0 ;0,1,2=173,3=0.000000
L 11.83091014 2.60512963 11.83011024 2.60179626 2 P 0 ;0,1,2=173,3=0.000000
L 11.83011024 2.60179626 11.82904341 2.59929606 2 P 0 ;0,1,2=173,3=0.000000
L 11.82904341 2.59929606 11.8274437 2.59721309 2 P 0 ;0,1,2=173,3=0.000000
L 11.8274437 2.59721309 11.82531033 2.59638002 2 P 0 ;0,1,2=173,3=0.000000
L 11.82531033 2.59638002 11.82317697 2.59721309 2 P 0 ;0,1,2=173,3=0.000000
L 11.82317697 2.59721309 11.82157677 2.59929606 2 P 0 ;0,1,2=173,3=0.000000
L 11.82157677 2.59929606 11.82050994 2.60179626 2 P 0 ;0,1,2=173,3=0.000000
L 11.82050994 2.60179626 11.81971004 2.60512963 2 P 0 ;0,1,2=173,3=0.000000
L 11.81971004 2.60512963 11.81944341 2.60887963 2 P 0 ;0,1,2=173,3=0.000000
L 11.81944341 2.60887963 11.81971004 2.61262953 2 P 0 ;0,1,2=173,3=0.000000
L 11.81971004 2.61262953 11.82050994 2.61596368 2 P 0 ;0,1,2=173,3=0.000000
L 11.82050994 2.61596368 11.82157677 2.61846319 2 P 0 ;0,1,2=173,3=0.000000
L 11.82157677 2.61846319 11.82317697 2.62054685 2 P 0 ;0,1,2=173,3=0.000000
L 11.82317697 2.62054685 11.82531033 2.62138002 2 P 0 ;0,1,2=173,3=0.000000
L 11.80131033 2.59638002 11.80131033 2.62138002 2 P 0 ;0,1,2=173,3=0.000000
L 11.80131033 2.62138002 11.80451014 2.61638032 2 P 0 ;0,1,2=173,3=0.000000
L 11.80451014 2.59638002 11.79811053 2.59638002 2 P 0 ;0,1,2=173,3=0.000000
A 11.64143996 2.495 11.64143996 2.495 11.63893002 2.495 1 P 0 N
L 11.89144341 2.50429636 11.8930436 2.50554685 2 P 0 ;0,1,2=174,3=0.000000
L 11.8930436 2.50554685 11.89490984 2.50638002 2 P 0 ;0,1,2=174,3=0.000000
L 11.89490984 2.50638002 11.89704321 2.50638002 2 P 0 ;0,1,2=174,3=0.000000
L 11.89704321 2.50638002 11.8994437 2.50512943 2 P 0 ;0,1,2=174,3=0.000000
L 11.8994437 2.50512943 11.90130994 2.50304656 2 P 0 ;0,1,2=174,3=0.000000
L 11.90130994 2.50304656 11.9026435 2.50054636 2 P 0 ;0,1,2=174,3=0.000000
L 11.9026435 2.50054636 11.90371043 2.49637982 2 P 0 ;0,1,2=174,3=0.000000
L 11.90371043 2.49637982 11.90397707 2.49262982 2 P 0 ;0,1,2=174,3=0.000000
L 11.90397707 2.49262982 11.90344331 2.48887992 2 P 0 ;0,1,2=174,3=0.000000
L 11.90344331 2.48887992 11.9026435 2.48637963 2 P 0 ;0,1,2=174,3=0.000000
L 11.9026435 2.48637963 11.90104341 2.48387943 2 P 0 ;0,1,2=174,3=0.000000
L 11.90104341 2.48387943 11.89917657 2.48221309 2 P 0 ;0,1,2=174,3=0.000000
L 11.89917657 2.48221309 11.89731033 2.48138002 2 P 0 ;0,1,2=174,3=0.000000
L 11.89731033 2.48138002 11.8954436 2.48138002 2 P 0 ;0,1,2=174,3=0.000000
L 11.8954436 2.48138002 11.89357677 2.48221309 2 P 0 ;0,1,2=174,3=0.000000
L 11.89357677 2.48221309 11.89197667 2.48346289 2 P 0 ;0,1,2=174,3=0.000000
L 11.89197667 2.48346289 11.89064311 2.48512913 2 P 0 ;0,1,2=174,3=0.000000
L 11.87837687 2.50221339 11.87677677 2.50471289 2 P 0 ;0,1,2=174,3=0.000000
L 11.87677677 2.50471289 11.87491004 2.50596339 2 P 0 ;0,1,2=174,3=0.000000
L 11.87491004 2.50596339 11.87277667 2.50638002 2 P 0 ;0,1,2=174,3=0.000000
L 11.87277667 2.50638002 11.87011004 2.50554685 2 P 0 ;0,1,2=174,3=0.000000
L 11.87011004 2.50554685 11.86824331 2.50346319 2 P 0 ;0,1,2=174,3=0.000000
L 11.86824331 2.50346319 11.86771004 2.50096368 2 P 0 ;0,1,2=174,3=0.000000
L 11.86771004 2.50096368 11.86797667 2.4984627 2 P 0 ;0,1,2=174,3=0.000000
L 11.86797667 2.4984627 11.8690436 2.49637982 2 P 0 ;0,1,2=174,3=0.000000
L 11.8690436 2.49637982 11.87437677 2.49221329 2 P 0 ;0,1,2=174,3=0.000000
L 11.87437677 2.49221329 11.87677677 2.48929646 2 P 0 ;0,1,2=174,3=0.000000
L 11.87677677 2.48929646 11.87837687 2.48512913 2 P 0 ;0,1,2=174,3=0.000000
L 11.87837687 2.48512913 11.87891014 2.48138002 2 P 0 ;0,1,2=174,3=0.000000
L 11.87891014 2.48138002 11.86771004 2.48138002 2 P 0 ;0,1,2=174,3=0.000000
L 11.85437687 2.50221339 11.85277677 2.50471289 2 P 0 ;0,1,2=174,3=0.000000
L 11.85277677 2.50471289 11.85091004 2.50596339 2 P 0 ;0,1,2=174,3=0.000000
L 11.85091004 2.50596339 11.84877667 2.50638002 2 P 0 ;0,1,2=174,3=0.000000
L 11.84877667 2.50638002 11.84611004 2.50554685 2 P 0 ;0,1,2=174,3=0.000000
L 11.84611004 2.50554685 11.84424331 2.50346319 2 P 0 ;0,1,2=174,3=0.000000
L 11.84424331 2.50346319 11.84371004 2.50096368 2 P 0 ;0,1,2=174,3=0.000000
L 11.84371004 2.50096368 11.84397667 2.4984627 2 P 0 ;0,1,2=174,3=0.000000
L 11.84397667 2.4984627 11.8450436 2.49637982 2 P 0 ;0,1,2=174,3=0.000000
L 11.8450436 2.49637982 11.85037677 2.49221329 2 P 0 ;0,1,2=174,3=0.000000
L 11.85037677 2.49221329 11.85277677 2.48929646 2 P 0 ;0,1,2=174,3=0.000000
L 11.85277677 2.48929646 11.85437687 2.48512913 2 P 0 ;0,1,2=174,3=0.000000
L 11.85437687 2.48512913 11.85491014 2.48138002 2 P 0 ;0,1,2=174,3=0.000000
L 11.85491014 2.48138002 11.84371004 2.48138002 2 P 0 ;0,1,2=174,3=0.000000
L 11.82531033 2.50638002 11.8274437 2.50554685 2 P 0 ;0,1,2=174,3=0.000000
L 11.8274437 2.50554685 11.82904341 2.50346319 2 P 0 ;0,1,2=174,3=0.000000
L 11.82904341 2.50346319 11.83011024 2.50096368 2 P 0 ;0,1,2=174,3=0.000000
L 11.83011024 2.50096368 11.83091014 2.49762953 2 P 0 ;0,1,2=174,3=0.000000
L 11.83091014 2.49762953 11.83117677 2.49387963 2 P 0 ;0,1,2=174,3=0.000000
L 11.83117677 2.49387963 11.83091014 2.49012963 2 P 0 ;0,1,2=174,3=0.000000
L 11.83091014 2.49012963 11.83011024 2.48679626 2 P 0 ;0,1,2=174,3=0.000000
L 11.83011024 2.48679626 11.82904341 2.48429606 2 P 0 ;0,1,2=174,3=0.000000
L 11.82904341 2.48429606 11.8274437 2.48221309 2 P 0 ;0,1,2=174,3=0.000000
L 11.8274437 2.48221309 11.82531033 2.48138002 2 P 0 ;0,1,2=174,3=0.000000
L 11.82531033 2.48138002 11.82317697 2.48221309 2 P 0 ;0,1,2=174,3=0.000000
L 11.82317697 2.48221309 11.82157677 2.48429606 2 P 0 ;0,1,2=174,3=0.000000
L 11.82157677 2.48429606 11.82050994 2.48679626 2 P 0 ;0,1,2=174,3=0.000000
L 11.82050994 2.48679626 11.81971004 2.49012963 2 P 0 ;0,1,2=174,3=0.000000
L 11.81971004 2.49012963 11.81944341 2.49387963 2 P 0 ;0,1,2=174,3=0.000000
L 11.81944341 2.49387963 11.81971004 2.49762953 2 P 0 ;0,1,2=174,3=0.000000
L 11.81971004 2.49762953 11.82050994 2.50096368 2 P 0 ;0,1,2=174,3=0.000000
L 11.82050994 2.50096368 11.82157677 2.50346319 2 P 0 ;0,1,2=174,3=0.000000
L 11.82157677 2.50346319 11.82317697 2.50554685 2 P 0 ;0,1,2=174,3=0.000000
L 11.82317697 2.50554685 11.82531033 2.50638002 2 P 0 ;0,1,2=174,3=0.000000
L 11.80637687 2.50221339 11.80477677 2.50471289 2 P 0 ;0,1,2=174,3=0.000000
L 11.80477677 2.50471289 11.80291004 2.50596339 2 P 0 ;0,1,2=174,3=0.000000
L 11.80291004 2.50596339 11.80077667 2.50638002 2 P 0 ;0,1,2=174,3=0.000000
L 11.80077667 2.50638002 11.79811004 2.50554685 2 P 0 ;0,1,2=174,3=0.000000
L 11.79811004 2.50554685 11.79624331 2.50346319 2 P 0 ;0,1,2=174,3=0.000000
L 11.79624331 2.50346319 11.79571004 2.50096368 2 P 0 ;0,1,2=174,3=0.000000
L 11.79571004 2.50096368 11.79597667 2.4984627 2 P 0 ;0,1,2=174,3=0.000000
L 11.79597667 2.4984627 11.7970436 2.49637982 2 P 0 ;0,1,2=174,3=0.000000
L 11.7970436 2.49637982 11.80237677 2.49221329 2 P 0 ;0,1,2=174,3=0.000000
L 11.80237677 2.49221329 11.80477677 2.48929646 2 P 0 ;0,1,2=174,3=0.000000
L 11.80477677 2.48929646 11.80637687 2.48512913 2 P 0 ;0,1,2=174,3=0.000000
L 11.80637687 2.48512913 11.80691014 2.48138002 2 P 0 ;0,1,2=174,3=0.000000
L 11.80691014 2.48138002 11.79571004 2.48138002 2 P 0 ;0,1,2=174,3=0.000000
A 11.64143996 2.45 11.64143996 2.45 11.63893002 2.45 1 P 0 N
L 11.89144341 2.45929636 11.8930436 2.46054685 2 P 0 ;0,1,2=175,3=0.000000
L 11.8930436 2.46054685 11.89490984 2.46138002 2 P 0 ;0,1,2=175,3=0.000000
L 11.89490984 2.46138002 11.89704321 2.46138002 2 P 0 ;0,1,2=175,3=0.000000
L 11.89704321 2.46138002 11.8994437 2.46012943 2 P 0 ;0,1,2=175,3=0.000000
L 11.8994437 2.46012943 11.90130994 2.45804656 2 P 0 ;0,1,2=175,3=0.000000
L 11.90130994 2.45804656 11.9026435 2.45554636 2 P 0 ;0,1,2=175,3=0.000000
L 11.9026435 2.45554636 11.90371043 2.45137982 2 P 0 ;0,1,2=175,3=0.000000
L 11.90371043 2.45137982 11.90397707 2.44762982 2 P 0 ;0,1,2=175,3=0.000000
L 11.90397707 2.44762982 11.90344331 2.44387992 2 P 0 ;0,1,2=175,3=0.000000
L 11.90344331 2.44387992 11.9026435 2.44137963 2 P 0 ;0,1,2=175,3=0.000000
L 11.9026435 2.44137963 11.90104341 2.43887943 2 P 0 ;0,1,2=175,3=0.000000
L 11.90104341 2.43887943 11.89917657 2.43721309 2 P 0 ;0,1,2=175,3=0.000000
L 11.89917657 2.43721309 11.89731033 2.43638002 2 P 0 ;0,1,2=175,3=0.000000
L 11.89731033 2.43638002 11.8954436 2.43638002 2 P 0 ;0,1,2=175,3=0.000000
L 11.8954436 2.43638002 11.89357677 2.43721309 2 P 0 ;0,1,2=175,3=0.000000
L 11.89357677 2.43721309 11.89197667 2.43846289 2 P 0 ;0,1,2=175,3=0.000000
L 11.89197667 2.43846289 11.89064311 2.44012913 2 P 0 ;0,1,2=175,3=0.000000
L 11.87837687 2.45721339 11.87677677 2.45971289 2 P 0 ;0,1,2=175,3=0.000000
L 11.87677677 2.45971289 11.87491004 2.46096339 2 P 0 ;0,1,2=175,3=0.000000
L 11.87491004 2.46096339 11.87277667 2.46138002 2 P 0 ;0,1,2=175,3=0.000000
L 11.87277667 2.46138002 11.87011004 2.46054685 2 P 0 ;0,1,2=175,3=0.000000
L 11.87011004 2.46054685 11.86824331 2.45846319 2 P 0 ;0,1,2=175,3=0.000000
L 11.86824331 2.45846319 11.86771004 2.45596368 2 P 0 ;0,1,2=175,3=0.000000
L 11.86771004 2.45596368 11.86797667 2.4534627 2 P 0 ;0,1,2=175,3=0.000000
L 11.86797667 2.4534627 11.8690436 2.45137982 2 P 0 ;0,1,2=175,3=0.000000
L 11.8690436 2.45137982 11.87437677 2.44721329 2 P 0 ;0,1,2=175,3=0.000000
L 11.87437677 2.44721329 11.87677677 2.44429646 2 P 0 ;0,1,2=175,3=0.000000
L 11.87677677 2.44429646 11.87837687 2.44012913 2 P 0 ;0,1,2=175,3=0.000000
L 11.87837687 2.44012913 11.87891014 2.43638002 2 P 0 ;0,1,2=175,3=0.000000
L 11.87891014 2.43638002 11.86771004 2.43638002 2 P 0 ;0,1,2=175,3=0.000000
L 11.85437687 2.45721339 11.85277677 2.45971289 2 P 0 ;0,1,2=175,3=0.000000
L 11.85277677 2.45971289 11.85091004 2.46096339 2 P 0 ;0,1,2=175,3=0.000000
L 11.85091004 2.46096339 11.84877667 2.46138002 2 P 0 ;0,1,2=175,3=0.000000
L 11.84877667 2.46138002 11.84611004 2.46054685 2 P 0 ;0,1,2=175,3=0.000000
L 11.84611004 2.46054685 11.84424331 2.45846319 2 P 0 ;0,1,2=175,3=0.000000
L 11.84424331 2.45846319 11.84371004 2.45596368 2 P 0 ;0,1,2=175,3=0.000000
L 11.84371004 2.45596368 11.84397667 2.4534627 2 P 0 ;0,1,2=175,3=0.000000
L 11.84397667 2.4534627 11.8450436 2.45137982 2 P 0 ;0,1,2=175,3=0.000000
L 11.8450436 2.45137982 11.85037677 2.44721329 2 P 0 ;0,1,2=175,3=0.000000
L 11.85037677 2.44721329 11.85277677 2.44429646 2 P 0 ;0,1,2=175,3=0.000000
L 11.85277677 2.44429646 11.85437687 2.44012913 2 P 0 ;0,1,2=175,3=0.000000
L 11.85437687 2.44012913 11.85491014 2.43638002 2 P 0 ;0,1,2=175,3=0.000000
L 11.85491014 2.43638002 11.84371004 2.43638002 2 P 0 ;0,1,2=175,3=0.000000
L 11.82531033 2.46138002 11.8274437 2.46054685 2 P 0 ;0,1,2=175,3=0.000000
L 11.8274437 2.46054685 11.82904341 2.45846319 2 P 0 ;0,1,2=175,3=0.000000
L 11.82904341 2.45846319 11.83011024 2.45596368 2 P 0 ;0,1,2=175,3=0.000000
L 11.83011024 2.45596368 11.83091014 2.45262953 2 P 0 ;0,1,2=175,3=0.000000
L 11.83091014 2.45262953 11.83117677 2.44887963 2 P 0 ;0,1,2=175,3=0.000000
L 11.83117677 2.44887963 11.83091014 2.44512963 2 P 0 ;0,1,2=175,3=0.000000
L 11.83091014 2.44512963 11.83011024 2.44179626 2 P 0 ;0,1,2=175,3=0.000000
L 11.83011024 2.44179626 11.82904341 2.43929606 2 P 0 ;0,1,2=175,3=0.000000
L 11.82904341 2.43929606 11.8274437 2.43721309 2 P 0 ;0,1,2=175,3=0.000000
L 11.8274437 2.43721309 11.82531033 2.43638002 2 P 0 ;0,1,2=175,3=0.000000
L 11.82531033 2.43638002 11.82317697 2.43721309 2 P 0 ;0,1,2=175,3=0.000000
L 11.82317697 2.43721309 11.82157677 2.43929606 2 P 0 ;0,1,2=175,3=0.000000
L 11.82157677 2.43929606 11.82050994 2.44179626 2 P 0 ;0,1,2=175,3=0.000000
L 11.82050994 2.44179626 11.81971004 2.44512963 2 P 0 ;0,1,2=175,3=0.000000
L 11.81971004 2.44512963 11.81944341 2.44887963 2 P 0 ;0,1,2=175,3=0.000000
L 11.81944341 2.44887963 11.81971004 2.45262953 2 P 0 ;0,1,2=175,3=0.000000
L 11.81971004 2.45262953 11.82050994 2.45596368 2 P 0 ;0,1,2=175,3=0.000000
L 11.82050994 2.45596368 11.82157677 2.45846319 2 P 0 ;0,1,2=175,3=0.000000
L 11.82157677 2.45846319 11.82317697 2.46054685 2 P 0 ;0,1,2=175,3=0.000000
L 11.82317697 2.46054685 11.82531033 2.46138002 2 P 0 ;0,1,2=175,3=0.000000
L 11.80717677 2.44137963 11.80557707 2.43846289 2 P 0 ;0,1,2=175,3=0.000000
L 11.80557707 2.43846289 11.8034437 2.43679656 2 P 0 ;0,1,2=175,3=0.000000
L 11.8034437 2.43679656 11.80104321 2.43638002 2 P 0 ;0,1,2=175,3=0.000000
L 11.80104321 2.43638002 11.79890984 2.43679656 2 P 0 ;0,1,2=175,3=0.000000
L 11.79890984 2.43679656 11.79677648 2.43887943 2 P 0 ;0,1,2=175,3=0.000000
L 11.79677648 2.43887943 11.79544341 2.44137963 2 P 0 ;0,1,2=175,3=0.000000
L 11.79544341 2.44137963 11.79517687 2.44387992 2 P 0 ;0,1,2=175,3=0.000000
L 11.79517687 2.44387992 11.79571004 2.44679596 2 P 0 ;0,1,2=175,3=0.000000
L 11.79571004 2.44679596 11.79757677 2.44887963 2 P 0 ;0,1,2=175,3=0.000000
L 11.79757677 2.44887963 11.7994436 2.44971348 2 P 0 ;0,1,2=175,3=0.000000
L 11.7994436 2.44971348 11.8018435 2.44971348 2 P 0 ;0,1,2=175,3=0.000000
L 11.7994436 2.44971348 11.79784341 2.45096329 2 P 0 ;0,1,2=175,3=0.000000
L 11.79784341 2.45096329 11.79650994 2.45304616 2 P 0 ;0,1,2=175,3=0.000000
L 11.79650994 2.45304616 11.79597667 2.45554636 2 P 0 ;0,1,2=175,3=0.000000
L 11.79597667 2.45554636 11.79650994 2.45804656 2 P 0 ;0,1,2=175,3=0.000000
L 11.79650994 2.45804656 11.79784341 2.46012943 2 P 0 ;0,1,2=175,3=0.000000
L 11.79784341 2.46012943 11.80024341 2.46138002 2 P 0 ;0,1,2=175,3=0.000000
L 11.80024341 2.46138002 11.80264341 2.46096339 2 P 0 ;0,1,2=175,3=0.000000
L 11.80264341 2.46096339 11.80504341 2.45929636 2 P 0 ;0,1,2=175,3=0.000000
A 11.44143996 2.415 11.44143996 2.415 11.43893002 2.415 1 P 0 N
L 11.65613337 2.42291634 11.65773356 2.42416683 2 P 0 ;0,1,2=176,3=0.000000
L 11.65773356 2.42416683 11.6595998 2.425 2 P 0 ;0,1,2=176,3=0.000000
L 11.6595998 2.425 11.66173317 2.425 2 P 0 ;0,1,2=176,3=0.000000
L 11.66173317 2.425 11.66413366 2.42374941 2 P 0 ;0,1,2=176,3=0.000000
L 11.66413366 2.42374941 11.6659999 2.42166654 2 P 0 ;0,1,2=176,3=0.000000
L 11.6659999 2.42166654 11.66733346 2.41916634 2 P 0 ;0,1,2=176,3=0.000000
L 11.66733346 2.41916634 11.66840039 2.4149998 2 P 0 ;0,1,2=176,3=0.000000
L 11.66840039 2.4149998 11.66866703 2.4112498 2 P 0 ;0,1,2=176,3=0.000000
L 11.66866703 2.4112498 11.66813327 2.4074999 2 P 0 ;0,1,2=176,3=0.000000
L 11.66813327 2.4074999 11.66733346 2.40499961 2 P 0 ;0,1,2=176,3=0.000000
L 11.66733346 2.40499961 11.66573337 2.40249941 2 P 0 ;0,1,2=176,3=0.000000
L 11.66573337 2.40249941 11.66386654 2.40083307 2 P 0 ;0,1,2=176,3=0.000000
L 11.66386654 2.40083307 11.6620003 2.4 2 P 0 ;0,1,2=176,3=0.000000
L 11.6620003 2.4 11.66013356 2.4 2 P 0 ;0,1,2=176,3=0.000000
L 11.66013356 2.4 11.65826673 2.40083307 2 P 0 ;0,1,2=176,3=0.000000
L 11.65826673 2.40083307 11.65666663 2.40208287 2 P 0 ;0,1,2=176,3=0.000000
L 11.65666663 2.40208287 11.65533307 2.40374911 2 P 0 ;0,1,2=176,3=0.000000
L 11.64306683 2.42083337 11.64146673 2.42333287 2 P 0 ;0,1,2=176,3=0.000000
L 11.64146673 2.42333287 11.6396 2.42458337 2 P 0 ;0,1,2=176,3=0.000000
L 11.6396 2.42458337 11.63746663 2.425 2 P 0 ;0,1,2=176,3=0.000000
L 11.63746663 2.425 11.6348 2.42416683 2 P 0 ;0,1,2=176,3=0.000000
L 11.6348 2.42416683 11.63293327 2.42208317 2 P 0 ;0,1,2=176,3=0.000000
L 11.63293327 2.42208317 11.6324 2.41958366 2 P 0 ;0,1,2=176,3=0.000000
L 11.6324 2.41958366 11.63266663 2.41708268 2 P 0 ;0,1,2=176,3=0.000000
L 11.63266663 2.41708268 11.63373356 2.4149998 2 P 0 ;0,1,2=176,3=0.000000
L 11.63373356 2.4149998 11.63906673 2.41083327 2 P 0 ;0,1,2=176,3=0.000000
L 11.63906673 2.41083327 11.64146673 2.40791644 2 P 0 ;0,1,2=176,3=0.000000
L 11.64146673 2.40791644 11.64306683 2.40374911 2 P 0 ;0,1,2=176,3=0.000000
L 11.64306683 2.40374911 11.6436001 2.4 2 P 0 ;0,1,2=176,3=0.000000
L 11.6436001 2.4 11.6324 2.4 2 P 0 ;0,1,2=176,3=0.000000
L 11.61906683 2.42083337 11.61746673 2.42333287 2 P 0 ;0,1,2=176,3=0.000000
L 11.61746673 2.42333287 11.6156 2.42458337 2 P 0 ;0,1,2=176,3=0.000000
L 11.6156 2.42458337 11.61346663 2.425 2 P 0 ;0,1,2=176,3=0.000000
L 11.61346663 2.425 11.6108 2.42416683 2 P 0 ;0,1,2=176,3=0.000000
L 11.6108 2.42416683 11.60893327 2.42208317 2 P 0 ;0,1,2=176,3=0.000000
L 11.60893327 2.42208317 11.6084 2.41958366 2 P 0 ;0,1,2=176,3=0.000000
L 11.6084 2.41958366 11.60866663 2.41708268 2 P 0 ;0,1,2=176,3=0.000000
L 11.60866663 2.41708268 11.60973356 2.4149998 2 P 0 ;0,1,2=176,3=0.000000
L 11.60973356 2.4149998 11.61506673 2.41083327 2 P 0 ;0,1,2=176,3=0.000000
L 11.61506673 2.41083327 11.61746673 2.40791644 2 P 0 ;0,1,2=176,3=0.000000
L 11.61746673 2.40791644 11.61906683 2.40374911 2 P 0 ;0,1,2=176,3=0.000000
L 11.61906683 2.40374911 11.6196001 2.4 2 P 0 ;0,1,2=176,3=0.000000
L 11.6196001 2.4 11.6084 2.4 2 P 0 ;0,1,2=176,3=0.000000
L 11.5900003 2.425 11.59213366 2.42416683 2 P 0 ;0,1,2=176,3=0.000000
L 11.59213366 2.42416683 11.59373337 2.42208317 2 P 0 ;0,1,2=176,3=0.000000
L 11.59373337 2.42208317 11.5948002 2.41958366 2 P 0 ;0,1,2=176,3=0.000000
L 11.5948002 2.41958366 11.5956001 2.41624951 2 P 0 ;0,1,2=176,3=0.000000
L 11.5956001 2.41624951 11.59586673 2.41249961 2 P 0 ;0,1,2=176,3=0.000000
L 11.59586673 2.41249961 11.5956001 2.40874961 2 P 0 ;0,1,2=176,3=0.000000
L 11.5956001 2.40874961 11.5948002 2.40541624 2 P 0 ;0,1,2=176,3=0.000000
L 11.5948002 2.40541624 11.59373337 2.40291604 2 P 0 ;0,1,2=176,3=0.000000
L 11.59373337 2.40291604 11.59213366 2.40083307 2 P 0 ;0,1,2=176,3=0.000000
L 11.59213366 2.40083307 11.5900003 2.4 2 P 0 ;0,1,2=176,3=0.000000
L 11.5900003 2.4 11.58786693 2.40083307 2 P 0 ;0,1,2=176,3=0.000000
L 11.58786693 2.40083307 11.58626673 2.40291604 2 P 0 ;0,1,2=176,3=0.000000
L 11.58626673 2.40291604 11.5851999 2.40541624 2 P 0 ;0,1,2=176,3=0.000000
L 11.5851999 2.40541624 11.5844 2.40874961 2 P 0 ;0,1,2=176,3=0.000000
L 11.5844 2.40874961 11.58413337 2.41249961 2 P 0 ;0,1,2=176,3=0.000000
L 11.58413337 2.41249961 11.5844 2.41624951 2 P 0 ;0,1,2=176,3=0.000000
L 11.5844 2.41624951 11.5851999 2.41958366 2 P 0 ;0,1,2=176,3=0.000000
L 11.5851999 2.41958366 11.58626673 2.42208317 2 P 0 ;0,1,2=176,3=0.000000
L 11.58626673 2.42208317 11.58786693 2.42416683 2 P 0 ;0,1,2=176,3=0.000000
L 11.58786693 2.42416683 11.5900003 2.425 2 P 0 ;0,1,2=176,3=0.000000
L 11.5628 2.4 11.5628 2.425 2 P 0 ;0,1,2=176,3=0.000000
L 11.5628 2.425 11.57266703 2.40708327 2 P 0 ;0,1,2=176,3=0.000000
L 11.57266703 2.40708327 11.55933307 2.40708327 2 P 0 ;0,1,2=176,3=0.000000
A 11.44143996 2.37 11.44143996 2.37 11.43893002 2.37 1 P 0 N
L 11.65613337 2.38291634 11.65773356 2.38416683 2 P 0 ;0,1,2=177,3=0.000000
L 11.65773356 2.38416683 11.6595998 2.385 2 P 0 ;0,1,2=177,3=0.000000
L 11.6595998 2.385 11.66173317 2.385 2 P 0 ;0,1,2=177,3=0.000000
L 11.66173317 2.385 11.66413366 2.38374941 2 P 0 ;0,1,2=177,3=0.000000
L 11.66413366 2.38374941 11.6659999 2.38166654 2 P 0 ;0,1,2=177,3=0.000000
L 11.6659999 2.38166654 11.66733346 2.37916634 2 P 0 ;0,1,2=177,3=0.000000
L 11.66733346 2.37916634 11.66840039 2.3749998 2 P 0 ;0,1,2=177,3=0.000000
L 11.66840039 2.3749998 11.66866703 2.3712498 2 P 0 ;0,1,2=177,3=0.000000
L 11.66866703 2.3712498 11.66813327 2.3674999 2 P 0 ;0,1,2=177,3=0.000000
L 11.66813327 2.3674999 11.66733346 2.36499961 2 P 0 ;0,1,2=177,3=0.000000
L 11.66733346 2.36499961 11.66573337 2.36249941 2 P 0 ;0,1,2=177,3=0.000000
L 11.66573337 2.36249941 11.66386654 2.36083307 2 P 0 ;0,1,2=177,3=0.000000
L 11.66386654 2.36083307 11.6620003 2.36 2 P 0 ;0,1,2=177,3=0.000000
L 11.6620003 2.36 11.66013356 2.36 2 P 0 ;0,1,2=177,3=0.000000
L 11.66013356 2.36 11.65826673 2.36083307 2 P 0 ;0,1,2=177,3=0.000000
L 11.65826673 2.36083307 11.65666663 2.36208287 2 P 0 ;0,1,2=177,3=0.000000
L 11.65666663 2.36208287 11.65533307 2.36374911 2 P 0 ;0,1,2=177,3=0.000000
L 11.64306683 2.38083337 11.64146673 2.38333287 2 P 0 ;0,1,2=177,3=0.000000
L 11.64146673 2.38333287 11.6396 2.38458337 2 P 0 ;0,1,2=177,3=0.000000
L 11.6396 2.38458337 11.63746663 2.385 2 P 0 ;0,1,2=177,3=0.000000
L 11.63746663 2.385 11.6348 2.38416683 2 P 0 ;0,1,2=177,3=0.000000
L 11.6348 2.38416683 11.63293327 2.38208317 2 P 0 ;0,1,2=177,3=0.000000
L 11.63293327 2.38208317 11.6324 2.37958366 2 P 0 ;0,1,2=177,3=0.000000
L 11.6324 2.37958366 11.63266663 2.37708268 2 P 0 ;0,1,2=177,3=0.000000
L 11.63266663 2.37708268 11.63373356 2.3749998 2 P 0 ;0,1,2=177,3=0.000000
L 11.63373356 2.3749998 11.63906673 2.37083327 2 P 0 ;0,1,2=177,3=0.000000
L 11.63906673 2.37083327 11.64146673 2.36791644 2 P 0 ;0,1,2=177,3=0.000000
L 11.64146673 2.36791644 11.64306683 2.36374911 2 P 0 ;0,1,2=177,3=0.000000
L 11.64306683 2.36374911 11.6436001 2.36 2 P 0 ;0,1,2=177,3=0.000000
L 11.6436001 2.36 11.6324 2.36 2 P 0 ;0,1,2=177,3=0.000000
L 11.61906683 2.38083337 11.61746673 2.38333287 2 P 0 ;0,1,2=177,3=0.000000
L 11.61746673 2.38333287 11.6156 2.38458337 2 P 0 ;0,1,2=177,3=0.000000
L 11.6156 2.38458337 11.61346663 2.385 2 P 0 ;0,1,2=177,3=0.000000
L 11.61346663 2.385 11.6108 2.38416683 2 P 0 ;0,1,2=177,3=0.000000
L 11.6108 2.38416683 11.60893327 2.38208317 2 P 0 ;0,1,2=177,3=0.000000
L 11.60893327 2.38208317 11.6084 2.37958366 2 P 0 ;0,1,2=177,3=0.000000
L 11.6084 2.37958366 11.60866663 2.37708268 2 P 0 ;0,1,2=177,3=0.000000
L 11.60866663 2.37708268 11.60973356 2.3749998 2 P 0 ;0,1,2=177,3=0.000000
L 11.60973356 2.3749998 11.61506673 2.37083327 2 P 0 ;0,1,2=177,3=0.000000
L 11.61506673 2.37083327 11.61746673 2.36791644 2 P 0 ;0,1,2=177,3=0.000000
L 11.61746673 2.36791644 11.61906683 2.36374911 2 P 0 ;0,1,2=177,3=0.000000
L 11.61906683 2.36374911 11.6196001 2.36 2 P 0 ;0,1,2=177,3=0.000000
L 11.6196001 2.36 11.6084 2.36 2 P 0 ;0,1,2=177,3=0.000000
L 11.5900003 2.385 11.59213366 2.38416683 2 P 0 ;0,1,2=177,3=0.000000
L 11.59213366 2.38416683 11.59373337 2.38208317 2 P 0 ;0,1,2=177,3=0.000000
L 11.59373337 2.38208317 11.5948002 2.37958366 2 P 0 ;0,1,2=177,3=0.000000
L 11.5948002 2.37958366 11.5956001 2.37624951 2 P 0 ;0,1,2=177,3=0.000000
L 11.5956001 2.37624951 11.59586673 2.37249961 2 P 0 ;0,1,2=177,3=0.000000
L 11.59586673 2.37249961 11.5956001 2.36874961 2 P 0 ;0,1,2=177,3=0.000000
L 11.5956001 2.36874961 11.5948002 2.36541624 2 P 0 ;0,1,2=177,3=0.000000
L 11.5948002 2.36541624 11.59373337 2.36291604 2 P 0 ;0,1,2=177,3=0.000000
L 11.59373337 2.36291604 11.59213366 2.36083307 2 P 0 ;0,1,2=177,3=0.000000
L 11.59213366 2.36083307 11.5900003 2.36 2 P 0 ;0,1,2=177,3=0.000000
L 11.5900003 2.36 11.58786693 2.36083307 2 P 0 ;0,1,2=177,3=0.000000
L 11.58786693 2.36083307 11.58626673 2.36291604 2 P 0 ;0,1,2=177,3=0.000000
L 11.58626673 2.36291604 11.5851999 2.36541624 2 P 0 ;0,1,2=177,3=0.000000
L 11.5851999 2.36541624 11.5844 2.36874961 2 P 0 ;0,1,2=177,3=0.000000
L 11.5844 2.36874961 11.58413337 2.37249961 2 P 0 ;0,1,2=177,3=0.000000
L 11.58413337 2.37249961 11.5844 2.37624951 2 P 0 ;0,1,2=177,3=0.000000
L 11.5844 2.37624951 11.5851999 2.37958366 2 P 0 ;0,1,2=177,3=0.000000
L 11.5851999 2.37958366 11.58626673 2.38208317 2 P 0 ;0,1,2=177,3=0.000000
L 11.58626673 2.38208317 11.58786693 2.38416683 2 P 0 ;0,1,2=177,3=0.000000
L 11.58786693 2.38416683 11.5900003 2.385 2 P 0 ;0,1,2=177,3=0.000000
L 11.57186673 2.36374911 11.57026703 2.36166624 2 P 0 ;0,1,2=177,3=0.000000
L 11.57026703 2.36166624 11.5684003 2.36041654 2 P 0 ;0,1,2=177,3=0.000000
L 11.5684003 2.36041654 11.5660003 2.36 2 P 0 ;0,1,2=177,3=0.000000
L 11.5660003 2.36 11.5635998 2.36083307 2 P 0 ;0,1,2=177,3=0.000000
L 11.5635998 2.36083307 11.56173356 2.36249941 2 P 0 ;0,1,2=177,3=0.000000
L 11.56173356 2.36249941 11.5604 2.36541624 2 P 0 ;0,1,2=177,3=0.000000
L 11.5604 2.36541624 11.56013337 2.36874961 2 P 0 ;0,1,2=177,3=0.000000
L 11.56013337 2.36874961 11.56066663 2.37208297 2 P 0 ;0,1,2=177,3=0.000000
L 11.56066663 2.37208297 11.5620002 2.37416663 2 P 0 ;0,1,2=177,3=0.000000
L 11.5620002 2.37416663 11.56386693 2.37583297 2 P 0 ;0,1,2=177,3=0.000000
L 11.56386693 2.37583297 11.56573317 2.37624951 2 P 0 ;0,1,2=177,3=0.000000
L 11.56573317 2.37624951 11.5676 2.37583297 2 P 0 ;0,1,2=177,3=0.000000
L 11.5676 2.37583297 11.5699999 2.37416663 2 P 0 ;0,1,2=177,3=0.000000
L 11.5699999 2.37416663 11.5692001 2.385 2 P 0 ;0,1,2=177,3=0.000000
L 11.5692001 2.385 11.5620002 2.385 2 P 0 ;0,1,2=177,3=0.000000
A 11.64143996 2.335 11.64143996 2.335 11.63893002 2.335 1 P 0 N
L 11.89144341 2.34929636 11.8930436 2.35054685 2 P 0 ;0,1,2=178,3=0.000000
L 11.8930436 2.35054685 11.89490984 2.35138002 2 P 0 ;0,1,2=178,3=0.000000
L 11.89490984 2.35138002 11.89704321 2.35138002 2 P 0 ;0,1,2=178,3=0.000000
L 11.89704321 2.35138002 11.8994437 2.35012943 2 P 0 ;0,1,2=178,3=0.000000
L 11.8994437 2.35012943 11.90130994 2.34804656 2 P 0 ;0,1,2=178,3=0.000000
L 11.90130994 2.34804656 11.9026435 2.34554636 2 P 0 ;0,1,2=178,3=0.000000
L 11.9026435 2.34554636 11.90371043 2.34137982 2 P 0 ;0,1,2=178,3=0.000000
L 11.90371043 2.34137982 11.90397707 2.33762982 2 P 0 ;0,1,2=178,3=0.000000
L 11.90397707 2.33762982 11.90344331 2.33387992 2 P 0 ;0,1,2=178,3=0.000000
L 11.90344331 2.33387992 11.9026435 2.33137963 2 P 0 ;0,1,2=178,3=0.000000
L 11.9026435 2.33137963 11.90104341 2.32887943 2 P 0 ;0,1,2=178,3=0.000000
L 11.90104341 2.32887943 11.89917657 2.32721309 2 P 0 ;0,1,2=178,3=0.000000
L 11.89917657 2.32721309 11.89731033 2.32638002 2 P 0 ;0,1,2=178,3=0.000000
L 11.89731033 2.32638002 11.8954436 2.32638002 2 P 0 ;0,1,2=178,3=0.000000
L 11.8954436 2.32638002 11.89357677 2.32721309 2 P 0 ;0,1,2=178,3=0.000000
L 11.89357677 2.32721309 11.89197667 2.32846289 2 P 0 ;0,1,2=178,3=0.000000
L 11.89197667 2.32846289 11.89064311 2.33012913 2 P 0 ;0,1,2=178,3=0.000000
L 11.87837687 2.34721339 11.87677677 2.34971289 2 P 0 ;0,1,2=178,3=0.000000
L 11.87677677 2.34971289 11.87491004 2.35096339 2 P 0 ;0,1,2=178,3=0.000000
L 11.87491004 2.35096339 11.87277667 2.35138002 2 P 0 ;0,1,2=178,3=0.000000
L 11.87277667 2.35138002 11.87011004 2.35054685 2 P 0 ;0,1,2=178,3=0.000000
L 11.87011004 2.35054685 11.86824331 2.34846319 2 P 0 ;0,1,2=178,3=0.000000
L 11.86824331 2.34846319 11.86771004 2.34596368 2 P 0 ;0,1,2=178,3=0.000000
L 11.86771004 2.34596368 11.86797667 2.3434627 2 P 0 ;0,1,2=178,3=0.000000
L 11.86797667 2.3434627 11.8690436 2.34137982 2 P 0 ;0,1,2=178,3=0.000000
L 11.8690436 2.34137982 11.87437677 2.33721329 2 P 0 ;0,1,2=178,3=0.000000
L 11.87437677 2.33721329 11.87677677 2.33429646 2 P 0 ;0,1,2=178,3=0.000000
L 11.87677677 2.33429646 11.87837687 2.33012913 2 P 0 ;0,1,2=178,3=0.000000
L 11.87837687 2.33012913 11.87891014 2.32638002 2 P 0 ;0,1,2=178,3=0.000000
L 11.87891014 2.32638002 11.86771004 2.32638002 2 P 0 ;0,1,2=178,3=0.000000
L 11.85437687 2.34721339 11.85277677 2.34971289 2 P 0 ;0,1,2=178,3=0.000000
L 11.85277677 2.34971289 11.85091004 2.35096339 2 P 0 ;0,1,2=178,3=0.000000
L 11.85091004 2.35096339 11.84877667 2.35138002 2 P 0 ;0,1,2=178,3=0.000000
L 11.84877667 2.35138002 11.84611004 2.35054685 2 P 0 ;0,1,2=178,3=0.000000
L 11.84611004 2.35054685 11.84424331 2.34846319 2 P 0 ;0,1,2=178,3=0.000000
L 11.84424331 2.34846319 11.84371004 2.34596368 2 P 0 ;0,1,2=178,3=0.000000
L 11.84371004 2.34596368 11.84397667 2.3434627 2 P 0 ;0,1,2=178,3=0.000000
L 11.84397667 2.3434627 11.8450436 2.34137982 2 P 0 ;0,1,2=178,3=0.000000
L 11.8450436 2.34137982 11.85037677 2.33721329 2 P 0 ;0,1,2=178,3=0.000000
L 11.85037677 2.33721329 11.85277677 2.33429646 2 P 0 ;0,1,2=178,3=0.000000
L 11.85277677 2.33429646 11.85437687 2.33012913 2 P 0 ;0,1,2=178,3=0.000000
L 11.85437687 2.33012913 11.85491014 2.32638002 2 P 0 ;0,1,2=178,3=0.000000
L 11.85491014 2.32638002 11.84371004 2.32638002 2 P 0 ;0,1,2=178,3=0.000000
L 11.82531033 2.35138002 11.8274437 2.35054685 2 P 0 ;0,1,2=178,3=0.000000
L 11.8274437 2.35054685 11.82904341 2.34846319 2 P 0 ;0,1,2=178,3=0.000000
L 11.82904341 2.34846319 11.83011024 2.34596368 2 P 0 ;0,1,2=178,3=0.000000
L 11.83011024 2.34596368 11.83091014 2.34262953 2 P 0 ;0,1,2=178,3=0.000000
L 11.83091014 2.34262953 11.83117677 2.33887963 2 P 0 ;0,1,2=178,3=0.000000
L 11.83117677 2.33887963 11.83091014 2.33512963 2 P 0 ;0,1,2=178,3=0.000000
L 11.83091014 2.33512963 11.83011024 2.33179626 2 P 0 ;0,1,2=178,3=0.000000
L 11.83011024 2.33179626 11.82904341 2.32929606 2 P 0 ;0,1,2=178,3=0.000000
L 11.82904341 2.32929606 11.8274437 2.32721309 2 P 0 ;0,1,2=178,3=0.000000
L 11.8274437 2.32721309 11.82531033 2.32638002 2 P 0 ;0,1,2=178,3=0.000000
L 11.82531033 2.32638002 11.82317697 2.32721309 2 P 0 ;0,1,2=178,3=0.000000
L 11.82317697 2.32721309 11.82157677 2.32929606 2 P 0 ;0,1,2=178,3=0.000000
L 11.82157677 2.32929606 11.82050994 2.33179626 2 P 0 ;0,1,2=178,3=0.000000
L 11.82050994 2.33179626 11.81971004 2.33512963 2 P 0 ;0,1,2=178,3=0.000000
L 11.81971004 2.33512963 11.81944341 2.33887963 2 P 0 ;0,1,2=178,3=0.000000
L 11.81944341 2.33887963 11.81971004 2.34262953 2 P 0 ;0,1,2=178,3=0.000000
L 11.81971004 2.34262953 11.82050994 2.34596368 2 P 0 ;0,1,2=178,3=0.000000
L 11.82050994 2.34596368 11.82157677 2.34846319 2 P 0 ;0,1,2=178,3=0.000000
L 11.82157677 2.34846319 11.82317697 2.35054685 2 P 0 ;0,1,2=178,3=0.000000
L 11.82317697 2.35054685 11.82531033 2.35138002 2 P 0 ;0,1,2=178,3=0.000000
L 11.80637687 2.33679596 11.80451014 2.33971348 2 P 0 ;0,1,2=178,3=0.000000
L 11.80451014 2.33971348 11.80291004 2.34137982 2 P 0 ;0,1,2=178,3=0.000000
L 11.80291004 2.34137982 11.80077667 2.34221299 2 P 0 ;0,1,2=178,3=0.000000
L 11.80077667 2.34221299 11.79890984 2.34137982 2 P 0 ;0,1,2=178,3=0.000000
L 11.79890984 2.34137982 11.79757677 2.33971348 2 P 0 ;0,1,2=178,3=0.000000
L 11.79757677 2.33971348 11.79650994 2.33721329 2 P 0 ;0,1,2=178,3=0.000000
L 11.79650994 2.33721329 11.79624331 2.33429646 2 P 0 ;0,1,2=178,3=0.000000
L 11.79624331 2.33429646 11.79650994 2.33179626 2 P 0 ;0,1,2=178,3=0.000000
L 11.79650994 2.33179626 11.79757677 2.32929606 2 P 0 ;0,1,2=178,3=0.000000
L 11.79757677 2.32929606 11.79917697 2.32721309 2 P 0 ;0,1,2=178,3=0.000000
L 11.79917697 2.32721309 11.80104321 2.32638002 2 P 0 ;0,1,2=178,3=0.000000
L 11.80104321 2.32638002 11.80317657 2.32721309 2 P 0 ;0,1,2=178,3=0.000000
L 11.80317657 2.32721309 11.80504341 2.3297126 2 P 0 ;0,1,2=178,3=0.000000
L 11.80504341 2.3297126 11.80611024 2.33346329 2 P 0 ;0,1,2=178,3=0.000000
L 11.80611024 2.33346329 11.80637687 2.33762982 2 P 0 ;0,1,2=178,3=0.000000
L 11.80637687 2.33762982 11.8058437 2.34304616 2 P 0 ;0,1,2=178,3=0.000000
L 11.8058437 2.34304616 11.80504341 2.34596368 2 P 0 ;0,1,2=178,3=0.000000
L 11.80504341 2.34596368 11.80371033 2.34887972 2 P 0 ;0,1,2=178,3=0.000000
L 11.80371033 2.34887972 11.8018435 2.35096339 2 P 0 ;0,1,2=178,3=0.000000
L 11.8018435 2.35096339 11.79997677 2.35138002 2 P 0 ;0,1,2=178,3=0.000000
L 11.79997677 2.35138002 11.79811004 2.35054685 2 P 0 ;0,1,2=178,3=0.000000
L 11.79811004 2.35054685 11.79677648 2.34846319 2 P 0 ;0,1,2=178,3=0.000000
A 11.64143996 2.29 11.64143996 2.29 11.63893002 2.29 1 P 0 N
L 11.89144341 2.30429636 11.8930436 2.30554685 2 P 0 ;0,1,2=179,3=0.000000
L 11.8930436 2.30554685 11.89490984 2.30638002 2 P 0 ;0,1,2=179,3=0.000000
L 11.89490984 2.30638002 11.89704321 2.30638002 2 P 0 ;0,1,2=179,3=0.000000
L 11.89704321 2.30638002 11.8994437 2.30512943 2 P 0 ;0,1,2=179,3=0.000000
L 11.8994437 2.30512943 11.90130994 2.30304656 2 P 0 ;0,1,2=179,3=0.000000
L 11.90130994 2.30304656 11.9026435 2.30054636 2 P 0 ;0,1,2=179,3=0.000000
L 11.9026435 2.30054636 11.90371043 2.29637982 2 P 0 ;0,1,2=179,3=0.000000
L 11.90371043 2.29637982 11.90397707 2.29262982 2 P 0 ;0,1,2=179,3=0.000000
L 11.90397707 2.29262982 11.90344331 2.28887992 2 P 0 ;0,1,2=179,3=0.000000
L 11.90344331 2.28887992 11.9026435 2.28637963 2 P 0 ;0,1,2=179,3=0.000000
L 11.9026435 2.28637963 11.90104341 2.28387943 2 P 0 ;0,1,2=179,3=0.000000
L 11.90104341 2.28387943 11.89917657 2.28221309 2 P 0 ;0,1,2=179,3=0.000000
L 11.89917657 2.28221309 11.89731033 2.28138002 2 P 0 ;0,1,2=179,3=0.000000
L 11.89731033 2.28138002 11.8954436 2.28138002 2 P 0 ;0,1,2=179,3=0.000000
L 11.8954436 2.28138002 11.89357677 2.28221309 2 P 0 ;0,1,2=179,3=0.000000
L 11.89357677 2.28221309 11.89197667 2.28346289 2 P 0 ;0,1,2=179,3=0.000000
L 11.89197667 2.28346289 11.89064311 2.28512913 2 P 0 ;0,1,2=179,3=0.000000
L 11.87837687 2.30221339 11.87677677 2.30471289 2 P 0 ;0,1,2=179,3=0.000000
L 11.87677677 2.30471289 11.87491004 2.30596339 2 P 0 ;0,1,2=179,3=0.000000
L 11.87491004 2.30596339 11.87277667 2.30638002 2 P 0 ;0,1,2=179,3=0.000000
L 11.87277667 2.30638002 11.87011004 2.30554685 2 P 0 ;0,1,2=179,3=0.000000
L 11.87011004 2.30554685 11.86824331 2.30346319 2 P 0 ;0,1,2=179,3=0.000000
L 11.86824331 2.30346319 11.86771004 2.30096368 2 P 0 ;0,1,2=179,3=0.000000
L 11.86771004 2.30096368 11.86797667 2.2984627 2 P 0 ;0,1,2=179,3=0.000000
L 11.86797667 2.2984627 11.8690436 2.29637982 2 P 0 ;0,1,2=179,3=0.000000
L 11.8690436 2.29637982 11.87437677 2.29221329 2 P 0 ;0,1,2=179,3=0.000000
L 11.87437677 2.29221329 11.87677677 2.28929646 2 P 0 ;0,1,2=179,3=0.000000
L 11.87677677 2.28929646 11.87837687 2.28512913 2 P 0 ;0,1,2=179,3=0.000000
L 11.87837687 2.28512913 11.87891014 2.28138002 2 P 0 ;0,1,2=179,3=0.000000
L 11.87891014 2.28138002 11.86771004 2.28138002 2 P 0 ;0,1,2=179,3=0.000000
L 11.85437687 2.30221339 11.85277677 2.30471289 2 P 0 ;0,1,2=179,3=0.000000
L 11.85277677 2.30471289 11.85091004 2.30596339 2 P 0 ;0,1,2=179,3=0.000000
L 11.85091004 2.30596339 11.84877667 2.30638002 2 P 0 ;0,1,2=179,3=0.000000
L 11.84877667 2.30638002 11.84611004 2.30554685 2 P 0 ;0,1,2=179,3=0.000000
L 11.84611004 2.30554685 11.84424331 2.30346319 2 P 0 ;0,1,2=179,3=0.000000
L 11.84424331 2.30346319 11.84371004 2.30096368 2 P 0 ;0,1,2=179,3=0.000000
L 11.84371004 2.30096368 11.84397667 2.2984627 2 P 0 ;0,1,2=179,3=0.000000
L 11.84397667 2.2984627 11.8450436 2.29637982 2 P 0 ;0,1,2=179,3=0.000000
L 11.8450436 2.29637982 11.85037677 2.29221329 2 P 0 ;0,1,2=179,3=0.000000
L 11.85037677 2.29221329 11.85277677 2.28929646 2 P 0 ;0,1,2=179,3=0.000000
L 11.85277677 2.28929646 11.85437687 2.28512913 2 P 0 ;0,1,2=179,3=0.000000
L 11.85437687 2.28512913 11.85491014 2.28138002 2 P 0 ;0,1,2=179,3=0.000000
L 11.85491014 2.28138002 11.84371004 2.28138002 2 P 0 ;0,1,2=179,3=0.000000
L 11.82531033 2.30638002 11.8274437 2.30554685 2 P 0 ;0,1,2=179,3=0.000000
L 11.8274437 2.30554685 11.82904341 2.30346319 2 P 0 ;0,1,2=179,3=0.000000
L 11.82904341 2.30346319 11.83011024 2.30096368 2 P 0 ;0,1,2=179,3=0.000000
L 11.83011024 2.30096368 11.83091014 2.29762953 2 P 0 ;0,1,2=179,3=0.000000
L 11.83091014 2.29762953 11.83117677 2.29387963 2 P 0 ;0,1,2=179,3=0.000000
L 11.83117677 2.29387963 11.83091014 2.29012963 2 P 0 ;0,1,2=179,3=0.000000
L 11.83091014 2.29012963 11.83011024 2.28679626 2 P 0 ;0,1,2=179,3=0.000000
L 11.83011024 2.28679626 11.82904341 2.28429606 2 P 0 ;0,1,2=179,3=0.000000
L 11.82904341 2.28429606 11.8274437 2.28221309 2 P 0 ;0,1,2=179,3=0.000000
L 11.8274437 2.28221309 11.82531033 2.28138002 2 P 0 ;0,1,2=179,3=0.000000
L 11.82531033 2.28138002 11.82317697 2.28221309 2 P 0 ;0,1,2=179,3=0.000000
L 11.82317697 2.28221309 11.82157677 2.28429606 2 P 0 ;0,1,2=179,3=0.000000
L 11.82157677 2.28429606 11.82050994 2.28679626 2 P 0 ;0,1,2=179,3=0.000000
L 11.82050994 2.28679626 11.81971004 2.29012963 2 P 0 ;0,1,2=179,3=0.000000
L 11.81971004 2.29012963 11.81944341 2.29387963 2 P 0 ;0,1,2=179,3=0.000000
L 11.81944341 2.29387963 11.81971004 2.29762953 2 P 0 ;0,1,2=179,3=0.000000
L 11.81971004 2.29762953 11.82050994 2.30096368 2 P 0 ;0,1,2=179,3=0.000000
L 11.82050994 2.30096368 11.82157677 2.30346319 2 P 0 ;0,1,2=179,3=0.000000
L 11.82157677 2.30346319 11.82317697 2.30554685 2 P 0 ;0,1,2=179,3=0.000000
L 11.82317697 2.30554685 11.82531033 2.30638002 2 P 0 ;0,1,2=179,3=0.000000
L 11.8018435 2.28138002 11.80131033 2.28679626 2 P 0 ;0,1,2=179,3=0.000000
L 11.80131033 2.28679626 11.80051004 2.29137933 2 P 0 ;0,1,2=179,3=0.000000
L 11.80051004 2.29137933 11.7994436 2.29554665 2 P 0 ;0,1,2=179,3=0.000000
L 11.7994436 2.29554665 11.79811004 2.30012982 2 P 0 ;0,1,2=179,3=0.000000
L 11.79811004 2.30012982 11.79597667 2.30638002 2 P 0 ;0,1,2=179,3=0.000000
L 11.79597667 2.30638002 11.8066435 2.30638002 2 P 0 ;0,1,2=179,3=0.000000
A 11.44143996 2.095 11.44143996 2.095 11.43893002 2.095 1 P 0 N
L 11.65613337 2.10291634 11.65773356 2.10416683 2 P 0 ;0,1,2=180,3=0.000000
L 11.65773356 2.10416683 11.6595998 2.105 2 P 0 ;0,1,2=180,3=0.000000
L 11.6595998 2.105 11.66173317 2.105 2 P 0 ;0,1,2=180,3=0.000000
L 11.66173317 2.105 11.66413366 2.10374941 2 P 0 ;0,1,2=180,3=0.000000
L 11.66413366 2.10374941 11.6659999 2.10166654 2 P 0 ;0,1,2=180,3=0.000000
L 11.6659999 2.10166654 11.66733346 2.09916634 2 P 0 ;0,1,2=180,3=0.000000
L 11.66733346 2.09916634 11.66840039 2.0949998 2 P 0 ;0,1,2=180,3=0.000000
L 11.66840039 2.0949998 11.66866703 2.0912498 2 P 0 ;0,1,2=180,3=0.000000
L 11.66866703 2.0912498 11.66813327 2.0874999 2 P 0 ;0,1,2=180,3=0.000000
L 11.66813327 2.0874999 11.66733346 2.08499961 2 P 0 ;0,1,2=180,3=0.000000
L 11.66733346 2.08499961 11.66573337 2.08249941 2 P 0 ;0,1,2=180,3=0.000000
L 11.66573337 2.08249941 11.66386654 2.08083307 2 P 0 ;0,1,2=180,3=0.000000
L 11.66386654 2.08083307 11.6620003 2.08 2 P 0 ;0,1,2=180,3=0.000000
L 11.6620003 2.08 11.66013356 2.08 2 P 0 ;0,1,2=180,3=0.000000
L 11.66013356 2.08 11.65826673 2.08083307 2 P 0 ;0,1,2=180,3=0.000000
L 11.65826673 2.08083307 11.65666663 2.08208287 2 P 0 ;0,1,2=180,3=0.000000
L 11.65666663 2.08208287 11.65533307 2.08374911 2 P 0 ;0,1,2=180,3=0.000000
L 11.64306683 2.10083337 11.64146673 2.10333287 2 P 0 ;0,1,2=180,3=0.000000
L 11.64146673 2.10333287 11.6396 2.10458337 2 P 0 ;0,1,2=180,3=0.000000
L 11.6396 2.10458337 11.63746663 2.105 2 P 0 ;0,1,2=180,3=0.000000
L 11.63746663 2.105 11.6348 2.10416683 2 P 0 ;0,1,2=180,3=0.000000
L 11.6348 2.10416683 11.63293327 2.10208317 2 P 0 ;0,1,2=180,3=0.000000
L 11.63293327 2.10208317 11.6324 2.09958366 2 P 0 ;0,1,2=180,3=0.000000
L 11.6324 2.09958366 11.63266663 2.09708268 2 P 0 ;0,1,2=180,3=0.000000
L 11.63266663 2.09708268 11.63373356 2.0949998 2 P 0 ;0,1,2=180,3=0.000000
L 11.63373356 2.0949998 11.63906673 2.09083327 2 P 0 ;0,1,2=180,3=0.000000
L 11.63906673 2.09083327 11.64146673 2.08791644 2 P 0 ;0,1,2=180,3=0.000000
L 11.64146673 2.08791644 11.64306683 2.08374911 2 P 0 ;0,1,2=180,3=0.000000
L 11.64306683 2.08374911 11.6436001 2.08 2 P 0 ;0,1,2=180,3=0.000000
L 11.6436001 2.08 11.6324 2.08 2 P 0 ;0,1,2=180,3=0.000000
L 11.61906683 2.10083337 11.61746673 2.10333287 2 P 0 ;0,1,2=180,3=0.000000
L 11.61746673 2.10333287 11.6156 2.10458337 2 P 0 ;0,1,2=180,3=0.000000
L 11.6156 2.10458337 11.61346663 2.105 2 P 0 ;0,1,2=180,3=0.000000
L 11.61346663 2.105 11.6108 2.10416683 2 P 0 ;0,1,2=180,3=0.000000
L 11.6108 2.10416683 11.60893327 2.10208317 2 P 0 ;0,1,2=180,3=0.000000
L 11.60893327 2.10208317 11.6084 2.09958366 2 P 0 ;0,1,2=180,3=0.000000
L 11.6084 2.09958366 11.60866663 2.09708268 2 P 0 ;0,1,2=180,3=0.000000
L 11.60866663 2.09708268 11.60973356 2.0949998 2 P 0 ;0,1,2=180,3=0.000000
L 11.60973356 2.0949998 11.61506673 2.09083327 2 P 0 ;0,1,2=180,3=0.000000
L 11.61506673 2.09083327 11.61746673 2.08791644 2 P 0 ;0,1,2=180,3=0.000000
L 11.61746673 2.08791644 11.61906683 2.08374911 2 P 0 ;0,1,2=180,3=0.000000
L 11.61906683 2.08374911 11.6196001 2.08 2 P 0 ;0,1,2=180,3=0.000000
L 11.6196001 2.08 11.6084 2.08 2 P 0 ;0,1,2=180,3=0.000000
L 11.5900003 2.105 11.59213366 2.10416683 2 P 0 ;0,1,2=180,3=0.000000
L 11.59213366 2.10416683 11.59373337 2.10208317 2 P 0 ;0,1,2=180,3=0.000000
L 11.59373337 2.10208317 11.5948002 2.09958366 2 P 0 ;0,1,2=180,3=0.000000
L 11.5948002 2.09958366 11.5956001 2.09624951 2 P 0 ;0,1,2=180,3=0.000000
L 11.5956001 2.09624951 11.59586673 2.09249961 2 P 0 ;0,1,2=180,3=0.000000
L 11.59586673 2.09249961 11.5956001 2.08874961 2 P 0 ;0,1,2=180,3=0.000000
L 11.5956001 2.08874961 11.5948002 2.08541624 2 P 0 ;0,1,2=180,3=0.000000
L 11.5948002 2.08541624 11.59373337 2.08291604 2 P 0 ;0,1,2=180,3=0.000000
L 11.59373337 2.08291604 11.59213366 2.08083307 2 P 0 ;0,1,2=180,3=0.000000
L 11.59213366 2.08083307 11.5900003 2.08 2 P 0 ;0,1,2=180,3=0.000000
L 11.5900003 2.08 11.58786693 2.08083307 2 P 0 ;0,1,2=180,3=0.000000
L 11.58786693 2.08083307 11.58626673 2.08291604 2 P 0 ;0,1,2=180,3=0.000000
L 11.58626673 2.08291604 11.5851999 2.08541624 2 P 0 ;0,1,2=180,3=0.000000
L 11.5851999 2.08541624 11.5844 2.08874961 2 P 0 ;0,1,2=180,3=0.000000
L 11.5844 2.08874961 11.58413337 2.09249961 2 P 0 ;0,1,2=180,3=0.000000
L 11.58413337 2.09249961 11.5844 2.09624951 2 P 0 ;0,1,2=180,3=0.000000
L 11.5844 2.09624951 11.5851999 2.09958366 2 P 0 ;0,1,2=180,3=0.000000
L 11.5851999 2.09958366 11.58626673 2.10208317 2 P 0 ;0,1,2=180,3=0.000000
L 11.58626673 2.10208317 11.58786693 2.10416683 2 P 0 ;0,1,2=180,3=0.000000
L 11.58786693 2.10416683 11.5900003 2.105 2 P 0 ;0,1,2=180,3=0.000000
L 11.5660003 2.08 11.56413356 2.08041654 2 P 0 ;0,1,2=180,3=0.000000
L 11.56413356 2.08041654 11.5620002 2.08166624 2 P 0 ;0,1,2=180,3=0.000000
L 11.5620002 2.08166624 11.56066663 2.08374911 2 P 0 ;0,1,2=180,3=0.000000
L 11.56066663 2.08374911 11.56013337 2.08666673 2 P 0 ;0,1,2=180,3=0.000000
L 11.56013337 2.08666673 11.56066663 2.08958278 2 P 0 ;0,1,2=180,3=0.000000
L 11.56066663 2.08958278 11.56226673 2.09208297 2 P 0 ;0,1,2=180,3=0.000000
L 11.56226673 2.09208297 11.56466673 2.09333346 2 P 0 ;0,1,2=180,3=0.000000
L 11.56466673 2.09333346 11.56733337 2.09333346 2 P 0 ;0,1,2=180,3=0.000000
L 11.56733337 2.09333346 11.56893346 2.09416663 2 P 0 ;0,1,2=180,3=0.000000
L 11.56893346 2.09416663 11.57026703 2.09624951 2 P 0 ;0,1,2=180,3=0.000000
L 11.57026703 2.09624951 11.5708002 2.09916634 2 P 0 ;0,1,2=180,3=0.000000
L 11.5708002 2.09916634 11.5699999 2.10208317 2 P 0 ;0,1,2=180,3=0.000000
L 11.5699999 2.10208317 11.56813366 2.10416683 2 P 0 ;0,1,2=180,3=0.000000
L 11.56813366 2.10416683 11.5660003 2.105 2 P 0 ;0,1,2=180,3=0.000000
L 11.5660003 2.105 11.56386693 2.10416683 2 P 0 ;0,1,2=180,3=0.000000
L 11.56386693 2.10416683 11.5620002 2.10208317 2 P 0 ;0,1,2=180,3=0.000000
L 11.5620002 2.10208317 11.5611999 2.09916634 2 P 0 ;0,1,2=180,3=0.000000
L 11.5611999 2.09916634 11.56173356 2.09624951 2 P 0 ;0,1,2=180,3=0.000000
L 11.56173356 2.09624951 11.56306663 2.09416663 2 P 0 ;0,1,2=180,3=0.000000
L 11.56306663 2.09416663 11.56466673 2.09333346 2 P 0 ;0,1,2=180,3=0.000000
L 11.56466673 2.09333346 11.56733337 2.09333346 2 P 0 ;0,1,2=180,3=0.000000
L 11.56733337 2.09333346 11.56973337 2.09208297 2 P 0 ;0,1,2=180,3=0.000000
L 11.56973337 2.09208297 11.57133346 2.08958278 2 P 0 ;0,1,2=180,3=0.000000
L 11.57133346 2.08958278 11.57186673 2.08666673 2 P 0 ;0,1,2=180,3=0.000000
L 11.57186673 2.08666673 11.57133346 2.08374911 2 P 0 ;0,1,2=180,3=0.000000
L 11.57133346 2.08374911 11.5699999 2.08166624 2 P 0 ;0,1,2=180,3=0.000000
L 11.5699999 2.08166624 11.56786654 2.08041654 2 P 0 ;0,1,2=180,3=0.000000
L 11.56786654 2.08041654 11.5660003 2.08 2 P 0 ;0,1,2=180,3=0.000000
A 11.44143996 2.05 11.44143996 2.05 11.43893002 2.05 1 P 0 N
L 11.65613337 2.06291634 11.65773356 2.06416683 2 P 0 ;0,1,2=181,3=0.000000
L 11.65773356 2.06416683 11.6595998 2.065 2 P 0 ;0,1,2=181,3=0.000000
L 11.6595998 2.065 11.66173317 2.065 2 P 0 ;0,1,2=181,3=0.000000
L 11.66173317 2.065 11.66413366 2.06374941 2 P 0 ;0,1,2=181,3=0.000000
L 11.66413366 2.06374941 11.6659999 2.06166654 2 P 0 ;0,1,2=181,3=0.000000
L 11.6659999 2.06166654 11.66733346 2.05916634 2 P 0 ;0,1,2=181,3=0.000000
L 11.66733346 2.05916634 11.66840039 2.0549998 2 P 0 ;0,1,2=181,3=0.000000
L 11.66840039 2.0549998 11.66866703 2.0512498 2 P 0 ;0,1,2=181,3=0.000000
L 11.66866703 2.0512498 11.66813327 2.0474999 2 P 0 ;0,1,2=181,3=0.000000
L 11.66813327 2.0474999 11.66733346 2.04499961 2 P 0 ;0,1,2=181,3=0.000000
L 11.66733346 2.04499961 11.66573337 2.04249941 2 P 0 ;0,1,2=181,3=0.000000
L 11.66573337 2.04249941 11.66386654 2.04083307 2 P 0 ;0,1,2=181,3=0.000000
L 11.66386654 2.04083307 11.6620003 2.04 2 P 0 ;0,1,2=181,3=0.000000
L 11.6620003 2.04 11.66013356 2.04 2 P 0 ;0,1,2=181,3=0.000000
L 11.66013356 2.04 11.65826673 2.04083307 2 P 0 ;0,1,2=181,3=0.000000
L 11.65826673 2.04083307 11.65666663 2.04208287 2 P 0 ;0,1,2=181,3=0.000000
L 11.65666663 2.04208287 11.65533307 2.04374911 2 P 0 ;0,1,2=181,3=0.000000
L 11.64306683 2.06083337 11.64146673 2.06333287 2 P 0 ;0,1,2=181,3=0.000000
L 11.64146673 2.06333287 11.6396 2.06458337 2 P 0 ;0,1,2=181,3=0.000000
L 11.6396 2.06458337 11.63746663 2.065 2 P 0 ;0,1,2=181,3=0.000000
L 11.63746663 2.065 11.6348 2.06416683 2 P 0 ;0,1,2=181,3=0.000000
L 11.6348 2.06416683 11.63293327 2.06208317 2 P 0 ;0,1,2=181,3=0.000000
L 11.63293327 2.06208317 11.6324 2.05958366 2 P 0 ;0,1,2=181,3=0.000000
L 11.6324 2.05958366 11.63266663 2.05708268 2 P 0 ;0,1,2=181,3=0.000000
L 11.63266663 2.05708268 11.63373356 2.0549998 2 P 0 ;0,1,2=181,3=0.000000
L 11.63373356 2.0549998 11.63906673 2.05083327 2 P 0 ;0,1,2=181,3=0.000000
L 11.63906673 2.05083327 11.64146673 2.04791644 2 P 0 ;0,1,2=181,3=0.000000
L 11.64146673 2.04791644 11.64306683 2.04374911 2 P 0 ;0,1,2=181,3=0.000000
L 11.64306683 2.04374911 11.6436001 2.04 2 P 0 ;0,1,2=181,3=0.000000
L 11.6436001 2.04 11.6324 2.04 2 P 0 ;0,1,2=181,3=0.000000
L 11.61906683 2.06083337 11.61746673 2.06333287 2 P 0 ;0,1,2=181,3=0.000000
L 11.61746673 2.06333287 11.6156 2.06458337 2 P 0 ;0,1,2=181,3=0.000000
L 11.6156 2.06458337 11.61346663 2.065 2 P 0 ;0,1,2=181,3=0.000000
L 11.61346663 2.065 11.6108 2.06416683 2 P 0 ;0,1,2=181,3=0.000000
L 11.6108 2.06416683 11.60893327 2.06208317 2 P 0 ;0,1,2=181,3=0.000000
L 11.60893327 2.06208317 11.6084 2.05958366 2 P 0 ;0,1,2=181,3=0.000000
L 11.6084 2.05958366 11.60866663 2.05708268 2 P 0 ;0,1,2=181,3=0.000000
L 11.60866663 2.05708268 11.60973356 2.0549998 2 P 0 ;0,1,2=181,3=0.000000
L 11.60973356 2.0549998 11.61506673 2.05083327 2 P 0 ;0,1,2=181,3=0.000000
L 11.61506673 2.05083327 11.61746673 2.04791644 2 P 0 ;0,1,2=181,3=0.000000
L 11.61746673 2.04791644 11.61906683 2.04374911 2 P 0 ;0,1,2=181,3=0.000000
L 11.61906683 2.04374911 11.6196001 2.04 2 P 0 ;0,1,2=181,3=0.000000
L 11.6196001 2.04 11.6084 2.04 2 P 0 ;0,1,2=181,3=0.000000
L 11.5900003 2.065 11.59213366 2.06416683 2 P 0 ;0,1,2=181,3=0.000000
L 11.59213366 2.06416683 11.59373337 2.06208317 2 P 0 ;0,1,2=181,3=0.000000
L 11.59373337 2.06208317 11.5948002 2.05958366 2 P 0 ;0,1,2=181,3=0.000000
L 11.5948002 2.05958366 11.5956001 2.05624951 2 P 0 ;0,1,2=181,3=0.000000
L 11.5956001 2.05624951 11.59586673 2.05249961 2 P 0 ;0,1,2=181,3=0.000000
L 11.59586673 2.05249961 11.5956001 2.04874961 2 P 0 ;0,1,2=181,3=0.000000
L 11.5956001 2.04874961 11.5948002 2.04541624 2 P 0 ;0,1,2=181,3=0.000000
L 11.5948002 2.04541624 11.59373337 2.04291604 2 P 0 ;0,1,2=181,3=0.000000
L 11.59373337 2.04291604 11.59213366 2.04083307 2 P 0 ;0,1,2=181,3=0.000000
L 11.59213366 2.04083307 11.5900003 2.04 2 P 0 ;0,1,2=181,3=0.000000
L 11.5900003 2.04 11.58786693 2.04083307 2 P 0 ;0,1,2=181,3=0.000000
L 11.58786693 2.04083307 11.58626673 2.04291604 2 P 0 ;0,1,2=181,3=0.000000
L 11.58626673 2.04291604 11.5851999 2.04541624 2 P 0 ;0,1,2=181,3=0.000000
L 11.5851999 2.04541624 11.5844 2.04874961 2 P 0 ;0,1,2=181,3=0.000000
L 11.5844 2.04874961 11.58413337 2.05249961 2 P 0 ;0,1,2=181,3=0.000000
L 11.58413337 2.05249961 11.5844 2.05624951 2 P 0 ;0,1,2=181,3=0.000000
L 11.5844 2.05624951 11.5851999 2.05958366 2 P 0 ;0,1,2=181,3=0.000000
L 11.5851999 2.05958366 11.58626673 2.06208317 2 P 0 ;0,1,2=181,3=0.000000
L 11.58626673 2.06208317 11.58786693 2.06416683 2 P 0 ;0,1,2=181,3=0.000000
L 11.58786693 2.06416683 11.5900003 2.065 2 P 0 ;0,1,2=181,3=0.000000
L 11.57053366 2.04291604 11.56866683 2.04083307 2 P 0 ;0,1,2=181,3=0.000000
L 11.56866683 2.04083307 11.56653346 2.04 2 P 0 ;0,1,2=181,3=0.000000
L 11.56653346 2.04 11.5644001 2.04083307 2 P 0 ;0,1,2=181,3=0.000000
L 11.5644001 2.04083307 11.56253337 2.04333258 2 P 0 ;0,1,2=181,3=0.000000
L 11.56253337 2.04333258 11.5611999 2.04708327 2 P 0 ;0,1,2=181,3=0.000000
L 11.5611999 2.04708327 11.56066663 2.05083327 2 P 0 ;0,1,2=181,3=0.000000
L 11.56066663 2.05083327 11.56066663 2.05541634 2 P 0 ;0,1,2=181,3=0.000000
L 11.56066663 2.05541634 11.5611999 2.05916634 2 P 0 ;0,1,2=181,3=0.000000
L 11.5611999 2.05916634 11.56253337 2.0624997 2 P 0 ;0,1,2=181,3=0.000000
L 11.56253337 2.0624997 11.56413356 2.06416683 2 P 0 ;0,1,2=181,3=0.000000
L 11.56413356 2.06416683 11.5660003 2.065 2 P 0 ;0,1,2=181,3=0.000000
L 11.5660003 2.065 11.56813366 2.06416683 2 P 0 ;0,1,2=181,3=0.000000
L 11.56813366 2.06416683 11.56973337 2.0624997 2 P 0 ;0,1,2=181,3=0.000000
L 11.56973337 2.0624997 11.5708002 2.0600003 2 P 0 ;0,1,2=181,3=0.000000
L 11.5708002 2.0600003 11.57133346 2.05666614 2 P 0 ;0,1,2=181,3=0.000000
L 11.57133346 2.05666614 11.5708002 2.0537501 2 P 0 ;0,1,2=181,3=0.000000
L 11.5708002 2.0537501 11.56946673 2.05083327 2 P 0 ;0,1,2=181,3=0.000000
L 11.56946673 2.05083327 11.56786654 2.04916614 2 P 0 ;0,1,2=181,3=0.000000
L 11.56786654 2.04916614 11.5660003 2.04874961 2 P 0 ;0,1,2=181,3=0.000000
L 11.5660003 2.04874961 11.56386693 2.04958278 2 P 0 ;0,1,2=181,3=0.000000
L 11.56386693 2.04958278 11.56226673 2.05166644 2 P 0 ;0,1,2=181,3=0.000000
L 11.56226673 2.05166644 11.56066663 2.05541634 2 P 0 ;0,1,2=181,3=0.000000
A 11.44143996 2.255 11.44143996 2.255 11.43893002 2.255 1 P 0 N
L 11.58113337 2.27791634 11.58273356 2.27916683 2 P 0 ;0,1,2=182,3=0.000000
L 11.58273356 2.27916683 11.5845998 2.28 2 P 0 ;0,1,2=182,3=0.000000
L 11.5845998 2.28 11.58673317 2.28 2 P 0 ;0,1,2=182,3=0.000000
L 11.58673317 2.28 11.58913366 2.27874941 2 P 0 ;0,1,2=182,3=0.000000
L 11.58913366 2.27874941 11.5909999 2.27666654 2 P 0 ;0,1,2=182,3=0.000000
L 11.5909999 2.27666654 11.59233346 2.27416634 2 P 0 ;0,1,2=182,3=0.000000
L 11.59233346 2.27416634 11.59340039 2.2699998 2 P 0 ;0,1,2=182,3=0.000000
L 11.59340039 2.2699998 11.59366703 2.2662498 2 P 0 ;0,1,2=182,3=0.000000
L 11.59366703 2.2662498 11.59313327 2.2624999 2 P 0 ;0,1,2=182,3=0.000000
L 11.59313327 2.2624999 11.59233346 2.25999961 2 P 0 ;0,1,2=182,3=0.000000
L 11.59233346 2.25999961 11.59073337 2.25749941 2 P 0 ;0,1,2=182,3=0.000000
L 11.59073337 2.25749941 11.58886654 2.25583307 2 P 0 ;0,1,2=182,3=0.000000
L 11.58886654 2.25583307 11.5870003 2.255 2 P 0 ;0,1,2=182,3=0.000000
L 11.5870003 2.255 11.58513356 2.255 2 P 0 ;0,1,2=182,3=0.000000
L 11.58513356 2.255 11.58326673 2.25583307 2 P 0 ;0,1,2=182,3=0.000000
L 11.58326673 2.25583307 11.58166663 2.25708287 2 P 0 ;0,1,2=182,3=0.000000
L 11.58166663 2.25708287 11.58033307 2.25874911 2 P 0 ;0,1,2=182,3=0.000000
L 11.56806683 2.27583337 11.56646673 2.27833287 2 P 0 ;0,1,2=182,3=0.000000
L 11.56646673 2.27833287 11.5646 2.27958337 2 P 0 ;0,1,2=182,3=0.000000
L 11.5646 2.27958337 11.56246663 2.28 2 P 0 ;0,1,2=182,3=0.000000
L 11.56246663 2.28 11.5598 2.27916683 2 P 0 ;0,1,2=182,3=0.000000
L 11.5598 2.27916683 11.55793327 2.27708317 2 P 0 ;0,1,2=182,3=0.000000
L 11.55793327 2.27708317 11.5574 2.27458366 2 P 0 ;0,1,2=182,3=0.000000
L 11.5574 2.27458366 11.55766663 2.27208268 2 P 0 ;0,1,2=182,3=0.000000
L 11.55766663 2.27208268 11.55873356 2.2699998 2 P 0 ;0,1,2=182,3=0.000000
L 11.55873356 2.2699998 11.56406673 2.26583327 2 P 0 ;0,1,2=182,3=0.000000
L 11.56406673 2.26583327 11.56646673 2.26291644 2 P 0 ;0,1,2=182,3=0.000000
L 11.56646673 2.26291644 11.56806683 2.25874911 2 P 0 ;0,1,2=182,3=0.000000
L 11.56806683 2.25874911 11.5686001 2.255 2 P 0 ;0,1,2=182,3=0.000000
L 11.5686001 2.255 11.5574 2.255 2 P 0 ;0,1,2=182,3=0.000000
L 11.54406683 2.27583337 11.54246673 2.27833287 2 P 0 ;0,1,2=182,3=0.000000
L 11.54246673 2.27833287 11.5406 2.27958337 2 P 0 ;0,1,2=182,3=0.000000
L 11.5406 2.27958337 11.53846663 2.28 2 P 0 ;0,1,2=182,3=0.000000
L 11.53846663 2.28 11.5358 2.27916683 2 P 0 ;0,1,2=182,3=0.000000
L 11.5358 2.27916683 11.53393327 2.27708317 2 P 0 ;0,1,2=182,3=0.000000
L 11.53393327 2.27708317 11.5334 2.27458366 2 P 0 ;0,1,2=182,3=0.000000
L 11.5334 2.27458366 11.53366663 2.27208268 2 P 0 ;0,1,2=182,3=0.000000
L 11.53366663 2.27208268 11.53473356 2.2699998 2 P 0 ;0,1,2=182,3=0.000000
L 11.53473356 2.2699998 11.54006673 2.26583327 2 P 0 ;0,1,2=182,3=0.000000
L 11.54006673 2.26583327 11.54246673 2.26291644 2 P 0 ;0,1,2=182,3=0.000000
L 11.54246673 2.26291644 11.54406683 2.25874911 2 P 0 ;0,1,2=182,3=0.000000
L 11.54406683 2.25874911 11.5446001 2.255 2 P 0 ;0,1,2=182,3=0.000000
L 11.5446001 2.255 11.5334 2.255 2 P 0 ;0,1,2=182,3=0.000000
L 11.5150003 2.255 11.5150003 2.28 2 P 0 ;0,1,2=182,3=0.000000
L 11.5150003 2.28 11.5182001 2.2750003 2 P 0 ;0,1,2=182,3=0.000000
L 11.5182001 2.255 11.51180049 2.255 2 P 0 ;0,1,2=182,3=0.000000
L 11.4910003 2.28 11.49313366 2.27916683 2 P 0 ;0,1,2=182,3=0.000000
L 11.49313366 2.27916683 11.49473337 2.27708317 2 P 0 ;0,1,2=182,3=0.000000
L 11.49473337 2.27708317 11.4958002 2.27458366 2 P 0 ;0,1,2=182,3=0.000000
L 11.4958002 2.27458366 11.4966001 2.27124951 2 P 0 ;0,1,2=182,3=0.000000
L 11.4966001 2.27124951 11.49686673 2.26749961 2 P 0 ;0,1,2=182,3=0.000000
L 11.49686673 2.26749961 11.4966001 2.26374961 2 P 0 ;0,1,2=182,3=0.000000
L 11.4966001 2.26374961 11.4958002 2.26041624 2 P 0 ;0,1,2=182,3=0.000000
L 11.4958002 2.26041624 11.49473337 2.25791604 2 P 0 ;0,1,2=182,3=0.000000
L 11.49473337 2.25791604 11.49313366 2.25583307 2 P 0 ;0,1,2=182,3=0.000000
L 11.49313366 2.25583307 11.4910003 2.255 2 P 0 ;0,1,2=182,3=0.000000
L 11.4910003 2.255 11.48886693 2.25583307 2 P 0 ;0,1,2=182,3=0.000000
L 11.48886693 2.25583307 11.48726673 2.25791604 2 P 0 ;0,1,2=182,3=0.000000
L 11.48726673 2.25791604 11.4861999 2.26041624 2 P 0 ;0,1,2=182,3=0.000000
L 11.4861999 2.26041624 11.4854 2.26374961 2 P 0 ;0,1,2=182,3=0.000000
L 11.4854 2.26374961 11.48513337 2.26749961 2 P 0 ;0,1,2=182,3=0.000000
L 11.48513337 2.26749961 11.4854 2.27124951 2 P 0 ;0,1,2=182,3=0.000000
L 11.4854 2.27124951 11.4861999 2.27458366 2 P 0 ;0,1,2=182,3=0.000000
L 11.4861999 2.27458366 11.48726673 2.27708317 2 P 0 ;0,1,2=182,3=0.000000
L 11.48726673 2.27708317 11.48886693 2.27916683 2 P 0 ;0,1,2=182,3=0.000000
L 11.48886693 2.27916683 11.4910003 2.28 2 P 0 ;0,1,2=182,3=0.000000
A 11.44143996 2.21 11.44143996 2.21 11.43893002 2.21 1 P 0 N
L 11.58113337 2.21291634 11.58273356 2.21416683 2 P 0 ;0,1,2=183,3=0.000000
L 11.58273356 2.21416683 11.5845998 2.215 2 P 0 ;0,1,2=183,3=0.000000
L 11.5845998 2.215 11.58673317 2.215 2 P 0 ;0,1,2=183,3=0.000000
L 11.58673317 2.215 11.58913366 2.21374941 2 P 0 ;0,1,2=183,3=0.000000
L 11.58913366 2.21374941 11.5909999 2.21166654 2 P 0 ;0,1,2=183,3=0.000000
L 11.5909999 2.21166654 11.59233346 2.20916634 2 P 0 ;0,1,2=183,3=0.000000
L 11.59233346 2.20916634 11.59340039 2.2049998 2 P 0 ;0,1,2=183,3=0.000000
L 11.59340039 2.2049998 11.59366703 2.2012498 2 P 0 ;0,1,2=183,3=0.000000
L 11.59366703 2.2012498 11.59313327 2.1974999 2 P 0 ;0,1,2=183,3=0.000000
L 11.59313327 2.1974999 11.59233346 2.19499961 2 P 0 ;0,1,2=183,3=0.000000
L 11.59233346 2.19499961 11.59073337 2.19249941 2 P 0 ;0,1,2=183,3=0.000000
L 11.59073337 2.19249941 11.58886654 2.19083307 2 P 0 ;0,1,2=183,3=0.000000
L 11.58886654 2.19083307 11.5870003 2.19 2 P 0 ;0,1,2=183,3=0.000000
L 11.5870003 2.19 11.58513356 2.19 2 P 0 ;0,1,2=183,3=0.000000
L 11.58513356 2.19 11.58326673 2.19083307 2 P 0 ;0,1,2=183,3=0.000000
L 11.58326673 2.19083307 11.58166663 2.19208287 2 P 0 ;0,1,2=183,3=0.000000
L 11.58166663 2.19208287 11.58033307 2.19374911 2 P 0 ;0,1,2=183,3=0.000000
L 11.56806683 2.21083337 11.56646673 2.21333287 2 P 0 ;0,1,2=183,3=0.000000
L 11.56646673 2.21333287 11.5646 2.21458337 2 P 0 ;0,1,2=183,3=0.000000
L 11.5646 2.21458337 11.56246663 2.215 2 P 0 ;0,1,2=183,3=0.000000
L 11.56246663 2.215 11.5598 2.21416683 2 P 0 ;0,1,2=183,3=0.000000
L 11.5598 2.21416683 11.55793327 2.21208317 2 P 0 ;0,1,2=183,3=0.000000
L 11.55793327 2.21208317 11.5574 2.20958366 2 P 0 ;0,1,2=183,3=0.000000
L 11.5574 2.20958366 11.55766663 2.20708268 2 P 0 ;0,1,2=183,3=0.000000
L 11.55766663 2.20708268 11.55873356 2.2049998 2 P 0 ;0,1,2=183,3=0.000000
L 11.55873356 2.2049998 11.56406673 2.20083327 2 P 0 ;0,1,2=183,3=0.000000
L 11.56406673 2.20083327 11.56646673 2.19791644 2 P 0 ;0,1,2=183,3=0.000000
L 11.56646673 2.19791644 11.56806683 2.19374911 2 P 0 ;0,1,2=183,3=0.000000
L 11.56806683 2.19374911 11.5686001 2.19 2 P 0 ;0,1,2=183,3=0.000000
L 11.5686001 2.19 11.5574 2.19 2 P 0 ;0,1,2=183,3=0.000000
L 11.54406683 2.21083337 11.54246673 2.21333287 2 P 0 ;0,1,2=183,3=0.000000
L 11.54246673 2.21333287 11.5406 2.21458337 2 P 0 ;0,1,2=183,3=0.000000
L 11.5406 2.21458337 11.53846663 2.215 2 P 0 ;0,1,2=183,3=0.000000
L 11.53846663 2.215 11.5358 2.21416683 2 P 0 ;0,1,2=183,3=0.000000
L 11.5358 2.21416683 11.53393327 2.21208317 2 P 0 ;0,1,2=183,3=0.000000
L 11.53393327 2.21208317 11.5334 2.20958366 2 P 0 ;0,1,2=183,3=0.000000
L 11.5334 2.20958366 11.53366663 2.20708268 2 P 0 ;0,1,2=183,3=0.000000
L 11.53366663 2.20708268 11.53473356 2.2049998 2 P 0 ;0,1,2=183,3=0.000000
L 11.53473356 2.2049998 11.54006673 2.20083327 2 P 0 ;0,1,2=183,3=0.000000
L 11.54006673 2.20083327 11.54246673 2.19791644 2 P 0 ;0,1,2=183,3=0.000000
L 11.54246673 2.19791644 11.54406683 2.19374911 2 P 0 ;0,1,2=183,3=0.000000
L 11.54406683 2.19374911 11.5446001 2.19 2 P 0 ;0,1,2=183,3=0.000000
L 11.5446001 2.19 11.5334 2.19 2 P 0 ;0,1,2=183,3=0.000000
L 11.5150003 2.19 11.5150003 2.215 2 P 0 ;0,1,2=183,3=0.000000
L 11.5150003 2.215 11.5182001 2.2100003 2 P 0 ;0,1,2=183,3=0.000000
L 11.5182001 2.19 11.51180049 2.19 2 P 0 ;0,1,2=183,3=0.000000
L 11.4910003 2.19 11.4910003 2.215 2 P 0 ;0,1,2=183,3=0.000000
L 11.4910003 2.215 11.4942001 2.2100003 2 P 0 ;0,1,2=183,3=0.000000
L 11.4942001 2.19 11.48780049 2.19 2 P 0 ;0,1,2=183,3=0.000000
A 11.64143996 2.175 11.64143996 2.175 11.63893002 2.175 1 P 0 N
L 11.89144341 2.18429636 11.8930436 2.18554685 2 P 0 ;0,1,2=184,3=0.000000
L 11.8930436 2.18554685 11.89490984 2.18638002 2 P 0 ;0,1,2=184,3=0.000000
L 11.89490984 2.18638002 11.89704321 2.18638002 2 P 0 ;0,1,2=184,3=0.000000
L 11.89704321 2.18638002 11.8994437 2.18512943 2 P 0 ;0,1,2=184,3=0.000000
L 11.8994437 2.18512943 11.90130994 2.18304656 2 P 0 ;0,1,2=184,3=0.000000
L 11.90130994 2.18304656 11.9026435 2.18054636 2 P 0 ;0,1,2=184,3=0.000000
L 11.9026435 2.18054636 11.90371043 2.17637982 2 P 0 ;0,1,2=184,3=0.000000
L 11.90371043 2.17637982 11.90397707 2.17262982 2 P 0 ;0,1,2=184,3=0.000000
L 11.90397707 2.17262982 11.90344331 2.16887992 2 P 0 ;0,1,2=184,3=0.000000
L 11.90344331 2.16887992 11.9026435 2.16637963 2 P 0 ;0,1,2=184,3=0.000000
L 11.9026435 2.16637963 11.90104341 2.16387943 2 P 0 ;0,1,2=184,3=0.000000
L 11.90104341 2.16387943 11.89917657 2.16221309 2 P 0 ;0,1,2=184,3=0.000000
L 11.89917657 2.16221309 11.89731033 2.16138002 2 P 0 ;0,1,2=184,3=0.000000
L 11.89731033 2.16138002 11.8954436 2.16138002 2 P 0 ;0,1,2=184,3=0.000000
L 11.8954436 2.16138002 11.89357677 2.16221309 2 P 0 ;0,1,2=184,3=0.000000
L 11.89357677 2.16221309 11.89197667 2.16346289 2 P 0 ;0,1,2=184,3=0.000000
L 11.89197667 2.16346289 11.89064311 2.16512913 2 P 0 ;0,1,2=184,3=0.000000
L 11.87837687 2.18221339 11.87677677 2.18471289 2 P 0 ;0,1,2=184,3=0.000000
L 11.87677677 2.18471289 11.87491004 2.18596339 2 P 0 ;0,1,2=184,3=0.000000
L 11.87491004 2.18596339 11.87277667 2.18638002 2 P 0 ;0,1,2=184,3=0.000000
L 11.87277667 2.18638002 11.87011004 2.18554685 2 P 0 ;0,1,2=184,3=0.000000
L 11.87011004 2.18554685 11.86824331 2.18346319 2 P 0 ;0,1,2=184,3=0.000000
L 11.86824331 2.18346319 11.86771004 2.18096368 2 P 0 ;0,1,2=184,3=0.000000
L 11.86771004 2.18096368 11.86797667 2.1784627 2 P 0 ;0,1,2=184,3=0.000000
L 11.86797667 2.1784627 11.8690436 2.17637982 2 P 0 ;0,1,2=184,3=0.000000
L 11.8690436 2.17637982 11.87437677 2.17221329 2 P 0 ;0,1,2=184,3=0.000000
L 11.87437677 2.17221329 11.87677677 2.16929646 2 P 0 ;0,1,2=184,3=0.000000
L 11.87677677 2.16929646 11.87837687 2.16512913 2 P 0 ;0,1,2=184,3=0.000000
L 11.87837687 2.16512913 11.87891014 2.16138002 2 P 0 ;0,1,2=184,3=0.000000
L 11.87891014 2.16138002 11.86771004 2.16138002 2 P 0 ;0,1,2=184,3=0.000000
L 11.85437687 2.18221339 11.85277677 2.18471289 2 P 0 ;0,1,2=184,3=0.000000
L 11.85277677 2.18471289 11.85091004 2.18596339 2 P 0 ;0,1,2=184,3=0.000000
L 11.85091004 2.18596339 11.84877667 2.18638002 2 P 0 ;0,1,2=184,3=0.000000
L 11.84877667 2.18638002 11.84611004 2.18554685 2 P 0 ;0,1,2=184,3=0.000000
L 11.84611004 2.18554685 11.84424331 2.18346319 2 P 0 ;0,1,2=184,3=0.000000
L 11.84424331 2.18346319 11.84371004 2.18096368 2 P 0 ;0,1,2=184,3=0.000000
L 11.84371004 2.18096368 11.84397667 2.1784627 2 P 0 ;0,1,2=184,3=0.000000
L 11.84397667 2.1784627 11.8450436 2.17637982 2 P 0 ;0,1,2=184,3=0.000000
L 11.8450436 2.17637982 11.85037677 2.17221329 2 P 0 ;0,1,2=184,3=0.000000
L 11.85037677 2.17221329 11.85277677 2.16929646 2 P 0 ;0,1,2=184,3=0.000000
L 11.85277677 2.16929646 11.85437687 2.16512913 2 P 0 ;0,1,2=184,3=0.000000
L 11.85437687 2.16512913 11.85491014 2.16138002 2 P 0 ;0,1,2=184,3=0.000000
L 11.85491014 2.16138002 11.84371004 2.16138002 2 P 0 ;0,1,2=184,3=0.000000
L 11.82531033 2.16138002 11.82531033 2.18638002 2 P 0 ;0,1,2=184,3=0.000000
L 11.82531033 2.18638002 11.82851014 2.18138032 2 P 0 ;0,1,2=184,3=0.000000
L 11.82851014 2.16138002 11.82211053 2.16138002 2 P 0 ;0,1,2=184,3=0.000000
L 11.80637687 2.18221339 11.80477677 2.18471289 2 P 0 ;0,1,2=184,3=0.000000
L 11.80477677 2.18471289 11.80291004 2.18596339 2 P 0 ;0,1,2=184,3=0.000000
L 11.80291004 2.18596339 11.80077667 2.18638002 2 P 0 ;0,1,2=184,3=0.000000
L 11.80077667 2.18638002 11.79811004 2.18554685 2 P 0 ;0,1,2=184,3=0.000000
L 11.79811004 2.18554685 11.79624331 2.18346319 2 P 0 ;0,1,2=184,3=0.000000
L 11.79624331 2.18346319 11.79571004 2.18096368 2 P 0 ;0,1,2=184,3=0.000000
L 11.79571004 2.18096368 11.79597667 2.1784627 2 P 0 ;0,1,2=184,3=0.000000
L 11.79597667 2.1784627 11.7970436 2.17637982 2 P 0 ;0,1,2=184,3=0.000000
L 11.7970436 2.17637982 11.80237677 2.17221329 2 P 0 ;0,1,2=184,3=0.000000
L 11.80237677 2.17221329 11.80477677 2.16929646 2 P 0 ;0,1,2=184,3=0.000000
L 11.80477677 2.16929646 11.80637687 2.16512913 2 P 0 ;0,1,2=184,3=0.000000
L 11.80637687 2.16512913 11.80691014 2.16138002 2 P 0 ;0,1,2=184,3=0.000000
L 11.80691014 2.16138002 11.79571004 2.16138002 2 P 0 ;0,1,2=184,3=0.000000
A 11.64143996 2.13 11.64143996 2.13 11.63893002 2.13 1 P 0 N
L 11.89144341 2.13929636 11.8930436 2.14054685 2 P 0 ;0,1,2=185,3=0.000000
L 11.8930436 2.14054685 11.89490984 2.14138002 2 P 0 ;0,1,2=185,3=0.000000
L 11.89490984 2.14138002 11.89704321 2.14138002 2 P 0 ;0,1,2=185,3=0.000000
L 11.89704321 2.14138002 11.8994437 2.14012943 2 P 0 ;0,1,2=185,3=0.000000
L 11.8994437 2.14012943 11.90130994 2.13804656 2 P 0 ;0,1,2=185,3=0.000000
L 11.90130994 2.13804656 11.9026435 2.13554636 2 P 0 ;0,1,2=185,3=0.000000
L 11.9026435 2.13554636 11.90371043 2.13137982 2 P 0 ;0,1,2=185,3=0.000000
L 11.90371043 2.13137982 11.90397707 2.12762982 2 P 0 ;0,1,2=185,3=0.000000
L 11.90397707 2.12762982 11.90344331 2.12387992 2 P 0 ;0,1,2=185,3=0.000000
L 11.90344331 2.12387992 11.9026435 2.12137963 2 P 0 ;0,1,2=185,3=0.000000
L 11.9026435 2.12137963 11.90104341 2.11887943 2 P 0 ;0,1,2=185,3=0.000000
L 11.90104341 2.11887943 11.89917657 2.11721309 2 P 0 ;0,1,2=185,3=0.000000
L 11.89917657 2.11721309 11.89731033 2.11638002 2 P 0 ;0,1,2=185,3=0.000000
L 11.89731033 2.11638002 11.8954436 2.11638002 2 P 0 ;0,1,2=185,3=0.000000
L 11.8954436 2.11638002 11.89357677 2.11721309 2 P 0 ;0,1,2=185,3=0.000000
L 11.89357677 2.11721309 11.89197667 2.11846289 2 P 0 ;0,1,2=185,3=0.000000
L 11.89197667 2.11846289 11.89064311 2.12012913 2 P 0 ;0,1,2=185,3=0.000000
L 11.87837687 2.13721339 11.87677677 2.13971289 2 P 0 ;0,1,2=185,3=0.000000
L 11.87677677 2.13971289 11.87491004 2.14096339 2 P 0 ;0,1,2=185,3=0.000000
L 11.87491004 2.14096339 11.87277667 2.14138002 2 P 0 ;0,1,2=185,3=0.000000
L 11.87277667 2.14138002 11.87011004 2.14054685 2 P 0 ;0,1,2=185,3=0.000000
L 11.87011004 2.14054685 11.86824331 2.13846319 2 P 0 ;0,1,2=185,3=0.000000
L 11.86824331 2.13846319 11.86771004 2.13596368 2 P 0 ;0,1,2=185,3=0.000000
L 11.86771004 2.13596368 11.86797667 2.1334627 2 P 0 ;0,1,2=185,3=0.000000
L 11.86797667 2.1334627 11.8690436 2.13137982 2 P 0 ;0,1,2=185,3=0.000000
L 11.8690436 2.13137982 11.87437677 2.12721329 2 P 0 ;0,1,2=185,3=0.000000
L 11.87437677 2.12721329 11.87677677 2.12429646 2 P 0 ;0,1,2=185,3=0.000000
L 11.87677677 2.12429646 11.87837687 2.12012913 2 P 0 ;0,1,2=185,3=0.000000
L 11.87837687 2.12012913 11.87891014 2.11638002 2 P 0 ;0,1,2=185,3=0.000000
L 11.87891014 2.11638002 11.86771004 2.11638002 2 P 0 ;0,1,2=185,3=0.000000
L 11.85437687 2.13721339 11.85277677 2.13971289 2 P 0 ;0,1,2=185,3=0.000000
L 11.85277677 2.13971289 11.85091004 2.14096339 2 P 0 ;0,1,2=185,3=0.000000
L 11.85091004 2.14096339 11.84877667 2.14138002 2 P 0 ;0,1,2=185,3=0.000000
L 11.84877667 2.14138002 11.84611004 2.14054685 2 P 0 ;0,1,2=185,3=0.000000
L 11.84611004 2.14054685 11.84424331 2.13846319 2 P 0 ;0,1,2=185,3=0.000000
L 11.84424331 2.13846319 11.84371004 2.13596368 2 P 0 ;0,1,2=185,3=0.000000
L 11.84371004 2.13596368 11.84397667 2.1334627 2 P 0 ;0,1,2=185,3=0.000000
L 11.84397667 2.1334627 11.8450436 2.13137982 2 P 0 ;0,1,2=185,3=0.000000
L 11.8450436 2.13137982 11.85037677 2.12721329 2 P 0 ;0,1,2=185,3=0.000000
L 11.85037677 2.12721329 11.85277677 2.12429646 2 P 0 ;0,1,2=185,3=0.000000
L 11.85277677 2.12429646 11.85437687 2.12012913 2 P 0 ;0,1,2=185,3=0.000000
L 11.85437687 2.12012913 11.85491014 2.11638002 2 P 0 ;0,1,2=185,3=0.000000
L 11.85491014 2.11638002 11.84371004 2.11638002 2 P 0 ;0,1,2=185,3=0.000000
L 11.82531033 2.11638002 11.82531033 2.14138002 2 P 0 ;0,1,2=185,3=0.000000
L 11.82531033 2.14138002 11.82851014 2.13638032 2 P 0 ;0,1,2=185,3=0.000000
L 11.82851014 2.11638002 11.82211053 2.11638002 2 P 0 ;0,1,2=185,3=0.000000
L 11.80717677 2.12137963 11.80557707 2.11846289 2 P 0 ;0,1,2=185,3=0.000000
L 11.80557707 2.11846289 11.8034437 2.11679656 2 P 0 ;0,1,2=185,3=0.000000
L 11.8034437 2.11679656 11.80104321 2.11638002 2 P 0 ;0,1,2=185,3=0.000000
L 11.80104321 2.11638002 11.79890984 2.11679656 2 P 0 ;0,1,2=185,3=0.000000
L 11.79890984 2.11679656 11.79677648 2.11887943 2 P 0 ;0,1,2=185,3=0.000000
L 11.79677648 2.11887943 11.79544341 2.12137963 2 P 0 ;0,1,2=185,3=0.000000
L 11.79544341 2.12137963 11.79517687 2.12387992 2 P 0 ;0,1,2=185,3=0.000000
L 11.79517687 2.12387992 11.79571004 2.12679596 2 P 0 ;0,1,2=185,3=0.000000
L 11.79571004 2.12679596 11.79757677 2.12887963 2 P 0 ;0,1,2=185,3=0.000000
L 11.79757677 2.12887963 11.7994436 2.12971348 2 P 0 ;0,1,2=185,3=0.000000
L 11.7994436 2.12971348 11.8018435 2.12971348 2 P 0 ;0,1,2=185,3=0.000000
L 11.7994436 2.12971348 11.79784341 2.13096329 2 P 0 ;0,1,2=185,3=0.000000
L 11.79784341 2.13096329 11.79650994 2.13304616 2 P 0 ;0,1,2=185,3=0.000000
L 11.79650994 2.13304616 11.79597667 2.13554636 2 P 0 ;0,1,2=185,3=0.000000
L 11.79597667 2.13554636 11.79650994 2.13804656 2 P 0 ;0,1,2=185,3=0.000000
L 11.79650994 2.13804656 11.79784341 2.14012943 2 P 0 ;0,1,2=185,3=0.000000
L 11.79784341 2.14012943 11.80024341 2.14138002 2 P 0 ;0,1,2=185,3=0.000000
L 11.80024341 2.14138002 11.80264341 2.14096339 2 P 0 ;0,1,2=185,3=0.000000
L 11.80264341 2.14096339 11.80504341 2.13929636 2 P 0 ;0,1,2=185,3=0.000000
A 11.44143996 1.935 11.44143996 1.935 11.43893002 1.935 1 P 0 N
L 11.65613337 1.94291634 11.65773356 1.94416683 2 P 0 ;0,1,2=186,3=0.000000
L 11.65773356 1.94416683 11.6595998 1.945 2 P 0 ;0,1,2=186,3=0.000000
L 11.6595998 1.945 11.66173317 1.945 2 P 0 ;0,1,2=186,3=0.000000
L 11.66173317 1.945 11.66413366 1.94374941 2 P 0 ;0,1,2=186,3=0.000000
L 11.66413366 1.94374941 11.6659999 1.94166654 2 P 0 ;0,1,2=186,3=0.000000
L 11.6659999 1.94166654 11.66733346 1.93916634 2 P 0 ;0,1,2=186,3=0.000000
L 11.66733346 1.93916634 11.66840039 1.9349998 2 P 0 ;0,1,2=186,3=0.000000
L 11.66840039 1.9349998 11.66866703 1.9312498 2 P 0 ;0,1,2=186,3=0.000000
L 11.66866703 1.9312498 11.66813327 1.9274999 2 P 0 ;0,1,2=186,3=0.000000
L 11.66813327 1.9274999 11.66733346 1.92499961 2 P 0 ;0,1,2=186,3=0.000000
L 11.66733346 1.92499961 11.66573337 1.92249941 2 P 0 ;0,1,2=186,3=0.000000
L 11.66573337 1.92249941 11.66386654 1.92083307 2 P 0 ;0,1,2=186,3=0.000000
L 11.66386654 1.92083307 11.6620003 1.92 2 P 0 ;0,1,2=186,3=0.000000
L 11.6620003 1.92 11.66013356 1.92 2 P 0 ;0,1,2=186,3=0.000000
L 11.66013356 1.92 11.65826673 1.92083307 2 P 0 ;0,1,2=186,3=0.000000
L 11.65826673 1.92083307 11.65666663 1.92208287 2 P 0 ;0,1,2=186,3=0.000000
L 11.65666663 1.92208287 11.65533307 1.92374911 2 P 0 ;0,1,2=186,3=0.000000
L 11.64306683 1.94083337 11.64146673 1.94333287 2 P 0 ;0,1,2=186,3=0.000000
L 11.64146673 1.94333287 11.6396 1.94458337 2 P 0 ;0,1,2=186,3=0.000000
L 11.6396 1.94458337 11.63746663 1.945 2 P 0 ;0,1,2=186,3=0.000000
L 11.63746663 1.945 11.6348 1.94416683 2 P 0 ;0,1,2=186,3=0.000000
L 11.6348 1.94416683 11.63293327 1.94208317 2 P 0 ;0,1,2=186,3=0.000000
L 11.63293327 1.94208317 11.6324 1.93958366 2 P 0 ;0,1,2=186,3=0.000000
L 11.6324 1.93958366 11.63266663 1.93708268 2 P 0 ;0,1,2=186,3=0.000000
L 11.63266663 1.93708268 11.63373356 1.9349998 2 P 0 ;0,1,2=186,3=0.000000
L 11.63373356 1.9349998 11.63906673 1.93083327 2 P 0 ;0,1,2=186,3=0.000000
L 11.63906673 1.93083327 11.64146673 1.92791644 2 P 0 ;0,1,2=186,3=0.000000
L 11.64146673 1.92791644 11.64306683 1.92374911 2 P 0 ;0,1,2=186,3=0.000000
L 11.64306683 1.92374911 11.6436001 1.92 2 P 0 ;0,1,2=186,3=0.000000
L 11.6436001 1.92 11.6324 1.92 2 P 0 ;0,1,2=186,3=0.000000
L 11.61906683 1.94083337 11.61746673 1.94333287 2 P 0 ;0,1,2=186,3=0.000000
L 11.61746673 1.94333287 11.6156 1.94458337 2 P 0 ;0,1,2=186,3=0.000000
L 11.6156 1.94458337 11.61346663 1.945 2 P 0 ;0,1,2=186,3=0.000000
L 11.61346663 1.945 11.6108 1.94416683 2 P 0 ;0,1,2=186,3=0.000000
L 11.6108 1.94416683 11.60893327 1.94208317 2 P 0 ;0,1,2=186,3=0.000000
L 11.60893327 1.94208317 11.6084 1.93958366 2 P 0 ;0,1,2=186,3=0.000000
L 11.6084 1.93958366 11.60866663 1.93708268 2 P 0 ;0,1,2=186,3=0.000000
L 11.60866663 1.93708268 11.60973356 1.9349998 2 P 0 ;0,1,2=186,3=0.000000
L 11.60973356 1.9349998 11.61506673 1.93083327 2 P 0 ;0,1,2=186,3=0.000000
L 11.61506673 1.93083327 11.61746673 1.92791644 2 P 0 ;0,1,2=186,3=0.000000
L 11.61746673 1.92791644 11.61906683 1.92374911 2 P 0 ;0,1,2=186,3=0.000000
L 11.61906683 1.92374911 11.6196001 1.92 2 P 0 ;0,1,2=186,3=0.000000
L 11.6196001 1.92 11.6084 1.92 2 P 0 ;0,1,2=186,3=0.000000
L 11.5900003 1.92 11.5900003 1.945 2 P 0 ;0,1,2=186,3=0.000000
L 11.5900003 1.945 11.5932001 1.9400003 2 P 0 ;0,1,2=186,3=0.000000
L 11.5932001 1.92 11.58680049 1.92 2 P 0 ;0,1,2=186,3=0.000000
L 11.5628 1.92 11.5628 1.945 2 P 0 ;0,1,2=186,3=0.000000
L 11.5628 1.945 11.57266703 1.92708327 2 P 0 ;0,1,2=186,3=0.000000
L 11.57266703 1.92708327 11.55933307 1.92708327 2 P 0 ;0,1,2=186,3=0.000000
A 11.44143996 1.89 11.44143996 1.89 11.43893002 1.89 1 P 0 N
L 11.65613337 1.90291634 11.65773356 1.90416683 2 P 0 ;0,1,2=187,3=0.000000
L 11.65773356 1.90416683 11.6595998 1.905 2 P 0 ;0,1,2=187,3=0.000000
L 11.6595998 1.905 11.66173317 1.905 2 P 0 ;0,1,2=187,3=0.000000
L 11.66173317 1.905 11.66413366 1.90374941 2 P 0 ;0,1,2=187,3=0.000000
L 11.66413366 1.90374941 11.6659999 1.90166654 2 P 0 ;0,1,2=187,3=0.000000
L 11.6659999 1.90166654 11.66733346 1.89916634 2 P 0 ;0,1,2=187,3=0.000000
L 11.66733346 1.89916634 11.66840039 1.8949998 2 P 0 ;0,1,2=187,3=0.000000
L 11.66840039 1.8949998 11.66866703 1.8912498 2 P 0 ;0,1,2=187,3=0.000000
L 11.66866703 1.8912498 11.66813327 1.8874999 2 P 0 ;0,1,2=187,3=0.000000
L 11.66813327 1.8874999 11.66733346 1.88499961 2 P 0 ;0,1,2=187,3=0.000000
L 11.66733346 1.88499961 11.66573337 1.88249941 2 P 0 ;0,1,2=187,3=0.000000
L 11.66573337 1.88249941 11.66386654 1.88083307 2 P 0 ;0,1,2=187,3=0.000000
L 11.66386654 1.88083307 11.6620003 1.88 2 P 0 ;0,1,2=187,3=0.000000
L 11.6620003 1.88 11.66013356 1.88 2 P 0 ;0,1,2=187,3=0.000000
L 11.66013356 1.88 11.65826673 1.88083307 2 P 0 ;0,1,2=187,3=0.000000
L 11.65826673 1.88083307 11.65666663 1.88208287 2 P 0 ;0,1,2=187,3=0.000000
L 11.65666663 1.88208287 11.65533307 1.88374911 2 P 0 ;0,1,2=187,3=0.000000
L 11.64306683 1.90083337 11.64146673 1.90333287 2 P 0 ;0,1,2=187,3=0.000000
L 11.64146673 1.90333287 11.6396 1.90458337 2 P 0 ;0,1,2=187,3=0.000000
L 11.6396 1.90458337 11.63746663 1.905 2 P 0 ;0,1,2=187,3=0.000000
L 11.63746663 1.905 11.6348 1.90416683 2 P 0 ;0,1,2=187,3=0.000000
L 11.6348 1.90416683 11.63293327 1.90208317 2 P 0 ;0,1,2=187,3=0.000000
L 11.63293327 1.90208317 11.6324 1.89958366 2 P 0 ;0,1,2=187,3=0.000000
L 11.6324 1.89958366 11.63266663 1.89708268 2 P 0 ;0,1,2=187,3=0.000000
L 11.63266663 1.89708268 11.63373356 1.8949998 2 P 0 ;0,1,2=187,3=0.000000
L 11.63373356 1.8949998 11.63906673 1.89083327 2 P 0 ;0,1,2=187,3=0.000000
L 11.63906673 1.89083327 11.64146673 1.88791644 2 P 0 ;0,1,2=187,3=0.000000
L 11.64146673 1.88791644 11.64306683 1.88374911 2 P 0 ;0,1,2=187,3=0.000000
L 11.64306683 1.88374911 11.6436001 1.88 2 P 0 ;0,1,2=187,3=0.000000
L 11.6436001 1.88 11.6324 1.88 2 P 0 ;0,1,2=187,3=0.000000
L 11.61906683 1.90083337 11.61746673 1.90333287 2 P 0 ;0,1,2=187,3=0.000000
L 11.61746673 1.90333287 11.6156 1.90458337 2 P 0 ;0,1,2=187,3=0.000000
L 11.6156 1.90458337 11.61346663 1.905 2 P 0 ;0,1,2=187,3=0.000000
L 11.61346663 1.905 11.6108 1.90416683 2 P 0 ;0,1,2=187,3=0.000000
L 11.6108 1.90416683 11.60893327 1.90208317 2 P 0 ;0,1,2=187,3=0.000000
L 11.60893327 1.90208317 11.6084 1.89958366 2 P 0 ;0,1,2=187,3=0.000000
L 11.6084 1.89958366 11.60866663 1.89708268 2 P 0 ;0,1,2=187,3=0.000000
L 11.60866663 1.89708268 11.60973356 1.8949998 2 P 0 ;0,1,2=187,3=0.000000
L 11.60973356 1.8949998 11.61506673 1.89083327 2 P 0 ;0,1,2=187,3=0.000000
L 11.61506673 1.89083327 11.61746673 1.88791644 2 P 0 ;0,1,2=187,3=0.000000
L 11.61746673 1.88791644 11.61906683 1.88374911 2 P 0 ;0,1,2=187,3=0.000000
L 11.61906683 1.88374911 11.6196001 1.88 2 P 0 ;0,1,2=187,3=0.000000
L 11.6196001 1.88 11.6084 1.88 2 P 0 ;0,1,2=187,3=0.000000
L 11.5900003 1.88 11.5900003 1.905 2 P 0 ;0,1,2=187,3=0.000000
L 11.5900003 1.905 11.5932001 1.9000003 2 P 0 ;0,1,2=187,3=0.000000
L 11.5932001 1.88 11.58680049 1.88 2 P 0 ;0,1,2=187,3=0.000000
L 11.57186673 1.88374911 11.57026703 1.88166624 2 P 0 ;0,1,2=187,3=0.000000
L 11.57026703 1.88166624 11.5684003 1.88041654 2 P 0 ;0,1,2=187,3=0.000000
L 11.5684003 1.88041654 11.5660003 1.88 2 P 0 ;0,1,2=187,3=0.000000
L 11.5660003 1.88 11.5635998 1.88083307 2 P 0 ;0,1,2=187,3=0.000000
L 11.5635998 1.88083307 11.56173356 1.88249941 2 P 0 ;0,1,2=187,3=0.000000
L 11.56173356 1.88249941 11.5604 1.88541624 2 P 0 ;0,1,2=187,3=0.000000
L 11.5604 1.88541624 11.56013337 1.88874961 2 P 0 ;0,1,2=187,3=0.000000
L 11.56013337 1.88874961 11.56066663 1.89208297 2 P 0 ;0,1,2=187,3=0.000000
L 11.56066663 1.89208297 11.5620002 1.89416663 2 P 0 ;0,1,2=187,3=0.000000
L 11.5620002 1.89416663 11.56386693 1.89583297 2 P 0 ;0,1,2=187,3=0.000000
L 11.56386693 1.89583297 11.56573317 1.89624951 2 P 0 ;0,1,2=187,3=0.000000
L 11.56573317 1.89624951 11.5676 1.89583297 2 P 0 ;0,1,2=187,3=0.000000
L 11.5676 1.89583297 11.5699999 1.89416663 2 P 0 ;0,1,2=187,3=0.000000
L 11.5699999 1.89416663 11.5692001 1.905 2 P 0 ;0,1,2=187,3=0.000000
L 11.5692001 1.905 11.5620002 1.905 2 P 0 ;0,1,2=187,3=0.000000
A 11.64143996 2.015 11.64143996 2.015 11.63893002 2.015 1 P 0 N
L 11.89144341 2.02429636 11.8930436 2.02554685 2 P 0 ;0,1,2=188,3=0.000000
L 11.8930436 2.02554685 11.89490984 2.02638002 2 P 0 ;0,1,2=188,3=0.000000
L 11.89490984 2.02638002 11.89704321 2.02638002 2 P 0 ;0,1,2=188,3=0.000000
L 11.89704321 2.02638002 11.8994437 2.02512943 2 P 0 ;0,1,2=188,3=0.000000
L 11.8994437 2.02512943 11.90130994 2.02304656 2 P 0 ;0,1,2=188,3=0.000000
L 11.90130994 2.02304656 11.9026435 2.02054636 2 P 0 ;0,1,2=188,3=0.000000
L 11.9026435 2.02054636 11.90371043 2.01637982 2 P 0 ;0,1,2=188,3=0.000000
L 11.90371043 2.01637982 11.90397707 2.01262982 2 P 0 ;0,1,2=188,3=0.000000
L 11.90397707 2.01262982 11.90344331 2.00887992 2 P 0 ;0,1,2=188,3=0.000000
L 11.90344331 2.00887992 11.9026435 2.00637963 2 P 0 ;0,1,2=188,3=0.000000
L 11.9026435 2.00637963 11.90104341 2.00387943 2 P 0 ;0,1,2=188,3=0.000000
L 11.90104341 2.00387943 11.89917657 2.00221309 2 P 0 ;0,1,2=188,3=0.000000
L 11.89917657 2.00221309 11.89731033 2.00138002 2 P 0 ;0,1,2=188,3=0.000000
L 11.89731033 2.00138002 11.8954436 2.00138002 2 P 0 ;0,1,2=188,3=0.000000
L 11.8954436 2.00138002 11.89357677 2.00221309 2 P 0 ;0,1,2=188,3=0.000000
L 11.89357677 2.00221309 11.89197667 2.00346289 2 P 0 ;0,1,2=188,3=0.000000
L 11.89197667 2.00346289 11.89064311 2.00512913 2 P 0 ;0,1,2=188,3=0.000000
L 11.87837687 2.02221339 11.87677677 2.02471289 2 P 0 ;0,1,2=188,3=0.000000
L 11.87677677 2.02471289 11.87491004 2.02596339 2 P 0 ;0,1,2=188,3=0.000000
L 11.87491004 2.02596339 11.87277667 2.02638002 2 P 0 ;0,1,2=188,3=0.000000
L 11.87277667 2.02638002 11.87011004 2.02554685 2 P 0 ;0,1,2=188,3=0.000000
L 11.87011004 2.02554685 11.86824331 2.02346319 2 P 0 ;0,1,2=188,3=0.000000
L 11.86824331 2.02346319 11.86771004 2.02096368 2 P 0 ;0,1,2=188,3=0.000000
L 11.86771004 2.02096368 11.86797667 2.0184627 2 P 0 ;0,1,2=188,3=0.000000
L 11.86797667 2.0184627 11.8690436 2.01637982 2 P 0 ;0,1,2=188,3=0.000000
L 11.8690436 2.01637982 11.87437677 2.01221329 2 P 0 ;0,1,2=188,3=0.000000
L 11.87437677 2.01221329 11.87677677 2.00929646 2 P 0 ;0,1,2=188,3=0.000000
L 11.87677677 2.00929646 11.87837687 2.00512913 2 P 0 ;0,1,2=188,3=0.000000
L 11.87837687 2.00512913 11.87891014 2.00138002 2 P 0 ;0,1,2=188,3=0.000000
L 11.87891014 2.00138002 11.86771004 2.00138002 2 P 0 ;0,1,2=188,3=0.000000
L 11.85437687 2.02221339 11.85277677 2.02471289 2 P 0 ;0,1,2=188,3=0.000000
L 11.85277677 2.02471289 11.85091004 2.02596339 2 P 0 ;0,1,2=188,3=0.000000
L 11.85091004 2.02596339 11.84877667 2.02638002 2 P 0 ;0,1,2=188,3=0.000000
L 11.84877667 2.02638002 11.84611004 2.02554685 2 P 0 ;0,1,2=188,3=0.000000
L 11.84611004 2.02554685 11.84424331 2.02346319 2 P 0 ;0,1,2=188,3=0.000000
L 11.84424331 2.02346319 11.84371004 2.02096368 2 P 0 ;0,1,2=188,3=0.000000
L 11.84371004 2.02096368 11.84397667 2.0184627 2 P 0 ;0,1,2=188,3=0.000000
L 11.84397667 2.0184627 11.8450436 2.01637982 2 P 0 ;0,1,2=188,3=0.000000
L 11.8450436 2.01637982 11.85037677 2.01221329 2 P 0 ;0,1,2=188,3=0.000000
L 11.85037677 2.01221329 11.85277677 2.00929646 2 P 0 ;0,1,2=188,3=0.000000
L 11.85277677 2.00929646 11.85437687 2.00512913 2 P 0 ;0,1,2=188,3=0.000000
L 11.85437687 2.00512913 11.85491014 2.00138002 2 P 0 ;0,1,2=188,3=0.000000
L 11.85491014 2.00138002 11.84371004 2.00138002 2 P 0 ;0,1,2=188,3=0.000000
L 11.82531033 2.00138002 11.82531033 2.02638002 2 P 0 ;0,1,2=188,3=0.000000
L 11.82531033 2.02638002 11.82851014 2.02138032 2 P 0 ;0,1,2=188,3=0.000000
L 11.82851014 2.00138002 11.82211053 2.00138002 2 P 0 ;0,1,2=188,3=0.000000
L 11.80637687 2.01179596 11.80451014 2.01471348 2 P 0 ;0,1,2=188,3=0.000000
L 11.80451014 2.01471348 11.80291004 2.01637982 2 P 0 ;0,1,2=188,3=0.000000
L 11.80291004 2.01637982 11.80077667 2.01721299 2 P 0 ;0,1,2=188,3=0.000000
L 11.80077667 2.01721299 11.79890984 2.01637982 2 P 0 ;0,1,2=188,3=0.000000
L 11.79890984 2.01637982 11.79757677 2.01471348 2 P 0 ;0,1,2=188,3=0.000000
L 11.79757677 2.01471348 11.79650994 2.01221329 2 P 0 ;0,1,2=188,3=0.000000
L 11.79650994 2.01221329 11.79624331 2.00929646 2 P 0 ;0,1,2=188,3=0.000000
L 11.79624331 2.00929646 11.79650994 2.00679626 2 P 0 ;0,1,2=188,3=0.000000
L 11.79650994 2.00679626 11.79757677 2.00429606 2 P 0 ;0,1,2=188,3=0.000000
L 11.79757677 2.00429606 11.79917697 2.00221309 2 P 0 ;0,1,2=188,3=0.000000
L 11.79917697 2.00221309 11.80104321 2.00138002 2 P 0 ;0,1,2=188,3=0.000000
L 11.80104321 2.00138002 11.80317657 2.00221309 2 P 0 ;0,1,2=188,3=0.000000
L 11.80317657 2.00221309 11.80504341 2.0047126 2 P 0 ;0,1,2=188,3=0.000000
L 11.80504341 2.0047126 11.80611024 2.00846329 2 P 0 ;0,1,2=188,3=0.000000
L 11.80611024 2.00846329 11.80637687 2.01262982 2 P 0 ;0,1,2=188,3=0.000000
L 11.80637687 2.01262982 11.8058437 2.01804616 2 P 0 ;0,1,2=188,3=0.000000
L 11.8058437 2.01804616 11.80504341 2.02096368 2 P 0 ;0,1,2=188,3=0.000000
L 11.80504341 2.02096368 11.80371033 2.02387972 2 P 0 ;0,1,2=188,3=0.000000
L 11.80371033 2.02387972 11.8018435 2.02596339 2 P 0 ;0,1,2=188,3=0.000000
L 11.8018435 2.02596339 11.79997677 2.02638002 2 P 0 ;0,1,2=188,3=0.000000
L 11.79997677 2.02638002 11.79811004 2.02554685 2 P 0 ;0,1,2=188,3=0.000000
L 11.79811004 2.02554685 11.79677648 2.02346319 2 P 0 ;0,1,2=188,3=0.000000
A 11.64143996 1.97 11.64143996 1.97 11.63893002 1.97 1 P 0 N
L 11.89144341 1.97929636 11.8930436 1.98054685 2 P 0 ;0,1,2=189,3=0.000000
L 11.8930436 1.98054685 11.89490984 1.98138002 2 P 0 ;0,1,2=189,3=0.000000
L 11.89490984 1.98138002 11.89704321 1.98138002 2 P 0 ;0,1,2=189,3=0.000000
L 11.89704321 1.98138002 11.8994437 1.98012943 2 P 0 ;0,1,2=189,3=0.000000
L 11.8994437 1.98012943 11.90130994 1.97804656 2 P 0 ;0,1,2=189,3=0.000000
L 11.90130994 1.97804656 11.9026435 1.97554636 2 P 0 ;0,1,2=189,3=0.000000
L 11.9026435 1.97554636 11.90371043 1.97137982 2 P 0 ;0,1,2=189,3=0.000000
L 11.90371043 1.97137982 11.90397707 1.96762982 2 P 0 ;0,1,2=189,3=0.000000
L 11.90397707 1.96762982 11.90344331 1.96387992 2 P 0 ;0,1,2=189,3=0.000000
L 11.90344331 1.96387992 11.9026435 1.96137963 2 P 0 ;0,1,2=189,3=0.000000
L 11.9026435 1.96137963 11.90104341 1.95887943 2 P 0 ;0,1,2=189,3=0.000000
L 11.90104341 1.95887943 11.89917657 1.95721309 2 P 0 ;0,1,2=189,3=0.000000
L 11.89917657 1.95721309 11.89731033 1.95638002 2 P 0 ;0,1,2=189,3=0.000000
L 11.89731033 1.95638002 11.8954436 1.95638002 2 P 0 ;0,1,2=189,3=0.000000
L 11.8954436 1.95638002 11.89357677 1.95721309 2 P 0 ;0,1,2=189,3=0.000000
L 11.89357677 1.95721309 11.89197667 1.95846289 2 P 0 ;0,1,2=189,3=0.000000
L 11.89197667 1.95846289 11.89064311 1.96012913 2 P 0 ;0,1,2=189,3=0.000000
L 11.87837687 1.97721339 11.87677677 1.97971289 2 P 0 ;0,1,2=189,3=0.000000
L 11.87677677 1.97971289 11.87491004 1.98096339 2 P 0 ;0,1,2=189,3=0.000000
L 11.87491004 1.98096339 11.87277667 1.98138002 2 P 0 ;0,1,2=189,3=0.000000
L 11.87277667 1.98138002 11.87011004 1.98054685 2 P 0 ;0,1,2=189,3=0.000000
L 11.87011004 1.98054685 11.86824331 1.97846319 2 P 0 ;0,1,2=189,3=0.000000
L 11.86824331 1.97846319 11.86771004 1.97596368 2 P 0 ;0,1,2=189,3=0.000000
L 11.86771004 1.97596368 11.86797667 1.9734627 2 P 0 ;0,1,2=189,3=0.000000
L 11.86797667 1.9734627 11.8690436 1.97137982 2 P 0 ;0,1,2=189,3=0.000000
L 11.8690436 1.97137982 11.87437677 1.96721329 2 P 0 ;0,1,2=189,3=0.000000
L 11.87437677 1.96721329 11.87677677 1.96429646 2 P 0 ;0,1,2=189,3=0.000000
L 11.87677677 1.96429646 11.87837687 1.96012913 2 P 0 ;0,1,2=189,3=0.000000
L 11.87837687 1.96012913 11.87891014 1.95638002 2 P 0 ;0,1,2=189,3=0.000000
L 11.87891014 1.95638002 11.86771004 1.95638002 2 P 0 ;0,1,2=189,3=0.000000
L 11.85437687 1.97721339 11.85277677 1.97971289 2 P 0 ;0,1,2=189,3=0.000000
L 11.85277677 1.97971289 11.85091004 1.98096339 2 P 0 ;0,1,2=189,3=0.000000
L 11.85091004 1.98096339 11.84877667 1.98138002 2 P 0 ;0,1,2=189,3=0.000000
L 11.84877667 1.98138002 11.84611004 1.98054685 2 P 0 ;0,1,2=189,3=0.000000
L 11.84611004 1.98054685 11.84424331 1.97846319 2 P 0 ;0,1,2=189,3=0.000000
L 11.84424331 1.97846319 11.84371004 1.97596368 2 P 0 ;0,1,2=189,3=0.000000
L 11.84371004 1.97596368 11.84397667 1.9734627 2 P 0 ;0,1,2=189,3=0.000000
L 11.84397667 1.9734627 11.8450436 1.97137982 2 P 0 ;0,1,2=189,3=0.000000
L 11.8450436 1.97137982 11.85037677 1.96721329 2 P 0 ;0,1,2=189,3=0.000000
L 11.85037677 1.96721329 11.85277677 1.96429646 2 P 0 ;0,1,2=189,3=0.000000
L 11.85277677 1.96429646 11.85437687 1.96012913 2 P 0 ;0,1,2=189,3=0.000000
L 11.85437687 1.96012913 11.85491014 1.95638002 2 P 0 ;0,1,2=189,3=0.000000
L 11.85491014 1.95638002 11.84371004 1.95638002 2 P 0 ;0,1,2=189,3=0.000000
L 11.82531033 1.95638002 11.82531033 1.98138002 2 P 0 ;0,1,2=189,3=0.000000
L 11.82531033 1.98138002 11.82851014 1.97638032 2 P 0 ;0,1,2=189,3=0.000000
L 11.82851014 1.95638002 11.82211053 1.95638002 2 P 0 ;0,1,2=189,3=0.000000
L 11.8018435 1.95638002 11.80131033 1.96179626 2 P 0 ;0,1,2=189,3=0.000000
L 11.80131033 1.96179626 11.80051004 1.96637933 2 P 0 ;0,1,2=189,3=0.000000
L 11.80051004 1.96637933 11.7994436 1.97054665 2 P 0 ;0,1,2=189,3=0.000000
L 11.7994436 1.97054665 11.79811004 1.97512982 2 P 0 ;0,1,2=189,3=0.000000
L 11.79811004 1.97512982 11.79597667 1.98138002 2 P 0 ;0,1,2=189,3=0.000000
L 11.79597667 1.98138002 11.8066435 1.98138002 2 P 0 ;0,1,2=189,3=0.000000
A 11.44143996 1.775 11.44143996 1.775 11.43893002 1.775 1 P 0 N
L 11.65613337 1.78291634 11.65773356 1.78416683 2 P 0 ;0,1,2=190,3=0.000000
L 11.65773356 1.78416683 11.6595998 1.785 2 P 0 ;0,1,2=190,3=0.000000
L 11.6595998 1.785 11.66173317 1.785 2 P 0 ;0,1,2=190,3=0.000000
L 11.66173317 1.785 11.66413366 1.78374941 2 P 0 ;0,1,2=190,3=0.000000
L 11.66413366 1.78374941 11.6659999 1.78166654 2 P 0 ;0,1,2=190,3=0.000000
L 11.6659999 1.78166654 11.66733346 1.77916634 2 P 0 ;0,1,2=190,3=0.000000
L 11.66733346 1.77916634 11.66840039 1.7749998 2 P 0 ;0,1,2=190,3=0.000000
L 11.66840039 1.7749998 11.66866703 1.7712498 2 P 0 ;0,1,2=190,3=0.000000
L 11.66866703 1.7712498 11.66813327 1.7674999 2 P 0 ;0,1,2=190,3=0.000000
L 11.66813327 1.7674999 11.66733346 1.76499961 2 P 0 ;0,1,2=190,3=0.000000
L 11.66733346 1.76499961 11.66573337 1.76249941 2 P 0 ;0,1,2=190,3=0.000000
L 11.66573337 1.76249941 11.66386654 1.76083307 2 P 0 ;0,1,2=190,3=0.000000
L 11.66386654 1.76083307 11.6620003 1.76 2 P 0 ;0,1,2=190,3=0.000000
L 11.6620003 1.76 11.66013356 1.76 2 P 0 ;0,1,2=190,3=0.000000
L 11.66013356 1.76 11.65826673 1.76083307 2 P 0 ;0,1,2=190,3=0.000000
L 11.65826673 1.76083307 11.65666663 1.76208287 2 P 0 ;0,1,2=190,3=0.000000
L 11.65666663 1.76208287 11.65533307 1.76374911 2 P 0 ;0,1,2=190,3=0.000000
L 11.64306683 1.78083337 11.64146673 1.78333287 2 P 0 ;0,1,2=190,3=0.000000
L 11.64146673 1.78333287 11.6396 1.78458337 2 P 0 ;0,1,2=190,3=0.000000
L 11.6396 1.78458337 11.63746663 1.785 2 P 0 ;0,1,2=190,3=0.000000
L 11.63746663 1.785 11.6348 1.78416683 2 P 0 ;0,1,2=190,3=0.000000
L 11.6348 1.78416683 11.63293327 1.78208317 2 P 0 ;0,1,2=190,3=0.000000
L 11.63293327 1.78208317 11.6324 1.77958366 2 P 0 ;0,1,2=190,3=0.000000
L 11.6324 1.77958366 11.63266663 1.77708268 2 P 0 ;0,1,2=190,3=0.000000
L 11.63266663 1.77708268 11.63373356 1.7749998 2 P 0 ;0,1,2=190,3=0.000000
L 11.63373356 1.7749998 11.63906673 1.77083327 2 P 0 ;0,1,2=190,3=0.000000
L 11.63906673 1.77083327 11.64146673 1.76791644 2 P 0 ;0,1,2=190,3=0.000000
L 11.64146673 1.76791644 11.64306683 1.76374911 2 P 0 ;0,1,2=190,3=0.000000
L 11.64306683 1.76374911 11.6436001 1.76 2 P 0 ;0,1,2=190,3=0.000000
L 11.6436001 1.76 11.6324 1.76 2 P 0 ;0,1,2=190,3=0.000000
L 11.61906683 1.78083337 11.61746673 1.78333287 2 P 0 ;0,1,2=190,3=0.000000
L 11.61746673 1.78333287 11.6156 1.78458337 2 P 0 ;0,1,2=190,3=0.000000
L 11.6156 1.78458337 11.61346663 1.785 2 P 0 ;0,1,2=190,3=0.000000
L 11.61346663 1.785 11.6108 1.78416683 2 P 0 ;0,1,2=190,3=0.000000
L 11.6108 1.78416683 11.60893327 1.78208317 2 P 0 ;0,1,2=190,3=0.000000
L 11.60893327 1.78208317 11.6084 1.77958366 2 P 0 ;0,1,2=190,3=0.000000
L 11.6084 1.77958366 11.60866663 1.77708268 2 P 0 ;0,1,2=190,3=0.000000
L 11.60866663 1.77708268 11.60973356 1.7749998 2 P 0 ;0,1,2=190,3=0.000000
L 11.60973356 1.7749998 11.61506673 1.77083327 2 P 0 ;0,1,2=190,3=0.000000
L 11.61506673 1.77083327 11.61746673 1.76791644 2 P 0 ;0,1,2=190,3=0.000000
L 11.61746673 1.76791644 11.61906683 1.76374911 2 P 0 ;0,1,2=190,3=0.000000
L 11.61906683 1.76374911 11.6196001 1.76 2 P 0 ;0,1,2=190,3=0.000000
L 11.6196001 1.76 11.6084 1.76 2 P 0 ;0,1,2=190,3=0.000000
L 11.5900003 1.76 11.5900003 1.785 2 P 0 ;0,1,2=190,3=0.000000
L 11.5900003 1.785 11.5932001 1.7800003 2 P 0 ;0,1,2=190,3=0.000000
L 11.5932001 1.76 11.58680049 1.76 2 P 0 ;0,1,2=190,3=0.000000
L 11.5660003 1.76 11.56413356 1.76041654 2 P 0 ;0,1,2=190,3=0.000000
L 11.56413356 1.76041654 11.5620002 1.76166624 2 P 0 ;0,1,2=190,3=0.000000
L 11.5620002 1.76166624 11.56066663 1.76374911 2 P 0 ;0,1,2=190,3=0.000000
L 11.56066663 1.76374911 11.56013337 1.76666673 2 P 0 ;0,1,2=190,3=0.000000
L 11.56013337 1.76666673 11.56066663 1.76958278 2 P 0 ;0,1,2=190,3=0.000000
L 11.56066663 1.76958278 11.56226673 1.77208297 2 P 0 ;0,1,2=190,3=0.000000
L 11.56226673 1.77208297 11.56466673 1.77333346 2 P 0 ;0,1,2=190,3=0.000000
L 11.56466673 1.77333346 11.56733337 1.77333346 2 P 0 ;0,1,2=190,3=0.000000
L 11.56733337 1.77333346 11.56893346 1.77416663 2 P 0 ;0,1,2=190,3=0.000000
L 11.56893346 1.77416663 11.57026703 1.77624951 2 P 0 ;0,1,2=190,3=0.000000
L 11.57026703 1.77624951 11.5708002 1.77916634 2 P 0 ;0,1,2=190,3=0.000000
L 11.5708002 1.77916634 11.5699999 1.78208317 2 P 0 ;0,1,2=190,3=0.000000
L 11.5699999 1.78208317 11.56813366 1.78416683 2 P 0 ;0,1,2=190,3=0.000000
L 11.56813366 1.78416683 11.5660003 1.785 2 P 0 ;0,1,2=190,3=0.000000
L 11.5660003 1.785 11.56386693 1.78416683 2 P 0 ;0,1,2=190,3=0.000000
L 11.56386693 1.78416683 11.5620002 1.78208317 2 P 0 ;0,1,2=190,3=0.000000
L 11.5620002 1.78208317 11.5611999 1.77916634 2 P 0 ;0,1,2=190,3=0.000000
L 11.5611999 1.77916634 11.56173356 1.77624951 2 P 0 ;0,1,2=190,3=0.000000
L 11.56173356 1.77624951 11.56306663 1.77416663 2 P 0 ;0,1,2=190,3=0.000000
L 11.56306663 1.77416663 11.56466673 1.77333346 2 P 0 ;0,1,2=190,3=0.000000
L 11.56466673 1.77333346 11.56733337 1.77333346 2 P 0 ;0,1,2=190,3=0.000000
L 11.56733337 1.77333346 11.56973337 1.77208297 2 P 0 ;0,1,2=190,3=0.000000
L 11.56973337 1.77208297 11.57133346 1.76958278 2 P 0 ;0,1,2=190,3=0.000000
L 11.57133346 1.76958278 11.57186673 1.76666673 2 P 0 ;0,1,2=190,3=0.000000
L 11.57186673 1.76666673 11.57133346 1.76374911 2 P 0 ;0,1,2=190,3=0.000000
L 11.57133346 1.76374911 11.5699999 1.76166624 2 P 0 ;0,1,2=190,3=0.000000
L 11.5699999 1.76166624 11.56786654 1.76041654 2 P 0 ;0,1,2=190,3=0.000000
L 11.56786654 1.76041654 11.5660003 1.76 2 P 0 ;0,1,2=190,3=0.000000
A 11.44143996 1.73 11.44143996 1.73 11.43893002 1.73 1 P 0 N
L 11.65613337 1.74291634 11.65773356 1.74416683 2 P 0 ;0,1,2=191,3=0.000000
L 11.65773356 1.74416683 11.6595998 1.745 2 P 0 ;0,1,2=191,3=0.000000
L 11.6595998 1.745 11.66173317 1.745 2 P 0 ;0,1,2=191,3=0.000000
L 11.66173317 1.745 11.66413366 1.74374941 2 P 0 ;0,1,2=191,3=0.000000
L 11.66413366 1.74374941 11.6659999 1.74166654 2 P 0 ;0,1,2=191,3=0.000000
L 11.6659999 1.74166654 11.66733346 1.73916634 2 P 0 ;0,1,2=191,3=0.000000
L 11.66733346 1.73916634 11.66840039 1.7349998 2 P 0 ;0,1,2=191,3=0.000000
L 11.66840039 1.7349998 11.66866703 1.7312498 2 P 0 ;0,1,2=191,3=0.000000
L 11.66866703 1.7312498 11.66813327 1.7274999 2 P 0 ;0,1,2=191,3=0.000000
L 11.66813327 1.7274999 11.66733346 1.72499961 2 P 0 ;0,1,2=191,3=0.000000
L 11.66733346 1.72499961 11.66573337 1.72249941 2 P 0 ;0,1,2=191,3=0.000000
L 11.66573337 1.72249941 11.66386654 1.72083307 2 P 0 ;0,1,2=191,3=0.000000
L 11.66386654 1.72083307 11.6620003 1.72 2 P 0 ;0,1,2=191,3=0.000000
L 11.6620003 1.72 11.66013356 1.72 2 P 0 ;0,1,2=191,3=0.000000
L 11.66013356 1.72 11.65826673 1.72083307 2 P 0 ;0,1,2=191,3=0.000000
L 11.65826673 1.72083307 11.65666663 1.72208287 2 P 0 ;0,1,2=191,3=0.000000
L 11.65666663 1.72208287 11.65533307 1.72374911 2 P 0 ;0,1,2=191,3=0.000000
L 11.64306683 1.74083337 11.64146673 1.74333287 2 P 0 ;0,1,2=191,3=0.000000
L 11.64146673 1.74333287 11.6396 1.74458337 2 P 0 ;0,1,2=191,3=0.000000
L 11.6396 1.74458337 11.63746663 1.745 2 P 0 ;0,1,2=191,3=0.000000
L 11.63746663 1.745 11.6348 1.74416683 2 P 0 ;0,1,2=191,3=0.000000
L 11.6348 1.74416683 11.63293327 1.74208317 2 P 0 ;0,1,2=191,3=0.000000
L 11.63293327 1.74208317 11.6324 1.73958366 2 P 0 ;0,1,2=191,3=0.000000
L 11.6324 1.73958366 11.63266663 1.73708268 2 P 0 ;0,1,2=191,3=0.000000
L 11.63266663 1.73708268 11.63373356 1.7349998 2 P 0 ;0,1,2=191,3=0.000000
L 11.63373356 1.7349998 11.63906673 1.73083327 2 P 0 ;0,1,2=191,3=0.000000
L 11.63906673 1.73083327 11.64146673 1.72791644 2 P 0 ;0,1,2=191,3=0.000000
L 11.64146673 1.72791644 11.64306683 1.72374911 2 P 0 ;0,1,2=191,3=0.000000
L 11.64306683 1.72374911 11.6436001 1.72 2 P 0 ;0,1,2=191,3=0.000000
L 11.6436001 1.72 11.6324 1.72 2 P 0 ;0,1,2=191,3=0.000000
L 11.61906683 1.74083337 11.61746673 1.74333287 2 P 0 ;0,1,2=191,3=0.000000
L 11.61746673 1.74333287 11.6156 1.74458337 2 P 0 ;0,1,2=191,3=0.000000
L 11.6156 1.74458337 11.61346663 1.745 2 P 0 ;0,1,2=191,3=0.000000
L 11.61346663 1.745 11.6108 1.74416683 2 P 0 ;0,1,2=191,3=0.000000
L 11.6108 1.74416683 11.60893327 1.74208317 2 P 0 ;0,1,2=191,3=0.000000
L 11.60893327 1.74208317 11.6084 1.73958366 2 P 0 ;0,1,2=191,3=0.000000
L 11.6084 1.73958366 11.60866663 1.73708268 2 P 0 ;0,1,2=191,3=0.000000
L 11.60866663 1.73708268 11.60973356 1.7349998 2 P 0 ;0,1,2=191,3=0.000000
L 11.60973356 1.7349998 11.61506673 1.73083327 2 P 0 ;0,1,2=191,3=0.000000
L 11.61506673 1.73083327 11.61746673 1.72791644 2 P 0 ;0,1,2=191,3=0.000000
L 11.61746673 1.72791644 11.61906683 1.72374911 2 P 0 ;0,1,2=191,3=0.000000
L 11.61906683 1.72374911 11.6196001 1.72 2 P 0 ;0,1,2=191,3=0.000000
L 11.6196001 1.72 11.6084 1.72 2 P 0 ;0,1,2=191,3=0.000000
L 11.5900003 1.72 11.5900003 1.745 2 P 0 ;0,1,2=191,3=0.000000
L 11.5900003 1.745 11.5932001 1.7400003 2 P 0 ;0,1,2=191,3=0.000000
L 11.5932001 1.72 11.58680049 1.72 2 P 0 ;0,1,2=191,3=0.000000
L 11.57053366 1.72291604 11.56866683 1.72083307 2 P 0 ;0,1,2=191,3=0.000000
L 11.56866683 1.72083307 11.56653346 1.72 2 P 0 ;0,1,2=191,3=0.000000
L 11.56653346 1.72 11.5644001 1.72083307 2 P 0 ;0,1,2=191,3=0.000000
L 11.5644001 1.72083307 11.56253337 1.72333258 2 P 0 ;0,1,2=191,3=0.000000
L 11.56253337 1.72333258 11.5611999 1.72708327 2 P 0 ;0,1,2=191,3=0.000000
L 11.5611999 1.72708327 11.56066663 1.73083327 2 P 0 ;0,1,2=191,3=0.000000
L 11.56066663 1.73083327 11.56066663 1.73541634 2 P 0 ;0,1,2=191,3=0.000000
L 11.56066663 1.73541634 11.5611999 1.73916634 2 P 0 ;0,1,2=191,3=0.000000
L 11.5611999 1.73916634 11.56253337 1.7424997 2 P 0 ;0,1,2=191,3=0.000000
L 11.56253337 1.7424997 11.56413356 1.74416683 2 P 0 ;0,1,2=191,3=0.000000
L 11.56413356 1.74416683 11.5660003 1.745 2 P 0 ;0,1,2=191,3=0.000000
L 11.5660003 1.745 11.56813366 1.74416683 2 P 0 ;0,1,2=191,3=0.000000
L 11.56813366 1.74416683 11.56973337 1.7424997 2 P 0 ;0,1,2=191,3=0.000000
L 11.56973337 1.7424997 11.5708002 1.7400003 2 P 0 ;0,1,2=191,3=0.000000
L 11.5708002 1.7400003 11.57133346 1.73666614 2 P 0 ;0,1,2=191,3=0.000000
L 11.57133346 1.73666614 11.5708002 1.7337501 2 P 0 ;0,1,2=191,3=0.000000
L 11.5708002 1.7337501 11.56946673 1.73083327 2 P 0 ;0,1,2=191,3=0.000000
L 11.56946673 1.73083327 11.56786654 1.72916614 2 P 0 ;0,1,2=191,3=0.000000
L 11.56786654 1.72916614 11.5660003 1.72874961 2 P 0 ;0,1,2=191,3=0.000000
L 11.5660003 1.72874961 11.56386693 1.72958278 2 P 0 ;0,1,2=191,3=0.000000
L 11.56386693 1.72958278 11.56226673 1.73166644 2 P 0 ;0,1,2=191,3=0.000000
L 11.56226673 1.73166644 11.56066663 1.73541634 2 P 0 ;0,1,2=191,3=0.000000
A 11.64143996 1.855 11.64143996 1.855 11.63893002 1.855 1 P 0 N
L 11.89144341 1.86429636 11.8930436 1.86554685 2 P 0 ;0,1,2=192,3=0.000000
L 11.8930436 1.86554685 11.89490984 1.86638002 2 P 0 ;0,1,2=192,3=0.000000
L 11.89490984 1.86638002 11.89704321 1.86638002 2 P 0 ;0,1,2=192,3=0.000000
L 11.89704321 1.86638002 11.8994437 1.86512943 2 P 0 ;0,1,2=192,3=0.000000
L 11.8994437 1.86512943 11.90130994 1.86304656 2 P 0 ;0,1,2=192,3=0.000000
L 11.90130994 1.86304656 11.9026435 1.86054636 2 P 0 ;0,1,2=192,3=0.000000
L 11.9026435 1.86054636 11.90371043 1.85637982 2 P 0 ;0,1,2=192,3=0.000000
L 11.90371043 1.85637982 11.90397707 1.85262982 2 P 0 ;0,1,2=192,3=0.000000
L 11.90397707 1.85262982 11.90344331 1.84887992 2 P 0 ;0,1,2=192,3=0.000000
L 11.90344331 1.84887992 11.9026435 1.84637963 2 P 0 ;0,1,2=192,3=0.000000
L 11.9026435 1.84637963 11.90104341 1.84387943 2 P 0 ;0,1,2=192,3=0.000000
L 11.90104341 1.84387943 11.89917657 1.84221309 2 P 0 ;0,1,2=192,3=0.000000
L 11.89917657 1.84221309 11.89731033 1.84138002 2 P 0 ;0,1,2=192,3=0.000000
L 11.89731033 1.84138002 11.8954436 1.84138002 2 P 0 ;0,1,2=192,3=0.000000
L 11.8954436 1.84138002 11.89357677 1.84221309 2 P 0 ;0,1,2=192,3=0.000000
L 11.89357677 1.84221309 11.89197667 1.84346289 2 P 0 ;0,1,2=192,3=0.000000
L 11.89197667 1.84346289 11.89064311 1.84512913 2 P 0 ;0,1,2=192,3=0.000000
L 11.87837687 1.86221339 11.87677677 1.86471289 2 P 0 ;0,1,2=192,3=0.000000
L 11.87677677 1.86471289 11.87491004 1.86596339 2 P 0 ;0,1,2=192,3=0.000000
L 11.87491004 1.86596339 11.87277667 1.86638002 2 P 0 ;0,1,2=192,3=0.000000
L 11.87277667 1.86638002 11.87011004 1.86554685 2 P 0 ;0,1,2=192,3=0.000000
L 11.87011004 1.86554685 11.86824331 1.86346319 2 P 0 ;0,1,2=192,3=0.000000
L 11.86824331 1.86346319 11.86771004 1.86096368 2 P 0 ;0,1,2=192,3=0.000000
L 11.86771004 1.86096368 11.86797667 1.8584627 2 P 0 ;0,1,2=192,3=0.000000
L 11.86797667 1.8584627 11.8690436 1.85637982 2 P 0 ;0,1,2=192,3=0.000000
L 11.8690436 1.85637982 11.87437677 1.85221329 2 P 0 ;0,1,2=192,3=0.000000
L 11.87437677 1.85221329 11.87677677 1.84929646 2 P 0 ;0,1,2=192,3=0.000000
L 11.87677677 1.84929646 11.87837687 1.84512913 2 P 0 ;0,1,2=192,3=0.000000
L 11.87837687 1.84512913 11.87891014 1.84138002 2 P 0 ;0,1,2=192,3=0.000000
L 11.87891014 1.84138002 11.86771004 1.84138002 2 P 0 ;0,1,2=192,3=0.000000
L 11.85437687 1.86221339 11.85277677 1.86471289 2 P 0 ;0,1,2=192,3=0.000000
L 11.85277677 1.86471289 11.85091004 1.86596339 2 P 0 ;0,1,2=192,3=0.000000
L 11.85091004 1.86596339 11.84877667 1.86638002 2 P 0 ;0,1,2=192,3=0.000000
L 11.84877667 1.86638002 11.84611004 1.86554685 2 P 0 ;0,1,2=192,3=0.000000
L 11.84611004 1.86554685 11.84424331 1.86346319 2 P 0 ;0,1,2=192,3=0.000000
L 11.84424331 1.86346319 11.84371004 1.86096368 2 P 0 ;0,1,2=192,3=0.000000
L 11.84371004 1.86096368 11.84397667 1.8584627 2 P 0 ;0,1,2=192,3=0.000000
L 11.84397667 1.8584627 11.8450436 1.85637982 2 P 0 ;0,1,2=192,3=0.000000
L 11.8450436 1.85637982 11.85037677 1.85221329 2 P 0 ;0,1,2=192,3=0.000000
L 11.85037677 1.85221329 11.85277677 1.84929646 2 P 0 ;0,1,2=192,3=0.000000
L 11.85277677 1.84929646 11.85437687 1.84512913 2 P 0 ;0,1,2=192,3=0.000000
L 11.85437687 1.84512913 11.85491014 1.84138002 2 P 0 ;0,1,2=192,3=0.000000
L 11.85491014 1.84138002 11.84371004 1.84138002 2 P 0 ;0,1,2=192,3=0.000000
L 11.83037687 1.86221339 11.82877677 1.86471289 2 P 0 ;0,1,2=192,3=0.000000
L 11.82877677 1.86471289 11.82691004 1.86596339 2 P 0 ;0,1,2=192,3=0.000000
L 11.82691004 1.86596339 11.82477667 1.86638002 2 P 0 ;0,1,2=192,3=0.000000
L 11.82477667 1.86638002 11.82211004 1.86554685 2 P 0 ;0,1,2=192,3=0.000000
L 11.82211004 1.86554685 11.82024331 1.86346319 2 P 0 ;0,1,2=192,3=0.000000
L 11.82024331 1.86346319 11.81971004 1.86096368 2 P 0 ;0,1,2=192,3=0.000000
L 11.81971004 1.86096368 11.81997667 1.8584627 2 P 0 ;0,1,2=192,3=0.000000
L 11.81997667 1.8584627 11.8210436 1.85637982 2 P 0 ;0,1,2=192,3=0.000000
L 11.8210436 1.85637982 11.82637677 1.85221329 2 P 0 ;0,1,2=192,3=0.000000
L 11.82637677 1.85221329 11.82877677 1.84929646 2 P 0 ;0,1,2=192,3=0.000000
L 11.82877677 1.84929646 11.83037687 1.84512913 2 P 0 ;0,1,2=192,3=0.000000
L 11.83037687 1.84512913 11.83091014 1.84138002 2 P 0 ;0,1,2=192,3=0.000000
L 11.83091014 1.84138002 11.81971004 1.84138002 2 P 0 ;0,1,2=192,3=0.000000
L 11.80131033 1.86638002 11.8034437 1.86554685 2 P 0 ;0,1,2=192,3=0.000000
L 11.8034437 1.86554685 11.80504341 1.86346319 2 P 0 ;0,1,2=192,3=0.000000
L 11.80504341 1.86346319 11.80611024 1.86096368 2 P 0 ;0,1,2=192,3=0.000000
L 11.80611024 1.86096368 11.80691014 1.85762953 2 P 0 ;0,1,2=192,3=0.000000
L 11.80691014 1.85762953 11.80717677 1.85387963 2 P 0 ;0,1,2=192,3=0.000000
L 11.80717677 1.85387963 11.80691014 1.85012963 2 P 0 ;0,1,2=192,3=0.000000
L 11.80691014 1.85012963 11.80611024 1.84679626 2 P 0 ;0,1,2=192,3=0.000000
L 11.80611024 1.84679626 11.80504341 1.84429606 2 P 0 ;0,1,2=192,3=0.000000
L 11.80504341 1.84429606 11.8034437 1.84221309 2 P 0 ;0,1,2=192,3=0.000000
L 11.8034437 1.84221309 11.80131033 1.84138002 2 P 0 ;0,1,2=192,3=0.000000
L 11.80131033 1.84138002 11.79917697 1.84221309 2 P 0 ;0,1,2=192,3=0.000000
L 11.79917697 1.84221309 11.79757677 1.84429606 2 P 0 ;0,1,2=192,3=0.000000
L 11.79757677 1.84429606 11.79650994 1.84679626 2 P 0 ;0,1,2=192,3=0.000000
L 11.79650994 1.84679626 11.79571004 1.85012963 2 P 0 ;0,1,2=192,3=0.000000
L 11.79571004 1.85012963 11.79544341 1.85387963 2 P 0 ;0,1,2=192,3=0.000000
L 11.79544341 1.85387963 11.79571004 1.85762953 2 P 0 ;0,1,2=192,3=0.000000
L 11.79571004 1.85762953 11.79650994 1.86096368 2 P 0 ;0,1,2=192,3=0.000000
L 11.79650994 1.86096368 11.79757677 1.86346319 2 P 0 ;0,1,2=192,3=0.000000
L 11.79757677 1.86346319 11.79917697 1.86554685 2 P 0 ;0,1,2=192,3=0.000000
L 11.79917697 1.86554685 11.80131033 1.86638002 2 P 0 ;0,1,2=192,3=0.000000
A 11.64143996 1.81 11.64143996 1.81 11.63893002 1.81 1 P 0 N
L 11.89113337 1.82291634 11.89273356 1.82416683 2 P 0 ;0,1,2=193,3=0.000000
L 11.89273356 1.82416683 11.8945998 1.825 2 P 0 ;0,1,2=193,3=0.000000
L 11.8945998 1.825 11.89673317 1.825 2 P 0 ;0,1,2=193,3=0.000000
L 11.89673317 1.825 11.89913366 1.82374941 2 P 0 ;0,1,2=193,3=0.000000
L 11.89913366 1.82374941 11.9009999 1.82166654 2 P 0 ;0,1,2=193,3=0.000000
L 11.9009999 1.82166654 11.90233346 1.81916634 2 P 0 ;0,1,2=193,3=0.000000
L 11.90233346 1.81916634 11.90340039 1.8149998 2 P 0 ;0,1,2=193,3=0.000000
L 11.90340039 1.8149998 11.90366703 1.8112498 2 P 0 ;0,1,2=193,3=0.000000
L 11.90366703 1.8112498 11.90313327 1.8074999 2 P 0 ;0,1,2=193,3=0.000000
L 11.90313327 1.8074999 11.90233346 1.80499961 2 P 0 ;0,1,2=193,3=0.000000
L 11.90233346 1.80499961 11.90073337 1.80249941 2 P 0 ;0,1,2=193,3=0.000000
L 11.90073337 1.80249941 11.89886654 1.80083307 2 P 0 ;0,1,2=193,3=0.000000
L 11.89886654 1.80083307 11.8970003 1.8 2 P 0 ;0,1,2=193,3=0.000000
L 11.8970003 1.8 11.89513356 1.8 2 P 0 ;0,1,2=193,3=0.000000
L 11.89513356 1.8 11.89326673 1.80083307 2 P 0 ;0,1,2=193,3=0.000000
L 11.89326673 1.80083307 11.89166663 1.80208287 2 P 0 ;0,1,2=193,3=0.000000
L 11.89166663 1.80208287 11.89033307 1.80374911 2 P 0 ;0,1,2=193,3=0.000000
L 11.87806683 1.82083337 11.87646673 1.82333287 2 P 0 ;0,1,2=193,3=0.000000
L 11.87646673 1.82333287 11.8746 1.82458337 2 P 0 ;0,1,2=193,3=0.000000
L 11.8746 1.82458337 11.87246663 1.825 2 P 0 ;0,1,2=193,3=0.000000
L 11.87246663 1.825 11.8698 1.82416683 2 P 0 ;0,1,2=193,3=0.000000
L 11.8698 1.82416683 11.86793327 1.82208317 2 P 0 ;0,1,2=193,3=0.000000
L 11.86793327 1.82208317 11.8674 1.81958366 2 P 0 ;0,1,2=193,3=0.000000
L 11.8674 1.81958366 11.86766663 1.81708268 2 P 0 ;0,1,2=193,3=0.000000
L 11.86766663 1.81708268 11.86873356 1.8149998 2 P 0 ;0,1,2=193,3=0.000000
L 11.86873356 1.8149998 11.87406673 1.81083327 2 P 0 ;0,1,2=193,3=0.000000
L 11.87406673 1.81083327 11.87646673 1.80791644 2 P 0 ;0,1,2=193,3=0.000000
L 11.87646673 1.80791644 11.87806683 1.80374911 2 P 0 ;0,1,2=193,3=0.000000
L 11.87806683 1.80374911 11.8786001 1.8 2 P 0 ;0,1,2=193,3=0.000000
L 11.8786001 1.8 11.8674 1.8 2 P 0 ;0,1,2=193,3=0.000000
L 11.85406683 1.82083337 11.85246673 1.82333287 2 P 0 ;0,1,2=193,3=0.000000
L 11.85246673 1.82333287 11.8506 1.82458337 2 P 0 ;0,1,2=193,3=0.000000
L 11.8506 1.82458337 11.84846663 1.825 2 P 0 ;0,1,2=193,3=0.000000
L 11.84846663 1.825 11.8458 1.82416683 2 P 0 ;0,1,2=193,3=0.000000
L 11.8458 1.82416683 11.84393327 1.82208317 2 P 0 ;0,1,2=193,3=0.000000
L 11.84393327 1.82208317 11.8434 1.81958366 2 P 0 ;0,1,2=193,3=0.000000
L 11.8434 1.81958366 11.84366663 1.81708268 2 P 0 ;0,1,2=193,3=0.000000
L 11.84366663 1.81708268 11.84473356 1.8149998 2 P 0 ;0,1,2=193,3=0.000000
L 11.84473356 1.8149998 11.85006673 1.81083327 2 P 0 ;0,1,2=193,3=0.000000
L 11.85006673 1.81083327 11.85246673 1.80791644 2 P 0 ;0,1,2=193,3=0.000000
L 11.85246673 1.80791644 11.85406683 1.80374911 2 P 0 ;0,1,2=193,3=0.000000
L 11.85406683 1.80374911 11.8546001 1.8 2 P 0 ;0,1,2=193,3=0.000000
L 11.8546001 1.8 11.8434 1.8 2 P 0 ;0,1,2=193,3=0.000000
L 11.83006683 1.82083337 11.82846673 1.82333287 2 P 0 ;0,1,2=193,3=0.000000
L 11.82846673 1.82333287 11.8266 1.82458337 2 P 0 ;0,1,2=193,3=0.000000
L 11.8266 1.82458337 11.82446663 1.825 2 P 0 ;0,1,2=193,3=0.000000
L 11.82446663 1.825 11.8218 1.82416683 2 P 0 ;0,1,2=193,3=0.000000
L 11.8218 1.82416683 11.81993327 1.82208317 2 P 0 ;0,1,2=193,3=0.000000
L 11.81993327 1.82208317 11.8194 1.81958366 2 P 0 ;0,1,2=193,3=0.000000
L 11.8194 1.81958366 11.81966663 1.81708268 2 P 0 ;0,1,2=193,3=0.000000
L 11.81966663 1.81708268 11.82073356 1.8149998 2 P 0 ;0,1,2=193,3=0.000000
L 11.82073356 1.8149998 11.82606673 1.81083327 2 P 0 ;0,1,2=193,3=0.000000
L 11.82606673 1.81083327 11.82846673 1.80791644 2 P 0 ;0,1,2=193,3=0.000000
L 11.82846673 1.80791644 11.83006683 1.80374911 2 P 0 ;0,1,2=193,3=0.000000
L 11.83006683 1.80374911 11.8306001 1.8 2 P 0 ;0,1,2=193,3=0.000000
L 11.8306001 1.8 11.8194 1.8 2 P 0 ;0,1,2=193,3=0.000000
L 11.8010003 1.8 11.8010003 1.825 2 P 0 ;0,1,2=193,3=0.000000
L 11.8010003 1.825 11.8042001 1.8200003 2 P 0 ;0,1,2=193,3=0.000000
L 11.8042001 1.8 11.79780049 1.8 2 P 0 ;0,1,2=193,3=0.000000
A 11.44143996 1.615 11.44143996 1.615 11.43893002 1.615 1 P 0 N
L 11.65613337 1.62291634 11.65773356 1.62416683 2 P 0 ;0,1,2=194,3=0.000000
L 11.65773356 1.62416683 11.6595998 1.625 2 P 0 ;0,1,2=194,3=0.000000
L 11.6595998 1.625 11.66173317 1.625 2 P 0 ;0,1,2=194,3=0.000000
L 11.66173317 1.625 11.66413366 1.62374941 2 P 0 ;0,1,2=194,3=0.000000
L 11.66413366 1.62374941 11.6659999 1.62166654 2 P 0 ;0,1,2=194,3=0.000000
L 11.6659999 1.62166654 11.66733346 1.61916634 2 P 0 ;0,1,2=194,3=0.000000
L 11.66733346 1.61916634 11.66840039 1.6149998 2 P 0 ;0,1,2=194,3=0.000000
L 11.66840039 1.6149998 11.66866703 1.6112498 2 P 0 ;0,1,2=194,3=0.000000
L 11.66866703 1.6112498 11.66813327 1.6074999 2 P 0 ;0,1,2=194,3=0.000000
L 11.66813327 1.6074999 11.66733346 1.60499961 2 P 0 ;0,1,2=194,3=0.000000
L 11.66733346 1.60499961 11.66573337 1.60249941 2 P 0 ;0,1,2=194,3=0.000000
L 11.66573337 1.60249941 11.66386654 1.60083307 2 P 0 ;0,1,2=194,3=0.000000
L 11.66386654 1.60083307 11.6620003 1.6 2 P 0 ;0,1,2=194,3=0.000000
L 11.6620003 1.6 11.66013356 1.6 2 P 0 ;0,1,2=194,3=0.000000
L 11.66013356 1.6 11.65826673 1.60083307 2 P 0 ;0,1,2=194,3=0.000000
L 11.65826673 1.60083307 11.65666663 1.60208287 2 P 0 ;0,1,2=194,3=0.000000
L 11.65666663 1.60208287 11.65533307 1.60374911 2 P 0 ;0,1,2=194,3=0.000000
L 11.64306683 1.62083337 11.64146673 1.62333287 2 P 0 ;0,1,2=194,3=0.000000
L 11.64146673 1.62333287 11.6396 1.62458337 2 P 0 ;0,1,2=194,3=0.000000
L 11.6396 1.62458337 11.63746663 1.625 2 P 0 ;0,1,2=194,3=0.000000
L 11.63746663 1.625 11.6348 1.62416683 2 P 0 ;0,1,2=194,3=0.000000
L 11.6348 1.62416683 11.63293327 1.62208317 2 P 0 ;0,1,2=194,3=0.000000
L 11.63293327 1.62208317 11.6324 1.61958366 2 P 0 ;0,1,2=194,3=0.000000
L 11.6324 1.61958366 11.63266663 1.61708268 2 P 0 ;0,1,2=194,3=0.000000
L 11.63266663 1.61708268 11.63373356 1.6149998 2 P 0 ;0,1,2=194,3=0.000000
L 11.63373356 1.6149998 11.63906673 1.61083327 2 P 0 ;0,1,2=194,3=0.000000
L 11.63906673 1.61083327 11.64146673 1.60791644 2 P 0 ;0,1,2=194,3=0.000000
L 11.64146673 1.60791644 11.64306683 1.60374911 2 P 0 ;0,1,2=194,3=0.000000
L 11.64306683 1.60374911 11.6436001 1.6 2 P 0 ;0,1,2=194,3=0.000000
L 11.6436001 1.6 11.6324 1.6 2 P 0 ;0,1,2=194,3=0.000000
L 11.61906683 1.62083337 11.61746673 1.62333287 2 P 0 ;0,1,2=194,3=0.000000
L 11.61746673 1.62333287 11.6156 1.62458337 2 P 0 ;0,1,2=194,3=0.000000
L 11.6156 1.62458337 11.61346663 1.625 2 P 0 ;0,1,2=194,3=0.000000
L 11.61346663 1.625 11.6108 1.62416683 2 P 0 ;0,1,2=194,3=0.000000
L 11.6108 1.62416683 11.60893327 1.62208317 2 P 0 ;0,1,2=194,3=0.000000
L 11.60893327 1.62208317 11.6084 1.61958366 2 P 0 ;0,1,2=194,3=0.000000
L 11.6084 1.61958366 11.60866663 1.61708268 2 P 0 ;0,1,2=194,3=0.000000
L 11.60866663 1.61708268 11.60973356 1.6149998 2 P 0 ;0,1,2=194,3=0.000000
L 11.60973356 1.6149998 11.61506673 1.61083327 2 P 0 ;0,1,2=194,3=0.000000
L 11.61506673 1.61083327 11.61746673 1.60791644 2 P 0 ;0,1,2=194,3=0.000000
L 11.61746673 1.60791644 11.61906683 1.60374911 2 P 0 ;0,1,2=194,3=0.000000
L 11.61906683 1.60374911 11.6196001 1.6 2 P 0 ;0,1,2=194,3=0.000000
L 11.6196001 1.6 11.6084 1.6 2 P 0 ;0,1,2=194,3=0.000000
L 11.59506683 1.62083337 11.59346673 1.62333287 2 P 0 ;0,1,2=194,3=0.000000
L 11.59346673 1.62333287 11.5916 1.62458337 2 P 0 ;0,1,2=194,3=0.000000
L 11.5916 1.62458337 11.58946663 1.625 2 P 0 ;0,1,2=194,3=0.000000
L 11.58946663 1.625 11.5868 1.62416683 2 P 0 ;0,1,2=194,3=0.000000
L 11.5868 1.62416683 11.58493327 1.62208317 2 P 0 ;0,1,2=194,3=0.000000
L 11.58493327 1.62208317 11.5844 1.61958366 2 P 0 ;0,1,2=194,3=0.000000
L 11.5844 1.61958366 11.58466663 1.61708268 2 P 0 ;0,1,2=194,3=0.000000
L 11.58466663 1.61708268 11.58573356 1.6149998 2 P 0 ;0,1,2=194,3=0.000000
L 11.58573356 1.6149998 11.59106673 1.61083327 2 P 0 ;0,1,2=194,3=0.000000
L 11.59106673 1.61083327 11.59346673 1.60791644 2 P 0 ;0,1,2=194,3=0.000000
L 11.59346673 1.60791644 11.59506683 1.60374911 2 P 0 ;0,1,2=194,3=0.000000
L 11.59506683 1.60374911 11.5956001 1.6 2 P 0 ;0,1,2=194,3=0.000000
L 11.5956001 1.6 11.5844 1.6 2 P 0 ;0,1,2=194,3=0.000000
L 11.57106683 1.62083337 11.56946673 1.62333287 2 P 0 ;0,1,2=194,3=0.000000
L 11.56946673 1.62333287 11.5676 1.62458337 2 P 0 ;0,1,2=194,3=0.000000
L 11.5676 1.62458337 11.56546663 1.625 2 P 0 ;0,1,2=194,3=0.000000
L 11.56546663 1.625 11.5628 1.62416683 2 P 0 ;0,1,2=194,3=0.000000
L 11.5628 1.62416683 11.56093327 1.62208317 2 P 0 ;0,1,2=194,3=0.000000
L 11.56093327 1.62208317 11.5604 1.61958366 2 P 0 ;0,1,2=194,3=0.000000
L 11.5604 1.61958366 11.56066663 1.61708268 2 P 0 ;0,1,2=194,3=0.000000
L 11.56066663 1.61708268 11.56173356 1.6149998 2 P 0 ;0,1,2=194,3=0.000000
L 11.56173356 1.6149998 11.56706673 1.61083327 2 P 0 ;0,1,2=194,3=0.000000
L 11.56706673 1.61083327 11.56946673 1.60791644 2 P 0 ;0,1,2=194,3=0.000000
L 11.56946673 1.60791644 11.57106683 1.60374911 2 P 0 ;0,1,2=194,3=0.000000
L 11.57106683 1.60374911 11.5716001 1.6 2 P 0 ;0,1,2=194,3=0.000000
L 11.5716001 1.6 11.5604 1.6 2 P 0 ;0,1,2=194,3=0.000000
A 11.44143996 1.57 11.44143996 1.57 11.43893002 1.57 1 P 0 N
L 11.65613337 1.58291634 11.65773356 1.58416683 2 P 0 ;0,1,2=195,3=0.000000
L 11.65773356 1.58416683 11.6595998 1.585 2 P 0 ;0,1,2=195,3=0.000000
L 11.6595998 1.585 11.66173317 1.585 2 P 0 ;0,1,2=195,3=0.000000
L 11.66173317 1.585 11.66413366 1.58374941 2 P 0 ;0,1,2=195,3=0.000000
L 11.66413366 1.58374941 11.6659999 1.58166654 2 P 0 ;0,1,2=195,3=0.000000
L 11.6659999 1.58166654 11.66733346 1.57916634 2 P 0 ;0,1,2=195,3=0.000000
L 11.66733346 1.57916634 11.66840039 1.5749998 2 P 0 ;0,1,2=195,3=0.000000
L 11.66840039 1.5749998 11.66866703 1.5712498 2 P 0 ;0,1,2=195,3=0.000000
L 11.66866703 1.5712498 11.66813327 1.5674999 2 P 0 ;0,1,2=195,3=0.000000
L 11.66813327 1.5674999 11.66733346 1.56499961 2 P 0 ;0,1,2=195,3=0.000000
L 11.66733346 1.56499961 11.66573337 1.56249941 2 P 0 ;0,1,2=195,3=0.000000
L 11.66573337 1.56249941 11.66386654 1.56083307 2 P 0 ;0,1,2=195,3=0.000000
L 11.66386654 1.56083307 11.6620003 1.56 2 P 0 ;0,1,2=195,3=0.000000
L 11.6620003 1.56 11.66013356 1.56 2 P 0 ;0,1,2=195,3=0.000000
L 11.66013356 1.56 11.65826673 1.56083307 2 P 0 ;0,1,2=195,3=0.000000
L 11.65826673 1.56083307 11.65666663 1.56208287 2 P 0 ;0,1,2=195,3=0.000000
L 11.65666663 1.56208287 11.65533307 1.56374911 2 P 0 ;0,1,2=195,3=0.000000
L 11.64306683 1.58083337 11.64146673 1.58333287 2 P 0 ;0,1,2=195,3=0.000000
L 11.64146673 1.58333287 11.6396 1.58458337 2 P 0 ;0,1,2=195,3=0.000000
L 11.6396 1.58458337 11.63746663 1.585 2 P 0 ;0,1,2=195,3=0.000000
L 11.63746663 1.585 11.6348 1.58416683 2 P 0 ;0,1,2=195,3=0.000000
L 11.6348 1.58416683 11.63293327 1.58208317 2 P 0 ;0,1,2=195,3=0.000000
L 11.63293327 1.58208317 11.6324 1.57958366 2 P 0 ;0,1,2=195,3=0.000000
L 11.6324 1.57958366 11.63266663 1.57708268 2 P 0 ;0,1,2=195,3=0.000000
L 11.63266663 1.57708268 11.63373356 1.5749998 2 P 0 ;0,1,2=195,3=0.000000
L 11.63373356 1.5749998 11.63906673 1.57083327 2 P 0 ;0,1,2=195,3=0.000000
L 11.63906673 1.57083327 11.64146673 1.56791644 2 P 0 ;0,1,2=195,3=0.000000
L 11.64146673 1.56791644 11.64306683 1.56374911 2 P 0 ;0,1,2=195,3=0.000000
L 11.64306683 1.56374911 11.6436001 1.56 2 P 0 ;0,1,2=195,3=0.000000
L 11.6436001 1.56 11.6324 1.56 2 P 0 ;0,1,2=195,3=0.000000
L 11.61906683 1.58083337 11.61746673 1.58333287 2 P 0 ;0,1,2=195,3=0.000000
L 11.61746673 1.58333287 11.6156 1.58458337 2 P 0 ;0,1,2=195,3=0.000000
L 11.6156 1.58458337 11.61346663 1.585 2 P 0 ;0,1,2=195,3=0.000000
L 11.61346663 1.585 11.6108 1.58416683 2 P 0 ;0,1,2=195,3=0.000000
L 11.6108 1.58416683 11.60893327 1.58208317 2 P 0 ;0,1,2=195,3=0.000000
L 11.60893327 1.58208317 11.6084 1.57958366 2 P 0 ;0,1,2=195,3=0.000000
L 11.6084 1.57958366 11.60866663 1.57708268 2 P 0 ;0,1,2=195,3=0.000000
L 11.60866663 1.57708268 11.60973356 1.5749998 2 P 0 ;0,1,2=195,3=0.000000
L 11.60973356 1.5749998 11.61506673 1.57083327 2 P 0 ;0,1,2=195,3=0.000000
L 11.61506673 1.57083327 11.61746673 1.56791644 2 P 0 ;0,1,2=195,3=0.000000
L 11.61746673 1.56791644 11.61906683 1.56374911 2 P 0 ;0,1,2=195,3=0.000000
L 11.61906683 1.56374911 11.6196001 1.56 2 P 0 ;0,1,2=195,3=0.000000
L 11.6196001 1.56 11.6084 1.56 2 P 0 ;0,1,2=195,3=0.000000
L 11.59506683 1.58083337 11.59346673 1.58333287 2 P 0 ;0,1,2=195,3=0.000000
L 11.59346673 1.58333287 11.5916 1.58458337 2 P 0 ;0,1,2=195,3=0.000000
L 11.5916 1.58458337 11.58946663 1.585 2 P 0 ;0,1,2=195,3=0.000000
L 11.58946663 1.585 11.5868 1.58416683 2 P 0 ;0,1,2=195,3=0.000000
L 11.5868 1.58416683 11.58493327 1.58208317 2 P 0 ;0,1,2=195,3=0.000000
L 11.58493327 1.58208317 11.5844 1.57958366 2 P 0 ;0,1,2=195,3=0.000000
L 11.5844 1.57958366 11.58466663 1.57708268 2 P 0 ;0,1,2=195,3=0.000000
L 11.58466663 1.57708268 11.58573356 1.5749998 2 P 0 ;0,1,2=195,3=0.000000
L 11.58573356 1.5749998 11.59106673 1.57083327 2 P 0 ;0,1,2=195,3=0.000000
L 11.59106673 1.57083327 11.59346673 1.56791644 2 P 0 ;0,1,2=195,3=0.000000
L 11.59346673 1.56791644 11.59506683 1.56374911 2 P 0 ;0,1,2=195,3=0.000000
L 11.59506683 1.56374911 11.5956001 1.56 2 P 0 ;0,1,2=195,3=0.000000
L 11.5956001 1.56 11.5844 1.56 2 P 0 ;0,1,2=195,3=0.000000
L 11.57186673 1.56499961 11.57026703 1.56208287 2 P 0 ;0,1,2=195,3=0.000000
L 11.57026703 1.56208287 11.56813366 1.56041654 2 P 0 ;0,1,2=195,3=0.000000
L 11.56813366 1.56041654 11.56573317 1.56 2 P 0 ;0,1,2=195,3=0.000000
L 11.56573317 1.56 11.5635998 1.56041654 2 P 0 ;0,1,2=195,3=0.000000
L 11.5635998 1.56041654 11.56146644 1.56249941 2 P 0 ;0,1,2=195,3=0.000000
L 11.56146644 1.56249941 11.56013337 1.56499961 2 P 0 ;0,1,2=195,3=0.000000
L 11.56013337 1.56499961 11.55986683 1.5674999 2 P 0 ;0,1,2=195,3=0.000000
L 11.55986683 1.5674999 11.5604 1.57041594 2 P 0 ;0,1,2=195,3=0.000000
L 11.5604 1.57041594 11.56226673 1.57249961 2 P 0 ;0,1,2=195,3=0.000000
L 11.56226673 1.57249961 11.56413356 1.57333346 2 P 0 ;0,1,2=195,3=0.000000
L 11.56413356 1.57333346 11.56653346 1.57333346 2 P 0 ;0,1,2=195,3=0.000000
L 11.56413356 1.57333346 11.56253337 1.57458327 2 P 0 ;0,1,2=195,3=0.000000
L 11.56253337 1.57458327 11.5611999 1.57666614 2 P 0 ;0,1,2=195,3=0.000000
L 11.5611999 1.57666614 11.56066663 1.57916634 2 P 0 ;0,1,2=195,3=0.000000
L 11.56066663 1.57916634 11.5611999 1.58166654 2 P 0 ;0,1,2=195,3=0.000000
L 11.5611999 1.58166654 11.56253337 1.58374941 2 P 0 ;0,1,2=195,3=0.000000
L 11.56253337 1.58374941 11.56493337 1.585 2 P 0 ;0,1,2=195,3=0.000000
L 11.56493337 1.585 11.56733337 1.58458337 2 P 0 ;0,1,2=195,3=0.000000
L 11.56733337 1.58458337 11.56973337 1.58291634 2 P 0 ;0,1,2=195,3=0.000000
A 11.44143996 1.41 11.44143996 1.41 11.43893002 1.41 1 P 0 N
L 11.65613337 1.41791634 11.65773356 1.41916683 2 P 0 ;0,1,2=196,3=0.000000
L 11.65773356 1.41916683 11.6595998 1.42 2 P 0 ;0,1,2=196,3=0.000000
L 11.6595998 1.42 11.66173317 1.42 2 P 0 ;0,1,2=196,3=0.000000
L 11.66173317 1.42 11.66413366 1.41874941 2 P 0 ;0,1,2=196,3=0.000000
L 11.66413366 1.41874941 11.6659999 1.41666654 2 P 0 ;0,1,2=196,3=0.000000
L 11.6659999 1.41666654 11.66733346 1.41416634 2 P 0 ;0,1,2=196,3=0.000000
L 11.66733346 1.41416634 11.66840039 1.4099998 2 P 0 ;0,1,2=196,3=0.000000
L 11.66840039 1.4099998 11.66866703 1.4062498 2 P 0 ;0,1,2=196,3=0.000000
L 11.66866703 1.4062498 11.66813327 1.4024999 2 P 0 ;0,1,2=196,3=0.000000
L 11.66813327 1.4024999 11.66733346 1.39999961 2 P 0 ;0,1,2=196,3=0.000000
L 11.66733346 1.39999961 11.66573337 1.39749941 2 P 0 ;0,1,2=196,3=0.000000
L 11.66573337 1.39749941 11.66386654 1.39583307 2 P 0 ;0,1,2=196,3=0.000000
L 11.66386654 1.39583307 11.6620003 1.395 2 P 0 ;0,1,2=196,3=0.000000
L 11.6620003 1.395 11.66013356 1.395 2 P 0 ;0,1,2=196,3=0.000000
L 11.66013356 1.395 11.65826673 1.39583307 2 P 0 ;0,1,2=196,3=0.000000
L 11.65826673 1.39583307 11.65666663 1.39708287 2 P 0 ;0,1,2=196,3=0.000000
L 11.65666663 1.39708287 11.65533307 1.39874911 2 P 0 ;0,1,2=196,3=0.000000
L 11.64306683 1.41583337 11.64146673 1.41833287 2 P 0 ;0,1,2=196,3=0.000000
L 11.64146673 1.41833287 11.6396 1.41958337 2 P 0 ;0,1,2=196,3=0.000000
L 11.6396 1.41958337 11.63746663 1.42 2 P 0 ;0,1,2=196,3=0.000000
L 11.63746663 1.42 11.6348 1.41916683 2 P 0 ;0,1,2=196,3=0.000000
L 11.6348 1.41916683 11.63293327 1.41708317 2 P 0 ;0,1,2=196,3=0.000000
L 11.63293327 1.41708317 11.6324 1.41458366 2 P 0 ;0,1,2=196,3=0.000000
L 11.6324 1.41458366 11.63266663 1.41208268 2 P 0 ;0,1,2=196,3=0.000000
L 11.63266663 1.41208268 11.63373356 1.4099998 2 P 0 ;0,1,2=196,3=0.000000
L 11.63373356 1.4099998 11.63906673 1.40583327 2 P 0 ;0,1,2=196,3=0.000000
L 11.63906673 1.40583327 11.64146673 1.40291644 2 P 0 ;0,1,2=196,3=0.000000
L 11.64146673 1.40291644 11.64306683 1.39874911 2 P 0 ;0,1,2=196,3=0.000000
L 11.64306683 1.39874911 11.6436001 1.395 2 P 0 ;0,1,2=196,3=0.000000
L 11.6436001 1.395 11.6324 1.395 2 P 0 ;0,1,2=196,3=0.000000
L 11.61906683 1.41583337 11.61746673 1.41833287 2 P 0 ;0,1,2=196,3=0.000000
L 11.61746673 1.41833287 11.6156 1.41958337 2 P 0 ;0,1,2=196,3=0.000000
L 11.6156 1.41958337 11.61346663 1.42 2 P 0 ;0,1,2=196,3=0.000000
L 11.61346663 1.42 11.6108 1.41916683 2 P 0 ;0,1,2=196,3=0.000000
L 11.6108 1.41916683 11.60893327 1.41708317 2 P 0 ;0,1,2=196,3=0.000000
L 11.60893327 1.41708317 11.6084 1.41458366 2 P 0 ;0,1,2=196,3=0.000000
L 11.6084 1.41458366 11.60866663 1.41208268 2 P 0 ;0,1,2=196,3=0.000000
L 11.60866663 1.41208268 11.60973356 1.4099998 2 P 0 ;0,1,2=196,3=0.000000
L 11.60973356 1.4099998 11.61506673 1.40583327 2 P 0 ;0,1,2=196,3=0.000000
L 11.61506673 1.40583327 11.61746673 1.40291644 2 P 0 ;0,1,2=196,3=0.000000
L 11.61746673 1.40291644 11.61906683 1.39874911 2 P 0 ;0,1,2=196,3=0.000000
L 11.61906683 1.39874911 11.6196001 1.395 2 P 0 ;0,1,2=196,3=0.000000
L 11.6196001 1.395 11.6084 1.395 2 P 0 ;0,1,2=196,3=0.000000
L 11.59506683 1.41583337 11.59346673 1.41833287 2 P 0 ;0,1,2=196,3=0.000000
L 11.59346673 1.41833287 11.5916 1.41958337 2 P 0 ;0,1,2=196,3=0.000000
L 11.5916 1.41958337 11.58946663 1.42 2 P 0 ;0,1,2=196,3=0.000000
L 11.58946663 1.42 11.5868 1.41916683 2 P 0 ;0,1,2=196,3=0.000000
L 11.5868 1.41916683 11.58493327 1.41708317 2 P 0 ;0,1,2=196,3=0.000000
L 11.58493327 1.41708317 11.5844 1.41458366 2 P 0 ;0,1,2=196,3=0.000000
L 11.5844 1.41458366 11.58466663 1.41208268 2 P 0 ;0,1,2=196,3=0.000000
L 11.58466663 1.41208268 11.58573356 1.4099998 2 P 0 ;0,1,2=196,3=0.000000
L 11.58573356 1.4099998 11.59106673 1.40583327 2 P 0 ;0,1,2=196,3=0.000000
L 11.59106673 1.40583327 11.59346673 1.40291644 2 P 0 ;0,1,2=196,3=0.000000
L 11.59346673 1.40291644 11.59506683 1.39874911 2 P 0 ;0,1,2=196,3=0.000000
L 11.59506683 1.39874911 11.5956001 1.395 2 P 0 ;0,1,2=196,3=0.000000
L 11.5956001 1.395 11.5844 1.395 2 P 0 ;0,1,2=196,3=0.000000
L 11.5628 1.395 11.5628 1.42 2 P 0 ;0,1,2=196,3=0.000000
L 11.5628 1.42 11.57266703 1.40208327 2 P 0 ;0,1,2=196,3=0.000000
L 11.57266703 1.40208327 11.55933307 1.40208327 2 P 0 ;0,1,2=196,3=0.000000
A 11.44143996 1.455 11.44143996 1.455 11.43893002 1.455 1 P 0 N
L 11.65613337 1.45791634 11.65773356 1.45916683 2 P 0 ;0,1,2=197,3=0.000000
L 11.65773356 1.45916683 11.6595998 1.46 2 P 0 ;0,1,2=197,3=0.000000
L 11.6595998 1.46 11.66173317 1.46 2 P 0 ;0,1,2=197,3=0.000000
L 11.66173317 1.46 11.66413366 1.45874941 2 P 0 ;0,1,2=197,3=0.000000
L 11.66413366 1.45874941 11.6659999 1.45666654 2 P 0 ;0,1,2=197,3=0.000000
L 11.6659999 1.45666654 11.66733346 1.45416634 2 P 0 ;0,1,2=197,3=0.000000
L 11.66733346 1.45416634 11.66840039 1.4499998 2 P 0 ;0,1,2=197,3=0.000000
L 11.66840039 1.4499998 11.66866703 1.4462498 2 P 0 ;0,1,2=197,3=0.000000
L 11.66866703 1.4462498 11.66813327 1.4424999 2 P 0 ;0,1,2=197,3=0.000000
L 11.66813327 1.4424999 11.66733346 1.43999961 2 P 0 ;0,1,2=197,3=0.000000
L 11.66733346 1.43999961 11.66573337 1.43749941 2 P 0 ;0,1,2=197,3=0.000000
L 11.66573337 1.43749941 11.66386654 1.43583307 2 P 0 ;0,1,2=197,3=0.000000
L 11.66386654 1.43583307 11.6620003 1.435 2 P 0 ;0,1,2=197,3=0.000000
L 11.6620003 1.435 11.66013356 1.435 2 P 0 ;0,1,2=197,3=0.000000
L 11.66013356 1.435 11.65826673 1.43583307 2 P 0 ;0,1,2=197,3=0.000000
L 11.65826673 1.43583307 11.65666663 1.43708287 2 P 0 ;0,1,2=197,3=0.000000
L 11.65666663 1.43708287 11.65533307 1.43874911 2 P 0 ;0,1,2=197,3=0.000000
L 11.64306683 1.45583337 11.64146673 1.45833287 2 P 0 ;0,1,2=197,3=0.000000
L 11.64146673 1.45833287 11.6396 1.45958337 2 P 0 ;0,1,2=197,3=0.000000
L 11.6396 1.45958337 11.63746663 1.46 2 P 0 ;0,1,2=197,3=0.000000
L 11.63746663 1.46 11.6348 1.45916683 2 P 0 ;0,1,2=197,3=0.000000
L 11.6348 1.45916683 11.63293327 1.45708317 2 P 0 ;0,1,2=197,3=0.000000
L 11.63293327 1.45708317 11.6324 1.45458366 2 P 0 ;0,1,2=197,3=0.000000
L 11.6324 1.45458366 11.63266663 1.45208268 2 P 0 ;0,1,2=197,3=0.000000
L 11.63266663 1.45208268 11.63373356 1.4499998 2 P 0 ;0,1,2=197,3=0.000000
L 11.63373356 1.4499998 11.63906673 1.44583327 2 P 0 ;0,1,2=197,3=0.000000
L 11.63906673 1.44583327 11.64146673 1.44291644 2 P 0 ;0,1,2=197,3=0.000000
L 11.64146673 1.44291644 11.64306683 1.43874911 2 P 0 ;0,1,2=197,3=0.000000
L 11.64306683 1.43874911 11.6436001 1.435 2 P 0 ;0,1,2=197,3=0.000000
L 11.6436001 1.435 11.6324 1.435 2 P 0 ;0,1,2=197,3=0.000000
L 11.61906683 1.45583337 11.61746673 1.45833287 2 P 0 ;0,1,2=197,3=0.000000
L 11.61746673 1.45833287 11.6156 1.45958337 2 P 0 ;0,1,2=197,3=0.000000
L 11.6156 1.45958337 11.61346663 1.46 2 P 0 ;0,1,2=197,3=0.000000
L 11.61346663 1.46 11.6108 1.45916683 2 P 0 ;0,1,2=197,3=0.000000
L 11.6108 1.45916683 11.60893327 1.45708317 2 P 0 ;0,1,2=197,3=0.000000
L 11.60893327 1.45708317 11.6084 1.45458366 2 P 0 ;0,1,2=197,3=0.000000
L 11.6084 1.45458366 11.60866663 1.45208268 2 P 0 ;0,1,2=197,3=0.000000
L 11.60866663 1.45208268 11.60973356 1.4499998 2 P 0 ;0,1,2=197,3=0.000000
L 11.60973356 1.4499998 11.61506673 1.44583327 2 P 0 ;0,1,2=197,3=0.000000
L 11.61506673 1.44583327 11.61746673 1.44291644 2 P 0 ;0,1,2=197,3=0.000000
L 11.61746673 1.44291644 11.61906683 1.43874911 2 P 0 ;0,1,2=197,3=0.000000
L 11.61906683 1.43874911 11.6196001 1.435 2 P 0 ;0,1,2=197,3=0.000000
L 11.6196001 1.435 11.6084 1.435 2 P 0 ;0,1,2=197,3=0.000000
L 11.59506683 1.45583337 11.59346673 1.45833287 2 P 0 ;0,1,2=197,3=0.000000
L 11.59346673 1.45833287 11.5916 1.45958337 2 P 0 ;0,1,2=197,3=0.000000
L 11.5916 1.45958337 11.58946663 1.46 2 P 0 ;0,1,2=197,3=0.000000
L 11.58946663 1.46 11.5868 1.45916683 2 P 0 ;0,1,2=197,3=0.000000
L 11.5868 1.45916683 11.58493327 1.45708317 2 P 0 ;0,1,2=197,3=0.000000
L 11.58493327 1.45708317 11.5844 1.45458366 2 P 0 ;0,1,2=197,3=0.000000
L 11.5844 1.45458366 11.58466663 1.45208268 2 P 0 ;0,1,2=197,3=0.000000
L 11.58466663 1.45208268 11.58573356 1.4499998 2 P 0 ;0,1,2=197,3=0.000000
L 11.58573356 1.4499998 11.59106673 1.44583327 2 P 0 ;0,1,2=197,3=0.000000
L 11.59106673 1.44583327 11.59346673 1.44291644 2 P 0 ;0,1,2=197,3=0.000000
L 11.59346673 1.44291644 11.59506683 1.43874911 2 P 0 ;0,1,2=197,3=0.000000
L 11.59506683 1.43874911 11.5956001 1.435 2 P 0 ;0,1,2=197,3=0.000000
L 11.5956001 1.435 11.5844 1.435 2 P 0 ;0,1,2=197,3=0.000000
L 11.57186673 1.43874911 11.57026703 1.43666624 2 P 0 ;0,1,2=197,3=0.000000
L 11.57026703 1.43666624 11.5684003 1.43541654 2 P 0 ;0,1,2=197,3=0.000000
L 11.5684003 1.43541654 11.5660003 1.435 2 P 0 ;0,1,2=197,3=0.000000
L 11.5660003 1.435 11.5635998 1.43583307 2 P 0 ;0,1,2=197,3=0.000000
L 11.5635998 1.43583307 11.56173356 1.43749941 2 P 0 ;0,1,2=197,3=0.000000
L 11.56173356 1.43749941 11.5604 1.44041624 2 P 0 ;0,1,2=197,3=0.000000
L 11.5604 1.44041624 11.56013337 1.44374961 2 P 0 ;0,1,2=197,3=0.000000
L 11.56013337 1.44374961 11.56066663 1.44708297 2 P 0 ;0,1,2=197,3=0.000000
L 11.56066663 1.44708297 11.5620002 1.44916663 2 P 0 ;0,1,2=197,3=0.000000
L 11.5620002 1.44916663 11.56386693 1.45083297 2 P 0 ;0,1,2=197,3=0.000000
L 11.56386693 1.45083297 11.56573317 1.45124951 2 P 0 ;0,1,2=197,3=0.000000
L 11.56573317 1.45124951 11.5676 1.45083297 2 P 0 ;0,1,2=197,3=0.000000
L 11.5676 1.45083297 11.5699999 1.44916663 2 P 0 ;0,1,2=197,3=0.000000
L 11.5699999 1.44916663 11.5692001 1.46 2 P 0 ;0,1,2=197,3=0.000000
L 11.5692001 1.46 11.5620002 1.46 2 P 0 ;0,1,2=197,3=0.000000
A 11.64143996 1.49 11.64143996 1.49 11.63893002 1.49 1 P 0 N
L 11.84113337 1.55791634 11.84273356 1.55916683 2 P 0 ;0,1,2=198,3=0.000000
L 11.84273356 1.55916683 11.8445998 1.56 2 P 0 ;0,1,2=198,3=0.000000
L 11.8445998 1.56 11.84673317 1.56 2 P 0 ;0,1,2=198,3=0.000000
L 11.84673317 1.56 11.84913366 1.55874941 2 P 0 ;0,1,2=198,3=0.000000
L 11.84913366 1.55874941 11.8509999 1.55666654 2 P 0 ;0,1,2=198,3=0.000000
L 11.8509999 1.55666654 11.85233346 1.55416634 2 P 0 ;0,1,2=198,3=0.000000
L 11.85233346 1.55416634 11.85340039 1.5499998 2 P 0 ;0,1,2=198,3=0.000000
L 11.85340039 1.5499998 11.85366703 1.5462498 2 P 0 ;0,1,2=198,3=0.000000
L 11.85366703 1.5462498 11.85313327 1.5424999 2 P 0 ;0,1,2=198,3=0.000000
L 11.85313327 1.5424999 11.85233346 1.53999961 2 P 0 ;0,1,2=198,3=0.000000
L 11.85233346 1.53999961 11.85073337 1.53749941 2 P 0 ;0,1,2=198,3=0.000000
L 11.85073337 1.53749941 11.84886654 1.53583307 2 P 0 ;0,1,2=198,3=0.000000
L 11.84886654 1.53583307 11.8470003 1.535 2 P 0 ;0,1,2=198,3=0.000000
L 11.8470003 1.535 11.84513356 1.535 2 P 0 ;0,1,2=198,3=0.000000
L 11.84513356 1.535 11.84326673 1.53583307 2 P 0 ;0,1,2=198,3=0.000000
L 11.84326673 1.53583307 11.84166663 1.53708287 2 P 0 ;0,1,2=198,3=0.000000
L 11.84166663 1.53708287 11.84033307 1.53874911 2 P 0 ;0,1,2=198,3=0.000000
L 11.82806683 1.55583337 11.82646673 1.55833287 2 P 0 ;0,1,2=198,3=0.000000
L 11.82646673 1.55833287 11.8246 1.55958337 2 P 0 ;0,1,2=198,3=0.000000
L 11.8246 1.55958337 11.82246663 1.56 2 P 0 ;0,1,2=198,3=0.000000
L 11.82246663 1.56 11.8198 1.55916683 2 P 0 ;0,1,2=198,3=0.000000
L 11.8198 1.55916683 11.81793327 1.55708317 2 P 0 ;0,1,2=198,3=0.000000
L 11.81793327 1.55708317 11.8174 1.55458366 2 P 0 ;0,1,2=198,3=0.000000
L 11.8174 1.55458366 11.81766663 1.55208268 2 P 0 ;0,1,2=198,3=0.000000
L 11.81766663 1.55208268 11.81873356 1.5499998 2 P 0 ;0,1,2=198,3=0.000000
L 11.81873356 1.5499998 11.82406673 1.54583327 2 P 0 ;0,1,2=198,3=0.000000
L 11.82406673 1.54583327 11.82646673 1.54291644 2 P 0 ;0,1,2=198,3=0.000000
L 11.82646673 1.54291644 11.82806683 1.53874911 2 P 0 ;0,1,2=198,3=0.000000
L 11.82806683 1.53874911 11.8286001 1.535 2 P 0 ;0,1,2=198,3=0.000000
L 11.8286001 1.535 11.8174 1.535 2 P 0 ;0,1,2=198,3=0.000000
L 11.80406683 1.55583337 11.80246673 1.55833287 2 P 0 ;0,1,2=198,3=0.000000
L 11.80246673 1.55833287 11.8006 1.55958337 2 P 0 ;0,1,2=198,3=0.000000
L 11.8006 1.55958337 11.79846663 1.56 2 P 0 ;0,1,2=198,3=0.000000
L 11.79846663 1.56 11.7958 1.55916683 2 P 0 ;0,1,2=198,3=0.000000
L 11.7958 1.55916683 11.79393327 1.55708317 2 P 0 ;0,1,2=198,3=0.000000
L 11.79393327 1.55708317 11.7934 1.55458366 2 P 0 ;0,1,2=198,3=0.000000
L 11.7934 1.55458366 11.79366663 1.55208268 2 P 0 ;0,1,2=198,3=0.000000
L 11.79366663 1.55208268 11.79473356 1.5499998 2 P 0 ;0,1,2=198,3=0.000000
L 11.79473356 1.5499998 11.80006673 1.54583327 2 P 0 ;0,1,2=198,3=0.000000
L 11.80006673 1.54583327 11.80246673 1.54291644 2 P 0 ;0,1,2=198,3=0.000000
L 11.80246673 1.54291644 11.80406683 1.53874911 2 P 0 ;0,1,2=198,3=0.000000
L 11.80406683 1.53874911 11.8046001 1.535 2 P 0 ;0,1,2=198,3=0.000000
L 11.8046001 1.535 11.7934 1.535 2 P 0 ;0,1,2=198,3=0.000000
L 11.78006683 1.55583337 11.77846673 1.55833287 2 P 0 ;0,1,2=198,3=0.000000
L 11.77846673 1.55833287 11.7766 1.55958337 2 P 0 ;0,1,2=198,3=0.000000
L 11.7766 1.55958337 11.77446663 1.56 2 P 0 ;0,1,2=198,3=0.000000
L 11.77446663 1.56 11.7718 1.55916683 2 P 0 ;0,1,2=198,3=0.000000
L 11.7718 1.55916683 11.76993327 1.55708317 2 P 0 ;0,1,2=198,3=0.000000
L 11.76993327 1.55708317 11.7694 1.55458366 2 P 0 ;0,1,2=198,3=0.000000
L 11.7694 1.55458366 11.76966663 1.55208268 2 P 0 ;0,1,2=198,3=0.000000
L 11.76966663 1.55208268 11.77073356 1.5499998 2 P 0 ;0,1,2=198,3=0.000000
L 11.77073356 1.5499998 11.77606673 1.54583327 2 P 0 ;0,1,2=198,3=0.000000
L 11.77606673 1.54583327 11.77846673 1.54291644 2 P 0 ;0,1,2=198,3=0.000000
L 11.77846673 1.54291644 11.78006683 1.53874911 2 P 0 ;0,1,2=198,3=0.000000
L 11.78006683 1.53874911 11.7806001 1.535 2 P 0 ;0,1,2=198,3=0.000000
L 11.7806001 1.535 11.7694 1.535 2 P 0 ;0,1,2=198,3=0.000000
L 11.75606683 1.54541594 11.7542001 1.54833346 2 P 0 ;0,1,2=198,3=0.000000
L 11.7542001 1.54833346 11.7526 1.5499998 2 P 0 ;0,1,2=198,3=0.000000
L 11.7526 1.5499998 11.75046663 1.55083297 2 P 0 ;0,1,2=198,3=0.000000
L 11.75046663 1.55083297 11.7485998 1.5499998 2 P 0 ;0,1,2=198,3=0.000000
L 11.7485998 1.5499998 11.74726673 1.54833346 2 P 0 ;0,1,2=198,3=0.000000
L 11.74726673 1.54833346 11.7461999 1.54583327 2 P 0 ;0,1,2=198,3=0.000000
L 11.7461999 1.54583327 11.74593327 1.54291644 2 P 0 ;0,1,2=198,3=0.000000
L 11.74593327 1.54291644 11.7461999 1.54041624 2 P 0 ;0,1,2=198,3=0.000000
L 11.7461999 1.54041624 11.74726673 1.53791604 2 P 0 ;0,1,2=198,3=0.000000
L 11.74726673 1.53791604 11.74886693 1.53583307 2 P 0 ;0,1,2=198,3=0.000000
L 11.74886693 1.53583307 11.75073317 1.535 2 P 0 ;0,1,2=198,3=0.000000
L 11.75073317 1.535 11.75286654 1.53583307 2 P 0 ;0,1,2=198,3=0.000000
L 11.75286654 1.53583307 11.75473337 1.53833258 2 P 0 ;0,1,2=198,3=0.000000
L 11.75473337 1.53833258 11.7558002 1.54208327 2 P 0 ;0,1,2=198,3=0.000000
L 11.7558002 1.54208327 11.75606683 1.5462498 2 P 0 ;0,1,2=198,3=0.000000
L 11.75606683 1.5462498 11.75553366 1.55166614 2 P 0 ;0,1,2=198,3=0.000000
L 11.75553366 1.55166614 11.75473337 1.55458366 2 P 0 ;0,1,2=198,3=0.000000
L 11.75473337 1.55458366 11.7534003 1.5574997 2 P 0 ;0,1,2=198,3=0.000000
L 11.7534003 1.5574997 11.75153346 1.55958337 2 P 0 ;0,1,2=198,3=0.000000
L 11.75153346 1.55958337 11.74966673 1.56 2 P 0 ;0,1,2=198,3=0.000000
L 11.74966673 1.56 11.7478 1.55916683 2 P 0 ;0,1,2=198,3=0.000000
L 11.7478 1.55916683 11.74646644 1.55708317 2 P 0 ;0,1,2=198,3=0.000000
A 11.64143996 1.535 11.64143996 1.535 11.63893002 1.535 1 P 0 N
L 11.84113337 1.59791634 11.84273356 1.59916683 2 P 0 ;0,1,2=199,3=0.000000
L 11.84273356 1.59916683 11.8445998 1.6 2 P 0 ;0,1,2=199,3=0.000000
L 11.8445998 1.6 11.84673317 1.6 2 P 0 ;0,1,2=199,3=0.000000
L 11.84673317 1.6 11.84913366 1.59874941 2 P 0 ;0,1,2=199,3=0.000000
L 11.84913366 1.59874941 11.8509999 1.59666654 2 P 0 ;0,1,2=199,3=0.000000
L 11.8509999 1.59666654 11.85233346 1.59416634 2 P 0 ;0,1,2=199,3=0.000000
L 11.85233346 1.59416634 11.85340039 1.5899998 2 P 0 ;0,1,2=199,3=0.000000
L 11.85340039 1.5899998 11.85366703 1.5862498 2 P 0 ;0,1,2=199,3=0.000000
L 11.85366703 1.5862498 11.85313327 1.5824999 2 P 0 ;0,1,2=199,3=0.000000
L 11.85313327 1.5824999 11.85233346 1.57999961 2 P 0 ;0,1,2=199,3=0.000000
L 11.85233346 1.57999961 11.85073337 1.57749941 2 P 0 ;0,1,2=199,3=0.000000
L 11.85073337 1.57749941 11.84886654 1.57583307 2 P 0 ;0,1,2=199,3=0.000000
L 11.84886654 1.57583307 11.8470003 1.575 2 P 0 ;0,1,2=199,3=0.000000
L 11.8470003 1.575 11.84513356 1.575 2 P 0 ;0,1,2=199,3=0.000000
L 11.84513356 1.575 11.84326673 1.57583307 2 P 0 ;0,1,2=199,3=0.000000
L 11.84326673 1.57583307 11.84166663 1.57708287 2 P 0 ;0,1,2=199,3=0.000000
L 11.84166663 1.57708287 11.84033307 1.57874911 2 P 0 ;0,1,2=199,3=0.000000
L 11.82806683 1.59583337 11.82646673 1.59833287 2 P 0 ;0,1,2=199,3=0.000000
L 11.82646673 1.59833287 11.8246 1.59958337 2 P 0 ;0,1,2=199,3=0.000000
L 11.8246 1.59958337 11.82246663 1.6 2 P 0 ;0,1,2=199,3=0.000000
L 11.82246663 1.6 11.8198 1.59916683 2 P 0 ;0,1,2=199,3=0.000000
L 11.8198 1.59916683 11.81793327 1.59708317 2 P 0 ;0,1,2=199,3=0.000000
L 11.81793327 1.59708317 11.8174 1.59458366 2 P 0 ;0,1,2=199,3=0.000000
L 11.8174 1.59458366 11.81766663 1.59208268 2 P 0 ;0,1,2=199,3=0.000000
L 11.81766663 1.59208268 11.81873356 1.5899998 2 P 0 ;0,1,2=199,3=0.000000
L 11.81873356 1.5899998 11.82406673 1.58583327 2 P 0 ;0,1,2=199,3=0.000000
L 11.82406673 1.58583327 11.82646673 1.58291644 2 P 0 ;0,1,2=199,3=0.000000
L 11.82646673 1.58291644 11.82806683 1.57874911 2 P 0 ;0,1,2=199,3=0.000000
L 11.82806683 1.57874911 11.8286001 1.575 2 P 0 ;0,1,2=199,3=0.000000
L 11.8286001 1.575 11.8174 1.575 2 P 0 ;0,1,2=199,3=0.000000
L 11.80406683 1.59583337 11.80246673 1.59833287 2 P 0 ;0,1,2=199,3=0.000000
L 11.80246673 1.59833287 11.8006 1.59958337 2 P 0 ;0,1,2=199,3=0.000000
L 11.8006 1.59958337 11.79846663 1.6 2 P 0 ;0,1,2=199,3=0.000000
L 11.79846663 1.6 11.7958 1.59916683 2 P 0 ;0,1,2=199,3=0.000000
L 11.7958 1.59916683 11.79393327 1.59708317 2 P 0 ;0,1,2=199,3=0.000000
L 11.79393327 1.59708317 11.7934 1.59458366 2 P 0 ;0,1,2=199,3=0.000000
L 11.7934 1.59458366 11.79366663 1.59208268 2 P 0 ;0,1,2=199,3=0.000000
L 11.79366663 1.59208268 11.79473356 1.5899998 2 P 0 ;0,1,2=199,3=0.000000
L 11.79473356 1.5899998 11.80006673 1.58583327 2 P 0 ;0,1,2=199,3=0.000000
L 11.80006673 1.58583327 11.80246673 1.58291644 2 P 0 ;0,1,2=199,3=0.000000
L 11.80246673 1.58291644 11.80406683 1.57874911 2 P 0 ;0,1,2=199,3=0.000000
L 11.80406683 1.57874911 11.8046001 1.575 2 P 0 ;0,1,2=199,3=0.000000
L 11.8046001 1.575 11.7934 1.575 2 P 0 ;0,1,2=199,3=0.000000
L 11.78006683 1.59583337 11.77846673 1.59833287 2 P 0 ;0,1,2=199,3=0.000000
L 11.77846673 1.59833287 11.7766 1.59958337 2 P 0 ;0,1,2=199,3=0.000000
L 11.7766 1.59958337 11.77446663 1.6 2 P 0 ;0,1,2=199,3=0.000000
L 11.77446663 1.6 11.7718 1.59916683 2 P 0 ;0,1,2=199,3=0.000000
L 11.7718 1.59916683 11.76993327 1.59708317 2 P 0 ;0,1,2=199,3=0.000000
L 11.76993327 1.59708317 11.7694 1.59458366 2 P 0 ;0,1,2=199,3=0.000000
L 11.7694 1.59458366 11.76966663 1.59208268 2 P 0 ;0,1,2=199,3=0.000000
L 11.76966663 1.59208268 11.77073356 1.5899998 2 P 0 ;0,1,2=199,3=0.000000
L 11.77073356 1.5899998 11.77606673 1.58583327 2 P 0 ;0,1,2=199,3=0.000000
L 11.77606673 1.58583327 11.77846673 1.58291644 2 P 0 ;0,1,2=199,3=0.000000
L 11.77846673 1.58291644 11.78006683 1.57874911 2 P 0 ;0,1,2=199,3=0.000000
L 11.78006683 1.57874911 11.7806001 1.575 2 P 0 ;0,1,2=199,3=0.000000
L 11.7806001 1.575 11.7694 1.575 2 P 0 ;0,1,2=199,3=0.000000
L 11.75153346 1.575 11.7510003 1.58041624 2 P 0 ;0,1,2=199,3=0.000000
L 11.7510003 1.58041624 11.7502 1.58499931 2 P 0 ;0,1,2=199,3=0.000000
L 11.7502 1.58499931 11.74913356 1.58916663 2 P 0 ;0,1,2=199,3=0.000000
L 11.74913356 1.58916663 11.7478 1.5937498 2 P 0 ;0,1,2=199,3=0.000000
L 11.7478 1.5937498 11.74566663 1.6 2 P 0 ;0,1,2=199,3=0.000000
L 11.74566663 1.6 11.75633346 1.6 2 P 0 ;0,1,2=199,3=0.000000
A 11.64143996 1.695 11.64143996 1.695 11.63893002 1.695 1 P 0 N
L 11.89144341 1.75929636 11.8930436 1.76054685 2 P 0 ;0,1,2=200,3=0.000000
L 11.8930436 1.76054685 11.89490984 1.76138002 2 P 0 ;0,1,2=200,3=0.000000
L 11.89490984 1.76138002 11.89704321 1.76138002 2 P 0 ;0,1,2=200,3=0.000000
L 11.89704321 1.76138002 11.8994437 1.76012943 2 P 0 ;0,1,2=200,3=0.000000
L 11.8994437 1.76012943 11.90130994 1.75804656 2 P 0 ;0,1,2=200,3=0.000000
L 11.90130994 1.75804656 11.9026435 1.75554636 2 P 0 ;0,1,2=200,3=0.000000
L 11.9026435 1.75554636 11.90371043 1.75137982 2 P 0 ;0,1,2=200,3=0.000000
L 11.90371043 1.75137982 11.90397707 1.74762982 2 P 0 ;0,1,2=200,3=0.000000
L 11.90397707 1.74762982 11.90344331 1.74387992 2 P 0 ;0,1,2=200,3=0.000000
L 11.90344331 1.74387992 11.9026435 1.74137963 2 P 0 ;0,1,2=200,3=0.000000
L 11.9026435 1.74137963 11.90104341 1.73887943 2 P 0 ;0,1,2=200,3=0.000000
L 11.90104341 1.73887943 11.89917657 1.73721309 2 P 0 ;0,1,2=200,3=0.000000
L 11.89917657 1.73721309 11.89731033 1.73638002 2 P 0 ;0,1,2=200,3=0.000000
L 11.89731033 1.73638002 11.8954436 1.73638002 2 P 0 ;0,1,2=200,3=0.000000
L 11.8954436 1.73638002 11.89357677 1.73721309 2 P 0 ;0,1,2=200,3=0.000000
L 11.89357677 1.73721309 11.89197667 1.73846289 2 P 0 ;0,1,2=200,3=0.000000
L 11.89197667 1.73846289 11.89064311 1.74012913 2 P 0 ;0,1,2=200,3=0.000000
L 11.87837687 1.75721339 11.87677677 1.75971289 2 P 0 ;0,1,2=200,3=0.000000
L 11.87677677 1.75971289 11.87491004 1.76096339 2 P 0 ;0,1,2=200,3=0.000000
L 11.87491004 1.76096339 11.87277667 1.76138002 2 P 0 ;0,1,2=200,3=0.000000
L 11.87277667 1.76138002 11.87011004 1.76054685 2 P 0 ;0,1,2=200,3=0.000000
L 11.87011004 1.76054685 11.86824331 1.75846319 2 P 0 ;0,1,2=200,3=0.000000
L 11.86824331 1.75846319 11.86771004 1.75596368 2 P 0 ;0,1,2=200,3=0.000000
L 11.86771004 1.75596368 11.86797667 1.7534627 2 P 0 ;0,1,2=200,3=0.000000
L 11.86797667 1.7534627 11.8690436 1.75137982 2 P 0 ;0,1,2=200,3=0.000000
L 11.8690436 1.75137982 11.87437677 1.74721329 2 P 0 ;0,1,2=200,3=0.000000
L 11.87437677 1.74721329 11.87677677 1.74429646 2 P 0 ;0,1,2=200,3=0.000000
L 11.87677677 1.74429646 11.87837687 1.74012913 2 P 0 ;0,1,2=200,3=0.000000
L 11.87837687 1.74012913 11.87891014 1.73638002 2 P 0 ;0,1,2=200,3=0.000000
L 11.87891014 1.73638002 11.86771004 1.73638002 2 P 0 ;0,1,2=200,3=0.000000
L 11.85437687 1.75721339 11.85277677 1.75971289 2 P 0 ;0,1,2=200,3=0.000000
L 11.85277677 1.75971289 11.85091004 1.76096339 2 P 0 ;0,1,2=200,3=0.000000
L 11.85091004 1.76096339 11.84877667 1.76138002 2 P 0 ;0,1,2=200,3=0.000000
L 11.84877667 1.76138002 11.84611004 1.76054685 2 P 0 ;0,1,2=200,3=0.000000
L 11.84611004 1.76054685 11.84424331 1.75846319 2 P 0 ;0,1,2=200,3=0.000000
L 11.84424331 1.75846319 11.84371004 1.75596368 2 P 0 ;0,1,2=200,3=0.000000
L 11.84371004 1.75596368 11.84397667 1.7534627 2 P 0 ;0,1,2=200,3=0.000000
L 11.84397667 1.7534627 11.8450436 1.75137982 2 P 0 ;0,1,2=200,3=0.000000
L 11.8450436 1.75137982 11.85037677 1.74721329 2 P 0 ;0,1,2=200,3=0.000000
L 11.85037677 1.74721329 11.85277677 1.74429646 2 P 0 ;0,1,2=200,3=0.000000
L 11.85277677 1.74429646 11.85437687 1.74012913 2 P 0 ;0,1,2=200,3=0.000000
L 11.85437687 1.74012913 11.85491014 1.73638002 2 P 0 ;0,1,2=200,3=0.000000
L 11.85491014 1.73638002 11.84371004 1.73638002 2 P 0 ;0,1,2=200,3=0.000000
L 11.83037687 1.75721339 11.82877677 1.75971289 2 P 0 ;0,1,2=200,3=0.000000
L 11.82877677 1.75971289 11.82691004 1.76096339 2 P 0 ;0,1,2=200,3=0.000000
L 11.82691004 1.76096339 11.82477667 1.76138002 2 P 0 ;0,1,2=200,3=0.000000
L 11.82477667 1.76138002 11.82211004 1.76054685 2 P 0 ;0,1,2=200,3=0.000000
L 11.82211004 1.76054685 11.82024331 1.75846319 2 P 0 ;0,1,2=200,3=0.000000
L 11.82024331 1.75846319 11.81971004 1.75596368 2 P 0 ;0,1,2=200,3=0.000000
L 11.81971004 1.75596368 11.81997667 1.7534627 2 P 0 ;0,1,2=200,3=0.000000
L 11.81997667 1.7534627 11.8210436 1.75137982 2 P 0 ;0,1,2=200,3=0.000000
L 11.8210436 1.75137982 11.82637677 1.74721329 2 P 0 ;0,1,2=200,3=0.000000
L 11.82637677 1.74721329 11.82877677 1.74429646 2 P 0 ;0,1,2=200,3=0.000000
L 11.82877677 1.74429646 11.83037687 1.74012913 2 P 0 ;0,1,2=200,3=0.000000
L 11.83037687 1.74012913 11.83091014 1.73638002 2 P 0 ;0,1,2=200,3=0.000000
L 11.83091014 1.73638002 11.81971004 1.73638002 2 P 0 ;0,1,2=200,3=0.000000
L 11.80131033 1.73638002 11.7994436 1.73679656 2 P 0 ;0,1,2=200,3=0.000000
L 11.7994436 1.73679656 11.79731024 1.73804626 2 P 0 ;0,1,2=200,3=0.000000
L 11.79731024 1.73804626 11.79597667 1.74012913 2 P 0 ;0,1,2=200,3=0.000000
L 11.79597667 1.74012913 11.79544341 1.74304675 2 P 0 ;0,1,2=200,3=0.000000
L 11.79544341 1.74304675 11.79597667 1.7459628 2 P 0 ;0,1,2=200,3=0.000000
L 11.79597667 1.7459628 11.79757677 1.74846299 2 P 0 ;0,1,2=200,3=0.000000
L 11.79757677 1.74846299 11.79997677 1.74971348 2 P 0 ;0,1,2=200,3=0.000000
L 11.79997677 1.74971348 11.80264341 1.74971348 2 P 0 ;0,1,2=200,3=0.000000
L 11.80264341 1.74971348 11.8042435 1.75054665 2 P 0 ;0,1,2=200,3=0.000000
L 11.8042435 1.75054665 11.80557707 1.75262953 2 P 0 ;0,1,2=200,3=0.000000
L 11.80557707 1.75262953 11.80611024 1.75554636 2 P 0 ;0,1,2=200,3=0.000000
L 11.80611024 1.75554636 11.80530994 1.75846319 2 P 0 ;0,1,2=200,3=0.000000
L 11.80530994 1.75846319 11.8034437 1.76054685 2 P 0 ;0,1,2=200,3=0.000000
L 11.8034437 1.76054685 11.80131033 1.76138002 2 P 0 ;0,1,2=200,3=0.000000
L 11.80131033 1.76138002 11.79917697 1.76054685 2 P 0 ;0,1,2=200,3=0.000000
L 11.79917697 1.76054685 11.79731024 1.75846319 2 P 0 ;0,1,2=200,3=0.000000
L 11.79731024 1.75846319 11.79650994 1.75554636 2 P 0 ;0,1,2=200,3=0.000000
L 11.79650994 1.75554636 11.7970436 1.75262953 2 P 0 ;0,1,2=200,3=0.000000
L 11.7970436 1.75262953 11.79837667 1.75054665 2 P 0 ;0,1,2=200,3=0.000000
L 11.79837667 1.75054665 11.79997677 1.74971348 2 P 0 ;0,1,2=200,3=0.000000
L 11.79997677 1.74971348 11.80264341 1.74971348 2 P 0 ;0,1,2=200,3=0.000000
L 11.80264341 1.74971348 11.80504341 1.74846299 2 P 0 ;0,1,2=200,3=0.000000
L 11.80504341 1.74846299 11.8066435 1.7459628 2 P 0 ;0,1,2=200,3=0.000000
L 11.8066435 1.7459628 11.80717677 1.74304675 2 P 0 ;0,1,2=200,3=0.000000
L 11.80717677 1.74304675 11.8066435 1.74012913 2 P 0 ;0,1,2=200,3=0.000000
L 11.8066435 1.74012913 11.80530994 1.73804626 2 P 0 ;0,1,2=200,3=0.000000
L 11.80530994 1.73804626 11.80317657 1.73679656 2 P 0 ;0,1,2=200,3=0.000000
L 11.80317657 1.73679656 11.80131033 1.73638002 2 P 0 ;0,1,2=200,3=0.000000
A 11.64143996 1.65 11.64143996 1.65 11.63893002 1.65 1 P 0 N
L 11.89144341 1.71429636 11.8930436 1.71554685 2 P 0 ;0,1,2=201,3=0.000000
L 11.8930436 1.71554685 11.89490984 1.71638002 2 P 0 ;0,1,2=201,3=0.000000
L 11.89490984 1.71638002 11.89704321 1.71638002 2 P 0 ;0,1,2=201,3=0.000000
L 11.89704321 1.71638002 11.8994437 1.71512943 2 P 0 ;0,1,2=201,3=0.000000
L 11.8994437 1.71512943 11.90130994 1.71304656 2 P 0 ;0,1,2=201,3=0.000000
L 11.90130994 1.71304656 11.9026435 1.71054636 2 P 0 ;0,1,2=201,3=0.000000
L 11.9026435 1.71054636 11.90371043 1.70637982 2 P 0 ;0,1,2=201,3=0.000000
L 11.90371043 1.70637982 11.90397707 1.70262982 2 P 0 ;0,1,2=201,3=0.000000
L 11.90397707 1.70262982 11.90344331 1.69887992 2 P 0 ;0,1,2=201,3=0.000000
L 11.90344331 1.69887992 11.9026435 1.69637963 2 P 0 ;0,1,2=201,3=0.000000
L 11.9026435 1.69637963 11.90104341 1.69387943 2 P 0 ;0,1,2=201,3=0.000000
L 11.90104341 1.69387943 11.89917657 1.69221309 2 P 0 ;0,1,2=201,3=0.000000
L 11.89917657 1.69221309 11.89731033 1.69138002 2 P 0 ;0,1,2=201,3=0.000000
L 11.89731033 1.69138002 11.8954436 1.69138002 2 P 0 ;0,1,2=201,3=0.000000
L 11.8954436 1.69138002 11.89357677 1.69221309 2 P 0 ;0,1,2=201,3=0.000000
L 11.89357677 1.69221309 11.89197667 1.69346289 2 P 0 ;0,1,2=201,3=0.000000
L 11.89197667 1.69346289 11.89064311 1.69512913 2 P 0 ;0,1,2=201,3=0.000000
L 11.87837687 1.71221339 11.87677677 1.71471289 2 P 0 ;0,1,2=201,3=0.000000
L 11.87677677 1.71471289 11.87491004 1.71596339 2 P 0 ;0,1,2=201,3=0.000000
L 11.87491004 1.71596339 11.87277667 1.71638002 2 P 0 ;0,1,2=201,3=0.000000
L 11.87277667 1.71638002 11.87011004 1.71554685 2 P 0 ;0,1,2=201,3=0.000000
L 11.87011004 1.71554685 11.86824331 1.71346319 2 P 0 ;0,1,2=201,3=0.000000
L 11.86824331 1.71346319 11.86771004 1.71096368 2 P 0 ;0,1,2=201,3=0.000000
L 11.86771004 1.71096368 11.86797667 1.7084627 2 P 0 ;0,1,2=201,3=0.000000
L 11.86797667 1.7084627 11.8690436 1.70637982 2 P 0 ;0,1,2=201,3=0.000000
L 11.8690436 1.70637982 11.87437677 1.70221329 2 P 0 ;0,1,2=201,3=0.000000
L 11.87437677 1.70221329 11.87677677 1.69929646 2 P 0 ;0,1,2=201,3=0.000000
L 11.87677677 1.69929646 11.87837687 1.69512913 2 P 0 ;0,1,2=201,3=0.000000
L 11.87837687 1.69512913 11.87891014 1.69138002 2 P 0 ;0,1,2=201,3=0.000000
L 11.87891014 1.69138002 11.86771004 1.69138002 2 P 0 ;0,1,2=201,3=0.000000
L 11.85437687 1.71221339 11.85277677 1.71471289 2 P 0 ;0,1,2=201,3=0.000000
L 11.85277677 1.71471289 11.85091004 1.71596339 2 P 0 ;0,1,2=201,3=0.000000
L 11.85091004 1.71596339 11.84877667 1.71638002 2 P 0 ;0,1,2=201,3=0.000000
L 11.84877667 1.71638002 11.84611004 1.71554685 2 P 0 ;0,1,2=201,3=0.000000
L 11.84611004 1.71554685 11.84424331 1.71346319 2 P 0 ;0,1,2=201,3=0.000000
L 11.84424331 1.71346319 11.84371004 1.71096368 2 P 0 ;0,1,2=201,3=0.000000
L 11.84371004 1.71096368 11.84397667 1.7084627 2 P 0 ;0,1,2=201,3=0.000000
L 11.84397667 1.7084627 11.8450436 1.70637982 2 P 0 ;0,1,2=201,3=0.000000
L 11.8450436 1.70637982 11.85037677 1.70221329 2 P 0 ;0,1,2=201,3=0.000000
L 11.85037677 1.70221329 11.85277677 1.69929646 2 P 0 ;0,1,2=201,3=0.000000
L 11.85277677 1.69929646 11.85437687 1.69512913 2 P 0 ;0,1,2=201,3=0.000000
L 11.85437687 1.69512913 11.85491014 1.69138002 2 P 0 ;0,1,2=201,3=0.000000
L 11.85491014 1.69138002 11.84371004 1.69138002 2 P 0 ;0,1,2=201,3=0.000000
L 11.83037687 1.71221339 11.82877677 1.71471289 2 P 0 ;0,1,2=201,3=0.000000
L 11.82877677 1.71471289 11.82691004 1.71596339 2 P 0 ;0,1,2=201,3=0.000000
L 11.82691004 1.71596339 11.82477667 1.71638002 2 P 0 ;0,1,2=201,3=0.000000
L 11.82477667 1.71638002 11.82211004 1.71554685 2 P 0 ;0,1,2=201,3=0.000000
L 11.82211004 1.71554685 11.82024331 1.71346319 2 P 0 ;0,1,2=201,3=0.000000
L 11.82024331 1.71346319 11.81971004 1.71096368 2 P 0 ;0,1,2=201,3=0.000000
L 11.81971004 1.71096368 11.81997667 1.7084627 2 P 0 ;0,1,2=201,3=0.000000
L 11.81997667 1.7084627 11.8210436 1.70637982 2 P 0 ;0,1,2=201,3=0.000000
L 11.8210436 1.70637982 11.82637677 1.70221329 2 P 0 ;0,1,2=201,3=0.000000
L 11.82637677 1.70221329 11.82877677 1.69929646 2 P 0 ;0,1,2=201,3=0.000000
L 11.82877677 1.69929646 11.83037687 1.69512913 2 P 0 ;0,1,2=201,3=0.000000
L 11.83037687 1.69512913 11.83091014 1.69138002 2 P 0 ;0,1,2=201,3=0.000000
L 11.83091014 1.69138002 11.81971004 1.69138002 2 P 0 ;0,1,2=201,3=0.000000
L 11.8058437 1.69429606 11.80397687 1.69221309 2 P 0 ;0,1,2=201,3=0.000000
L 11.80397687 1.69221309 11.8018435 1.69138002 2 P 0 ;0,1,2=201,3=0.000000
L 11.8018435 1.69138002 11.79971014 1.69221309 2 P 0 ;0,1,2=201,3=0.000000
L 11.79971014 1.69221309 11.79784341 1.6947126 2 P 0 ;0,1,2=201,3=0.000000
L 11.79784341 1.6947126 11.79650994 1.69846329 2 P 0 ;0,1,2=201,3=0.000000
L 11.79650994 1.69846329 11.79597667 1.70221329 2 P 0 ;0,1,2=201,3=0.000000
L 11.79597667 1.70221329 11.79597667 1.70679636 2 P 0 ;0,1,2=201,3=0.000000
L 11.79597667 1.70679636 11.79650994 1.71054636 2 P 0 ;0,1,2=201,3=0.000000
L 11.79650994 1.71054636 11.79784341 1.71387972 2 P 0 ;0,1,2=201,3=0.000000
L 11.79784341 1.71387972 11.7994436 1.71554685 2 P 0 ;0,1,2=201,3=0.000000
L 11.7994436 1.71554685 11.80131033 1.71638002 2 P 0 ;0,1,2=201,3=0.000000
L 11.80131033 1.71638002 11.8034437 1.71554685 2 P 0 ;0,1,2=201,3=0.000000
L 11.8034437 1.71554685 11.80504341 1.71387972 2 P 0 ;0,1,2=201,3=0.000000
L 11.80504341 1.71387972 11.80611024 1.71138032 2 P 0 ;0,1,2=201,3=0.000000
L 11.80611024 1.71138032 11.8066435 1.70804616 2 P 0 ;0,1,2=201,3=0.000000
L 11.8066435 1.70804616 11.80611024 1.70513012 2 P 0 ;0,1,2=201,3=0.000000
L 11.80611024 1.70513012 11.80477677 1.70221329 2 P 0 ;0,1,2=201,3=0.000000
L 11.80477677 1.70221329 11.80317657 1.70054616 2 P 0 ;0,1,2=201,3=0.000000
L 11.80317657 1.70054616 11.80131033 1.70012963 2 P 0 ;0,1,2=201,3=0.000000
L 11.80131033 1.70012963 11.79917697 1.7009628 2 P 0 ;0,1,2=201,3=0.000000
L 11.79917697 1.7009628 11.79757677 1.70304646 2 P 0 ;0,1,2=201,3=0.000000
L 11.79757677 1.70304646 11.79597667 1.70679636 2 P 0 ;0,1,2=201,3=0.000000
A 5.48308996 1.8533 5.48308996 1.8533 5.48058002 1.8533 1 P 0 N
L 5.71613337 1.86291634 5.71773356 1.86416683 2 P 0 ;0,1,2=202,3=0.000000
L 5.71773356 1.86416683 5.7195998 1.865 2 P 0 ;0,1,2=202,3=0.000000
L 5.7195998 1.865 5.72173317 1.865 2 P 0 ;0,1,2=202,3=0.000000
L 5.72173317 1.865 5.72413366 1.86374941 2 P 0 ;0,1,2=202,3=0.000000
L 5.72413366 1.86374941 5.7259999 1.86166654 2 P 0 ;0,1,2=202,3=0.000000
L 5.7259999 1.86166654 5.72733346 1.85916634 2 P 0 ;0,1,2=202,3=0.000000
L 5.72733346 1.85916634 5.72840039 1.8549998 2 P 0 ;0,1,2=202,3=0.000000
L 5.72840039 1.8549998 5.72866703 1.8512498 2 P 0 ;0,1,2=202,3=0.000000
L 5.72866703 1.8512498 5.72813327 1.8474999 2 P 0 ;0,1,2=202,3=0.000000
L 5.72813327 1.8474999 5.72733346 1.84499961 2 P 0 ;0,1,2=202,3=0.000000
L 5.72733346 1.84499961 5.72573337 1.84249941 2 P 0 ;0,1,2=202,3=0.000000
L 5.72573337 1.84249941 5.72386654 1.84083307 2 P 0 ;0,1,2=202,3=0.000000
L 5.72386654 1.84083307 5.7220003 1.84 2 P 0 ;0,1,2=202,3=0.000000
L 5.7220003 1.84 5.72013356 1.84 2 P 0 ;0,1,2=202,3=0.000000
L 5.72013356 1.84 5.71826673 1.84083307 2 P 0 ;0,1,2=202,3=0.000000
L 5.71826673 1.84083307 5.71666663 1.84208287 2 P 0 ;0,1,2=202,3=0.000000
L 5.71666663 1.84208287 5.71533307 1.84374911 2 P 0 ;0,1,2=202,3=0.000000
L 5.6948 1.84 5.6948 1.865 2 P 0 ;0,1,2=202,3=0.000000
L 5.6948 1.865 5.70466703 1.84708327 2 P 0 ;0,1,2=202,3=0.000000
L 5.70466703 1.84708327 5.69133307 1.84708327 2 P 0 ;0,1,2=202,3=0.000000
L 5.6740003 1.84 5.6740003 1.865 2 P 0 ;0,1,2=202,3=0.000000
L 5.6740003 1.865 5.6772001 1.8600003 2 P 0 ;0,1,2=202,3=0.000000
L 5.6772001 1.84 5.67080049 1.84 2 P 0 ;0,1,2=202,3=0.000000
L 5.65586673 1.84374911 5.65426703 1.84166624 2 P 0 ;0,1,2=202,3=0.000000
L 5.65426703 1.84166624 5.6524003 1.84041654 2 P 0 ;0,1,2=202,3=0.000000
L 5.6524003 1.84041654 5.6500003 1.84 2 P 0 ;0,1,2=202,3=0.000000
L 5.6500003 1.84 5.6475998 1.84083307 2 P 0 ;0,1,2=202,3=0.000000
L 5.6475998 1.84083307 5.64573356 1.84249941 2 P 0 ;0,1,2=202,3=0.000000
L 5.64573356 1.84249941 5.6444 1.84541624 2 P 0 ;0,1,2=202,3=0.000000
L 5.6444 1.84541624 5.64413337 1.84874961 2 P 0 ;0,1,2=202,3=0.000000
L 5.64413337 1.84874961 5.64466663 1.85208297 2 P 0 ;0,1,2=202,3=0.000000
L 5.64466663 1.85208297 5.6460002 1.85416663 2 P 0 ;0,1,2=202,3=0.000000
L 5.6460002 1.85416663 5.64786693 1.85583297 2 P 0 ;0,1,2=202,3=0.000000
L 5.64786693 1.85583297 5.64973317 1.85624951 2 P 0 ;0,1,2=202,3=0.000000
L 5.64973317 1.85624951 5.6516 1.85583297 2 P 0 ;0,1,2=202,3=0.000000
L 5.6516 1.85583297 5.6539999 1.85416663 2 P 0 ;0,1,2=202,3=0.000000
L 5.6539999 1.85416663 5.6532001 1.865 2 P 0 ;0,1,2=202,3=0.000000
L 5.6532001 1.865 5.6460002 1.865 2 P 0 ;0,1,2=202,3=0.000000
A 11.63613002 2.855 11.63613002 2.855 11.63361998 2.855 1 P 0 N
L 12.00113337 2.86291634 12.00273356 2.86416683 2 P 0 ;0,1,2=203,3=0.000000
L 12.00273356 2.86416683 12.0045998 2.865 2 P 0 ;0,1,2=203,3=0.000000
L 12.0045998 2.865 12.00673317 2.865 2 P 0 ;0,1,2=203,3=0.000000
L 12.00673317 2.865 12.00913366 2.86374941 2 P 0 ;0,1,2=203,3=0.000000
L 12.00913366 2.86374941 12.0109999 2.86166654 2 P 0 ;0,1,2=203,3=0.000000
L 12.0109999 2.86166654 12.01233346 2.85916634 2 P 0 ;0,1,2=203,3=0.000000
L 12.01233346 2.85916634 12.01340039 2.8549998 2 P 0 ;0,1,2=203,3=0.000000
L 12.01340039 2.8549998 12.01366703 2.8512498 2 P 0 ;0,1,2=203,3=0.000000
L 12.01366703 2.8512498 12.01313327 2.8474999 2 P 0 ;0,1,2=203,3=0.000000
L 12.01313327 2.8474999 12.01233346 2.84499961 2 P 0 ;0,1,2=203,3=0.000000
L 12.01233346 2.84499961 12.01073337 2.84249941 2 P 0 ;0,1,2=203,3=0.000000
L 12.01073337 2.84249941 12.00886654 2.84083307 2 P 0 ;0,1,2=203,3=0.000000
L 12.00886654 2.84083307 12.0070003 2.84 2 P 0 ;0,1,2=203,3=0.000000
L 12.0070003 2.84 12.00513356 2.84 2 P 0 ;0,1,2=203,3=0.000000
L 12.00513356 2.84 12.00326673 2.84083307 2 P 0 ;0,1,2=203,3=0.000000
L 12.00326673 2.84083307 12.00166663 2.84208287 2 P 0 ;0,1,2=203,3=0.000000
L 12.00166663 2.84208287 12.00033307 2.84374911 2 P 0 ;0,1,2=203,3=0.000000
L 11.98806683 2.86083337 11.98646673 2.86333287 2 P 0 ;0,1,2=203,3=0.000000
L 11.98646673 2.86333287 11.9846 2.86458337 2 P 0 ;0,1,2=203,3=0.000000
L 11.9846 2.86458337 11.98246663 2.865 2 P 0 ;0,1,2=203,3=0.000000
L 11.98246663 2.865 11.9798 2.86416683 2 P 0 ;0,1,2=203,3=0.000000
L 11.9798 2.86416683 11.97793327 2.86208317 2 P 0 ;0,1,2=203,3=0.000000
L 11.97793327 2.86208317 11.9774 2.85958366 2 P 0 ;0,1,2=203,3=0.000000
L 11.9774 2.85958366 11.97766663 2.85708268 2 P 0 ;0,1,2=203,3=0.000000
L 11.97766663 2.85708268 11.97873356 2.8549998 2 P 0 ;0,1,2=203,3=0.000000
L 11.97873356 2.8549998 11.98406673 2.85083327 2 P 0 ;0,1,2=203,3=0.000000
L 11.98406673 2.85083327 11.98646673 2.84791644 2 P 0 ;0,1,2=203,3=0.000000
L 11.98646673 2.84791644 11.98806683 2.84374911 2 P 0 ;0,1,2=203,3=0.000000
L 11.98806683 2.84374911 11.9886001 2.84 2 P 0 ;0,1,2=203,3=0.000000
L 11.9886001 2.84 11.9774 2.84 2 P 0 ;0,1,2=203,3=0.000000
L 11.96406683 2.86083337 11.96246673 2.86333287 2 P 0 ;0,1,2=203,3=0.000000
L 11.96246673 2.86333287 11.9606 2.86458337 2 P 0 ;0,1,2=203,3=0.000000
L 11.9606 2.86458337 11.95846663 2.865 2 P 0 ;0,1,2=203,3=0.000000
L 11.95846663 2.865 11.9558 2.86416683 2 P 0 ;0,1,2=203,3=0.000000
L 11.9558 2.86416683 11.95393327 2.86208317 2 P 0 ;0,1,2=203,3=0.000000
L 11.95393327 2.86208317 11.9534 2.85958366 2 P 0 ;0,1,2=203,3=0.000000
L 11.9534 2.85958366 11.95366663 2.85708268 2 P 0 ;0,1,2=203,3=0.000000
L 11.95366663 2.85708268 11.95473356 2.8549998 2 P 0 ;0,1,2=203,3=0.000000
L 11.95473356 2.8549998 11.96006673 2.85083327 2 P 0 ;0,1,2=203,3=0.000000
L 11.96006673 2.85083327 11.96246673 2.84791644 2 P 0 ;0,1,2=203,3=0.000000
L 11.96246673 2.84791644 11.96406683 2.84374911 2 P 0 ;0,1,2=203,3=0.000000
L 11.96406683 2.84374911 11.9646001 2.84 2 P 0 ;0,1,2=203,3=0.000000
L 11.9646001 2.84 11.9534 2.84 2 P 0 ;0,1,2=203,3=0.000000
L 11.94086673 2.84499961 11.93926703 2.84208287 2 P 0 ;0,1,2=203,3=0.000000
L 11.93926703 2.84208287 11.93713366 2.84041654 2 P 0 ;0,1,2=203,3=0.000000
L 11.93713366 2.84041654 11.93473317 2.84 2 P 0 ;0,1,2=203,3=0.000000
L 11.93473317 2.84 11.9325998 2.84041654 2 P 0 ;0,1,2=203,3=0.000000
L 11.9325998 2.84041654 11.93046644 2.84249941 2 P 0 ;0,1,2=203,3=0.000000
L 11.93046644 2.84249941 11.92913337 2.84499961 2 P 0 ;0,1,2=203,3=0.000000
L 11.92913337 2.84499961 11.92886683 2.8474999 2 P 0 ;0,1,2=203,3=0.000000
L 11.92886683 2.8474999 11.9294 2.85041594 2 P 0 ;0,1,2=203,3=0.000000
L 11.9294 2.85041594 11.93126673 2.85249961 2 P 0 ;0,1,2=203,3=0.000000
L 11.93126673 2.85249961 11.93313356 2.85333346 2 P 0 ;0,1,2=203,3=0.000000
L 11.93313356 2.85333346 11.93553346 2.85333346 2 P 0 ;0,1,2=203,3=0.000000
L 11.93313356 2.85333346 11.93153337 2.85458327 2 P 0 ;0,1,2=203,3=0.000000
L 11.93153337 2.85458327 11.9301999 2.85666614 2 P 0 ;0,1,2=203,3=0.000000
L 11.9301999 2.85666614 11.92966663 2.85916634 2 P 0 ;0,1,2=203,3=0.000000
L 11.92966663 2.85916634 11.9301999 2.86166654 2 P 0 ;0,1,2=203,3=0.000000
L 11.9301999 2.86166654 11.93153337 2.86374941 2 P 0 ;0,1,2=203,3=0.000000
L 11.93153337 2.86374941 11.93393337 2.865 2 P 0 ;0,1,2=203,3=0.000000
L 11.93393337 2.865 11.93633337 2.86458337 2 P 0 ;0,1,2=203,3=0.000000
L 11.93633337 2.86458337 11.93873337 2.86291634 2 P 0 ;0,1,2=203,3=0.000000
L 11.9110003 2.865 11.91313366 2.86416683 2 P 0 ;0,1,2=203,3=0.000000
L 11.91313366 2.86416683 11.91473337 2.86208317 2 P 0 ;0,1,2=203,3=0.000000
L 11.91473337 2.86208317 11.9158002 2.85958366 2 P 0 ;0,1,2=203,3=0.000000
L 11.9158002 2.85958366 11.9166001 2.85624951 2 P 0 ;0,1,2=203,3=0.000000
L 11.9166001 2.85624951 11.91686673 2.85249961 2 P 0 ;0,1,2=203,3=0.000000
L 11.91686673 2.85249961 11.9166001 2.84874961 2 P 0 ;0,1,2=203,3=0.000000
L 11.9166001 2.84874961 11.9158002 2.84541624 2 P 0 ;0,1,2=203,3=0.000000
L 11.9158002 2.84541624 11.91473337 2.84291604 2 P 0 ;0,1,2=203,3=0.000000
L 11.91473337 2.84291604 11.91313366 2.84083307 2 P 0 ;0,1,2=203,3=0.000000
L 11.91313366 2.84083307 11.9110003 2.84 2 P 0 ;0,1,2=203,3=0.000000
L 11.9110003 2.84 11.90886693 2.84083307 2 P 0 ;0,1,2=203,3=0.000000
L 11.90886693 2.84083307 11.90726673 2.84291604 2 P 0 ;0,1,2=203,3=0.000000
L 11.90726673 2.84291604 11.9061999 2.84541624 2 P 0 ;0,1,2=203,3=0.000000
L 11.9061999 2.84541624 11.9054 2.84874961 2 P 0 ;0,1,2=203,3=0.000000
L 11.9054 2.84874961 11.90513337 2.85249961 2 P 0 ;0,1,2=203,3=0.000000
L 11.90513337 2.85249961 11.9054 2.85624951 2 P 0 ;0,1,2=203,3=0.000000
L 11.9054 2.85624951 11.9061999 2.85958366 2 P 0 ;0,1,2=203,3=0.000000
L 11.9061999 2.85958366 11.90726673 2.86208317 2 P 0 ;0,1,2=203,3=0.000000
L 11.90726673 2.86208317 11.90886693 2.86416683 2 P 0 ;0,1,2=203,3=0.000000
L 11.90886693 2.86416683 11.9110003 2.865 2 P 0 ;0,1,2=203,3=0.000000
A 5.48308996 1.8083 5.48308996 1.8083 5.48058002 1.8083 1 P 0 N
L 5.71613337 1.82791634 5.71773356 1.82916683 2 P 0 ;0,1,2=204,3=0.000000
L 5.71773356 1.82916683 5.7195998 1.83 2 P 0 ;0,1,2=204,3=0.000000
L 5.7195998 1.83 5.72173317 1.83 2 P 0 ;0,1,2=204,3=0.000000
L 5.72173317 1.83 5.72413366 1.82874941 2 P 0 ;0,1,2=204,3=0.000000
L 5.72413366 1.82874941 5.7259999 1.82666654 2 P 0 ;0,1,2=204,3=0.000000
L 5.7259999 1.82666654 5.72733346 1.82416634 2 P 0 ;0,1,2=204,3=0.000000
L 5.72733346 1.82416634 5.72840039 1.8199998 2 P 0 ;0,1,2=204,3=0.000000
L 5.72840039 1.8199998 5.72866703 1.8162498 2 P 0 ;0,1,2=204,3=0.000000
L 5.72866703 1.8162498 5.72813327 1.8124999 2 P 0 ;0,1,2=204,3=0.000000
L 5.72813327 1.8124999 5.72733346 1.80999961 2 P 0 ;0,1,2=204,3=0.000000
L 5.72733346 1.80999961 5.72573337 1.80749941 2 P 0 ;0,1,2=204,3=0.000000
L 5.72573337 1.80749941 5.72386654 1.80583307 2 P 0 ;0,1,2=204,3=0.000000
L 5.72386654 1.80583307 5.7220003 1.805 2 P 0 ;0,1,2=204,3=0.000000
L 5.7220003 1.805 5.72013356 1.805 2 P 0 ;0,1,2=204,3=0.000000
L 5.72013356 1.805 5.71826673 1.80583307 2 P 0 ;0,1,2=204,3=0.000000
L 5.71826673 1.80583307 5.71666663 1.80708287 2 P 0 ;0,1,2=204,3=0.000000
L 5.71666663 1.80708287 5.71533307 1.80874911 2 P 0 ;0,1,2=204,3=0.000000
L 5.6948 1.805 5.6948 1.83 2 P 0 ;0,1,2=204,3=0.000000
L 5.6948 1.83 5.70466703 1.81208327 2 P 0 ;0,1,2=204,3=0.000000
L 5.70466703 1.81208327 5.69133307 1.81208327 2 P 0 ;0,1,2=204,3=0.000000
L 5.6740003 1.805 5.6740003 1.83 2 P 0 ;0,1,2=204,3=0.000000
L 5.6740003 1.83 5.6772001 1.8250003 2 P 0 ;0,1,2=204,3=0.000000
L 5.6772001 1.805 5.67080049 1.805 2 P 0 ;0,1,2=204,3=0.000000
L 5.65506683 1.81541594 5.6532001 1.81833346 2 P 0 ;0,1,2=204,3=0.000000
L 5.6532001 1.81833346 5.6516 1.8199998 2 P 0 ;0,1,2=204,3=0.000000
L 5.6516 1.8199998 5.64946663 1.82083297 2 P 0 ;0,1,2=204,3=0.000000
L 5.64946663 1.82083297 5.6475998 1.8199998 2 P 0 ;0,1,2=204,3=0.000000
L 5.6475998 1.8199998 5.64626673 1.81833346 2 P 0 ;0,1,2=204,3=0.000000
L 5.64626673 1.81833346 5.6451999 1.81583327 2 P 0 ;0,1,2=204,3=0.000000
L 5.6451999 1.81583327 5.64493327 1.81291644 2 P 0 ;0,1,2=204,3=0.000000
L 5.64493327 1.81291644 5.6451999 1.81041624 2 P 0 ;0,1,2=204,3=0.000000
L 5.6451999 1.81041624 5.64626673 1.80791604 2 P 0 ;0,1,2=204,3=0.000000
L 5.64626673 1.80791604 5.64786693 1.80583307 2 P 0 ;0,1,2=204,3=0.000000
L 5.64786693 1.80583307 5.64973317 1.805 2 P 0 ;0,1,2=204,3=0.000000
L 5.64973317 1.805 5.65186654 1.80583307 2 P 0 ;0,1,2=204,3=0.000000
L 5.65186654 1.80583307 5.65373337 1.80833258 2 P 0 ;0,1,2=204,3=0.000000
L 5.65373337 1.80833258 5.6548002 1.81208327 2 P 0 ;0,1,2=204,3=0.000000
L 5.6548002 1.81208327 5.65506683 1.8162498 2 P 0 ;0,1,2=204,3=0.000000
L 5.65506683 1.8162498 5.65453366 1.82166614 2 P 0 ;0,1,2=204,3=0.000000
L 5.65453366 1.82166614 5.65373337 1.82458366 2 P 0 ;0,1,2=204,3=0.000000
L 5.65373337 1.82458366 5.6524003 1.8274997 2 P 0 ;0,1,2=204,3=0.000000
L 5.6524003 1.8274997 5.65053346 1.82958337 2 P 0 ;0,1,2=204,3=0.000000
L 5.65053346 1.82958337 5.64866673 1.83 2 P 0 ;0,1,2=204,3=0.000000
L 5.64866673 1.83 5.6468 1.82916683 2 P 0 ;0,1,2=204,3=0.000000
L 5.6468 1.82916683 5.64546644 1.82708317 2 P 0 ;0,1,2=204,3=0.000000
A 5.6322 2.855 5.6322 2.855 5.62968996 2.855 1 P 0 N
L 5.54613337 2.87791634 5.54773356 2.87916683 2 P 0 ;0,1,2=205,3=0.000000
L 5.54773356 2.87916683 5.5495998 2.88 2 P 0 ;0,1,2=205,3=0.000000
L 5.5495998 2.88 5.55173317 2.88 2 P 0 ;0,1,2=205,3=0.000000
L 5.55173317 2.88 5.55413366 2.87874941 2 P 0 ;0,1,2=205,3=0.000000
L 5.55413366 2.87874941 5.5559999 2.87666654 2 P 0 ;0,1,2=205,3=0.000000
L 5.5559999 2.87666654 5.55733346 2.87416634 2 P 0 ;0,1,2=205,3=0.000000
L 5.55733346 2.87416634 5.55840039 2.8699998 2 P 0 ;0,1,2=205,3=0.000000
L 5.55840039 2.8699998 5.55866703 2.8662498 2 P 0 ;0,1,2=205,3=0.000000
L 5.55866703 2.8662498 5.55813327 2.8624999 2 P 0 ;0,1,2=205,3=0.000000
L 5.55813327 2.8624999 5.55733346 2.85999961 2 P 0 ;0,1,2=205,3=0.000000
L 5.55733346 2.85999961 5.55573337 2.85749941 2 P 0 ;0,1,2=205,3=0.000000
L 5.55573337 2.85749941 5.55386654 2.85583307 2 P 0 ;0,1,2=205,3=0.000000
L 5.55386654 2.85583307 5.5520003 2.855 2 P 0 ;0,1,2=205,3=0.000000
L 5.5520003 2.855 5.55013356 2.855 2 P 0 ;0,1,2=205,3=0.000000
L 5.55013356 2.855 5.54826673 2.85583307 2 P 0 ;0,1,2=205,3=0.000000
L 5.54826673 2.85583307 5.54666663 2.85708287 2 P 0 ;0,1,2=205,3=0.000000
L 5.54666663 2.85708287 5.54533307 2.85874911 2 P 0 ;0,1,2=205,3=0.000000
L 5.53306683 2.87583337 5.53146673 2.87833287 2 P 0 ;0,1,2=205,3=0.000000
L 5.53146673 2.87833287 5.5296 2.87958337 2 P 0 ;0,1,2=205,3=0.000000
L 5.5296 2.87958337 5.52746663 2.88 2 P 0 ;0,1,2=205,3=0.000000
L 5.52746663 2.88 5.5248 2.87916683 2 P 0 ;0,1,2=205,3=0.000000
L 5.5248 2.87916683 5.52293327 2.87708317 2 P 0 ;0,1,2=205,3=0.000000
L 5.52293327 2.87708317 5.5224 2.87458366 2 P 0 ;0,1,2=205,3=0.000000
L 5.5224 2.87458366 5.52266663 2.87208268 2 P 0 ;0,1,2=205,3=0.000000
L 5.52266663 2.87208268 5.52373356 2.8699998 2 P 0 ;0,1,2=205,3=0.000000
L 5.52373356 2.8699998 5.52906673 2.86583327 2 P 0 ;0,1,2=205,3=0.000000
L 5.52906673 2.86583327 5.53146673 2.86291644 2 P 0 ;0,1,2=205,3=0.000000
L 5.53146673 2.86291644 5.53306683 2.85874911 2 P 0 ;0,1,2=205,3=0.000000
L 5.53306683 2.85874911 5.5336001 2.855 2 P 0 ;0,1,2=205,3=0.000000
L 5.5336001 2.855 5.5224 2.855 2 P 0 ;0,1,2=205,3=0.000000
L 5.5040003 2.855 5.5040003 2.88 2 P 0 ;0,1,2=205,3=0.000000
L 5.5040003 2.88 5.5072001 2.8750003 2 P 0 ;0,1,2=205,3=0.000000
L 5.5072001 2.855 5.50080049 2.855 2 P 0 ;0,1,2=205,3=0.000000
L 5.4800003 2.855 5.47813356 2.85541654 2 P 0 ;0,1,2=205,3=0.000000
L 5.47813356 2.85541654 5.4760002 2.85666624 2 P 0 ;0,1,2=205,3=0.000000
L 5.4760002 2.85666624 5.47466663 2.85874911 2 P 0 ;0,1,2=205,3=0.000000
L 5.47466663 2.85874911 5.47413337 2.86166673 2 P 0 ;0,1,2=205,3=0.000000
L 5.47413337 2.86166673 5.47466663 2.86458278 2 P 0 ;0,1,2=205,3=0.000000
L 5.47466663 2.86458278 5.47626673 2.86708297 2 P 0 ;0,1,2=205,3=0.000000
L 5.47626673 2.86708297 5.47866673 2.86833346 2 P 0 ;0,1,2=205,3=0.000000
L 5.47866673 2.86833346 5.48133337 2.86833346 2 P 0 ;0,1,2=205,3=0.000000
L 5.48133337 2.86833346 5.48293346 2.86916663 2 P 0 ;0,1,2=205,3=0.000000
L 5.48293346 2.86916663 5.48426703 2.87124951 2 P 0 ;0,1,2=205,3=0.000000
L 5.48426703 2.87124951 5.4848002 2.87416634 2 P 0 ;0,1,2=205,3=0.000000
L 5.4848002 2.87416634 5.4839999 2.87708317 2 P 0 ;0,1,2=205,3=0.000000
L 5.4839999 2.87708317 5.48213366 2.87916683 2 P 0 ;0,1,2=205,3=0.000000
L 5.48213366 2.87916683 5.4800003 2.88 2 P 0 ;0,1,2=205,3=0.000000
L 5.4800003 2.88 5.47786693 2.87916683 2 P 0 ;0,1,2=205,3=0.000000
L 5.47786693 2.87916683 5.4760002 2.87708317 2 P 0 ;0,1,2=205,3=0.000000
L 5.4760002 2.87708317 5.4751999 2.87416634 2 P 0 ;0,1,2=205,3=0.000000
L 5.4751999 2.87416634 5.47573356 2.87124951 2 P 0 ;0,1,2=205,3=0.000000
L 5.47573356 2.87124951 5.47706663 2.86916663 2 P 0 ;0,1,2=205,3=0.000000
L 5.47706663 2.86916663 5.47866673 2.86833346 2 P 0 ;0,1,2=205,3=0.000000
L 5.47866673 2.86833346 5.48133337 2.86833346 2 P 0 ;0,1,2=205,3=0.000000
L 5.48133337 2.86833346 5.48373337 2.86708297 2 P 0 ;0,1,2=205,3=0.000000
L 5.48373337 2.86708297 5.48533346 2.86458278 2 P 0 ;0,1,2=205,3=0.000000
L 5.48533346 2.86458278 5.48586673 2.86166673 2 P 0 ;0,1,2=205,3=0.000000
L 5.48586673 2.86166673 5.48533346 2.85874911 2 P 0 ;0,1,2=205,3=0.000000
L 5.48533346 2.85874911 5.4839999 2.85666624 2 P 0 ;0,1,2=205,3=0.000000
L 5.4839999 2.85666624 5.48186654 2.85541654 2 P 0 ;0,1,2=205,3=0.000000
L 5.48186654 2.85541654 5.4800003 2.855 2 P 0 ;0,1,2=205,3=0.000000
L 5.4528 2.855 5.4528 2.88 2 P 0 ;0,1,2=205,3=0.000000
L 5.4528 2.88 5.46266703 2.86208327 2 P 0 ;0,1,2=205,3=0.000000
L 5.46266703 2.86208327 5.44933307 2.86208327 2 P 0 ;0,1,2=205,3=0.000000
A 5.90251004 2.97 5.90251004 2.97 5.9 2.97 1 P 0 N
L 6.04613337 2.97791634 6.04773356 2.97916683 2 P 0 ;0,1,2=206,3=0.000000
L 6.04773356 2.97916683 6.0495998 2.98 2 P 0 ;0,1,2=206,3=0.000000
L 6.0495998 2.98 6.05173317 2.98 2 P 0 ;0,1,2=206,3=0.000000
L 6.05173317 2.98 6.05413366 2.97874941 2 P 0 ;0,1,2=206,3=0.000000
L 6.05413366 2.97874941 6.0559999 2.97666654 2 P 0 ;0,1,2=206,3=0.000000
L 6.0559999 2.97666654 6.05733346 2.97416634 2 P 0 ;0,1,2=206,3=0.000000
L 6.05733346 2.97416634 6.05840039 2.9699998 2 P 0 ;0,1,2=206,3=0.000000
L 6.05840039 2.9699998 6.05866703 2.9662498 2 P 0 ;0,1,2=206,3=0.000000
L 6.05866703 2.9662498 6.05813327 2.9624999 2 P 0 ;0,1,2=206,3=0.000000
L 6.05813327 2.9624999 6.05733346 2.95999961 2 P 0 ;0,1,2=206,3=0.000000
L 6.05733346 2.95999961 6.05573337 2.95749941 2 P 0 ;0,1,2=206,3=0.000000
L 6.05573337 2.95749941 6.05386654 2.95583307 2 P 0 ;0,1,2=206,3=0.000000
L 6.05386654 2.95583307 6.0520003 2.955 2 P 0 ;0,1,2=206,3=0.000000
L 6.0520003 2.955 6.05013356 2.955 2 P 0 ;0,1,2=206,3=0.000000
L 6.05013356 2.955 6.04826673 2.95583307 2 P 0 ;0,1,2=206,3=0.000000
L 6.04826673 2.95583307 6.04666663 2.95708287 2 P 0 ;0,1,2=206,3=0.000000
L 6.04666663 2.95708287 6.04533307 2.95874911 2 P 0 ;0,1,2=206,3=0.000000
L 6.03306683 2.97583337 6.03146673 2.97833287 2 P 0 ;0,1,2=206,3=0.000000
L 6.03146673 2.97833287 6.0296 2.97958337 2 P 0 ;0,1,2=206,3=0.000000
L 6.0296 2.97958337 6.02746663 2.98 2 P 0 ;0,1,2=206,3=0.000000
L 6.02746663 2.98 6.0248 2.97916683 2 P 0 ;0,1,2=206,3=0.000000
L 6.0248 2.97916683 6.02293327 2.97708317 2 P 0 ;0,1,2=206,3=0.000000
L 6.02293327 2.97708317 6.0224 2.97458366 2 P 0 ;0,1,2=206,3=0.000000
L 6.0224 2.97458366 6.02266663 2.97208268 2 P 0 ;0,1,2=206,3=0.000000
L 6.02266663 2.97208268 6.02373356 2.9699998 2 P 0 ;0,1,2=206,3=0.000000
L 6.02373356 2.9699998 6.02906673 2.96583327 2 P 0 ;0,1,2=206,3=0.000000
L 6.02906673 2.96583327 6.03146673 2.96291644 2 P 0 ;0,1,2=206,3=0.000000
L 6.03146673 2.96291644 6.03306683 2.95874911 2 P 0 ;0,1,2=206,3=0.000000
L 6.03306683 2.95874911 6.0336001 2.955 2 P 0 ;0,1,2=206,3=0.000000
L 6.0336001 2.955 6.0224 2.955 2 P 0 ;0,1,2=206,3=0.000000
L 6.0040003 2.955 6.0040003 2.98 2 P 0 ;0,1,2=206,3=0.000000
L 6.0040003 2.98 6.0072001 2.9750003 2 P 0 ;0,1,2=206,3=0.000000
L 6.0072001 2.955 6.00080049 2.955 2 P 0 ;0,1,2=206,3=0.000000
L 5.9800003 2.955 5.97813356 2.95541654 2 P 0 ;0,1,2=206,3=0.000000
L 5.97813356 2.95541654 5.9760002 2.95666624 2 P 0 ;0,1,2=206,3=0.000000
L 5.9760002 2.95666624 5.97466663 2.95874911 2 P 0 ;0,1,2=206,3=0.000000
L 5.97466663 2.95874911 5.97413337 2.96166673 2 P 0 ;0,1,2=206,3=0.000000
L 5.97413337 2.96166673 5.97466663 2.96458278 2 P 0 ;0,1,2=206,3=0.000000
L 5.97466663 2.96458278 5.97626673 2.96708297 2 P 0 ;0,1,2=206,3=0.000000
L 5.97626673 2.96708297 5.97866673 2.96833346 2 P 0 ;0,1,2=206,3=0.000000
L 5.97866673 2.96833346 5.98133337 2.96833346 2 P 0 ;0,1,2=206,3=0.000000
L 5.98133337 2.96833346 5.98293346 2.96916663 2 P 0 ;0,1,2=206,3=0.000000
L 5.98293346 2.96916663 5.98426703 2.97124951 2 P 0 ;0,1,2=206,3=0.000000
L 5.98426703 2.97124951 5.9848002 2.97416634 2 P 0 ;0,1,2=206,3=0.000000
L 5.9848002 2.97416634 5.9839999 2.97708317 2 P 0 ;0,1,2=206,3=0.000000
L 5.9839999 2.97708317 5.98213366 2.97916683 2 P 0 ;0,1,2=206,3=0.000000
L 5.98213366 2.97916683 5.9800003 2.98 2 P 0 ;0,1,2=206,3=0.000000
L 5.9800003 2.98 5.97786693 2.97916683 2 P 0 ;0,1,2=206,3=0.000000
L 5.97786693 2.97916683 5.9760002 2.97708317 2 P 0 ;0,1,2=206,3=0.000000
L 5.9760002 2.97708317 5.9751999 2.97416634 2 P 0 ;0,1,2=206,3=0.000000
L 5.9751999 2.97416634 5.97573356 2.97124951 2 P 0 ;0,1,2=206,3=0.000000
L 5.97573356 2.97124951 5.97706663 2.96916663 2 P 0 ;0,1,2=206,3=0.000000
L 5.97706663 2.96916663 5.97866673 2.96833346 2 P 0 ;0,1,2=206,3=0.000000
L 5.97866673 2.96833346 5.98133337 2.96833346 2 P 0 ;0,1,2=206,3=0.000000
L 5.98133337 2.96833346 5.98373337 2.96708297 2 P 0 ;0,1,2=206,3=0.000000
L 5.98373337 2.96708297 5.98533346 2.96458278 2 P 0 ;0,1,2=206,3=0.000000
L 5.98533346 2.96458278 5.98586673 2.96166673 2 P 0 ;0,1,2=206,3=0.000000
L 5.98586673 2.96166673 5.98533346 2.95874911 2 P 0 ;0,1,2=206,3=0.000000
L 5.98533346 2.95874911 5.9839999 2.95666624 2 P 0 ;0,1,2=206,3=0.000000
L 5.9839999 2.95666624 5.98186654 2.95541654 2 P 0 ;0,1,2=206,3=0.000000
L 5.98186654 2.95541654 5.9800003 2.955 2 P 0 ;0,1,2=206,3=0.000000
L 5.9560003 2.955 5.9560003 2.98 2 P 0 ;0,1,2=206,3=0.000000
L 5.9560003 2.98 5.9592001 2.9750003 2 P 0 ;0,1,2=206,3=0.000000
L 5.9592001 2.955 5.95280049 2.955 2 P 0 ;0,1,2=206,3=0.000000
A 10.1203 2.82 10.1203 2.82 10.11778996 2.82 1 P 0 N
L 10.28113337 2.82291634 10.28273356 2.82416683 2 P 0 ;0,1,2=207,3=0.000000
L 10.28273356 2.82416683 10.2845998 2.825 2 P 0 ;0,1,2=207,3=0.000000
L 10.2845998 2.825 10.28673317 2.825 2 P 0 ;0,1,2=207,3=0.000000
L 10.28673317 2.825 10.28913366 2.82374941 2 P 0 ;0,1,2=207,3=0.000000
L 10.28913366 2.82374941 10.2909999 2.82166654 2 P 0 ;0,1,2=207,3=0.000000
L 10.2909999 2.82166654 10.29233346 2.81916634 2 P 0 ;0,1,2=207,3=0.000000
L 10.29233346 2.81916634 10.29340039 2.8149998 2 P 0 ;0,1,2=207,3=0.000000
L 10.29340039 2.8149998 10.29366703 2.8112498 2 P 0 ;0,1,2=207,3=0.000000
L 10.29366703 2.8112498 10.29313327 2.8074999 2 P 0 ;0,1,2=207,3=0.000000
L 10.29313327 2.8074999 10.29233346 2.80499961 2 P 0 ;0,1,2=207,3=0.000000
L 10.29233346 2.80499961 10.29073337 2.80249941 2 P 0 ;0,1,2=207,3=0.000000
L 10.29073337 2.80249941 10.28886654 2.80083307 2 P 0 ;0,1,2=207,3=0.000000
L 10.28886654 2.80083307 10.2870003 2.8 2 P 0 ;0,1,2=207,3=0.000000
L 10.2870003 2.8 10.28513356 2.8 2 P 0 ;0,1,2=207,3=0.000000
L 10.28513356 2.8 10.28326673 2.80083307 2 P 0 ;0,1,2=207,3=0.000000
L 10.28326673 2.80083307 10.28166663 2.80208287 2 P 0 ;0,1,2=207,3=0.000000
L 10.28166663 2.80208287 10.28033307 2.80374911 2 P 0 ;0,1,2=207,3=0.000000
L 10.26806683 2.82083337 10.26646673 2.82333287 2 P 0 ;0,1,2=207,3=0.000000
L 10.26646673 2.82333287 10.2646 2.82458337 2 P 0 ;0,1,2=207,3=0.000000
L 10.2646 2.82458337 10.26246663 2.825 2 P 0 ;0,1,2=207,3=0.000000
L 10.26246663 2.825 10.2598 2.82416683 2 P 0 ;0,1,2=207,3=0.000000
L 10.2598 2.82416683 10.25793327 2.82208317 2 P 0 ;0,1,2=207,3=0.000000
L 10.25793327 2.82208317 10.2574 2.81958366 2 P 0 ;0,1,2=207,3=0.000000
L 10.2574 2.81958366 10.25766663 2.81708268 2 P 0 ;0,1,2=207,3=0.000000
L 10.25766663 2.81708268 10.25873356 2.8149998 2 P 0 ;0,1,2=207,3=0.000000
L 10.25873356 2.8149998 10.26406673 2.81083327 2 P 0 ;0,1,2=207,3=0.000000
L 10.26406673 2.81083327 10.26646673 2.80791644 2 P 0 ;0,1,2=207,3=0.000000
L 10.26646673 2.80791644 10.26806683 2.80374911 2 P 0 ;0,1,2=207,3=0.000000
L 10.26806683 2.80374911 10.2686001 2.8 2 P 0 ;0,1,2=207,3=0.000000
L 10.2686001 2.8 10.2574 2.8 2 P 0 ;0,1,2=207,3=0.000000
L 10.2390003 2.8 10.2390003 2.825 2 P 0 ;0,1,2=207,3=0.000000
L 10.2390003 2.825 10.2422001 2.8200003 2 P 0 ;0,1,2=207,3=0.000000
L 10.2422001 2.8 10.23580049 2.8 2 P 0 ;0,1,2=207,3=0.000000
L 10.21553346 2.8 10.2150003 2.80541624 2 P 0 ;0,1,2=207,3=0.000000
L 10.2150003 2.80541624 10.2142 2.80999931 2 P 0 ;0,1,2=207,3=0.000000
L 10.2142 2.80999931 10.21313356 2.81416663 2 P 0 ;0,1,2=207,3=0.000000
L 10.21313356 2.81416663 10.2118 2.8187498 2 P 0 ;0,1,2=207,3=0.000000
L 10.2118 2.8187498 10.20966663 2.825 2 P 0 ;0,1,2=207,3=0.000000
L 10.20966663 2.825 10.22033346 2.825 2 P 0 ;0,1,2=207,3=0.000000
L 10.19606683 2.81041594 10.1942001 2.81333346 2 P 0 ;0,1,2=207,3=0.000000
L 10.1942001 2.81333346 10.1926 2.8149998 2 P 0 ;0,1,2=207,3=0.000000
L 10.1926 2.8149998 10.19046663 2.81583297 2 P 0 ;0,1,2=207,3=0.000000
L 10.19046663 2.81583297 10.1885998 2.8149998 2 P 0 ;0,1,2=207,3=0.000000
L 10.1885998 2.8149998 10.18726673 2.81333346 2 P 0 ;0,1,2=207,3=0.000000
L 10.18726673 2.81333346 10.1861999 2.81083327 2 P 0 ;0,1,2=207,3=0.000000
L 10.1861999 2.81083327 10.18593327 2.80791644 2 P 0 ;0,1,2=207,3=0.000000
L 10.18593327 2.80791644 10.1861999 2.80541624 2 P 0 ;0,1,2=207,3=0.000000
L 10.1861999 2.80541624 10.18726673 2.80291604 2 P 0 ;0,1,2=207,3=0.000000
L 10.18726673 2.80291604 10.18886693 2.80083307 2 P 0 ;0,1,2=207,3=0.000000
L 10.18886693 2.80083307 10.19073317 2.8 2 P 0 ;0,1,2=207,3=0.000000
L 10.19073317 2.8 10.19286654 2.80083307 2 P 0 ;0,1,2=207,3=0.000000
L 10.19286654 2.80083307 10.19473337 2.80333258 2 P 0 ;0,1,2=207,3=0.000000
L 10.19473337 2.80333258 10.1958002 2.80708327 2 P 0 ;0,1,2=207,3=0.000000
L 10.1958002 2.80708327 10.19606683 2.8112498 2 P 0 ;0,1,2=207,3=0.000000
L 10.19606683 2.8112498 10.19553366 2.81666614 2 P 0 ;0,1,2=207,3=0.000000
L 10.19553366 2.81666614 10.19473337 2.81958366 2 P 0 ;0,1,2=207,3=0.000000
L 10.19473337 2.81958366 10.1934003 2.8224997 2 P 0 ;0,1,2=207,3=0.000000
L 10.1934003 2.8224997 10.19153346 2.82458337 2 P 0 ;0,1,2=207,3=0.000000
L 10.19153346 2.82458337 10.18966673 2.825 2 P 0 ;0,1,2=207,3=0.000000
L 10.18966673 2.825 10.1878 2.82416683 2 P 0 ;0,1,2=207,3=0.000000
L 10.1878 2.82416683 10.18646644 2.82208317 2 P 0 ;0,1,2=207,3=0.000000
A 4.07636998 2.59 4.07636998 2.59 4.07386004 2.59 1 P 0 N
L 4.24613337 2.61291634 4.24773356 2.61416683 2 P 0 ;0,1,2=208,3=0.000000
L 4.24773356 2.61416683 4.2495998 2.615 2 P 0 ;0,1,2=208,3=0.000000
L 4.2495998 2.615 4.25173317 2.615 2 P 0 ;0,1,2=208,3=0.000000
L 4.25173317 2.615 4.25413366 2.61374941 2 P 0 ;0,1,2=208,3=0.000000
L 4.25413366 2.61374941 4.2559999 2.61166654 2 P 0 ;0,1,2=208,3=0.000000
L 4.2559999 2.61166654 4.25733346 2.60916634 2 P 0 ;0,1,2=208,3=0.000000
L 4.25733346 2.60916634 4.25840039 2.6049998 2 P 0 ;0,1,2=208,3=0.000000
L 4.25840039 2.6049998 4.25866703 2.6012498 2 P 0 ;0,1,2=208,3=0.000000
L 4.25866703 2.6012498 4.25813327 2.5974999 2 P 0 ;0,1,2=208,3=0.000000
L 4.25813327 2.5974999 4.25733346 2.59499961 2 P 0 ;0,1,2=208,3=0.000000
L 4.25733346 2.59499961 4.25573337 2.59249941 2 P 0 ;0,1,2=208,3=0.000000
L 4.25573337 2.59249941 4.25386654 2.59083307 2 P 0 ;0,1,2=208,3=0.000000
L 4.25386654 2.59083307 4.2520003 2.59 2 P 0 ;0,1,2=208,3=0.000000
L 4.2520003 2.59 4.25013356 2.59 2 P 0 ;0,1,2=208,3=0.000000
L 4.25013356 2.59 4.24826673 2.59083307 2 P 0 ;0,1,2=208,3=0.000000
L 4.24826673 2.59083307 4.24666663 2.59208287 2 P 0 ;0,1,2=208,3=0.000000
L 4.24666663 2.59208287 4.24533307 2.59374911 2 P 0 ;0,1,2=208,3=0.000000
L 4.23306683 2.61083337 4.23146673 2.61333287 2 P 0 ;0,1,2=208,3=0.000000
L 4.23146673 2.61333287 4.2296 2.61458337 2 P 0 ;0,1,2=208,3=0.000000
L 4.2296 2.61458337 4.22746663 2.615 2 P 0 ;0,1,2=208,3=0.000000
L 4.22746663 2.615 4.2248 2.61416683 2 P 0 ;0,1,2=208,3=0.000000
L 4.2248 2.61416683 4.22293327 2.61208317 2 P 0 ;0,1,2=208,3=0.000000
L 4.22293327 2.61208317 4.2224 2.60958366 2 P 0 ;0,1,2=208,3=0.000000
L 4.2224 2.60958366 4.22266663 2.60708268 2 P 0 ;0,1,2=208,3=0.000000
L 4.22266663 2.60708268 4.22373356 2.6049998 2 P 0 ;0,1,2=208,3=0.000000
L 4.22373356 2.6049998 4.22906673 2.60083327 2 P 0 ;0,1,2=208,3=0.000000
L 4.22906673 2.60083327 4.23146673 2.59791644 2 P 0 ;0,1,2=208,3=0.000000
L 4.23146673 2.59791644 4.23306683 2.59374911 2 P 0 ;0,1,2=208,3=0.000000
L 4.23306683 2.59374911 4.2336001 2.59 2 P 0 ;0,1,2=208,3=0.000000
L 4.2336001 2.59 4.2224 2.59 2 P 0 ;0,1,2=208,3=0.000000
L 4.2040003 2.59 4.2040003 2.615 2 P 0 ;0,1,2=208,3=0.000000
L 4.2040003 2.615 4.2072001 2.6100003 2 P 0 ;0,1,2=208,3=0.000000
L 4.2072001 2.59 4.20080049 2.59 2 P 0 ;0,1,2=208,3=0.000000
L 4.18053346 2.59 4.1800003 2.59541624 2 P 0 ;0,1,2=208,3=0.000000
L 4.1800003 2.59541624 4.1792 2.59999931 2 P 0 ;0,1,2=208,3=0.000000
L 4.1792 2.59999931 4.17813356 2.60416663 2 P 0 ;0,1,2=208,3=0.000000
L 4.17813356 2.60416663 4.1768 2.6087498 2 P 0 ;0,1,2=208,3=0.000000
L 4.1768 2.6087498 4.17466663 2.615 2 P 0 ;0,1,2=208,3=0.000000
L 4.17466663 2.615 4.18533346 2.615 2 P 0 ;0,1,2=208,3=0.000000
L 4.16186673 2.59374911 4.16026703 2.59166624 2 P 0 ;0,1,2=208,3=0.000000
L 4.16026703 2.59166624 4.1584003 2.59041654 2 P 0 ;0,1,2=208,3=0.000000
L 4.1584003 2.59041654 4.1560003 2.59 2 P 0 ;0,1,2=208,3=0.000000
L 4.1560003 2.59 4.1535998 2.59083307 2 P 0 ;0,1,2=208,3=0.000000
L 4.1535998 2.59083307 4.15173356 2.59249941 2 P 0 ;0,1,2=208,3=0.000000
L 4.15173356 2.59249941 4.1504 2.59541624 2 P 0 ;0,1,2=208,3=0.000000
L 4.1504 2.59541624 4.15013337 2.59874961 2 P 0 ;0,1,2=208,3=0.000000
L 4.15013337 2.59874961 4.15066663 2.60208297 2 P 0 ;0,1,2=208,3=0.000000
L 4.15066663 2.60208297 4.1520002 2.60416663 2 P 0 ;0,1,2=208,3=0.000000
L 4.1520002 2.60416663 4.15386693 2.60583297 2 P 0 ;0,1,2=208,3=0.000000
L 4.15386693 2.60583297 4.15573317 2.60624951 2 P 0 ;0,1,2=208,3=0.000000
L 4.15573317 2.60624951 4.1576 2.60583297 2 P 0 ;0,1,2=208,3=0.000000
L 4.1576 2.60583297 4.1599999 2.60416663 2 P 0 ;0,1,2=208,3=0.000000
L 4.1599999 2.60416663 4.1592001 2.615 2 P 0 ;0,1,2=208,3=0.000000
L 4.1592001 2.615 4.1520002 2.615 2 P 0 ;0,1,2=208,3=0.000000
A 5.48308996 1.7143 5.48308996 1.7143 5.48058002 1.7143 1 P 0 N
L 5.71613337 1.72291634 5.71773356 1.72416683 2 P 0 ;0,1,2=209,3=0.000000
L 5.71773356 1.72416683 5.7195998 1.725 2 P 0 ;0,1,2=209,3=0.000000
L 5.7195998 1.725 5.72173317 1.725 2 P 0 ;0,1,2=209,3=0.000000
L 5.72173317 1.725 5.72413366 1.72374941 2 P 0 ;0,1,2=209,3=0.000000
L 5.72413366 1.72374941 5.7259999 1.72166654 2 P 0 ;0,1,2=209,3=0.000000
L 5.7259999 1.72166654 5.72733346 1.71916634 2 P 0 ;0,1,2=209,3=0.000000
L 5.72733346 1.71916634 5.72840039 1.7149998 2 P 0 ;0,1,2=209,3=0.000000
L 5.72840039 1.7149998 5.72866703 1.7112498 2 P 0 ;0,1,2=209,3=0.000000
L 5.72866703 1.7112498 5.72813327 1.7074999 2 P 0 ;0,1,2=209,3=0.000000
L 5.72813327 1.7074999 5.72733346 1.70499961 2 P 0 ;0,1,2=209,3=0.000000
L 5.72733346 1.70499961 5.72573337 1.70249941 2 P 0 ;0,1,2=209,3=0.000000
L 5.72573337 1.70249941 5.72386654 1.70083307 2 P 0 ;0,1,2=209,3=0.000000
L 5.72386654 1.70083307 5.7220003 1.7 2 P 0 ;0,1,2=209,3=0.000000
L 5.7220003 1.7 5.72013356 1.7 2 P 0 ;0,1,2=209,3=0.000000
L 5.72013356 1.7 5.71826673 1.70083307 2 P 0 ;0,1,2=209,3=0.000000
L 5.71826673 1.70083307 5.71666663 1.70208287 2 P 0 ;0,1,2=209,3=0.000000
L 5.71666663 1.70208287 5.71533307 1.70374911 2 P 0 ;0,1,2=209,3=0.000000
L 5.6948 1.7 5.6948 1.725 2 P 0 ;0,1,2=209,3=0.000000
L 5.6948 1.725 5.70466703 1.70708327 2 P 0 ;0,1,2=209,3=0.000000
L 5.70466703 1.70708327 5.69133307 1.70708327 2 P 0 ;0,1,2=209,3=0.000000
L 5.6740003 1.7 5.6740003 1.725 2 P 0 ;0,1,2=209,3=0.000000
L 5.6740003 1.725 5.6772001 1.7200003 2 P 0 ;0,1,2=209,3=0.000000
L 5.6772001 1.7 5.67080049 1.7 2 P 0 ;0,1,2=209,3=0.000000
L 5.6500003 1.7 5.64813356 1.70041654 2 P 0 ;0,1,2=209,3=0.000000
L 5.64813356 1.70041654 5.6460002 1.70166624 2 P 0 ;0,1,2=209,3=0.000000
L 5.6460002 1.70166624 5.64466663 1.70374911 2 P 0 ;0,1,2=209,3=0.000000
L 5.64466663 1.70374911 5.64413337 1.70666673 2 P 0 ;0,1,2=209,3=0.000000
L 5.64413337 1.70666673 5.64466663 1.70958278 2 P 0 ;0,1,2=209,3=0.000000
L 5.64466663 1.70958278 5.64626673 1.71208297 2 P 0 ;0,1,2=209,3=0.000000
L 5.64626673 1.71208297 5.64866673 1.71333346 2 P 0 ;0,1,2=209,3=0.000000
L 5.64866673 1.71333346 5.65133337 1.71333346 2 P 0 ;0,1,2=209,3=0.000000
L 5.65133337 1.71333346 5.65293346 1.71416663 2 P 0 ;0,1,2=209,3=0.000000
L 5.65293346 1.71416663 5.65426703 1.71624951 2 P 0 ;0,1,2=209,3=0.000000
L 5.65426703 1.71624951 5.6548002 1.71916634 2 P 0 ;0,1,2=209,3=0.000000
L 5.6548002 1.71916634 5.6539999 1.72208317 2 P 0 ;0,1,2=209,3=0.000000
L 5.6539999 1.72208317 5.65213366 1.72416683 2 P 0 ;0,1,2=209,3=0.000000
L 5.65213366 1.72416683 5.6500003 1.725 2 P 0 ;0,1,2=209,3=0.000000
L 5.6500003 1.725 5.64786693 1.72416683 2 P 0 ;0,1,2=209,3=0.000000
L 5.64786693 1.72416683 5.6460002 1.72208317 2 P 0 ;0,1,2=209,3=0.000000
L 5.6460002 1.72208317 5.6451999 1.71916634 2 P 0 ;0,1,2=209,3=0.000000
L 5.6451999 1.71916634 5.64573356 1.71624951 2 P 0 ;0,1,2=209,3=0.000000
L 5.64573356 1.71624951 5.64706663 1.71416663 2 P 0 ;0,1,2=209,3=0.000000
L 5.64706663 1.71416663 5.64866673 1.71333346 2 P 0 ;0,1,2=209,3=0.000000
L 5.64866673 1.71333346 5.65133337 1.71333346 2 P 0 ;0,1,2=209,3=0.000000
L 5.65133337 1.71333346 5.65373337 1.71208297 2 P 0 ;0,1,2=209,3=0.000000
L 5.65373337 1.71208297 5.65533346 1.70958278 2 P 0 ;0,1,2=209,3=0.000000
L 5.65533346 1.70958278 5.65586673 1.70666673 2 P 0 ;0,1,2=209,3=0.000000
L 5.65586673 1.70666673 5.65533346 1.70374911 2 P 0 ;0,1,2=209,3=0.000000
L 5.65533346 1.70374911 5.6539999 1.70166624 2 P 0 ;0,1,2=209,3=0.000000
L 5.6539999 1.70166624 5.65186654 1.70041654 2 P 0 ;0,1,2=209,3=0.000000
L 5.65186654 1.70041654 5.6500003 1.7 2 P 0 ;0,1,2=209,3=0.000000
A 5.32826004 1.7371 5.32826004 1.7371 5.32575 1.7371 1 P 0 N
L 5.61113337 1.75291634 5.61273356 1.75416683 2 P 0 ;0,1,2=210,3=0.000000
L 5.61273356 1.75416683 5.6145998 1.755 2 P 0 ;0,1,2=210,3=0.000000
L 5.6145998 1.755 5.61673317 1.755 2 P 0 ;0,1,2=210,3=0.000000
L 5.61673317 1.755 5.61913366 1.75374941 2 P 0 ;0,1,2=210,3=0.000000
L 5.61913366 1.75374941 5.6209999 1.75166654 2 P 0 ;0,1,2=210,3=0.000000
L 5.6209999 1.75166654 5.62233346 1.74916634 2 P 0 ;0,1,2=210,3=0.000000
L 5.62233346 1.74916634 5.62340039 1.7449998 2 P 0 ;0,1,2=210,3=0.000000
L 5.62340039 1.7449998 5.62366703 1.7412498 2 P 0 ;0,1,2=210,3=0.000000
L 5.62366703 1.7412498 5.62313327 1.7374999 2 P 0 ;0,1,2=210,3=0.000000
L 5.62313327 1.7374999 5.62233346 1.73499961 2 P 0 ;0,1,2=210,3=0.000000
L 5.62233346 1.73499961 5.62073337 1.73249941 2 P 0 ;0,1,2=210,3=0.000000
L 5.62073337 1.73249941 5.61886654 1.73083307 2 P 0 ;0,1,2=210,3=0.000000
L 5.61886654 1.73083307 5.6170003 1.73 2 P 0 ;0,1,2=210,3=0.000000
L 5.6170003 1.73 5.61513356 1.73 2 P 0 ;0,1,2=210,3=0.000000
L 5.61513356 1.73 5.61326673 1.73083307 2 P 0 ;0,1,2=210,3=0.000000
L 5.61326673 1.73083307 5.61166663 1.73208287 2 P 0 ;0,1,2=210,3=0.000000
L 5.61166663 1.73208287 5.61033307 1.73374911 2 P 0 ;0,1,2=210,3=0.000000
L 5.5898 1.73 5.5898 1.755 2 P 0 ;0,1,2=210,3=0.000000
L 5.5898 1.755 5.59966703 1.73708327 2 P 0 ;0,1,2=210,3=0.000000
L 5.59966703 1.73708327 5.58633307 1.73708327 2 P 0 ;0,1,2=210,3=0.000000
L 5.57406683 1.75083337 5.57246673 1.75333287 2 P 0 ;0,1,2=210,3=0.000000
L 5.57246673 1.75333287 5.5706 1.75458337 2 P 0 ;0,1,2=210,3=0.000000
L 5.5706 1.75458337 5.56846663 1.755 2 P 0 ;0,1,2=210,3=0.000000
L 5.56846663 1.755 5.5658 1.75416683 2 P 0 ;0,1,2=210,3=0.000000
L 5.5658 1.75416683 5.56393327 1.75208317 2 P 0 ;0,1,2=210,3=0.000000
L 5.56393327 1.75208317 5.5634 1.74958366 2 P 0 ;0,1,2=210,3=0.000000
L 5.5634 1.74958366 5.56366663 1.74708268 2 P 0 ;0,1,2=210,3=0.000000
L 5.56366663 1.74708268 5.56473356 1.7449998 2 P 0 ;0,1,2=210,3=0.000000
L 5.56473356 1.7449998 5.57006673 1.74083327 2 P 0 ;0,1,2=210,3=0.000000
L 5.57006673 1.74083327 5.57246673 1.73791644 2 P 0 ;0,1,2=210,3=0.000000
L 5.57246673 1.73791644 5.57406683 1.73374911 2 P 0 ;0,1,2=210,3=0.000000
L 5.57406683 1.73374911 5.5746001 1.73 2 P 0 ;0,1,2=210,3=0.000000
L 5.5746001 1.73 5.5634 1.73 2 P 0 ;0,1,2=210,3=0.000000
L 5.5450003 1.755 5.54713366 1.75416683 2 P 0 ;0,1,2=210,3=0.000000
L 5.54713366 1.75416683 5.54873337 1.75208317 2 P 0 ;0,1,2=210,3=0.000000
L 5.54873337 1.75208317 5.5498002 1.74958366 2 P 0 ;0,1,2=210,3=0.000000
L 5.5498002 1.74958366 5.5506001 1.74624951 2 P 0 ;0,1,2=210,3=0.000000
L 5.5506001 1.74624951 5.55086673 1.74249961 2 P 0 ;0,1,2=210,3=0.000000
L 5.55086673 1.74249961 5.5506001 1.73874961 2 P 0 ;0,1,2=210,3=0.000000
L 5.5506001 1.73874961 5.5498002 1.73541624 2 P 0 ;0,1,2=210,3=0.000000
L 5.5498002 1.73541624 5.54873337 1.73291604 2 P 0 ;0,1,2=210,3=0.000000
L 5.54873337 1.73291604 5.54713366 1.73083307 2 P 0 ;0,1,2=210,3=0.000000
L 5.54713366 1.73083307 5.5450003 1.73 2 P 0 ;0,1,2=210,3=0.000000
L 5.5450003 1.73 5.54286693 1.73083307 2 P 0 ;0,1,2=210,3=0.000000
L 5.54286693 1.73083307 5.54126673 1.73291604 2 P 0 ;0,1,2=210,3=0.000000
L 5.54126673 1.73291604 5.5401999 1.73541624 2 P 0 ;0,1,2=210,3=0.000000
L 5.5401999 1.73541624 5.5394 1.73874961 2 P 0 ;0,1,2=210,3=0.000000
L 5.5394 1.73874961 5.53913337 1.74249961 2 P 0 ;0,1,2=210,3=0.000000
L 5.53913337 1.74249961 5.5394 1.74624951 2 P 0 ;0,1,2=210,3=0.000000
L 5.5394 1.74624951 5.5401999 1.74958366 2 P 0 ;0,1,2=210,3=0.000000
L 5.5401999 1.74958366 5.54126673 1.75208317 2 P 0 ;0,1,2=210,3=0.000000
L 5.54126673 1.75208317 5.54286693 1.75416683 2 P 0 ;0,1,2=210,3=0.000000
L 5.54286693 1.75416683 5.5450003 1.755 2 P 0 ;0,1,2=210,3=0.000000
A 5.32826004 1.6458 5.32826004 1.6458 5.32575 1.6458 1 P 0 N
L 5.61113337 1.64791634 5.61273356 1.64916683 2 P 0 ;0,1,2=211,3=0.000000
L 5.61273356 1.64916683 5.6145998 1.65 2 P 0 ;0,1,2=211,3=0.000000
L 5.6145998 1.65 5.61673317 1.65 2 P 0 ;0,1,2=211,3=0.000000
L 5.61673317 1.65 5.61913366 1.64874941 2 P 0 ;0,1,2=211,3=0.000000
L 5.61913366 1.64874941 5.6209999 1.64666654 2 P 0 ;0,1,2=211,3=0.000000
L 5.6209999 1.64666654 5.62233346 1.64416634 2 P 0 ;0,1,2=211,3=0.000000
L 5.62233346 1.64416634 5.62340039 1.6399998 2 P 0 ;0,1,2=211,3=0.000000
L 5.62340039 1.6399998 5.62366703 1.6362498 2 P 0 ;0,1,2=211,3=0.000000
L 5.62366703 1.6362498 5.62313327 1.6324999 2 P 0 ;0,1,2=211,3=0.000000
L 5.62313327 1.6324999 5.62233346 1.62999961 2 P 0 ;0,1,2=211,3=0.000000
L 5.62233346 1.62999961 5.62073337 1.62749941 2 P 0 ;0,1,2=211,3=0.000000
L 5.62073337 1.62749941 5.61886654 1.62583307 2 P 0 ;0,1,2=211,3=0.000000
L 5.61886654 1.62583307 5.6170003 1.625 2 P 0 ;0,1,2=211,3=0.000000
L 5.6170003 1.625 5.61513356 1.625 2 P 0 ;0,1,2=211,3=0.000000
L 5.61513356 1.625 5.61326673 1.62583307 2 P 0 ;0,1,2=211,3=0.000000
L 5.61326673 1.62583307 5.61166663 1.62708287 2 P 0 ;0,1,2=211,3=0.000000
L 5.61166663 1.62708287 5.61033307 1.62874911 2 P 0 ;0,1,2=211,3=0.000000
L 5.5898 1.625 5.5898 1.65 2 P 0 ;0,1,2=211,3=0.000000
L 5.5898 1.65 5.59966703 1.63208327 2 P 0 ;0,1,2=211,3=0.000000
L 5.59966703 1.63208327 5.58633307 1.63208327 2 P 0 ;0,1,2=211,3=0.000000
L 5.5690003 1.625 5.5690003 1.65 2 P 0 ;0,1,2=211,3=0.000000
L 5.5690003 1.65 5.5722001 1.6450003 2 P 0 ;0,1,2=211,3=0.000000
L 5.5722001 1.625 5.56580049 1.625 2 P 0 ;0,1,2=211,3=0.000000
L 5.54953366 1.62791604 5.54766683 1.62583307 2 P 0 ;0,1,2=211,3=0.000000
L 5.54766683 1.62583307 5.54553346 1.625 2 P 0 ;0,1,2=211,3=0.000000
L 5.54553346 1.625 5.5434001 1.62583307 2 P 0 ;0,1,2=211,3=0.000000
L 5.5434001 1.62583307 5.54153337 1.62833258 2 P 0 ;0,1,2=211,3=0.000000
L 5.54153337 1.62833258 5.5401999 1.63208327 2 P 0 ;0,1,2=211,3=0.000000
L 5.5401999 1.63208327 5.53966663 1.63583327 2 P 0 ;0,1,2=211,3=0.000000
L 5.53966663 1.63583327 5.53966663 1.64041634 2 P 0 ;0,1,2=211,3=0.000000
L 5.53966663 1.64041634 5.5401999 1.64416634 2 P 0 ;0,1,2=211,3=0.000000
L 5.5401999 1.64416634 5.54153337 1.6474997 2 P 0 ;0,1,2=211,3=0.000000
L 5.54153337 1.6474997 5.54313356 1.64916683 2 P 0 ;0,1,2=211,3=0.000000
L 5.54313356 1.64916683 5.5450003 1.65 2 P 0 ;0,1,2=211,3=0.000000
L 5.5450003 1.65 5.54713366 1.64916683 2 P 0 ;0,1,2=211,3=0.000000
L 5.54713366 1.64916683 5.54873337 1.6474997 2 P 0 ;0,1,2=211,3=0.000000
L 5.54873337 1.6474997 5.5498002 1.6450003 2 P 0 ;0,1,2=211,3=0.000000
L 5.5498002 1.6450003 5.55033346 1.64166614 2 P 0 ;0,1,2=211,3=0.000000
L 5.55033346 1.64166614 5.5498002 1.6387501 2 P 0 ;0,1,2=211,3=0.000000
L 5.5498002 1.6387501 5.54846673 1.63583327 2 P 0 ;0,1,2=211,3=0.000000
L 5.54846673 1.63583327 5.54686654 1.63416614 2 P 0 ;0,1,2=211,3=0.000000
L 5.54686654 1.63416614 5.5450003 1.63374961 2 P 0 ;0,1,2=211,3=0.000000
L 5.5450003 1.63374961 5.54286693 1.63458278 2 P 0 ;0,1,2=211,3=0.000000
L 5.54286693 1.63458278 5.54126673 1.63666644 2 P 0 ;0,1,2=211,3=0.000000
L 5.54126673 1.63666644 5.53966663 1.64041634 2 P 0 ;0,1,2=211,3=0.000000
L 3.92236004 2.56213002 3.91843002 2.56213002 3 P 0 
L 3.9639 2.57276004 3.96173002 2.57276004 3 P 0 
L 3.96173002 2.57276004 3.95386004 2.58063002 3 P 0 
L 3.95386004 2.58063002 3.94598996 2.57276004 3 P 0 
L 3.94598996 2.57276004 3.94381998 2.57276004 3 P 0 
L 3.94381998 2.57276004 3.94381998 2.66723996 3 P 0 
L 3.94381998 2.66723996 3.9639 2.66723996 3 P 0 
L 3.9639 2.66723996 3.9639 2.57276004 3 P 0 
L 3.91843002 2.56213002 3.90661998 2.56213002 3 P 0 
L 3.90661998 2.56213002 3.91448996 2.57393996 3 P 0 
L 3.91448996 2.57393996 3.92236004 2.56213002 3 P 0 
L 3.92236004 2.56213002 3.91153996 2.56606004 3 P 0 
L 3.91153996 2.56606004 3.91448996 2.57 3 P 0 
L 3.91448996 2.57 3.91743996 2.56606004 3 P 0 
L 3.91743996 2.56606004 3.91153996 2.56606004 3 P 0 
L 3.91153996 2.56606004 3.91843002 2.56213002 3 P 0 
L 3.91843002 2.56213002 3.90661998 2.56213002 3 P 0 
L 3.90661998 2.56213002 3.92236004 2.56213002 3 P 0 
L 3.98786673 2.545 3.98786673 2.52708327 2 P 0 ;0,1,2=212,3=0.000000
L 3.98786673 2.52708327 3.9868002 2.52333258 2 P 0 ;0,1,2=212,3=0.000000
L 3.9868002 2.52333258 3.98466683 2.52083307 2 P 0 ;0,1,2=212,3=0.000000
L 3.98466683 2.52083307 3.9820003 2.52 2 P 0 ;0,1,2=212,3=0.000000
L 3.9820003 2.52 3.97933327 2.52083307 2 P 0 ;0,1,2=212,3=0.000000
L 3.97933327 2.52083307 3.9771999 2.52333258 2 P 0 ;0,1,2=212,3=0.000000
L 3.9771999 2.52333258 3.97613337 2.52708327 2 P 0 ;0,1,2=212,3=0.000000
L 3.97613337 2.52708327 3.97613337 2.545 2 P 0 ;0,1,2=212,3=0.000000
L 3.9580003 2.52 3.9580003 2.545 2 P 0 ;0,1,2=212,3=0.000000
L 3.9580003 2.545 3.9612001 2.5400003 2 P 0 ;0,1,2=212,3=0.000000
L 3.9612001 2.52 3.95480049 2.52 2 P 0 ;0,1,2=212,3=0.000000
L 3.93906683 2.53041594 3.9372001 2.53333346 2 P 0 ;0,1,2=212,3=0.000000
L 3.9372001 2.53333346 3.9356 2.5349998 2 P 0 ;0,1,2=212,3=0.000000
L 3.9356 2.5349998 3.93346663 2.53583297 2 P 0 ;0,1,2=212,3=0.000000
L 3.93346663 2.53583297 3.9315998 2.5349998 2 P 0 ;0,1,2=212,3=0.000000
L 3.9315998 2.5349998 3.93026673 2.53333346 2 P 0 ;0,1,2=212,3=0.000000
L 3.93026673 2.53333346 3.9291999 2.53083327 2 P 0 ;0,1,2=212,3=0.000000
L 3.9291999 2.53083327 3.92893327 2.52791644 2 P 0 ;0,1,2=212,3=0.000000
L 3.92893327 2.52791644 3.9291999 2.52541624 2 P 0 ;0,1,2=212,3=0.000000
L 3.9291999 2.52541624 3.93026673 2.52291604 2 P 0 ;0,1,2=212,3=0.000000
L 3.93026673 2.52291604 3.93186693 2.52083307 2 P 0 ;0,1,2=212,3=0.000000
L 3.93186693 2.52083307 3.93373317 2.52 2 P 0 ;0,1,2=212,3=0.000000
L 3.93373317 2.52 3.93586654 2.52083307 2 P 0 ;0,1,2=212,3=0.000000
L 3.93586654 2.52083307 3.93773337 2.52333258 2 P 0 ;0,1,2=212,3=0.000000
L 3.93773337 2.52333258 3.9388002 2.52708327 2 P 0 ;0,1,2=212,3=0.000000
L 3.9388002 2.52708327 3.93906683 2.5312498 2 P 0 ;0,1,2=212,3=0.000000
L 3.93906683 2.5312498 3.93853366 2.53666614 2 P 0 ;0,1,2=212,3=0.000000
L 3.93853366 2.53666614 3.93773337 2.53958366 2 P 0 ;0,1,2=212,3=0.000000
L 3.93773337 2.53958366 3.9364003 2.5424997 2 P 0 ;0,1,2=212,3=0.000000
L 3.9364003 2.5424997 3.93453346 2.54458337 2 P 0 ;0,1,2=212,3=0.000000
L 3.93453346 2.54458337 3.93266673 2.545 2 P 0 ;0,1,2=212,3=0.000000
L 3.93266673 2.545 3.9308 2.54416683 2 P 0 ;0,1,2=212,3=0.000000
L 3.9308 2.54416683 3.92946644 2.54208317 2 P 0 ;0,1,2=212,3=0.000000
L 3.91506683 2.53041594 3.9132001 2.53333346 2 P 0 ;0,1,2=212,3=0.000000
L 3.9132001 2.53333346 3.9116 2.5349998 2 P 0 ;0,1,2=212,3=0.000000
L 3.9116 2.5349998 3.90946663 2.53583297 2 P 0 ;0,1,2=212,3=0.000000
L 3.90946663 2.53583297 3.9075998 2.5349998 2 P 0 ;0,1,2=212,3=0.000000
L 3.9075998 2.5349998 3.90626673 2.53333346 2 P 0 ;0,1,2=212,3=0.000000
L 3.90626673 2.53333346 3.9051999 2.53083327 2 P 0 ;0,1,2=212,3=0.000000
L 3.9051999 2.53083327 3.90493327 2.52791644 2 P 0 ;0,1,2=212,3=0.000000
L 3.90493327 2.52791644 3.9051999 2.52541624 2 P 0 ;0,1,2=212,3=0.000000
L 3.9051999 2.52541624 3.90626673 2.52291604 2 P 0 ;0,1,2=212,3=0.000000
L 3.90626673 2.52291604 3.90786693 2.52083307 2 P 0 ;0,1,2=212,3=0.000000
L 3.90786693 2.52083307 3.90973317 2.52 2 P 0 ;0,1,2=212,3=0.000000
L 3.90973317 2.52 3.91186654 2.52083307 2 P 0 ;0,1,2=212,3=0.000000
L 3.91186654 2.52083307 3.91373337 2.52333258 2 P 0 ;0,1,2=212,3=0.000000
L 3.91373337 2.52333258 3.9148002 2.52708327 2 P 0 ;0,1,2=212,3=0.000000
L 3.9148002 2.52708327 3.91506683 2.5312498 2 P 0 ;0,1,2=212,3=0.000000
L 3.91506683 2.5312498 3.91453366 2.53666614 2 P 0 ;0,1,2=212,3=0.000000
L 3.91453366 2.53666614 3.91373337 2.53958366 2 P 0 ;0,1,2=212,3=0.000000
L 3.91373337 2.53958366 3.9124003 2.5424997 2 P 0 ;0,1,2=212,3=0.000000
L 3.9124003 2.5424997 3.91053346 2.54458337 2 P 0 ;0,1,2=212,3=0.000000
L 3.91053346 2.54458337 3.90866673 2.545 2 P 0 ;0,1,2=212,3=0.000000
L 3.90866673 2.545 3.9068 2.54416683 2 P 0 ;0,1,2=212,3=0.000000
L 3.9068 2.54416683 3.90546644 2.54208317 2 P 0 ;0,1,2=212,3=0.000000
L 9.96628996 2.79213002 9.96236004 2.79213002 3 P 0 
L 10.00783002 2.80276004 10.00566004 2.80276004 3 P 0 
L 10.00566004 2.80276004 9.99778996 2.81063002 3 P 0 
L 9.99778996 2.81063002 9.98991998 2.80276004 3 P 0 
L 9.98991998 2.80276004 9.98775 2.80276004 3 P 0 
L 9.98775 2.80276004 9.98775 2.89723996 3 P 0 
L 9.98775 2.89723996 10.00783002 2.89723996 3 P 0 
L 10.00783002 2.89723996 10.00783002 2.80276004 3 P 0 
L 9.96236004 2.79213002 9.95055 2.79213002 3 P 0 
L 9.95055 2.79213002 9.95841998 2.80393996 3 P 0 
L 9.95841998 2.80393996 9.96628996 2.79213002 3 P 0 
L 9.96628996 2.79213002 9.95546998 2.79606004 3 P 0 
L 9.95546998 2.79606004 9.95841998 2.8 3 P 0 
L 9.95841998 2.8 9.96136998 2.79606004 3 P 0 
L 9.96136998 2.79606004 9.95546998 2.79606004 3 P 0 
L 9.95546998 2.79606004 9.96236004 2.79213002 3 P 0 
L 9.96236004 2.79213002 9.95055 2.79213002 3 P 0 
L 9.95055 2.79213002 9.96628996 2.79213002 3 P 0 
L 10.03786673 2.765 10.03786673 2.74708327 2 P 0 ;0,1,2=213,3=0.000000
L 10.03786673 2.74708327 10.0368002 2.74333258 2 P 0 ;0,1,2=213,3=0.000000
L 10.0368002 2.74333258 10.03466683 2.74083307 2 P 0 ;0,1,2=213,3=0.000000
L 10.03466683 2.74083307 10.0320003 2.74 2 P 0 ;0,1,2=213,3=0.000000
L 10.0320003 2.74 10.02933327 2.74083307 2 P 0 ;0,1,2=213,3=0.000000
L 10.02933327 2.74083307 10.0271999 2.74333258 2 P 0 ;0,1,2=213,3=0.000000
L 10.0271999 2.74333258 10.02613337 2.74708327 2 P 0 ;0,1,2=213,3=0.000000
L 10.02613337 2.74708327 10.02613337 2.765 2 P 0 ;0,1,2=213,3=0.000000
L 10.0080003 2.74 10.0080003 2.765 2 P 0 ;0,1,2=213,3=0.000000
L 10.0080003 2.765 10.0112001 2.7600003 2 P 0 ;0,1,2=213,3=0.000000
L 10.0112001 2.74 10.00480049 2.74 2 P 0 ;0,1,2=213,3=0.000000
L 9.98906683 2.75041594 9.9872001 2.75333346 2 P 0 ;0,1,2=213,3=0.000000
L 9.9872001 2.75333346 9.9856 2.7549998 2 P 0 ;0,1,2=213,3=0.000000
L 9.9856 2.7549998 9.98346663 2.75583297 2 P 0 ;0,1,2=213,3=0.000000
L 9.98346663 2.75583297 9.9815998 2.7549998 2 P 0 ;0,1,2=213,3=0.000000
L 9.9815998 2.7549998 9.98026673 2.75333346 2 P 0 ;0,1,2=213,3=0.000000
L 9.98026673 2.75333346 9.9791999 2.75083327 2 P 0 ;0,1,2=213,3=0.000000
L 9.9791999 2.75083327 9.97893327 2.74791644 2 P 0 ;0,1,2=213,3=0.000000
L 9.97893327 2.74791644 9.9791999 2.74541624 2 P 0 ;0,1,2=213,3=0.000000
L 9.9791999 2.74541624 9.98026673 2.74291604 2 P 0 ;0,1,2=213,3=0.000000
L 9.98026673 2.74291604 9.98186693 2.74083307 2 P 0 ;0,1,2=213,3=0.000000
L 9.98186693 2.74083307 9.98373317 2.74 2 P 0 ;0,1,2=213,3=0.000000
L 9.98373317 2.74 9.98586654 2.74083307 2 P 0 ;0,1,2=213,3=0.000000
L 9.98586654 2.74083307 9.98773337 2.74333258 2 P 0 ;0,1,2=213,3=0.000000
L 9.98773337 2.74333258 9.9888002 2.74708327 2 P 0 ;0,1,2=213,3=0.000000
L 9.9888002 2.74708327 9.98906683 2.7512498 2 P 0 ;0,1,2=213,3=0.000000
L 9.98906683 2.7512498 9.98853366 2.75666614 2 P 0 ;0,1,2=213,3=0.000000
L 9.98853366 2.75666614 9.98773337 2.75958366 2 P 0 ;0,1,2=213,3=0.000000
L 9.98773337 2.75958366 9.9864003 2.7624997 2 P 0 ;0,1,2=213,3=0.000000
L 9.9864003 2.7624997 9.98453346 2.76458337 2 P 0 ;0,1,2=213,3=0.000000
L 9.98453346 2.76458337 9.98266673 2.765 2 P 0 ;0,1,2=213,3=0.000000
L 9.98266673 2.765 9.9808 2.76416683 2 P 0 ;0,1,2=213,3=0.000000
L 9.9808 2.76416683 9.97946644 2.76208317 2 P 0 ;0,1,2=213,3=0.000000
L 9.96053346 2.74 9.9600003 2.74541624 2 P 0 ;0,1,2=213,3=0.000000
L 9.9600003 2.74541624 9.9592 2.74999931 2 P 0 ;0,1,2=213,3=0.000000
L 9.9592 2.74999931 9.95813356 2.75416663 2 P 0 ;0,1,2=213,3=0.000000
L 9.95813356 2.75416663 9.9568 2.7587498 2 P 0 ;0,1,2=213,3=0.000000
L 9.9568 2.7587498 9.95466663 2.765 2 P 0 ;0,1,2=213,3=0.000000
L 9.95466663 2.765 9.96533346 2.765 2 P 0 ;0,1,2=213,3=0.000000
L 5.7307 2.94213002 5.72676998 2.94213002 3 P 0 
L 5.77223996 2.95276004 5.77006998 2.95276004 3 P 0 
L 5.77006998 2.95276004 5.7622 2.96063002 3 P 0 
L 5.7622 2.96063002 5.75433002 2.95276004 3 P 0 
L 5.75433002 2.95276004 5.75216004 2.95276004 3 P 0 
L 5.75216004 2.95276004 5.75216004 3.04723996 3 P 0 
L 5.75216004 3.04723996 5.77223996 3.04723996 3 P 0 
L 5.77223996 3.04723996 5.77223996 2.95276004 3 P 0 
L 5.72676998 2.94213002 5.71496004 2.94213002 3 P 0 
L 5.71496004 2.94213002 5.72283002 2.95393996 3 P 0 
L 5.72283002 2.95393996 5.7307 2.94213002 3 P 0 
L 5.7307 2.94213002 5.71988002 2.94606004 3 P 0 
L 5.71988002 2.94606004 5.72283002 2.95 3 P 0 
L 5.72283002 2.95 5.72578002 2.94606004 3 P 0 
L 5.72578002 2.94606004 5.71988002 2.94606004 3 P 0 
L 5.71988002 2.94606004 5.72676998 2.94213002 3 P 0 
L 5.72676998 2.94213002 5.71496004 2.94213002 3 P 0 
L 5.71496004 2.94213002 5.7307 2.94213002 3 P 0 
L 5.76286673 3.095 5.76286673 3.07708327 2 P 0 ;0,1,2=214,3=0.000000
L 5.76286673 3.07708327 5.7618002 3.07333258 2 P 0 ;0,1,2=214,3=0.000000
L 5.7618002 3.07333258 5.75966683 3.07083307 2 P 0 ;0,1,2=214,3=0.000000
L 5.75966683 3.07083307 5.7570003 3.07 2 P 0 ;0,1,2=214,3=0.000000
L 5.7570003 3.07 5.75433327 3.07083307 2 P 0 ;0,1,2=214,3=0.000000
L 5.75433327 3.07083307 5.7521999 3.07333258 2 P 0 ;0,1,2=214,3=0.000000
L 5.7521999 3.07333258 5.75113337 3.07708327 2 P 0 ;0,1,2=214,3=0.000000
L 5.75113337 3.07708327 5.75113337 3.095 2 P 0 ;0,1,2=214,3=0.000000
L 5.7330003 3.07 5.7330003 3.095 2 P 0 ;0,1,2=214,3=0.000000
L 5.7330003 3.095 5.7362001 3.0900003 2 P 0 ;0,1,2=214,3=0.000000
L 5.7362001 3.07 5.72980049 3.07 2 P 0 ;0,1,2=214,3=0.000000
L 5.71406683 3.08041594 5.7122001 3.08333346 2 P 0 ;0,1,2=214,3=0.000000
L 5.7122001 3.08333346 5.7106 3.0849998 2 P 0 ;0,1,2=214,3=0.000000
L 5.7106 3.0849998 5.70846663 3.08583297 2 P 0 ;0,1,2=214,3=0.000000
L 5.70846663 3.08583297 5.7065998 3.0849998 2 P 0 ;0,1,2=214,3=0.000000
L 5.7065998 3.0849998 5.70526673 3.08333346 2 P 0 ;0,1,2=214,3=0.000000
L 5.70526673 3.08333346 5.7041999 3.08083327 2 P 0 ;0,1,2=214,3=0.000000
L 5.7041999 3.08083327 5.70393327 3.07791644 2 P 0 ;0,1,2=214,3=0.000000
L 5.70393327 3.07791644 5.7041999 3.07541624 2 P 0 ;0,1,2=214,3=0.000000
L 5.7041999 3.07541624 5.70526673 3.07291604 2 P 0 ;0,1,2=214,3=0.000000
L 5.70526673 3.07291604 5.70686693 3.07083307 2 P 0 ;0,1,2=214,3=0.000000
L 5.70686693 3.07083307 5.70873317 3.07 2 P 0 ;0,1,2=214,3=0.000000
L 5.70873317 3.07 5.71086654 3.07083307 2 P 0 ;0,1,2=214,3=0.000000
L 5.71086654 3.07083307 5.71273337 3.07333258 2 P 0 ;0,1,2=214,3=0.000000
L 5.71273337 3.07333258 5.7138002 3.07708327 2 P 0 ;0,1,2=214,3=0.000000
L 5.7138002 3.07708327 5.71406683 3.0812498 2 P 0 ;0,1,2=214,3=0.000000
L 5.71406683 3.0812498 5.71353366 3.08666614 2 P 0 ;0,1,2=214,3=0.000000
L 5.71353366 3.08666614 5.71273337 3.08958366 2 P 0 ;0,1,2=214,3=0.000000
L 5.71273337 3.08958366 5.7114003 3.0924997 2 P 0 ;0,1,2=214,3=0.000000
L 5.7114003 3.0924997 5.70953346 3.09458337 2 P 0 ;0,1,2=214,3=0.000000
L 5.70953346 3.09458337 5.70766673 3.095 2 P 0 ;0,1,2=214,3=0.000000
L 5.70766673 3.095 5.7058 3.09416683 2 P 0 ;0,1,2=214,3=0.000000
L 5.7058 3.09416683 5.70446644 3.09208317 2 P 0 ;0,1,2=214,3=0.000000
L 5.6850003 3.07 5.68313356 3.07041654 2 P 0 ;0,1,2=214,3=0.000000
L 5.68313356 3.07041654 5.6810002 3.07166624 2 P 0 ;0,1,2=214,3=0.000000
L 5.6810002 3.07166624 5.67966663 3.07374911 2 P 0 ;0,1,2=214,3=0.000000
L 5.67966663 3.07374911 5.67913337 3.07666673 2 P 0 ;0,1,2=214,3=0.000000
L 5.67913337 3.07666673 5.67966663 3.07958278 2 P 0 ;0,1,2=214,3=0.000000
L 5.67966663 3.07958278 5.68126673 3.08208297 2 P 0 ;0,1,2=214,3=0.000000
L 5.68126673 3.08208297 5.68366673 3.08333346 2 P 0 ;0,1,2=214,3=0.000000
L 5.68366673 3.08333346 5.68633337 3.08333346 2 P 0 ;0,1,2=214,3=0.000000
L 5.68633337 3.08333346 5.68793346 3.08416663 2 P 0 ;0,1,2=214,3=0.000000
L 5.68793346 3.08416663 5.68926703 3.08624951 2 P 0 ;0,1,2=214,3=0.000000
L 5.68926703 3.08624951 5.6898002 3.08916634 2 P 0 ;0,1,2=214,3=0.000000
L 5.6898002 3.08916634 5.6889999 3.09208317 2 P 0 ;0,1,2=214,3=0.000000
L 5.6889999 3.09208317 5.68713366 3.09416683 2 P 0 ;0,1,2=214,3=0.000000
L 5.68713366 3.09416683 5.6850003 3.095 2 P 0 ;0,1,2=214,3=0.000000
L 5.6850003 3.095 5.68286693 3.09416683 2 P 0 ;0,1,2=214,3=0.000000
L 5.68286693 3.09416683 5.6810002 3.09208317 2 P 0 ;0,1,2=214,3=0.000000
L 5.6810002 3.09208317 5.6801999 3.08916634 2 P 0 ;0,1,2=214,3=0.000000
L 5.6801999 3.08916634 5.68073356 3.08624951 2 P 0 ;0,1,2=214,3=0.000000
L 5.68073356 3.08624951 5.68206663 3.08416663 2 P 0 ;0,1,2=214,3=0.000000
L 5.68206663 3.08416663 5.68366673 3.08333346 2 P 0 ;0,1,2=214,3=0.000000
L 5.68366673 3.08333346 5.68633337 3.08333346 2 P 0 ;0,1,2=214,3=0.000000
L 5.68633337 3.08333346 5.68873337 3.08208297 2 P 0 ;0,1,2=214,3=0.000000
L 5.68873337 3.08208297 5.69033346 3.07958278 2 P 0 ;0,1,2=214,3=0.000000
L 5.69033346 3.07958278 5.69086673 3.07666673 2 P 0 ;0,1,2=214,3=0.000000
L 5.69086673 3.07666673 5.69033346 3.07374911 2 P 0 ;0,1,2=214,3=0.000000
L 5.69033346 3.07374911 5.6889999 3.07166624 2 P 0 ;0,1,2=214,3=0.000000
L 5.6889999 3.07166624 5.68686654 3.07041654 2 P 0 ;0,1,2=214,3=0.000000
L 5.68686654 3.07041654 5.6850003 3.07 2 P 0 ;0,1,2=214,3=0.000000
L 11.79275 2.89291004 11.79275 2.89606004 1 P 0 
L 11.79275 2.89606004 11.77661004 2.89606004 1 P 0 
L 11.77661004 2.89606004 11.76361998 2.88346004 1 P 0 
L 11.76361998 2.88346004 11.75141998 2.89606004 1 P 0 
L 11.75141998 2.89606004 11.73448996 2.89606004 1 P 0 
L 11.73448996 2.89606004 11.73448996 2.89251998 1 P 0 
L 11.79275 2.80748002 11.79275 2.80393996 1 P 0 
L 11.79275 2.80393996 11.73448996 2.80393996 1 P 0 
L 11.73448996 2.80393996 11.73448996 2.80748002 1 P 0 
A 11.81558996 2.89488002 11.81558996 2.89488002 11.81165 2.89488002 3 P 0 N
L 12.06 2.81213327 12.04208327 2.81213327 2 P 0 ;0,1,2=215,3=90.000000
L 12.04208327 2.81213327 12.03833258 2.8131998 2 P 0 ;0,1,2=215,3=90.000000
L 12.03833258 2.8131998 12.03583307 2.81533317 2 P 0 ;0,1,2=215,3=90.000000
L 12.03583307 2.81533317 12.035 2.8179997 2 P 0 ;0,1,2=215,3=90.000000
L 12.035 2.8179997 12.03583307 2.82066673 2 P 0 ;0,1,2=215,3=90.000000
L 12.03583307 2.82066673 12.03833258 2.8228001 2 P 0 ;0,1,2=215,3=90.000000
L 12.03833258 2.8228001 12.04208327 2.82386663 2 P 0 ;0,1,2=215,3=90.000000
L 12.04208327 2.82386663 12.06 2.82386663 2 P 0 ;0,1,2=215,3=90.000000
L 12.035 2.8419997 12.06 2.8419997 2 P 0 ;0,1,2=215,3=90.000000
L 12.06 2.8419997 12.0550003 2.8387999 2 P 0 ;0,1,2=215,3=90.000000
L 12.035 2.8387999 12.035 2.84519951 2 P 0 ;0,1,2=215,3=90.000000
L 12.035 2.86546654 12.04041624 2.8659997 2 P 0 ;0,1,2=215,3=90.000000
L 12.04041624 2.8659997 12.04499931 2.8668 2 P 0 ;0,1,2=215,3=90.000000
L 12.04499931 2.8668 12.04916663 2.86786644 2 P 0 ;0,1,2=215,3=90.000000
L 12.04916663 2.86786644 12.0537498 2.8692 2 P 0 ;0,1,2=215,3=90.000000
L 12.0537498 2.8692 12.06 2.87133337 2 P 0 ;0,1,2=215,3=90.000000
L 12.06 2.87133337 12.06 2.86066654 2 P 0 ;0,1,2=215,3=90.000000
L 12.05583337 2.88493317 12.05833287 2.88653327 2 P 0 ;0,1,2=215,3=90.000000
L 12.05833287 2.88653327 12.05958337 2.8884 2 P 0 ;0,1,2=215,3=90.000000
L 12.05958337 2.8884 12.06 2.89053337 2 P 0 ;0,1,2=215,3=90.000000
L 12.06 2.89053337 12.05916683 2.8932 2 P 0 ;0,1,2=215,3=90.000000
L 12.05916683 2.8932 12.05708317 2.89506673 2 P 0 ;0,1,2=215,3=90.000000
L 12.05708317 2.89506673 12.05458366 2.8956 2 P 0 ;0,1,2=215,3=90.000000
L 12.05458366 2.8956 12.05208268 2.89533337 2 P 0 ;0,1,2=215,3=90.000000
L 12.05208268 2.89533337 12.0499998 2.89426644 2 P 0 ;0,1,2=215,3=90.000000
L 12.0499998 2.89426644 12.04583327 2.88893327 2 P 0 ;0,1,2=215,3=90.000000
L 12.04583327 2.88893327 12.04291644 2.88653327 2 P 0 ;0,1,2=215,3=90.000000
L 12.04291644 2.88653327 12.03874911 2.88493317 2 P 0 ;0,1,2=215,3=90.000000
L 12.03874911 2.88493317 12.035 2.8843999 2 P 0 ;0,1,2=215,3=90.000000
L 12.035 2.8843999 12.035 2.8956 2 P 0 ;0,1,2=215,3=90.000000
L 5.78881998 2.89291004 5.78881998 2.89606004 1 P 0 
L 5.78881998 2.89606004 5.77268002 2.89606004 1 P 0 
L 5.77268002 2.89606004 5.75968996 2.88346004 1 P 0 
L 5.75968996 2.88346004 5.74748996 2.89606004 1 P 0 
L 5.74748996 2.89606004 5.73056004 2.89606004 1 P 0 
L 5.73056004 2.89606004 5.73056004 2.89251998 1 P 0 
L 5.78881998 2.80748002 5.78881998 2.80393996 1 P 0 
L 5.78881998 2.80393996 5.73056004 2.80393996 1 P 0 
L 5.73056004 2.80393996 5.73056004 2.80748002 1 P 0 
A 5.81166004 2.89488002 5.81166004 2.89488002 5.80771998 2.89488002 3 P 0 N
L 5.78786673 2.785 5.78786673 2.76708327 2 P 0 ;0,1,2=216,3=0.000000
L 5.78786673 2.76708327 5.7868002 2.76333258 2 P 0 ;0,1,2=216,3=0.000000
L 5.7868002 2.76333258 5.78466683 2.76083307 2 P 0 ;0,1,2=216,3=0.000000
L 5.78466683 2.76083307 5.7820003 2.76 2 P 0 ;0,1,2=216,3=0.000000
L 5.7820003 2.76 5.77933327 2.76083307 2 P 0 ;0,1,2=216,3=0.000000
L 5.77933327 2.76083307 5.7771999 2.76333258 2 P 0 ;0,1,2=216,3=0.000000
L 5.7771999 2.76333258 5.77613337 2.76708327 2 P 0 ;0,1,2=216,3=0.000000
L 5.77613337 2.76708327 5.77613337 2.785 2 P 0 ;0,1,2=216,3=0.000000
L 5.75853346 2.76 5.7580003 2.76541624 2 P 0 ;0,1,2=216,3=0.000000
L 5.7580003 2.76541624 5.7572 2.76999931 2 P 0 ;0,1,2=216,3=0.000000
L 5.7572 2.76999931 5.75613356 2.77416663 2 P 0 ;0,1,2=216,3=0.000000
L 5.75613356 2.77416663 5.7548 2.7787498 2 P 0 ;0,1,2=216,3=0.000000
L 5.7548 2.7787498 5.75266663 2.785 2 P 0 ;0,1,2=216,3=0.000000
L 5.75266663 2.785 5.76333346 2.785 2 P 0 ;0,1,2=216,3=0.000000
L 5.73986673 2.76374911 5.73826703 2.76166624 2 P 0 ;0,1,2=216,3=0.000000
L 5.73826703 2.76166624 5.7364003 2.76041654 2 P 0 ;0,1,2=216,3=0.000000
L 5.7364003 2.76041654 5.7340003 2.76 2 P 0 ;0,1,2=216,3=0.000000
L 5.7340003 2.76 5.7315998 2.76083307 2 P 0 ;0,1,2=216,3=0.000000
L 5.7315998 2.76083307 5.72973356 2.76249941 2 P 0 ;0,1,2=216,3=0.000000
L 5.72973356 2.76249941 5.7284 2.76541624 2 P 0 ;0,1,2=216,3=0.000000
L 5.7284 2.76541624 5.72813337 2.76874961 2 P 0 ;0,1,2=216,3=0.000000
L 5.72813337 2.76874961 5.72866663 2.77208297 2 P 0 ;0,1,2=216,3=0.000000
L 5.72866663 2.77208297 5.7300002 2.77416663 2 P 0 ;0,1,2=216,3=0.000000
L 5.7300002 2.77416663 5.73186693 2.77583297 2 P 0 ;0,1,2=216,3=0.000000
L 5.73186693 2.77583297 5.73373317 2.77624951 2 P 0 ;0,1,2=216,3=0.000000
L 5.73373317 2.77624951 5.7356 2.77583297 2 P 0 ;0,1,2=216,3=0.000000
L 5.7356 2.77583297 5.7379999 2.77416663 2 P 0 ;0,1,2=216,3=0.000000
L 5.7379999 2.77416663 5.7372001 2.785 2 P 0 ;0,1,2=216,3=0.000000
L 5.7372001 2.785 5.7300002 2.785 2 P 0 ;0,1,2=216,3=0.000000

### steps/drc/layers/ls/features
#
#Feature symbol names
#
$0 r2
$1 r5
$2 r6
$3 r7.7
$4 r10
$5 r15
$6 r17
$7 r20
$8 r30
$9 r39.37
$10 r40
$11 r43.7
$12 r46.06
$13 r51.18
$14 r74.8
$15 r92.52
$16 r98.43
$17 r118.11
$18 r125
$19 r129.92
$20 r137.8
$21 r157.48
$22 r177.17
$23 r393.7
$24 s15
$25 s20
$26 s43.7
$27 s50
$28 s74.8
$29 oval196.85x137.8
$30 rect35.43x15.75
$31 sp-8c5_2p0_254
$32 sp-8c5_2p0_254+2
$33 sp-9c5_7p0_254
$34 sp-9c5_7p0_254+2

#
#Feature attribute names
#
@0 .nomenclature
@1 .pattern_fill
@2 .smd
@3 .test_point
@4 .string_mirrored
@5 .geometry
@6 .string
@7 .pad_usage
@8 .string_angle

#
#Feature attribute text strings
#
&0 S0_508
&1 TPB30V20D10AT28BPM
&2 C1_11P0_7
&3 C1_11P0_7TP
&4 V17D8AT30SM11
&5 ICT-TPB30BPM
&6 V20D10AT28SM14
&7 C2_5N
&8 R0_9X0_4
&9 S1_11P0_7TP
&10 S1_11P0_7
&11 S1_27
&12 V20D10AT28PG
&13 C1_17P0_76TPM
&14 C1_9P1_4
&15 S1_9P1_4
&16 SP-8C5_2P0_254
&17 SP-9C5_7P0_254
&18 C3_175N-A
&19 E-C40SM100PM5-G
&20 C10N
&21 C3_3N
&22 C4_5N-B
&23 C4N-B
&24 C3_5N
&25 O5X3_5N
&26 C3N
&27 C1_3N
&28 C2_35N
&29 C1N
&30 45
&31 L12
&32 L10
&33 L5
&34 L3
&35 L1
&36 85
&37 SHEET
&38 TITLE
&39 SCALE 1:1
&40 LAYER
&41 OF
&42 ART
&43 12
&44 BOTTOM SIDE
&45 Barreleye G2 SXM2-Riser
&46 A1
&47 DATE OCT/27/2017

#
#Layer features
#
L 7.785 4.45 7.785 4.48446004 3 P 0 
L 7.785 4.48446004 7.82853996 4.528 3 P 0 
P 7.82853996 4.528 25 P 0 0;2,5=0,7=0
P 7.785 4.45 8 P 0 0;3,5=1,7=1
P 9.11353996 4.542 25 P 0 0;2,5=0,7=0
L 7.785 4.45 7.785 4.4227 3 P 0 
L 7.785 4.4227 7.7977 4.41 3 P 0 
L 7.7977 4.41 7.895 4.41 3 P 0 
L 7.895 4.41 8.027 4.542 3 P 0 
L 8.027 4.542 9.11353996 4.542 3 P 0 
L 7.835 4.45 7.835 4.47946004 3 P 0 
L 7.835 4.47946004 7.88353996 4.528 3 P 0 
L 9.16353996 4.542 9.16353996 4.5673 3 P 0 
L 9.16353996 4.5673 9.15583996 4.575 3 P 0 
L 9.15583996 4.575 8.02 4.575 3 P 0 
L 8.02 4.575 7.895 4.45 3 P 0 
L 7.895 4.45 7.835 4.45 3 P 0 
P 7.88353996 4.528 25 P 0 0;2,5=0,7=0
P 7.835 4.45 8 P 0 0;3,5=1,7=1
P 9.16353996 4.542 25 P 0 0;2,5=0,7=0
L 1.825 4.528 1.8 4.503 3 P 0 
L 1.8 4.503 1.8 4.485 3 P 0 
L 1.8 4.485 1.84 4.445 3 P 0 
L 1.84 4.445 1.9 4.445 3 P 0 
L 1.9 4.445 1.997 4.542 3 P 0 
L 1.997 4.542 3.11 4.542 3 P 0 
P 1.8 4.485 8 P 0 0;3,5=1,7=1
P 1.825 4.528 25 P 0 0;2,5=0,7=0
P 3.11 4.542 25 P 0 0;2,5=0,7=0
L 1.86 4.485 1.9 4.485 3 P 0 
L 1.9 4.485 1.99 4.575 3 P 0 
L 1.99 4.575 3.1523 4.575 3 P 0 
L 3.1523 4.575 3.16 4.5673 3 P 0 
L 3.16 4.5673 3.16 4.542 3 P 0 
P 1.86 4.485 8 P 0 0;3,5=1,7=1
P 1.88 4.528 25 P 0 0;2,5=0,7=0
P 3.16 4.542 25 P 0 0;2,5=0,7=0
L 1.88 4.528 1.88 4.505 3 P 0 
L 1.88 4.505 1.86 4.485 3 P 0 
P 0.27165 1.72835 11 P 0 0;3,5=2,7=0
P 0.17323002 2.12205 11 P 0 0;3,5=2,7=0
P 12.73621004 1.76771998 11 P 0 0;3,5=2,7=0
P 12.81495 2.59448996 11 P 0 0;3,5=2,7=0
P 12.63778996 2.16141998 11 P 0 0;3,5=2,7=0
P 0.725 -0.25 11 P 0 0;3,5=3,7=0
L 3.055 -0.275 3.055 -0.19913002 3 P 0 
L 3.055 -0.19913002 3.04586998 -0.19 3 P 0 
L 3.04586998 -0.19 2.99856998 -0.19 3 P 0 
L 2.99856998 -0.19 2.99086998 -0.1977 3 P 0 
L 2.99086998 -0.1977 2.99086998 -0.4123 3 P 0 
L 2.99086998 -0.4123 2.98316998 -0.42 3 P 0 
L 2.98316998 -0.42 2.93586998 -0.42 3 P 0 
L 2.93586998 -0.42 2.92816998 -0.4123 3 P 0 
L 2.92816998 -0.4123 2.92816998 -0.1977 3 P 0 
L 2.92816998 -0.1977 2.92046998 -0.19 3 P 0 
L 2.92046998 -0.19 2.87316998 -0.19 3 P 0 
L 2.87316998 -0.19 2.86546998 -0.1977 3 P 0 
L 2.86546998 -0.1977 2.86546998 -0.4123 3 P 0 
L 2.86546998 -0.4123 2.85776998 -0.42 3 P 0 
L 2.85776998 -0.42 2.81046998 -0.42 3 P 0 
L 2.81046998 -0.42 2.80276998 -0.4123 3 P 0 
L 2.80276998 -0.4123 2.80276998 -0.1977 3 P 0 
L 2.80276998 -0.1977 2.79506998 -0.19 3 P 0 
L 2.79506998 -0.19 2.74776998 -0.19 3 P 0 
L 2.74776998 -0.19 2.74006998 -0.1977 3 P 0 
L 2.74006998 -0.1977 2.74006998 -0.4123 3 P 0 
L 2.74006998 -0.4123 2.73236998 -0.42 3 P 0 
L 2.73236998 -0.42 2.68506998 -0.42 3 P 0 
L 2.68506998 -0.42 2.67736998 -0.4123 3 P 0 
L 2.67736998 -0.4123 2.67736998 -0.1977 3 P 0 
L 2.67736998 -0.1977 2.66966998 -0.19 3 P 0 
L 2.66966998 -0.19 2.62236998 -0.19 3 P 0 
L 2.62236998 -0.19 2.61466998 -0.1977 3 P 0 
L 2.61466998 -0.1977 2.61466998 -0.4123 3 P 0 
L 2.61466998 -0.4123 2.60696998 -0.42 3 P 0 
L 2.60696998 -0.42 2.55966998 -0.42 3 P 0 
L 2.55966998 -0.42 2.55196998 -0.4123 3 P 0 
L 2.55196998 -0.4123 2.55196998 -0.1977 3 P 0 
L 2.55196998 -0.1977 2.54426998 -0.19 3 P 0 
L 2.54426998 -0.19 2.49696998 -0.19 3 P 0 
L 2.49696998 -0.19 2.48926998 -0.1977 3 P 0 
L 2.48926998 -0.1977 2.48926998 -0.4123 3 P 0 
L 2.48926998 -0.4123 2.48156998 -0.42 3 P 0 
L 2.48156998 -0.42 2.43426998 -0.42 3 P 0 
L 2.43426998 -0.42 2.42656998 -0.4123 3 P 0 
L 2.42656998 -0.4123 2.42656998 -0.1977 3 P 0 
L 2.42656998 -0.1977 2.41886998 -0.19 3 P 0 
L 2.41886998 -0.19 2.37156998 -0.19 3 P 0 
L 2.37156998 -0.19 2.36386998 -0.1977 3 P 0 
L 2.36386998 -0.1977 2.36386998 -0.4123 3 P 0 
L 2.36386998 -0.4123 2.35616998 -0.42 3 P 0 
L 2.35616998 -0.42 2.30886998 -0.42 3 P 0 
L 2.30886998 -0.42 2.30116998 -0.4123 3 P 0 
L 2.30116998 -0.4123 2.30116998 -0.1977 3 P 0 
L 2.30116998 -0.1977 2.29346998 -0.19 3 P 0 
L 2.29346998 -0.19 2.24616998 -0.19 3 P 0 
L 2.24616998 -0.19 2.23846998 -0.1977 3 P 0 
L 2.23846998 -0.1977 2.23846998 -0.4123 3 P 0 
L 2.23846998 -0.4123 2.23076998 -0.42 3 P 0 
L 2.23076998 -0.42 2.18346998 -0.42 3 P 0 
L 2.18346998 -0.42 2.17576998 -0.4123 3 P 0 
L 2.17576998 -0.4123 2.17576998 -0.1977 3 P 0 
L 2.17576998 -0.1977 2.16806998 -0.19 3 P 0 
L 2.16806998 -0.19 2.12076998 -0.19 3 P 0 
L 2.12076998 -0.19 2.11306998 -0.1977 3 P 0 
L 2.11306998 -0.1977 2.11306998 -0.4123 3 P 0 
L 2.11306998 -0.4123 2.10536998 -0.42 3 P 0 
L 2.10536998 -0.42 2.05806998 -0.42 3 P 0 
L 2.05806998 -0.42 2.05036998 -0.4123 3 P 0 
L 2.05036998 -0.4123 2.05036998 -0.1977 3 P 0 
L 2.05036998 -0.1977 2.04266998 -0.19 3 P 0 
L 2.04266998 -0.19 1.99536998 -0.19 3 P 0 
L 1.99536998 -0.19 1.98766998 -0.1977 3 P 0 
L 1.98766998 -0.1977 1.98766998 -0.4123 3 P 0 
L 1.98766998 -0.4123 1.97996998 -0.42 3 P 0 
L 1.97996998 -0.42 1.93266998 -0.42 3 P 0 
L 1.93266998 -0.42 1.92496998 -0.4123 3 P 0 
L 1.92496998 -0.4123 1.92496998 -0.1977 3 P 0 
L 1.92496998 -0.1977 1.91726998 -0.19 3 P 0 
L 1.91726998 -0.19 1.86996998 -0.19 3 P 0 
L 1.86996998 -0.19 1.86226998 -0.1977 3 P 0 
L 1.86226998 -0.1977 1.86226998 -0.4123 3 P 0 
L 1.86226998 -0.4123 1.85456998 -0.42 3 P 0 
L 1.85456998 -0.42 1.80726998 -0.42 3 P 0 
L 1.80726998 -0.42 1.79956998 -0.4123 3 P 0 
L 1.79956998 -0.4123 1.79956998 -0.1977 3 P 0 
L 1.79956998 -0.1977 1.79186998 -0.19 3 P 0 
L 1.79186998 -0.19 1.74456998 -0.19 3 P 0 
L 1.74456998 -0.19 1.73686998 -0.1977 3 P 0 
L 1.73686998 -0.1977 1.73686998 -0.4123 3 P 0 
L 1.73686998 -0.4123 1.72916998 -0.42 3 P 0 
L 1.72916998 -0.42 1.68186998 -0.42 3 P 0 
L 1.68186998 -0.42 1.67416998 -0.4123 3 P 0 
L 1.67416998 -0.4123 1.67416998 -0.1977 3 P 0 
L 1.67416998 -0.1977 1.66646998 -0.19 3 P 0 
L 1.66646998 -0.19 1.61916998 -0.19 3 P 0 
L 1.61916998 -0.19 1.61146998 -0.1977 3 P 0 
L 1.61146998 -0.1977 1.61146998 -0.4123 3 P 0 
L 1.61146998 -0.4123 1.60376998 -0.42 3 P 0 
L 1.60376998 -0.42 1.55646998 -0.42 3 P 0 
L 1.55646998 -0.42 1.54876998 -0.4123 3 P 0 
L 1.54876998 -0.4123 1.54876998 -0.1977 3 P 0 
L 1.54876998 -0.1977 1.54106998 -0.19 3 P 0 
L 1.54106998 -0.19 1.49376998 -0.19 3 P 0 
L 1.49376998 -0.19 1.48606998 -0.1977 3 P 0 
L 1.48606998 -0.1977 1.48606998 -0.4123 3 P 0 
L 1.48606998 -0.4123 1.47836998 -0.42 3 P 0 
L 1.47836998 -0.42 1.4227 -0.42 3 P 0 
L 1.4227 -0.42 1.415 -0.4123 3 P 0 
L 1.415 -0.4123 1.415 -0.3077 3 P 0 
L 1.415 -0.3077 1.4073 -0.3 3 P 0 
L 1.4073 -0.3 0.775 -0.3 3 P 0 
L 0.775 -0.3 0.725 -0.25 3 P 0 
P 0.875 -0.25 11 P 0 0;3,5=3,7=0
P 1.065 6.26 11 P 0 0;3,5=3,7=0
P 1.065 6.36 11 P 0 0;3,5=3,7=0
P 1.29 6.26 11 P 0 0;3,5=3,7=0
P 1.29 6.36 11 P 0 0;3,5=3,7=0
P 1.515 6.26 11 P 0 0;3,5=3,7=0
P 1.515 6.36 11 P 0 0;3,5=3,7=0
P 0.84 6.26 11 P 0 0;3,5=3,7=0
L 8.8 6.30445 0.846 6.30445 2 P 0 
L 0.846 6.30445 0.84 6.29845 2 P 0 
L 0.84 6.29845 0.84 6.26 2 P 0 
P 0.84 6.36 11 P 0 0;3,5=3,7=0
L 8.8 6.31555 0.846 6.31555 2 P 0 
L 0.846 6.31555 0.84 6.32155 2 P 0 
L 0.84 6.32155 0.84 6.36 2 P 0 
P 1.74 6.26 11 P 0 0;3,5=3,7=0
P 1.74 6.36 11 P 0 0;3,5=3,7=0
L 1.9 3.61 1.95001004 3.61 3 P 0 
L 1.95001004 3.61 1.96886004 3.59115 3 P 0 
L 1.96886004 3.59115 2.07106004 3.59115 3 P 0 
L 2.07106004 3.59115 2.09606004 3.56615 3 P 0 
L 1.857 3.61 1.9 3.61 3 P 0 
P 1.857 3.61 25 P 0 0;2,5=0,7=0
P 2.09606004 3.56615 6 P 0 0;5=4,7=1
P 1.9 3.61 8 P 0 0;3,5=5,7=1
P 7.86093996 3.61 25 P 0 0;2,5=0,7=0
L 7.90393996 3.61 7.86093996 3.61 3 P 0 
P 7.90393996 3.61 8 P 0 0;3,5=5,7=1
L 7.90393996 3.61 7.95395 3.61 3 P 0 
L 7.95395 3.61 7.9728 3.59115 3 P 0 
L 7.9728 3.59115 8.075 3.59115 3 P 0 
L 8.075 3.59115 8.1 3.56615 3 P 0 
P 8.1 3.56615 6 P 0 0;5=4,7=1
P 12.55905 3.38188996 11 P 0 0;3,5=2,7=0
P 12.81495 4.64173996 11 P 0 0;3,5=2,7=0
P 12.81495 1.88583002 11 P 0 0;3,5=2,7=0
P 0.35038996 4.60236998 11 P 0 0;3,5=2,7=0
P 0.35038996 2.55511998 11 P 0 0;3,5=2,7=0
P 0.35038996 1.84646004 11 P 0 0;3,5=2,7=0
P 0.09448996 3.34251998 11 P 0 0;3,5=2,7=0
L 6.42418996 4.99705 6.42418996 4.96418996 3 P 0 
L 6.42418996 4.96418996 6.415 4.955 3 P 0 
L 6.42418996 4.99705 6.38348996 4.99705 3 P 0 
P 6.38348996 4.99705 25 P 0 0;2,5=0,7=0
P 6.42418996 4.99705 25 P 0 0;2,5=0,7=0
L 6.38348996 4.99705 6.38348996 5.02848996 3 P 0 
L 6.38348996 5.02848996 6.385 5.03 3 P 0 
P 6.385 5.03 7 P 0 0;5=6,7=1
P 6.415 4.955 8 P 0 0;3,5=5,7=1
P 12.68701998 0.97243996 16 P 0 0;5=7
P 0.22245 0.93306998 16 P 0 0;5=7
P 12.68701004 4.91338002 16 P 0 0;5=7
P 3.94 4.545 8 P 0 0;3,5=1,7=1
P 4.91 5.375 7 P 0 0;5=6,7=1
L 3.94 4.545 4.105 4.545 3 P 0 
L 4.105 4.545 4.175 4.615 3 P 0 
L 4.175 4.615 4.175 5.26 3 P 0 
L 4.175 5.26 4.225 5.31 3 P 0 
L 4.225 5.31 4.845 5.31 3 P 0 
L 4.845 5.31 4.91 5.375 3 P 0 
L 1.08 5.85 1.08 5.9 3 P 0 
L 1.08 5.9 1.1 5.92 3 P 0 
L 1.1 5.92 3.5017 5.92 3 P 0 
L 3.5017 5.92 3.6817 5.74 3 P 0 
P 1.08 5.85 8 P 0 0;3,5=1,7=1
P 3.6817 5.74 7 P 0 0;5=6,7=1
L 10.099 2.928 10.07 2.928 3 P 0 
L 10.099 2.928 10.099 2.88 3 P 0 
L 10.099 2.88 10.07778996 2.88 3 P 0 
L 10.07778996 2.88 10.07338002 2.87558996 3 P 0 
L 10.07338002 2.87558996 10.03813996 2.87558996 3 P 0 
P 10.03813996 2.87558996 30 P 0 0;2,5=8,7=0
P 10.099 2.88 25 P 0 0;2,5=0,7=0
P 10.099 2.928 25 P 0 0;2,5=0,7=0
P 10.07 2.928 7 P 0 0;5=6,7=1
P 4.105 4.985 8 P 0 0;3,5=1,7=1
L 4.057 2.7 4.057 2.65013996 3 P 0 
L 4.057 2.65013996 4.05686004 2.65 3 P 0 
L 3.99421004 2.64558996 4.02945 2.64558996 3 P 0 
L 4.02945 2.64558996 4.03386004 2.65 3 P 0 
L 4.03386004 2.65 4.05686004 2.65 3 P 0 
P 4.05686004 2.65 25 P 0 0;2,5=0,7=0
P 3.99421004 2.64558996 30 P 0 0;2,5=8,7=0
P 4.057 2.7 25 P 0 0;2,5=0,7=0
P 4.125 2.725 7 P 0 0;5=6,7=1
L 4.125 2.725 4.12 2.73 3 P 0 
L 4.12 2.73 4.0702 2.73 3 P 0 
L 4.0702 2.73 4.057 2.7168 3 P 0 
L 4.057 2.7168 4.057 2.7 3 P 0 
P 4.02 4.355 8 P 0 0;3,5=1,7=1
L 1.16 5.85 3.5 5.85 3 P 0 
L 3.5 5.85 3.645 5.705 3 P 0 
L 3.645 5.705 3.705 5.705 3 P 0 
L 3.705 5.705 3.815 5.815 3 P 0 
P 1.16 5.85 8 P 0 0;3,5=1,7=1
P 3.815 5.815 7 P 0 0;5=6,7=1
P 1.19 6.36 26 P 0 0;3,5=9,7=0
P 1.19 6.26 26 P 0 0;5=9,7=0
P 1.415 6.36 26 P 0 0;5=9,7=0
P 1.415 6.26 26 P 0 0;5=9,7=0
P 1.64 6.36 26 P 0 0;5=9,7=0
P 1.64 6.26 26 P 0 0;5=9,7=0
P 0.965 6.26 26 P 0 0;5=9,7=0
P 0.965 6.36 26 P 0 0;5=9,7=0
P 0.74 6.26 26 P 0 0;5=9,7=0
P 0.74 6.36 26 P 0 0;3,5=9,7=0
L 12.33998996 1.3061 12.56986998 1.3061 3 P 0 
L 12.56986998 1.3061 12.63778996 1.37401998 3 P 0 
P 12.33998996 1.3061 25 P 0 0;2,5=0,7=0
P 12.63778996 1.37401998 26 P 0 0;3,5=10,7=0
L 0.17323002 1.33465 0.17323002 1.296 3 P 0 
L 0.17323002 1.296 0.19113002 1.2781 3 P 0 
L 0.19113002 1.2781 0.52298996 1.2781 3 P 0 
L 0.52298996 1.2781 0.58298996 1.3381 3 P 0 
P 0.17323002 1.33465 26 P 0 0;3,5=10,7=0
P 0.58298996 1.3381 25 P 0 0;2,5=0,7=0
L 6.45818996 4.99705 6.47813996 5.017 3 P 0 
L 6.47813996 5.017 6.501 5.017 3 P 0 
P 6.501 5.017 8 P 0 0;3,5=1,7=1
P 6.45818996 4.99705 25 P 0 0;2,5=0,7=0
L 7.425 3.43 7.47363996 3.43 3 P 0 
L 7.47363996 3.43 7.65363996 3.61 3 P 0 
L 7.65363996 3.61 7.82693996 3.61 3 P 0 
P 7.82693996 3.61 25 P 0 0;2,5=0,7=0
P 7.425 3.43 8 P 0 0;3,5=1,7=1
P 7.445 1.705 7 P 0 0;5=6,7=1
P 11.03661004 3.81615 6 P 0 0;5=4,7=1
P 11.135 2.845 7 P 0 0;5=6,7=1
P 11.03661004 2.16615 6 P 0 0;5=4,7=1
P 3.8899 4.765 8 P 0 0;3,5=1,7=1
P 4.93268002 2.41615 6 P 0 0;5=4,7=1
L 4.93268002 2.41615 4.93268002 2.4296 2 P 0 
L 4.93268002 2.4296 4.93868002 2.4356 2 P 0 
L 4.93868002 2.4356 4.95073002 2.4356 2 P 0 
L 4.95073002 2.4356 4.96323002 2.4481 2 P 0 
L 4.96323002 2.4481 4.96323002 2.5296 2 P 0 
L 4.96323002 2.5296 4.96923002 2.5356 2 P 0 
L 4.96923002 2.5356 5.1213 2.5356 2 P 0 
L 5.1213 2.5356 5.23315 2.64745 2 P 0 
L 5.23315 2.64745 5.44663002 2.64745 2 P 0 
L 5.44663002 2.64745 5.46358002 2.6305 2 P 0 
P 5.46358002 2.6305 25 P 0 0;2,5=0,7=0
P 4.93268002 2.46615 6 P 0 0;5=4,7=1
L 4.93268002 2.46615 4.93268002 2.4527 2 P 0 
L 4.93268002 2.4527 4.93868002 2.4467 2 P 0 
L 4.93868002 2.4467 4.94613002 2.4467 2 P 0 
L 4.94613002 2.4467 4.95213002 2.4527 2 P 0 
L 4.95213002 2.4527 4.95213002 2.5342 2 P 0 
L 4.95213002 2.5342 4.96463002 2.5467 2 P 0 
L 4.96463002 2.5467 5.1167 2.5467 2 P 0 
L 5.1167 2.5467 5.22855 2.65855 2 P 0 
L 5.22855 2.65855 5.44663002 2.65855 2 P 0 
L 5.44663002 2.65855 5.46358002 2.6755 2 P 0 
P 5.46358002 2.6755 25 P 0 0;2,5=0,7=0
L 7.2926 5.04351004 7.3226 5.01351004 3 P 0 
L 7.3226 5.01351004 7.3226 4.97551004 3 P 0 
P 7.2926 5.04351004 8 P 0 0;3,5=1,7=1
P 7.3226 4.97551004 25 P 0 0;2,5=0,7=0
L 7.2426 5.04351004 7.25575 5.03036004 3 P 0 
L 7.25575 5.03036004 7.25575 5.02823996 3 P 0 
L 7.25575 5.02823996 7.2726 5.01138996 3 P 0 
L 7.2726 5.01138996 7.2726 4.97551004 3 P 0 
P 7.2426 5.04351004 8 P 0 0;3,5=1,7=1
P 7.2726 4.97551004 25 P 0 0;2,5=0,7=0
L 3.33646004 5.298 3.38146004 5.298 3 P 0 
P 3.38146004 5.298 25 P 0 0;2,5=0,7=0
P 3.33646004 5.298 25 P 0 0;2,5=0,7=0
L 3.38146004 5.298 3.45446004 5.298 3 P 0 
L 3.45446004 5.298 3.45646004 5.3 3 P 0 
P 3.45646004 5.3 8 P 0 0;3,5=1,7=1
P 1.28906004 5.04351004 8 P 0 0;3,5=1,7=1
P 1.31906004 4.97551004 25 P 0 0;2,5=0,7=0
L 1.28906004 5.04351004 1.31906004 5.01351004 3 P 0 
L 1.31906004 5.01351004 1.31906004 4.97551004 3 P 0 
L 1.23906004 5.04351004 1.25221004 5.03036004 3 P 0 
L 1.25221004 5.03036004 1.25221004 5.02823996 3 P 0 
L 1.25221004 5.02823996 1.26906004 5.01138996 3 P 0 
L 1.26906004 5.01138996 1.26906004 4.97551004 3 P 0 
P 1.23906004 5.04351004 8 P 0 0;3,5=1,7=1
P 1.26906004 4.97551004 25 P 0 0;2,5=0,7=0
L 9.46 5.3 9.458 5.298 3 P 0 
L 9.458 5.298 9.385 5.298 3 P 0 
L 9.34 5.298 9.385 5.298 3 P 0 
P 9.385 5.298 25 P 0 0;2,5=0,7=0
P 9.34 5.298 25 P 0 0;2,5=0,7=0
P 9.46 5.3 8 P 0 0;3,5=1,7=1
P 4.68268002 2.36615 6 P 0 0;5=4,7=1
P 0.27165 4.01181004 11 P 0 0;3,5=2,7=0
P 4.58268002 2.36615 6 P 0 0;5=4,7=1
P 0.27165 4.16928996 11 P 0 0;3,5=2,7=0
P 4.63268002 2.41615 6 P 0 0;5=4,7=1
P 0.27165 4.32676998 11 P 0 0;3,5=2,7=0
P 4.73268002 2.26615 6 P 0 0;5=4,7=1
P 0.27165 3.38188996 11 P 0 0;3,5=2,7=0
P 4.73268002 2.41615 6 P 0 0;5=4,7=1
P 0.27165 4.48425 11 P 0 0;3,5=2,7=0
P 4.68268002 2.21615 6 P 0 0;5=4,7=1
P 0.27165 3.53936998 11 P 0 0;3,5=2,7=0
P 4.63268002 2.26615 6 P 0 0;5=4,7=1
P 0.27165 3.85433002 11 P 0 0;3,5=2,7=0
P 4.58268002 2.06615 6 P 0 0;5=4,7=1
P 0.35038996 3.02756004 11 P 0 0;3,5=2,7=0
P 4.58268002 2.11615 6 P 0 0;5=4,7=1
P 0.27165 2.98818996 11 P 0 0;3,5=2,7=0
P 4.63268002 1.86615 6 P 0 0;5=4,7=1
P 0.35038996 2.3189 11 P 0 0;3,5=2,7=0
P 4.58268002 1.96615 6 P 0 0;5=4,7=1
P 0.27165 2.43701004 11 P 0 0;3,5=2,7=0
P 4.68268002 2.06615 6 P 0 0;5=4,7=1
P 0.35038996 3.18503996 11 P 0 0;3,5=2,7=0
P 4.58268002 1.91615 6 P 0 0;5=4,7=1
P 0.35038996 2.47638002 11 P 0 0;3,5=2,7=0
P 0.27165 2.27953002 11 P 0 0;3,5=2,7=0
P 4.63268002 1.91615 6 P 0 0;5=4,7=1
L 5.34275 1.7371 5.36065 1.755 2 P 0 
L 5.36065 1.755 5.40508002 1.755 2 P 0 
L 5.40508002 1.755 5.42048002 1.7396 2 P 0 
P 5.42048002 1.7396 6 P 0 0;5=4,7=1
P 5.34275 1.7371 25 P 0 0;2,5=0,7=0
P 0.09448996 2.55511998 11 P 0 0;3,5=2,7=0
P 4.68268002 2.11615 6 P 0 0;5=4,7=1
P 0.27165 3.14566998 11 P 0 0;3,5=2,7=0
L 5.34275 1.7821 5.35875 1.7661 2 P 0 
L 5.35875 1.7661 5.40698002 1.7661 2 P 0 
L 5.40698002 1.7661 5.42048002 1.7796 2 P 0 
P 5.42048002 1.7796 6 P 0 0;5=4,7=1
P 5.34275 1.7821 25 P 0 0;2,5=0,7=0
P 0.17323002 2.51575 11 P 0 0;3,5=2,7=0
P 4.68268002 1.91615 6 P 0 0;5=4,7=1
P 0.35038996 2.16141998 11 P 0 0;3,5=2,7=0
P 4.68268002 1.96615 6 P 0 0;5=4,7=1
P 0.27165 2.12205 11 P 0 0;3,5=2,7=0
L 5.57531004 2.0878 5.55991004 2.1032 2 P 0 
L 5.55991004 2.1032 5.51548002 2.1032 2 P 0 
L 5.51548002 2.1032 5.49758002 2.0853 2 P 0 
P 5.49758002 2.0853 25 P 0 0;2,5=0,7=0
P 5.57531004 2.0878 6 P 0 0;5=4,7=1
P 0.09448996 3.1063 11 P 0 0;3,5=2,7=0
L 5.57531004 2.1278 5.56181004 2.1143 2 P 0 
L 5.56181004 2.1143 5.51358002 2.1143 2 P 0 
L 5.51358002 2.1143 5.49758002 2.1303 2 P 0 
P 5.49758002 2.1303 25 P 0 0;2,5=0,7=0
P 5.57531004 2.1278 6 P 0 0;5=4,7=1
P 0.17323002 3.06693002 11 P 0 0;3,5=2,7=0
L 5.49758002 2.2207 5.51548002 2.2386 2 P 0 
L 5.51548002 2.2386 5.55991004 2.2386 2 P 0 
L 5.55991004 2.2386 5.57531004 2.2232 2 P 0 
P 5.49758002 2.2207 25 P 0 0;2,5=0,7=0
P 5.57531004 2.2232 6 P 0 0;5=4,7=1
P 0.17323002 3.46063002 11 P 0 0;3,5=2,7=0
L 5.49758002 2.2657 5.51358002 2.2497 2 P 0 
L 5.51358002 2.2497 5.56181004 2.2497 2 P 0 
L 5.56181004 2.2497 5.57531004 2.2632 2 P 0 
P 5.49758002 2.2657 25 P 0 0;2,5=0,7=0
P 5.57531004 2.2632 6 P 0 0;5=4,7=1
P 0.09448996 3.42126004 11 P 0 0;3,5=2,7=0
L 5.42048002 2.4662 5.40698002 2.4527 2 P 0 
L 5.40698002 2.4527 5.35875 2.4527 2 P 0 
L 5.35875 2.4527 5.34275 2.4687 2 P 0 
P 5.34275 2.4687 25 P 0 0;2,5=0,7=0
P 5.42048002 2.4662 6 P 0 0;5=4,7=1
P 0.09448996 4.05118002 11 P 0 0;3,5=2,7=0
P 5.49758002 2.4011 25 P 0 0;2,5=0,7=0
L 5.57531004 2.3986 5.56181004 2.3851 2 P 0 
L 5.56181004 2.3851 5.51358002 2.3851 2 P 0 
L 5.51358002 2.3851 5.49758002 2.4011 2 P 0 
P 5.57531004 2.3986 6 P 0 0;5=4,7=1
P 0.09448996 3.8937 11 P 0 0;3,5=2,7=0
L 5.49758002 2.6755 5.51358002 2.6595 2 P 0 
L 5.51358002 2.6595 5.56181004 2.6595 2 P 0 
L 5.56181004 2.6595 5.57531004 2.673 2 P 0 
P 5.49758002 2.6755 25 P 0 0;2,5=0,7=0
P 5.57531004 2.673 6 P 0 0;5=4,7=1
P 0.09448996 4.36613996 11 P 0 0;3,5=2,7=0
L 5.57531004 1.9869 5.56181004 1.9734 2 P 0 
L 5.56181004 1.9734 5.51358002 1.9734 2 P 0 
L 5.51358002 1.9734 5.49758002 1.9894 2 P 0 
P 5.49758002 1.9894 25 P 0 0;2,5=0,7=0
P 5.57531004 1.9869 6 P 0 0;5=4,7=1
P 0.17323002 2.75196998 11 P 0 0;3,5=2,7=0
L 5.57531004 2.4978 5.55991004 2.5132 2 P 0 
L 5.55991004 2.5132 5.51548002 2.5132 2 P 0 
L 5.51548002 2.5132 5.49758002 2.4953 2 P 0 
P 5.49758002 2.4953 25 P 0 0;2,5=0,7=0
P 5.57531004 2.4978 6 P 0 0;5=4,7=1
P 0.17323002 4.24803002 11 P 0 0;3,5=2,7=0
L 5.49758002 1.6693 5.51548002 1.6872 2 P 0 
L 5.51548002 1.6872 5.55991004 1.6872 2 P 0 
L 5.55991004 1.6872 5.57531004 1.6718 2 P 0 
P 5.57531004 1.6718 6 P 0 0;5=4,7=1
P 5.49758002 1.6693 25 P 0 0;2,5=0,7=0
P 0.17323002 2.20078996 11 P 0 0;3,5=2,7=0
L 5.49758002 2.6305 5.51548002 2.6484 2 P 0 
L 5.51548002 2.6484 5.55991004 2.6484 2 P 0 
L 5.55991004 2.6484 5.57531004 2.633 2 P 0 
P 5.49758002 2.6305 25 P 0 0;2,5=0,7=0
P 5.57531004 2.633 6 P 0 0;5=4,7=1
P 0.17323002 4.40551004 11 P 0 0;3,5=2,7=0
L 5.49758002 1.7143 5.51358002 1.6983 2 P 0 
L 5.51358002 1.6983 5.56181004 1.6983 2 P 0 
L 5.56181004 1.6983 5.57531004 1.7118 2 P 0 
P 5.57531004 1.7118 6 P 0 0;5=4,7=1
P 5.49758002 1.7143 25 P 0 0;2,5=0,7=0
P 0.09448996 2.24016004 11 P 0 0;3,5=2,7=0
L 5.57531004 2.5378 5.56181004 2.5243 2 P 0 
L 5.56181004 2.5243 5.51358002 2.5243 2 P 0 
L 5.51358002 2.5243 5.49758002 2.5403 2 P 0 
P 5.49758002 2.5403 25 P 0 0;2,5=0,7=0
P 5.57531004 2.5378 6 P 0 0;5=4,7=1
P 0.09448996 4.20866004 11 P 0 0;3,5=2,7=0
L 5.34275 1.6458 5.35875 1.6298 2 P 0 
L 5.35875 1.6298 5.40698002 1.6298 2 P 0 
L 5.40698002 1.6298 5.42048002 1.6433 2 P 0 
P 5.42048002 1.6433 6 P 0 0;5=4,7=1
P 5.34275 1.6458 25 P 0 0;2,5=0,7=0
P 0.09448996 2.39763996 11 P 0 0;3,5=2,7=0
L 5.42048002 2.6054 5.40698002 2.5919 2 P 0 
L 5.40698002 2.5919 5.35875 2.5919 2 P 0 
L 5.35875 2.5919 5.34275 2.6079 2 P 0 
P 5.34275 2.6079 25 P 0 0;2,5=0,7=0
P 5.42048002 2.6054 6 P 0 0;5=4,7=1
P 0.09448996 4.52361998 11 P 0 0;3,5=2,7=0
L 5.42048002 1.87835 5.40413002 1.8947 2 P 0 
L 5.40413002 1.8947 5.36065 1.8947 2 P 0 
L 5.36065 1.8947 5.34275 1.8768 2 P 0 
P 5.34275 1.8768 25 P 0 0;2,5=0,7=0
P 5.42048002 1.87835 6 P 0 0;5=4,7=1
P 0.09448996 2.94881998 11 P 0 0;3,5=2,7=0
P 5.49758002 2.3561 25 P 0 0;2,5=0,7=0
L 5.57531004 2.3586 5.55991004 2.374 2 P 0 
L 5.55991004 2.374 5.51548002 2.374 2 P 0 
L 5.51548002 2.374 5.49758002 2.3561 2 P 0 
P 5.57531004 2.3586 6 P 0 0;5=4,7=1
P 0.17323002 3.93306998 11 P 0 0;3,5=2,7=0
L 5.34275 1.6008 5.36065 1.6187 2 P 0 
L 5.36065 1.6187 5.40508002 1.6187 2 P 0 
L 5.40508002 1.6187 5.42048002 1.6033 2 P 0 
P 5.42048002 1.6033 6 P 0 0;5=4,7=1
P 5.34275 1.6008 25 P 0 0;2,5=0,7=0
P 0.17323002 2.35826998 11 P 0 0;3,5=2,7=0
L 5.42048002 2.4262 5.40508002 2.4416 2 P 0 
L 5.40508002 2.4416 5.36065 2.4416 2 P 0 
L 5.36065 2.4416 5.34275 2.4237 2 P 0 
P 5.34275 2.4237 25 P 0 0;2,5=0,7=0
P 5.42048002 2.4262 6 P 0 0;5=4,7=1
P 0.17323002 4.09055 11 P 0 0;3,5=2,7=0
P 5.34275 1.9218 25 P 0 0;2,5=0,7=0
P 5.42048002 1.91835 6 P 0 0;5=4,7=1
P 0.17323002 2.90945 11 P 0 0;3,5=2,7=0
L 5.42048002 1.91835 5.40793002 1.9058 2 P 0 
L 5.40793002 1.9058 5.35875 1.9058 2 P 0 
L 5.35875 1.9058 5.34275 1.9218 2 P 0 
L 5.42048002 2.0547 5.40698002 2.0412 2 P 0 
L 5.40698002 2.0412 5.35875 2.0412 2 P 0 
L 5.35875 2.0412 5.34275 2.0572 2 P 0 
P 5.34275 2.0572 25 P 0 0;2,5=0,7=0
P 5.42048002 2.0547 6 P 0 0;5=4,7=1
P 0.17323002 3.22441004 11 P 0 0;3,5=2,7=0
L 5.57531004 1.9469 5.55991004 1.9623 2 P 0 
L 5.55991004 1.9623 5.51548002 1.9623 2 P 0 
L 5.51548002 1.9623 5.49758002 1.9444 2 P 0 
P 5.49758002 1.9444 25 P 0 0;2,5=0,7=0
P 5.57531004 1.9469 6 P 0 0;5=4,7=1
P 0.09448996 2.79133996 11 P 0 0;3,5=2,7=0
L 5.42048002 2.0147 5.40508002 2.0301 2 P 0 
L 5.40508002 2.0301 5.36065 2.0301 2 P 0 
L 5.36065 2.0301 5.34275 2.0122 2 P 0 
P 5.34275 2.0122 25 P 0 0;2,5=0,7=0
P 5.42048002 2.0147 6 P 0 0;5=4,7=1
P 0.09448996 3.26378002 11 P 0 0;3,5=2,7=0
L 5.57531004 1.8508 5.56181004 1.8373 2 P 0 
L 5.56181004 1.8373 5.51358002 1.8373 2 P 0 
L 5.51358002 1.8373 5.49758002 1.8533 2 P 0 
P 5.57531004 1.8508 6 P 0 0;5=4,7=1
P 5.49758002 1.8533 25 P 0 0;2,5=0,7=0
P 0.09448996 2.00393996 11 P 0 0;3,5=2,7=0
L 5.57531004 1.8108 5.55991004 1.8262 2 P 0 
L 5.55991004 1.8262 5.51548002 1.8262 2 P 0 
L 5.51548002 1.8262 5.49758002 1.8083 2 P 0 
P 5.57531004 1.8108 6 P 0 0;5=4,7=1
P 5.49758002 1.8083 25 P 0 0;2,5=0,7=0
P 0.17323002 2.04331004 11 P 0 0;3,5=2,7=0
P 0.35038996 3.97243996 11 P 0 0;3,5=2,7=0
P 4.68268002 2.41615 6 P 0 0;5=4,7=1
P 4.73268002 2.46615 6 P 0 0;5=4,7=1
P 0.35038996 4.44488002 11 P 0 0;3,5=2,7=0
P 4.63268002 2.46615 6 P 0 0;5=4,7=1
P 0.35038996 4.2874 11 P 0 0;3,5=2,7=0
P 0.35038996 4.12991998 11 P 0 0;3,5=2,7=0
P 4.58268002 2.41615 6 P 0 0;5=4,7=1
P 4.68268002 2.26615 6 P 0 0;5=4,7=1
P 0.35038996 3.5 11 P 0 0;3,5=2,7=0
L 5.34275 2.1529 5.36065 2.1708 2 P 0 
L 5.36065 2.1708 5.40508002 2.1708 2 P 0 
L 5.40508002 2.1708 5.42048002 2.1554 2 P 0 
P 5.34275 2.1529 25 P 0 0;2,5=0,7=0
P 5.42048002 2.1554 6 P 0 0;5=4,7=1
P 0.17323002 3.77558996 11 P 0 0;3,5=2,7=0
P 4.73268002 2.31615 6 P 0 0;5=4,7=1
P 0.35038996 3.34251998 11 P 0 0;3,5=2,7=0
P 4.63268002 2.31615 6 P 0 0;5=4,7=1
P 0.35038996 3.81496004 11 P 0 0;3,5=2,7=0
P 4.58268002 2.26615 6 P 0 0;5=4,7=1
P 0.35038996 3.65748002 11 P 0 0;3,5=2,7=0
L 5.42048002 2.5654 5.40508002 2.5808 2 P 0 
L 5.40508002 2.5808 5.36065 2.5808 2 P 0 
L 5.36065 2.5808 5.34275 2.5629 2 P 0 
P 5.34275 2.5629 25 P 0 0;2,5=0,7=0
P 5.42048002 2.5654 6 P 0 0;5=4,7=1
P 0.17323002 4.563 11 P 0 0;3,5=2,7=0
L 5.34275 2.1979 5.35875 2.1819 2 P 0 
L 5.35875 2.1819 5.40698002 2.1819 2 P 0 
L 5.40698002 2.1819 5.42048002 2.1954 2 P 0 
P 5.34275 2.1979 25 P 0 0;2,5=0,7=0
P 5.42048002 2.1954 6 P 0 0;5=4,7=1
P 0.09448996 3.73621998 11 P 0 0;3,5=2,7=0
P 0.09448996 3.57873996 11 P 0 0;3,5=2,7=0
P 5.42048002 2.3308 6 P 0 0;5=4,7=1
L 5.42048002 2.3308 5.40698002 2.3173 2 P 0 
L 5.40698002 2.3173 5.35875 2.3173 2 P 0 
L 5.35875 2.3173 5.34275 2.3333 2 P 0 
P 5.34275 2.3333 25 P 0 0;2,5=0,7=0
P 0.17323002 3.61811004 11 P 0 0;3,5=2,7=0
P 5.42048002 2.2908 6 P 0 0;5=4,7=1
L 5.42048002 2.2908 5.40508002 2.3062 2 P 0 
L 5.40508002 2.3062 5.36065 2.3062 2 P 0 
L 5.36065 2.3062 5.34275 2.2883 2 P 0 
P 5.34275 2.2883 25 P 0 0;2,5=0,7=0
P 0.35038996 1.9252 11 P 0 0;3,5=2,7=0
P 4.73268002 1.91615 6 P 0 0;5=4,7=1
P 4.73268002 1.86615 6 P 0 0;5=4,7=1
P 0.27165 1.96456998 11 P 0 0;3,5=2,7=0
P 4.58268002 2.21615 6 P 0 0;5=4,7=1
P 0.27165 3.69685 11 P 0 0;3,5=2,7=0
P 4.73268002 2.06615 6 P 0 0;5=4,7=1
P 0.27165 2.67323002 11 P 0 0;3,5=2,7=0
P 4.73268002 2.01615 6 P 0 0;5=4,7=1
P 0.35038996 2.7126 11 P 0 0;3,5=2,7=0
P 4.63268002 2.01615 6 P 0 0;5=4,7=1
P 0.35038996 2.87008002 11 P 0 0;3,5=2,7=0
P 4.63268002 2.06615 6 P 0 0;5=4,7=1
P 0.27165 2.83071004 11 P 0 0;3,5=2,7=0
P 6.785 4.725 7 P 0 0;5=6,7=1
P 6.785 4.685 7 P 0 0;5=6,7=1
P 6.74018996 4.765 7 P 0 0;5=6,7=1
P 6.74 4.805 8 P 0 0;3,5=1,7=1
P 6.785 4.845 7 P 0 0;5=6,7=1
P 6.785 4.805 7 P 0 0;5=6,7=1
P 6.785 4.765 7 P 0 0;5=6,7=1
P 6.74 4.845 7 P 0 0;5=6,7=1
P 6.83118996 4.73868002 27 P 0 0;2,5=11,7=0
P 6.74208996 4.6252 27 P 0 0;2,5=11,7=0
P 6.74208996 4.7052 27 P 0 0;2,5=11,7=0
P 6.83118996 4.81705 27 P 0 0;2,5=11,7=0
P 6.83318996 4.89705 25 P 0 0;2,5=0,7=0
S P 0
OB 6.72118996063 4.86205 I
OS 6.805 4.86205
OS 6.822 4.87905
OS 6.822 4.907
OS 6.826 4.911
OS 6.852 4.911
OS 6.85618996063 4.90681003937
OS 6.85618996063 4.6023
OS 6.85008996063 4.5962
OS 6.72108996063 4.5962
OS 6.71618996063 4.6011
OS 6.71618996063 4.85705
OS 6.72118996063 4.86205
OE
SE
P 6.65 5.055 8 P 0 0;3,5=1,7=1
L 6.53918996 5.09705 6.49205 5.09705 3 P 0 
L 6.45818996 5.04705 6.45818996 5.08038996 3 P 0 
L 6.45818996 5.08038996 6.47485 5.09705 3 P 0 
L 6.47485 5.09705 6.49205 5.09705 3 P 0 
P 6.53918996 5.09705 25 P 0 0;2,5=0,7=0
P 6.49205 5.09705 8 P 0 0;3,5=1,7=1
P 6.45818996 5.04705 25 P 0 0;2,5=0,7=0
P 6.495 4.9328 8 P 0 0;3,5=1,7=1
L 6.55118996 5.04705 6.57418996 5.02405 4 P 0 
L 6.57418996 5.02405 6.57418996 4.99705 4 P 0 
P 6.57418996 4.99705 25 P 0 0;2,5=0,7=0
P 6.55118996 5.04705 8 P 0 0;3,5=1,7=1
L 6.60818996 4.99705 6.65418996 4.99705 5 P 0 
P 6.65418996 4.99705 25 P 0 0;2,5=0,7=0
P 6.60818996 4.99705 25 P 0 0;2,5=0,7=0
P 6.78 4.94705 8 P 0 0;3,5=1,7=1
L 6.78 4.94705 6.77495 4.942 5 P 0 
L 6.77495 4.942 6.684 4.942 5 P 0 
L 6.684 4.942 6.65418996 4.97181004 5 P 0 
L 6.65418996 4.97181004 6.65418996 4.99705 5 P 0 
L 6.79918996 4.89705 6.755 4.89705 7 P 0 
P 6.755 4.89705 8 P 0 0;3,5=1,7=1
P 6.79918996 4.89705 25 P 0 0;2,5=0,7=0
L 6.74 4.987 6.767 4.987 4 P 0 
L 6.767 4.987 6.78 5 4 P 0 
L 6.78 5 6.803 5 4 P 0 
L 6.68818996 4.99705 6.70995 4.99705 4 P 0 
L 6.70995 4.99705 6.72 4.987 4 P 0 
L 6.72 4.987 6.74 4.987 4 P 0 
P 6.74 4.987 8 P 0 0;3,5=1,7=1
P 6.68818996 4.99705 25 P 0 0;2,5=0,7=0
P 6.803 5 25 P 0 0;2,5=0,7=0
L 12.84813996 2.63386004 12.854 2.628 3 P 0 
L 12.854 2.628 12.854 2.09536004 3 P 0 
L 12.854 2.09536004 12.84131998 2.08268002 3 P 0 
L 12.84131998 2.08268002 12.853 2.071 3 P 0 
L 12.853 2.071 12.853 1.56 3 P 0 
L 12.853 1.56 12.823 1.53 3 P 0 
L 12.823 1.53 12.79101004 1.53 3 P 0 
L 12.79101004 1.53 12.75401004 1.493 3 P 0 
L 12.75401004 1.493 12.62096998 1.493 3 P 0 
L 12.62096998 1.493 12.58096998 1.453 3 P 0 
L 12.58096998 1.453 12.45288996 1.453 3 P 0 
L 12.45288996 1.453 12.33998996 1.3401 3 P 0 
L 12.84813996 2.63386004 12.73621004 2.63386004 3 P 0 
P 12.33998996 1.3401 25 P 0 0;2,5=0,7=0
P 12.34198002 2.155 25 P 0 0;2,5=0,7=0
P 12.73621004 2.08268002 11 P 0 0;3,5=2,7=0
L 12.73621004 2.08268002 12.84131998 2.08268002 3 P 0 
L 12.73621004 2.08268002 12.685 2.13388996 3 P 0 
L 12.685 2.13388996 12.685 2.175 3 P 0 
L 12.685 2.175 12.66 2.2 3 P 0 
L 12.66 2.2 12.615 2.2 3 P 0 
L 12.615 2.2 12.57498996 2.15998996 3 P 0 
L 12.57498996 2.15998996 12.49016004 2.15998996 3 P 0 
L 12.49016004 2.15998996 12.48516004 2.15498996 3 P 0 
L 12.48516004 2.15498996 12.34198996 2.15498996 3 P 0 
L 12.34198996 2.15498996 12.34198002 2.155 3 P 0 
P 12.73621004 2.63386004 11 P 0 0;5=2,7=0
L 12.81495 3.30315 12.853 3.2651 3 P 0 
L 12.853 3.2651 12.853 2.63871998 3 P 0 
L 12.853 2.63871998 12.84813996 2.63386004 3 P 0 
P 12.81495 3.30315 11 P 0 0;5=2,7=0
L 12.73621004 4.60236998 12.84163002 4.60236998 3 P 0 
L 12.84163002 4.60236998 12.854 4.59 3 P 0 
L 12.854 4.59 12.854 3.3422 3 P 0 
L 12.854 3.3422 12.81495 3.30315 3 P 0 
P 12.73621004 4.60236998 11 P 0 0;5=2,7=0
P 12.33901004 1.93958996 25 P 0 0;2,5=0,7=0
P 12.55905 1.96456998 11 P 0 0;3,5=2,7=0
L 12.33901004 1.93958996 12.35846004 1.95903996 2 P 0 
L 12.35846004 1.95903996 12.38243996 1.95903996 2 P 0 
L 12.38243996 1.95903996 12.40413996 1.96286004 2 P 0 
L 12.40413996 1.96286004 12.41003996 1.95871998 2 P 0 
L 12.41003996 1.95871998 12.42778002 1.96183996 2 P 0 
L 12.42778002 1.96183996 12.43191998 1.96776004 2 P 0 
L 12.43191998 1.96776004 12.44963996 1.97088002 2 P 0 
L 12.44963996 1.97088002 12.45553996 1.96673996 2 P 0 
L 12.45553996 1.96673996 12.47328002 1.96986004 2 P 0 
L 12.47328002 1.96986004 12.47741998 1.97578002 2 P 0 
L 12.47741998 1.97578002 12.49513996 1.9789 2 P 0 
L 12.49513996 1.9789 12.51563996 1.99326004 2 P 0 
L 12.51563996 1.99326004 12.51563996 1.99325 2 P 0 
L 12.51563996 1.99325 12.542 1.9979 2 P 0 
L 12.542 1.9979 12.57958996 1.9979 2 P 0 
L 12.57958996 1.9979 12.6036 1.97388996 2 P 0 
L 12.6036 1.97388996 12.6036 1.9576 2 P 0 
L 12.6036 1.9576 12.59528002 1.94928002 2 P 0 
L 12.59528002 1.94928002 12.58963002 1.94928002 2 P 0 
L 12.58963002 1.94928002 12.55905 1.96456998 2 P 0 
P 12.33901004 1.98958996 25 P 0 0;2,5=0,7=0
P 12.63778996 1.9252 11 P 0 0;3,5=2,7=0
L 12.33901004 1.98958996 12.35846004 1.97013996 2 P 0 
L 12.35846004 1.97013996 12.38146004 1.97013996 2 P 0 
L 12.38146004 1.97013996 12.49078002 1.98941004 2 P 0 
L 12.49078002 1.98941004 12.51128996 2.00376998 2 P 0 
L 12.51128996 2.00376998 12.54103002 2.009 2 P 0 
L 12.54103002 2.009 12.58418996 2.009 2 P 0 
L 12.58418996 2.009 12.6147 1.97848996 2 P 0 
L 12.6147 1.97848996 12.6147 1.94828996 2 P 0 
L 12.6147 1.94828996 12.63778996 1.9252 2 P 0 
P 0.09448996 1.9252 11 P 0 0;3,5=2,7=0
P 0.58298996 1.91181998 25 P 0 0;2,5=0,7=0
L 0.58298996 1.91181998 0.56353996 1.89236998 2 P 0 
L 0.56353996 1.89236998 0.50276998 1.89236998 2 P 0 
L 0.50276998 1.89236998 0.502 1.8916 2 P 0 
L 0.502 1.8916 0.33468996 1.8916 2 P 0 
L 0.33468996 1.8916 0.31551004 1.91078002 2 P 0 
L 0.31551004 1.91078002 0.28948002 1.92901998 2 P 0 
L 0.28948002 1.92901998 0.27595 1.9314 2 P 0 
L 0.27595 1.9314 0.198 1.9314 2 P 0 
L 0.198 1.9314 0.1964 1.9298 2 P 0 
L 0.1964 1.9298 0.1461 1.9298 2 P 0 
L 0.1461 1.9298 0.1334 1.9171 2 P 0 
L 0.1334 1.9171 0.10258996 1.9171 2 P 0 
L 0.10258996 1.9171 0.09448996 1.9252 2 P 0 
P 0.17323002 1.88583002 11 P 0 0;3,5=2,7=0
P 0.58298996 1.86181998 25 P 0 0;2,5=0,7=0
L 0.17323002 1.88583002 0.14766998 1.88583002 2 P 0 
L 0.14766998 1.88583002 0.1411 1.8924 2 P 0 
L 0.1411 1.8924 0.1411 1.9091 2 P 0 
L 0.1411 1.9091 0.1507 1.9187 2 P 0 
L 0.1507 1.9187 0.201 1.9187 2 P 0 
L 0.201 1.9187 0.2026 1.9203 2 P 0 
L 0.2026 1.9203 0.27498002 1.9203 2 P 0 
L 0.27498002 1.9203 0.28513002 1.91851004 2 P 0 
L 0.28513002 1.91851004 0.30833996 1.90223996 2 P 0 
L 0.30833996 1.90223996 0.33008996 1.8805 2 P 0 
L 0.33008996 1.8805 0.5066 1.8805 2 P 0 
L 0.5066 1.8805 0.50736998 1.88126998 2 P 0 
L 0.50736998 1.88126998 0.56353996 1.88126998 2 P 0 
L 0.56353996 1.88126998 0.58298996 1.86181998 2 P 0 
L 0.27165 2.04331004 0.52831004 2.04331004 3 P 0 
L 0.52831004 2.04331004 0.53 2.045 3 P 0 
L 0.53 2.045 0.58298002 2.045 3 P 0 
P 0.61698996 1.3381 25 P 0 0;2,5=0,7=0
P 0.58298002 2.045 25 P 0 0;2,5=0,7=0
P 0.27165 2.04331004 11 P 0 0;3,5=2,7=0
L 0.61698996 1.3381 0.73678996 1.3381 3 P 0 
L 0.73678996 1.3381 0.746 1.34731004 3 P 0 
L 0.746 1.34731004 0.746 1.639 3 P 0 
L 0.746 1.639 0.789 1.682 3 P 0 
L 0.789 1.682 0.789 1.96601004 3 P 0 
L 0.789 1.96601004 0.76201004 1.993 3 P 0 
L 0.76201004 1.993 0.59148002 1.993 3 P 0 
L 0.59148002 1.993 0.58298002 2.0015 3 P 0 
L 0.58298002 2.0015 0.58298002 2.045 3 P 0 
P 0.27165 4.563 11 P 0 0;5=2,7=0
L 0.35038996 3.26378002 0.435 3.34838996 3 P 0 
L 0.435 3.34838996 0.435 4.54 3 P 0 
L 0.435 4.54 0.412 4.563 3 P 0 
L 0.412 4.563 0.27165 4.563 3 P 0 
P 0.35038996 3.26378002 11 P 0 0;5=2,7=0
P 0.27165 2.59448996 11 P 0 0;5=2,7=0
L 0.27165 2.59448996 0.4195 2.59448996 3 P 0 
L 0.4195 2.59448996 0.435 2.60998996 3 P 0 
L 0.435 2.60998996 0.435 3.17916998 3 P 0 
L 0.435 3.17916998 0.35038996 3.26378002 3 P 0 
L 0.27165 2.04331004 0.225 2.08996004 3 P 0 
L 0.225 2.08996004 0.225 2.54783996 3 P 0 
L 0.225 2.54783996 0.27165 2.59448996 3 P 0 
L 0.58298002 1.655 0.508 1.655 3 P 0 
L 0.508 1.655 0.504 1.651 3 P 0 
L 0.504 1.651 0.327 1.651 3 P 0 
L 0.327 1.651 0.28531004 1.69268996 3 P 0 
L 0.28531004 1.69268996 0.20888996 1.69268996 3 P 0 
L 0.20888996 1.69268996 0.17323002 1.72835 3 P 0 
P 0.58298002 1.655 25 P 0 0;2,5=0,7=0
P 0.17323002 1.72835 11 P 0 0;3,5=2,7=0
P 5.03268002 1.91615 6 P 0 0;5=4,7=1
P 5.46358002 1.6693 25 P 0 0;2,5=0,7=0
L 5.03268002 1.91615 5.03268002 1.908 2 P 0 
L 5.03268002 1.908 5.02668002 1.902 2 P 0 
L 5.02668002 1.902 5.01463996 1.902 2 P 0 
L 5.01463996 1.902 5.00213996 1.8895 2 P 0 
L 5.00213996 1.8895 5.00213996 1.80316004 2 P 0 
L 5.00213996 1.80316004 5.11905 1.68625 2 P 0 
L 5.11905 1.68625 5.44663002 1.68625 2 P 0 
L 5.44663002 1.68625 5.46358002 1.6693 2 P 0 
P 1.025 -0.25 11 P 0 0;3,5=3,7=0
P 1.175 -0.25 11 P 0 0;3,5=3,7=0
P 1.325 -0.25 11 P 0 0;3,5=3,7=0
P 5.03268002 2.06615 6 P 0 0;5=4,7=1
L 5.03268002 2.06615 5.03268002 2.0527 2 P 0 
L 5.03268002 2.0527 5.03868002 2.0467 2 P 0 
L 5.03868002 2.0467 5.16 2.0467 2 P 0 
L 5.16 2.0467 5.23425 1.97245 2 P 0 
L 5.23425 1.97245 5.44663002 1.97245 2 P 0 
L 5.44663002 1.97245 5.46358002 1.9894 2 P 0 
P 5.46358002 1.9894 25 P 0 0;2,5=0,7=0
P 12.63778996 4.12991998 11 P 0 0;3,5=2,7=0
L 11.53316004 2.372 11.51776004 2.3874 2 P 0 
L 11.51776004 2.3874 11.47333002 2.3874 2 P 0 
L 11.47333002 2.3874 11.45593002 2.37 2 P 0 
P 11.53316004 2.372 6 P 0 0;5=4,7=1
P 11.45593002 2.37 25 P 0 0;2,5=0,7=0
P 5.08268002 2.26615 6 P 0 0;5=4,7=1
L 5.08268002 2.26615 5.08268002 2.2527 2 P 0 
L 5.08268002 2.2527 5.08868002 2.2467 2 P 0 
L 5.08868002 2.2467 5.281 2.2467 2 P 0 
L 5.281 2.2467 5.28305 2.24875 2 P 0 
L 5.28305 2.24875 5.44663002 2.24875 2 P 0 
L 5.44663002 2.24875 5.46358002 2.2657 2 P 0 
P 5.46358002 2.2657 25 P 0 0;2,5=0,7=0
P 11.53316004 1.892 6 P 0 0;5=4,7=1
P 11.45593002 1.89 25 P 0 0;2,5=0,7=0
P 12.55905 3.30315 11 P 0 0;3,5=2,7=0
L 11.45593002 1.89 11.47333002 1.9074 2 P 0 
L 11.47333002 1.9074 11.51776004 1.9074 2 P 0 
L 11.51776004 1.9074 11.53316004 1.892 2 P 0 
P 12.81495 2.51575 11 P 0 0;3,5=2,7=0
P 10.58661004 1.91615 6 P 0 0;5=4,7=1
L 10.58661004 1.91615 10.58661004 1.9296 2 P 0 
L 10.58661004 1.9296 10.58061004 1.9356 2 P 0 
L 10.58061004 1.9356 10.5613 1.9356 2 P 0 
L 10.5613 1.9356 10.55385 1.92815 2 P 0 
L 10.55385 1.92815 10.43285 1.7553 2 P 0 
L 10.43285 1.7553 10.33103002 1.68401998 2 P 0 
L 10.33103002 1.68401998 10.302 1.6789 2 P 0 
L 10.302 1.6789 10.27445 1.6789 2 P 0 
L 10.27445 1.6789 10.26 1.66445 2 P 0 
P 10.26 1.66445 6 P 0 0;5=4,7=1
P 11.03998996 4.8431 7 P 0 0;5=6,7=1
P 11.08498996 4.8431 7 P 0 0;5=6,7=1
P 11.13498996 4.8431 7 P 0 0;5=6,7=1
P 11.17998996 4.8431 7 P 0 0;5=6,7=1
P 11.17998996 4.8031 7 P 0 0;5=6,7=1
P 11.17998996 4.7581 7 P 0 0;5=6,7=1
P 11.17998996 4.7131 7 P 0 0;5=6,7=1
P 11.17998996 4.6731 7 P 0 0;5=6,7=1
P 11.03998996 4.6731 7 P 0 0;5=6,7=1
P 11.08498996 4.6731 7 P 0 0;5=6,7=1
P 11.13498996 4.6731 7 P 0 0;5=6,7=1
P 11.03998996 4.7131 7 P 0 0;5=6,7=1
P 11.03998996 4.8031 7 P 0 0;5=6,7=1
P 11.03998996 4.7581 7 P 0 0;5=6,7=1
P 10.81998996 4.6631 7 P 0 0;5=6,7=1
P 10.85998996 4.6631 7 P 0 0;5=6,7=1
P 10.65998996 4.6631 7 P 0 0;5=6,7=1
P 10.69998996 4.6631 7 P 0 0;5=6,7=1
P 10.81998996 4.7031 7 P 0 0;5=6,7=1
P 10.81998996 4.8381 7 P 0 0;5=6,7=1
P 10.81998996 4.7931 7 P 0 0;5=6,7=1
P 10.81998996 4.7481 7 P 0 0;5=6,7=1
P 10.85998996 4.7031 7 P 0 0;5=6,7=1
P 10.85998996 4.8381 7 P 0 0;5=6,7=1
P 10.85998996 4.7931 7 P 0 0;5=6,7=1
P 10.85998996 4.7481 7 P 0 0;5=6,7=1
P 10.65998996 4.7031 7 P 0 0;5=6,7=1
P 10.65998996 4.8381 7 P 0 0;5=6,7=1
P 10.65998996 4.7931 7 P 0 0;5=6,7=1
P 10.65998996 4.7481 7 P 0 0;5=6,7=1
P 10.69998996 4.7031 7 P 0 0;5=6,7=1
P 10.69998996 4.8381 7 P 0 0;5=6,7=1
P 10.69998996 4.7931 7 P 0 0;5=6,7=1
P 10.69998996 4.7481 7 P 0 0;5=6,7=1
P 10.77998996 4.6431 7 P 0 0;5=6,7=1
P 10.73498996 4.6431 7 P 0 0;5=6,7=1
P 10.73998996 4.8381 7 P 0 0;5=6,7=1
P 10.77998996 4.8381 7 P 0 0;5=6,7=1
P 10.30998996 4.6631 7 P 0 0;5=6,7=1
P 10.26998996 4.6631 7 P 0 0;5=6,7=1
P 10.34498996 4.6431 7 P 0 0;5=6,7=1
P 10.38998996 4.6431 7 P 0 0;5=6,7=1
P 10.42998996 4.6631 7 P 0 0;5=6,7=1
P 10.46998996 4.6631 7 P 0 0;5=6,7=1
P 10.30998996 4.7481 7 P 0 0;5=6,7=1
P 10.30998996 4.7931 7 P 0 0;5=6,7=1
P 10.30998996 4.7031 7 P 0 0;5=6,7=1
P 10.26998996 4.7481 7 P 0 0;5=6,7=1
P 10.26998996 4.7931 7 P 0 0;5=6,7=1
P 10.26998996 4.7031 7 P 0 0;5=6,7=1
P 10.26998996 4.8381 7 P 0 0;5=6,7=1
P 10.30998996 4.8381 7 P 0 0;5=6,7=1
P 10.38998996 4.8381 7 P 0 0;5=6,7=1
P 10.34998996 4.8381 7 P 0 0;5=6,7=1
P 10.46998996 4.8381 7 P 0 0;5=6,7=1
P 10.42998996 4.8381 7 P 0 0;5=6,7=1
P 10.42998996 4.7031 7 P 0 0;5=6,7=1
P 10.42998996 4.7931 7 P 0 0;5=6,7=1
P 10.42998996 4.7481 7 P 0 0;5=6,7=1
P 10.46998996 4.7031 7 P 0 0;5=6,7=1
P 10.46998996 4.7931 7 P 0 0;5=6,7=1
P 10.46998996 4.7481 7 P 0 0;5=6,7=1
P 10.58661004 3.16615 6 P 0 0;5=4,7=1
P 10.63661004 3.01615 6 P 0 0;5=4,7=1
P 10.58661004 3.11615 6 P 0 0;5=4,7=1
P 10.58661004 3.01615 6 P 0 0;5=4,7=1
P 10.63661004 3.11615 6 P 0 0;5=4,7=1
P 10.63661004 2.96615 6 P 0 0;5=4,7=1
P 10.58661004 2.96615 6 P 0 0;5=4,7=1
P 10.58661004 3.41615 6 P 0 0;5=4,7=1
P 10.63661004 3.16615 6 P 0 0;5=4,7=1
P 10.63661004 3.26615 6 P 0 0;5=4,7=1
P 10.58661004 3.31615 6 P 0 0;5=4,7=1
P 10.58661004 3.26615 6 P 0 0;5=4,7=1
P 10.63661004 3.31615 6 P 0 0;5=4,7=1
P 10.63661004 3.56615 6 P 0 0;5=4,7=1
P 10.63661004 3.61615 6 P 0 0;5=4,7=1
P 10.58661004 3.56615 6 P 0 0;5=4,7=1
P 10.58661004 3.61615 6 P 0 0;5=4,7=1
P 10.63661004 3.46615 6 P 0 0;5=4,7=1
P 10.63661004 3.41615 6 P 0 0;5=4,7=1
P 10.58661004 3.46615 6 P 0 0;5=4,7=1
P 10.63661004 3.86615 6 P 0 0;5=4,7=1
P 10.63661004 3.76615 6 P 0 0;5=4,7=1
P 10.58661004 3.86615 6 P 0 0;5=4,7=1
P 10.58661004 3.76615 6 P 0 0;5=4,7=1
P 10.63661004 3.71615 6 P 0 0;5=4,7=1
P 10.58661004 3.71615 6 P 0 0;5=4,7=1
P 10.88661004 2.96615 6 P 0 0;5=4,7=1
P 10.83661004 2.96615 6 P 0 0;5=4,7=1
P 10.88661004 3.01615 6 P 0 0;5=4,7=1
P 10.83661004 3.01615 6 P 0 0;5=4,7=1
P 10.88661004 3.11615 6 P 0 0;5=4,7=1
P 10.83661004 3.11615 6 P 0 0;5=4,7=1
P 10.83661004 3.16615 6 P 0 0;5=4,7=1
P 10.78661004 3.16615 6 P 0 0;5=4,7=1
P 10.68661004 3.16615 6 P 0 0;5=4,7=1
P 10.73661004 3.16615 6 P 0 0;5=4,7=1
P 10.78661004 3.01615 6 P 0 0;5=4,7=1
P 10.78661004 3.11615 6 P 0 0;5=4,7=1
P 10.73661004 3.01615 6 P 0 0;5=4,7=1
P 10.73661004 3.11615 6 P 0 0;5=4,7=1
P 10.68661004 3.01615 6 P 0 0;5=4,7=1
P 10.68661004 3.11615 6 P 0 0;5=4,7=1
P 10.78661004 2.96615 6 P 0 0;5=4,7=1
P 10.73661004 2.96615 6 P 0 0;5=4,7=1
P 10.68661004 2.96615 6 P 0 0;5=4,7=1
P 10.88661004 3.16615 6 P 0 0;5=4,7=1
P 10.88661004 3.26615 6 P 0 0;5=4,7=1
P 10.83661004 3.26615 6 P 0 0;5=4,7=1
P 10.83661004 3.31615 6 P 0 0;5=4,7=1
P 10.88661004 3.31615 6 P 0 0;5=4,7=1
P 10.83661004 3.41615 6 P 0 0;5=4,7=1
P 10.78661004 3.41615 6 P 0 0;5=4,7=1
P 10.68661004 3.41615 6 P 0 0;5=4,7=1
P 10.73661004 3.41615 6 P 0 0;5=4,7=1
P 10.78661004 3.31615 6 P 0 0;5=4,7=1
P 10.78661004 3.26615 6 P 0 0;5=4,7=1
P 10.68661004 3.31615 6 P 0 0;5=4,7=1
P 10.68661004 3.26615 6 P 0 0;5=4,7=1
P 10.73661004 3.26615 6 P 0 0;5=4,7=1
P 10.73661004 3.31615 6 P 0 0;5=4,7=1
P 10.88661004 3.41615 6 P 0 0;5=4,7=1
P 10.83661004 3.46615 6 P 0 0;5=4,7=1
P 10.88661004 3.46615 6 P 0 0;5=4,7=1
P 10.83661004 3.56615 6 P 0 0;5=4,7=1
P 10.88661004 3.56615 6 P 0 0;5=4,7=1
P 10.83661004 3.61615 6 P 0 0;5=4,7=1
P 10.88661004 3.61615 6 P 0 0;5=4,7=1
P 10.78661004 3.56615 6 P 0 0;5=4,7=1
P 10.78661004 3.61615 6 P 0 0;5=4,7=1
P 10.68661004 3.61615 6 P 0 0;5=4,7=1
P 10.68661004 3.56615 6 P 0 0;5=4,7=1
P 10.73661004 3.61615 6 P 0 0;5=4,7=1
P 10.73661004 3.56615 6 P 0 0;5=4,7=1
P 10.78661004 3.46615 6 P 0 0;5=4,7=1
P 10.73661004 3.46615 6 P 0 0;5=4,7=1
P 10.68661004 3.46615 6 P 0 0;5=4,7=1
P 10.83661004 3.71615 6 P 0 0;5=4,7=1
P 10.88661004 3.71615 6 P 0 0;5=4,7=1
P 10.83661004 3.76615 6 P 0 0;5=4,7=1
P 10.88661004 3.76615 6 P 0 0;5=4,7=1
P 10.83661004 3.86615 6 P 0 0;5=4,7=1
P 10.88661004 3.86615 6 P 0 0;5=4,7=1
P 10.78661004 3.86615 6 P 0 0;5=4,7=1
P 10.78661004 3.76615 6 P 0 0;5=4,7=1
P 10.68661004 3.86615 6 P 0 0;5=4,7=1
P 10.68661004 3.76615 6 P 0 0;5=4,7=1
P 10.73661004 3.86615 6 P 0 0;5=4,7=1
P 10.73661004 3.76615 6 P 0 0;5=4,7=1
P 10.78661004 3.71615 6 P 0 0;5=4,7=1
P 10.68661004 3.71615 6 P 0 0;5=4,7=1
P 10.73661004 3.71615 6 P 0 0;5=4,7=1
P 11.03661004 2.96615 6 P 0 0;5=4,7=1
P 10.93661004 2.96615 6 P 0 0;5=4,7=1
P 10.98661004 2.96615 6 P 0 0;5=4,7=1
P 11.03661004 3.01615 6 P 0 0;5=4,7=1
P 10.93661004 3.01615 6 P 0 0;5=4,7=1
P 10.98661004 3.01615 6 P 0 0;5=4,7=1
P 11.03661004 3.11615 6 P 0 0;5=4,7=1
P 10.93661004 3.11615 6 P 0 0;5=4,7=1
P 10.98661004 3.11615 6 P 0 0;5=4,7=1
P 11.03661004 3.16615 6 P 0 0;5=4,7=1
P 10.93661004 3.16615 6 P 0 0;5=4,7=1
P 10.98661004 3.16615 6 P 0 0;5=4,7=1
P 11.03661004 3.26615 6 P 0 0;5=4,7=1
P 10.93661004 3.26615 6 P 0 0;5=4,7=1
P 10.98661004 3.26615 6 P 0 0;5=4,7=1
P 10.98661004 3.31615 6 P 0 0;5=4,7=1
P 10.93661004 3.31615 6 P 0 0;5=4,7=1
P 11.03661004 3.31615 6 P 0 0;5=4,7=1
P 10.98661004 3.41615 6 P 0 0;5=4,7=1
P 10.93661004 3.41615 6 P 0 0;5=4,7=1
P 11.03661004 3.41615 6 P 0 0;5=4,7=1
P 10.98661004 3.46615 6 P 0 0;5=4,7=1
P 10.93661004 3.46615 6 P 0 0;5=4,7=1
P 11.03661004 3.46615 6 P 0 0;5=4,7=1
P 10.98661004 3.56615 6 P 0 0;5=4,7=1
P 10.93661004 3.56615 6 P 0 0;5=4,7=1
P 11.03661004 3.56615 6 P 0 0;5=4,7=1
P 10.98661004 3.61615 6 P 0 0;5=4,7=1
P 10.93661004 3.61615 6 P 0 0;5=4,7=1
P 11.03661004 3.61615 6 P 0 0;5=4,7=1
P 10.98661004 3.71615 6 P 0 0;5=4,7=1
P 10.93661004 3.71615 6 P 0 0;5=4,7=1
P 11.03661004 3.71615 6 P 0 0;5=4,7=1
P 10.98661004 3.76615 6 P 0 0;5=4,7=1
P 10.93661004 3.76615 6 P 0 0;5=4,7=1
P 11.03661004 3.76615 6 P 0 0;5=4,7=1
P 10.98661004 3.86615 6 P 0 0;5=4,7=1
P 10.93661004 3.86615 6 P 0 0;5=4,7=1
P 11.03661004 3.86615 6 P 0 0;5=4,7=1
P 10.41393996 4.21 8 P 0 0;3,5=5,7=1
S P 0
OB 11.173 2.943 I
OS 10.587 2.943
OS 10.25998996063 3.27001003937
OS 10.25998996063 4.8381
OS 10.26998996063 4.8481
OS 11.18498996063 4.8481
OS 11.2 4.83308996063
OS 11.2 2.97
OS 11.173 2.943
OE
OB 10.602630019685 3.06615 H
OC 10.602630019685 3.06615 10.58661003937 3.06615 N
OE
OB 10.602630019685 3.21615 H
OC 10.602630019685 3.21615 10.58661003937 3.21615 N
OE
OB 10.602630019685 3.36615 H
OC 10.602630019685 3.36615 10.58661003937 3.36615 N
OE
OB 10.602630019685 3.51615 H
OC 10.602630019685 3.51615 10.58661003937 3.51615 N
OE
OB 10.602630019685 3.81615 H
OC 10.602630019685 3.81615 10.58661003937 3.81615 N
OE
OB 10.602630019685 3.66615 H
OC 10.602630019685 3.66615 10.58661003937 3.66615 N
OE
OB 10.702630019685 3.06615 H
OC 10.702630019685 3.06615 10.68661003937 3.06615 N
OE
OB 10.752630019685 3.06615 H
OC 10.752630019685 3.06615 10.73661003937 3.06615 N
OE
OB 10.802630019685 3.06615 H
OC 10.802630019685 3.06615 10.78661003937 3.06615 N
OE
OB 10.852630019685 3.06615 H
OC 10.852630019685 3.06615 10.83661003937 3.06615 N
OE
OB 10.652630019685 3.06615 H
OC 10.652630019685 3.06615 10.63661003937 3.06615 N
OE
OB 10.702630019685 3.21615 H
OC 10.702630019685 3.21615 10.68661003937 3.21615 N
OE
OB 10.702630019685 3.36615 H
OC 10.702630019685 3.36615 10.68661003937 3.36615 N
OE
OB 10.752630019685 3.21615 H
OC 10.752630019685 3.21615 10.73661003937 3.21615 N
OE
OB 10.802630019685 3.21615 H
OC 10.802630019685 3.21615 10.78661003937 3.21615 N
OE
OB 10.752630019685 3.36615 H
OC 10.752630019685 3.36615 10.73661003937 3.36615 N
OE
OB 10.802630019685 3.36615 H
OC 10.802630019685 3.36615 10.78661003937 3.36615 N
OE
OB 10.852630019685 3.36615 H
OC 10.852630019685 3.36615 10.83661003937 3.36615 N
OE
OB 10.852630019685 3.21615 H
OC 10.852630019685 3.21615 10.83661003937 3.21615 N
OE
OB 10.652630019685 3.21615 H
OC 10.652630019685 3.21615 10.63661003937 3.21615 N
OE
OB 10.652630019685 3.36615 H
OC 10.652630019685 3.36615 10.63661003937 3.36615 N
OE
OB 10.702630019685 3.51615 H
OC 10.702630019685 3.51615 10.68661003937 3.51615 N
OE
OB 10.752630019685 3.51615 H
OC 10.752630019685 3.51615 10.73661003937 3.51615 N
OE
OB 10.802630019685 3.51615 H
OC 10.802630019685 3.51615 10.78661003937 3.51615 N
OE
OB 10.852630019685 3.51615 H
OC 10.852630019685 3.51615 10.83661003937 3.51615 N
OE
OB 10.652630019685 3.51615 H
OC 10.652630019685 3.51615 10.63661003937 3.51615 N
OE
OB 10.702630019685 3.81615 H
OC 10.702630019685 3.81615 10.68661003937 3.81615 N
OE
OB 10.752630019685 3.81615 H
OC 10.752630019685 3.81615 10.73661003937 3.81615 N
OE
OB 10.802630019685 3.81615 H
OC 10.802630019685 3.81615 10.78661003937 3.81615 N
OE
OB 10.852630019685 3.81615 H
OC 10.852630019685 3.81615 10.83661003937 3.81615 N
OE
OB 10.702630019685 3.66615 H
OC 10.702630019685 3.66615 10.68661003937 3.66615 N
OE
OB 10.752630019685 3.66615 H
OC 10.752630019685 3.66615 10.73661003937 3.66615 N
OE
OB 10.802630019685 3.66615 H
OC 10.802630019685 3.66615 10.78661003937 3.66615 N
OE
OB 10.852630019685 3.66615 H
OC 10.852630019685 3.66615 10.83661003937 3.66615 N
OE
OB 10.652630019685 3.66615 H
OC 10.652630019685 3.66615 10.63661003937 3.66615 N
OE
OB 10.652630019685 3.81615 H
OC 10.652630019685 3.81615 10.63661003937 3.81615 N
OE
OB 11.002630019685 3.06615 H
OC 11.002630019685 3.06615 10.98661003937 3.06615 N
OE
OB 10.952630019685 3.06615 H
OC 10.952630019685 3.06615 10.93661003937 3.06615 N
OE
OB 11.052630019685 3.06615 H
OC 11.052630019685 3.06615 11.03661003937 3.06615 N
OE
OB 10.902630019685 3.06615 H
OC 10.902630019685 3.06615 10.88661003937 3.06615 N
OE
OB 11.052630019685 3.36615 H
OC 11.052630019685 3.36615 11.03661003937 3.36615 N
OE
OB 10.952630019685 3.36615 H
OC 10.952630019685 3.36615 10.93661003937 3.36615 N
OE
OB 11.002630019685 3.36615 H
OC 11.002630019685 3.36615 10.98661003937 3.36615 N
OE
OB 11.002630019685 3.21615 H
OC 11.002630019685 3.21615 10.98661003937 3.21615 N
OE
OB 10.952630019685 3.21615 H
OC 10.952630019685 3.21615 10.93661003937 3.21615 N
OE
OB 11.052630019685 3.21615 H
OC 11.052630019685 3.21615 11.03661003937 3.21615 N
OE
OB 10.902630019685 3.36615 H
OC 10.902630019685 3.36615 10.88661003937 3.36615 N
OE
OB 10.902630019685 3.21615 H
OC 10.902630019685 3.21615 10.88661003937 3.21615 N
OE
OB 11.052630019685 3.51615 H
OC 11.052630019685 3.51615 11.03661003937 3.51615 N
OE
OB 10.952630019685 3.51615 H
OC 10.952630019685 3.51615 10.93661003937 3.51615 N
OE
OB 11.002630019685 3.51615 H
OC 11.002630019685 3.51615 10.98661003937 3.51615 N
OE
OB 10.902630019685 3.51615 H
OC 10.902630019685 3.51615 10.88661003937 3.51615 N
OE
OB 10.952630019685 3.81615 H
OC 10.952630019685 3.81615 10.93661003937 3.81615 N
OE
OB 11.002630019685 3.81615 H
OC 11.002630019685 3.81615 10.98661003937 3.81615 N
OE
OB 11.052630019685 3.66615 H
OC 11.052630019685 3.66615 11.03661003937 3.66615 N
OE
OB 10.952630019685 3.66615 H
OC 10.952630019685 3.66615 10.93661003937 3.66615 N
OE
OB 11.002630019685 3.66615 H
OC 11.002630019685 3.66615 10.98661003937 3.66615 N
OE
OB 10.902630019685 3.66615 H
OC 10.902630019685 3.66615 10.88661003937 3.66615 N
OE
OB 10.902630019685 3.81615 H
OC 10.902630019685 3.81615 10.88661003937 3.81615 N
OE
OB 11.052630019685 3.81615 H
OC 11.052630019685 3.81615 11.03661003937 3.81615 N
OE
OB 11.044369980315 4.22441003937 H
OC 11.044369980315 4.22441003937 10.836619980315 4.22441003937 N
OE
SE
P 5.08268002 2.06615 6 P 0 0;5=4,7=1
L 5.08268002 2.06615 5.08268002 2.0796 2 P 0 
L 5.08268002 2.0796 5.08868002 2.0856 2 P 0 
L 5.08868002 2.0856 5.1817 2.0856 2 P 0 
L 5.1817 2.0856 5.23815 2.02915 2 P 0 
L 5.23815 2.02915 5.2918 2.02915 2 P 0 
L 5.2918 2.02915 5.30875 2.0122 2 P 0 
P 5.30875 2.0122 25 P 0 0;2,5=0,7=0
P 10.58661004 2.36615 6 P 0 0;5=4,7=1
L 10.58661004 2.36615 10.58661004 2.3796 2 P 0 
L 10.58661004 2.3796 10.58061004 2.3856 2 P 0 
L 10.58061004 2.3856 10.5534 2.3856 2 P 0 
L 10.5534 2.3856 10.45365 2.48535 2 P 0 
L 10.45365 2.48535 9.98945 2.48535 2 P 0 
L 9.98945 2.48535 9.975 2.4709 2 P 0 
P 9.975 2.4709 6 P 0 0;5=4,7=1
P 12.73621004 4.20866004 11 P 0 0;3,5=2,7=0
P 11.08661004 2.36615 6 P 0 0;5=4,7=1
L 11.08661004 2.36615 11.08661004 2.3796 2 P 0 
L 11.08661004 2.3796 11.09261004 2.3856 2 P 0 
L 11.09261004 2.3856 11.196 2.3856 2 P 0 
L 11.196 2.3856 11.29125 2.40238996 2 P 0 
L 11.29125 2.40238996 11.3788 2.38695 2 P 0 
L 11.3788 2.38695 11.40498002 2.38695 2 P 0 
L 11.40498002 2.38695 11.42193002 2.37 2 P 0 
P 11.42193002 2.37 25 P 0 0;2,5=0,7=0
P 5.08268002 2.11615 6 P 0 0;5=4,7=1
L 5.08268002 2.11615 5.08268002 2.1027 2 P 0 
L 5.08268002 2.1027 5.08868002 2.0967 2 P 0 
L 5.08868002 2.0967 5.1863 2.0967 2 P 0 
L 5.1863 2.0967 5.24275 2.04025 2 P 0 
L 5.24275 2.04025 5.2918 2.04025 2 P 0 
L 5.2918 2.04025 5.30875 2.0572 2 P 0 
P 5.30875 2.0572 25 P 0 0;2,5=0,7=0
L 11.08661004 2.41615 11.08661004 2.4027 2 P 0 
L 11.08661004 2.4027 11.09261004 2.3967 2 P 0 
L 11.09261004 2.3967 11.19501998 2.3967 2 P 0 
L 11.19501998 2.3967 11.29125 2.41366998 2 P 0 
L 11.29125 2.41366998 11.37978002 2.39805 2 P 0 
L 11.37978002 2.39805 11.40498002 2.39805 2 P 0 
L 11.40498002 2.39805 11.42193002 2.415 2 P 0 
P 11.42193002 2.415 25 P 0 0;2,5=0,7=0
P 11.08661004 2.41615 6 P 0 0;5=4,7=1
P 12.73621004 2.47638002 11 P 0 0;3,5=2,7=0
P 10.58661004 1.96615 6 P 0 0;5=4,7=1
L 10.58661004 1.96615 10.58661004 1.9527 2 P 0 
L 10.58661004 1.9527 10.58061004 1.9467 2 P 0 
L 10.58061004 1.9467 10.5567 1.9467 2 P 0 
L 10.5567 1.9467 10.54531004 1.93531004 2 P 0 
L 10.54531004 1.93531004 10.42486998 1.76328002 2 P 0 
L 10.42486998 1.76328002 10.32668002 1.69453002 2 P 0 
L 10.32668002 1.69453002 10.30101998 1.69 2 P 0 
L 10.30101998 1.69 10.30098002 1.69 2 P 0 
L 10.30098002 1.69 10.29948996 1.68973996 2 P 0 
L 10.29948996 1.68973996 10.298 1.69 2 P 0 
L 10.298 1.69 10.27445 1.69 2 P 0 
L 10.27445 1.69 10.26 1.70445 2 P 0 
P 10.26 1.70445 6 P 0 0;5=4,7=1
L 10.98661004 2.41615 10.98661004 2.4027 2 P 0 
L 10.98661004 2.4027 10.99261004 2.3967 2 P 0 
L 10.99261004 2.3967 11.00006004 2.3967 2 P 0 
L 11.00006004 2.3967 11.00606004 2.4027 2 P 0 
L 11.00606004 2.4027 11.00606004 2.4342 2 P 0 
L 11.00606004 2.4342 11.01856004 2.4467 2 P 0 
L 11.01856004 2.4467 11.16696998 2.4467 2 P 0 
L 11.16696998 2.4467 11.34196998 2.47755 2 P 0 
L 11.34196998 2.47755 11.60448002 2.47755 2 P 0 
L 11.60448002 2.47755 11.62193002 2.495 2 P 0 
P 11.62193002 2.495 25 P 0 0;2,5=0,7=0
P 10.98661004 2.41615 6 P 0 0;5=4,7=1
P 8.5 3.76615 6 P 0 0;5=4,7=1
P 9.35271004 5.1035 6 P 0 0;5=4,7=1
P 4.98268002 2.06615 6 P 0 0;5=4,7=1
L 4.98268002 2.06615 4.98268002 2.0796 2 P 0 
L 4.98268002 2.0796 4.98868002 2.0856 2 P 0 
L 4.98868002 2.0856 5.00073002 2.0856 2 P 0 
L 5.00073002 2.0856 5.01323002 2.0981 2 P 0 
L 5.01323002 2.0981 5.01323002 2.1296 2 P 0 
L 5.01323002 2.1296 5.01923002 2.1356 2 P 0 
L 5.01923002 2.1356 5.2097 2.1356 2 P 0 
L 5.2097 2.1356 5.24305 2.10225 2 P 0 
L 5.24305 2.10225 5.44663002 2.10225 2 P 0 
L 5.44663002 2.10225 5.46358002 2.0853 2 P 0 
P 5.46358002 2.0853 25 P 0 0;2,5=0,7=0
P 8.5 3.81615 6 P 0 0;5=4,7=1
P 9.31271004 5.1035 6 P 0 0;5=4,7=1
P 12.55905 2.59448996 11 P 0 0;3,5=2,7=0
P 11.53316004 1.572 6 P 0 0;5=4,7=1
P 11.45593002 1.57 25 P 0 0;2,5=0,7=0
L 11.45593002 1.57 11.47333002 1.5874 2 P 0 
L 11.47333002 1.5874 11.51776004 1.5874 2 P 0 
L 11.51776004 1.5874 11.53316004 1.572 2 P 0 
P 4.98268002 2.11615 6 P 0 0;5=4,7=1
L 4.98268002 2.11615 4.98268002 2.1027 2 P 0 
L 4.98268002 2.1027 4.98868002 2.0967 2 P 0 
L 4.98868002 2.0967 4.99613002 2.0967 2 P 0 
L 4.99613002 2.0967 5.00213002 2.1027 2 P 0 
L 5.00213002 2.1027 5.00213002 2.1342 2 P 0 
L 5.00213002 2.1342 5.01463002 2.1467 2 P 0 
L 5.01463002 2.1467 5.2143 2.1467 2 P 0 
L 5.2143 2.1467 5.24765 2.11335 2 P 0 
L 5.24765 2.11335 5.44663002 2.11335 2 P 0 
L 5.44663002 2.11335 5.46358002 2.1303 2 P 0 
P 5.46358002 2.1303 25 P 0 0;2,5=0,7=0
P 10.98661004 2.36615 6 P 0 0;5=4,7=1
L 10.98661004 2.36615 10.98661004 2.3796 2 P 0 
L 10.98661004 2.3796 10.99261004 2.3856 2 P 0 
L 10.99261004 2.3856 11.00466004 2.3856 2 P 0 
L 11.00466004 2.3856 11.01716004 2.3981 2 P 0 
L 11.01716004 2.3981 11.01716004 2.4296 2 P 0 
L 11.01716004 2.4296 11.02316004 2.4356 2 P 0 
L 11.02316004 2.4356 11.16795 2.4356 2 P 0 
L 11.16795 2.4356 11.34295 2.46645 2 P 0 
L 11.34295 2.46645 11.60448002 2.46645 2 P 0 
L 11.60448002 2.46645 11.62093002 2.45 2 P 0 
L 11.62093002 2.45 11.62193002 2.45 2 P 0 
P 11.62193002 2.45 25 P 0 0;2,5=0,7=0
P 8.5 3.61615 6 P 0 0;5=4,7=1
P 9.56531004 5.14 6 P 0 0;5=4,7=1
P 4.93268002 2.01615 6 P 0 0;5=4,7=1
L 4.93268002 2.01615 4.93268002 2.0296 2 P 0 
L 4.93268002 2.0296 4.93868002 2.0356 2 P 0 
L 4.93868002 2.0356 4.996 2.0356 2 P 0 
L 4.996 2.0356 5.00213002 2.02946998 2 P 0 
L 5.00213002 2.02946998 5.00213002 1.9981 2 P 0 
L 5.00213002 1.9981 5.01463002 1.9856 2 P 0 
L 5.01463002 1.9856 5.1297 1.9856 2 P 0 
L 5.1297 1.9856 5.22155 1.89375 2 P 0 
L 5.22155 1.89375 5.2918 1.89375 2 P 0 
L 5.2918 1.89375 5.30875 1.8768 2 P 0 
P 5.30875 1.8768 25 P 0 0;2,5=0,7=0
P 11.45593002 1.41 25 P 0 0;2,5=0,7=0
L 11.45593002 1.41 11.47333002 1.4274 2 P 0 
L 11.47333002 1.4274 11.51776004 1.4274 2 P 0 
L 11.51776004 1.4274 11.53316004 1.412 2 P 0 
P 11.53316004 1.412 6 P 0 0;5=4,7=1
P 12.63778996 2.39763996 11 P 0 0;3,5=2,7=0
P 8.5 3.66615 6 P 0 0;5=4,7=1
P 9.52531004 5.14 6 P 0 0;5=4,7=1
L 11.80693002 2.87558996 11.82058996 2.87558996 3 P 0 
L 11.82058996 2.87558996 11.83 2.885 3 P 0 
L 11.83 2.885 11.875 2.885 3 P 0 
P 11.80693002 2.87558996 30 P 0 0;2,5=8,7=0
P 12.308 2.11 25 P 0 0;2,5=0,7=0
P 11.875 2.885 8 P 0 0;3,5=5,7=1
L 11.875 2.885 12.11 2.885 3 P 0 
L 12.11 2.885 12.195 2.8 3 P 0 
L 12.195 2.8 12.195 2.15 3 P 0 
L 12.195 2.15 12.235 2.11 3 P 0 
L 12.235 2.11 12.308 2.11 3 P 0 
P 12.73621004 2.87008002 11 P 0 0;3,5=2,7=0
P 10.63661004 2.06615 6 P 0 0;5=4,7=1
P 10.225 1.96645 6 P 0 0;5=4,7=1
L 10.63661004 2.06615 10.63661004 2.0527 2 P 0 
L 10.63661004 2.0527 10.63061004 2.0467 2 P 0 
L 10.63061004 2.0467 10.5421 2.0467 2 P 0 
L 10.5421 2.0467 10.45493002 2.03133002 2 P 0 
L 10.45493002 2.03133002 10.35801004 1.96346004 2 P 0 
L 10.35801004 1.96346004 10.29301998 1.952 2 P 0 
L 10.29301998 1.952 10.23945 1.952 2 P 0 
L 10.23945 1.952 10.225 1.96645 2 P 0 
L 11.53316004 1.452 11.51966004 1.4385 2 P 0 
L 11.51966004 1.4385 11.47243002 1.4385 2 P 0 
L 11.47243002 1.4385 11.45593002 1.455 2 P 0 
P 11.53316004 1.452 6 P 0 0;5=4,7=1
P 11.45593002 1.455 25 P 0 0;2,5=0,7=0
P 12.55905 2.43701004 11 P 0 0;3,5=2,7=0
P 8.35 3.66615 6 P 0 0;5=4,7=1
P 9.56531004 4.71973002 6 P 0 0;5=4,7=1
P 4.93268002 2.06615 6 P 0 0;5=4,7=1
L 4.93268002 2.06615 4.93268002 2.0527 2 P 0 
L 4.93268002 2.0527 4.93868002 2.0467 2 P 0 
L 4.93868002 2.0467 5.0006 2.0467 2 P 0 
L 5.0006 2.0467 5.01323002 2.03406998 2 P 0 
L 5.01323002 2.03406998 5.01323002 2.0027 2 P 0 
L 5.01323002 2.0027 5.01923002 1.9967 2 P 0 
L 5.01923002 1.9967 5.1343 1.9967 2 P 0 
L 5.1343 1.9967 5.22615 1.90485 2 P 0 
L 5.22615 1.90485 5.2918 1.90485 2 P 0 
L 5.2918 1.90485 5.30875 1.9218 2 P 0 
P 5.30875 1.9218 25 P 0 0;2,5=0,7=0
P 8.35 3.71615 6 P 0 0;5=4,7=1
P 9.52531004 4.71973002 6 P 0 0;5=4,7=1
P 11.83316004 2.212 6 P 0 0;5=4,7=1
P 11.45593002 2.21 25 P 0 0;2,5=0,7=0
P 12.63778996 3.65748002 11 P 0 0;3,5=2,7=0
L 11.45593002 2.21 11.47333002 2.2274 2 P 0 
L 11.47333002 2.2274 11.81776004 2.2274 2 P 0 
L 11.81776004 2.2274 11.83316004 2.212 2 P 0 
P 12.73621004 3.02756004 11 P 0 0;3,5=2,7=0
P 10.58661004 2.11615 6 P 0 0;5=4,7=1
L 10.58661004 2.11615 10.58661004 2.1027 2 P 0 
L 10.58661004 2.1027 10.58061004 2.0967 2 P 0 
L 10.58061004 2.0967 10.51901998 2.0967 2 P 0 
L 10.51901998 2.0967 10.17791004 2.03653002 2 P 0 
L 10.17791004 2.03653002 10.14631004 2.0421 2 P 0 
L 10.14631004 2.0421 10.10445 2.0421 2 P 0 
L 10.10445 2.0421 10.09 2.05655 2 P 0 
P 10.09 2.05655 6 P 0 0;5=4,7=1
L 11.45593002 1.935 11.47243002 1.9185 2 P 0 
L 11.47243002 1.9185 11.51966004 1.9185 2 P 0 
L 11.51966004 1.9185 11.53316004 1.932 2 P 0 
P 11.53316004 1.932 6 P 0 0;5=4,7=1
P 11.45593002 1.935 25 P 0 0;2,5=0,7=0
P 12.63778996 3.26378002 11 P 0 0;3,5=2,7=0
P 8.74578996 5.14 6 P 0 0;5=4,7=1
P 8.05 3.61615 6 P 0 0;5=4,7=1
P 12.81495 4.01181004 11 P 0 0;3,5=2,7=0
L 10.68661004 2.41615 10.68661004 2.4027 2 P 0 
L 10.68661004 2.4027 10.68061004 2.3967 2 P 0 
L 10.68061004 2.3967 10.62316004 2.3967 2 P 0 
L 10.62316004 2.3967 10.61716004 2.4027 2 P 0 
L 10.61716004 2.4027 10.61716004 2.4842 2 P 0 
L 10.61716004 2.4842 10.60466004 2.4967 2 P 0 
L 10.60466004 2.4967 10.531 2.4967 2 P 0 
L 10.531 2.4967 10.4776 2.5501 2 P 0 
L 10.4776 2.5501 10.3506 2.5501 2 P 0 
L 10.3506 2.5501 10.3367 2.564 2 P 0 
L 10.3367 2.564 10.10445 2.564 2 P 0 
L 10.10445 2.564 10.09 2.57845 2 P 0 
P 10.09 2.57845 6 P 0 0;5=4,7=1
P 10.68661004 2.41615 6 P 0 0;5=4,7=1
P 11.73316004 1.492 6 P 0 0;5=4,7=1
P 11.65593002 1.49 25 P 0 0;2,5=0,7=0
P 12.63778996 2.24016004 11 P 0 0;3,5=2,7=0
L 11.65593002 1.49 11.67333002 1.5074 2 P 0 
L 11.67333002 1.5074 11.71776004 1.5074 2 P 0 
L 11.71776004 1.5074 11.73316004 1.492 2 P 0 
P 8.78578996 5.14 6 P 0 0;5=4,7=1
P 8.05 3.66615 6 P 0 0;5=4,7=1
P 12.73621004 2.7126 11 P 0 0;3,5=2,7=0
P 10.73661004 2.06615 6 P 0 0;5=4,7=1
L 10.73661004 2.06615 10.73661004 2.0527 2 P 0 
L 10.73661004 2.0527 10.73061004 2.0467 2 P 0 
L 10.73061004 2.0467 10.66856004 2.0467 2 P 0 
L 10.66856004 2.0467 10.65606004 2.0342 2 P 0 
L 10.65606004 2.0342 10.65606004 2.0027 2 P 0 
L 10.65606004 2.0027 10.65006004 1.9967 2 P 0 
L 10.65006004 1.9967 10.53821998 1.9967 2 P 0 
L 10.53821998 1.9967 10.50805 1.9756 2 P 0 
L 10.50805 1.9756 10.47911998 1.93426998 2 P 0 
L 10.47911998 1.93426998 10.37933996 1.86438996 2 P 0 
L 10.37933996 1.86438996 10.32043002 1.854 2 P 0 
L 10.32043002 1.854 10.2747 1.854 2 P 0 
L 10.2747 1.854 10.26025 1.86845 2 P 0 
P 10.26025 1.86845 6 P 0 0;5=4,7=1
P 11.03661004 2.46615 6 P 0 0;5=4,7=1
P 11.42193002 2.53 25 P 0 0;2,5=0,7=0
L 11.03661004 2.46615 11.03661004 2.4796 2 P 0 
L 11.03661004 2.4796 11.04261004 2.4856 2 P 0 
L 11.04261004 2.4856 11.13516998 2.4856 2 P 0 
L 11.13516998 2.4856 11.30031998 2.51471998 2 P 0 
L 11.30031998 2.51471998 11.33736998 2.54066998 2 P 0 
L 11.33736998 2.54066998 11.373 2.54695 2 P 0 
L 11.373 2.54695 11.40498002 2.54695 2 P 0 
L 11.40498002 2.54695 11.42193002 2.53 2 P 0 
P 8.15 3.61615 6 P 0 0;5=4,7=1
P 8.88441004 5.17001998 6 P 0 0;5=4,7=1
P 12.55905 4.09055 11 P 0 0;3,5=2,7=0
L 11.53316004 2.412 11.51966004 2.3985 2 P 0 
L 11.51966004 2.3985 11.47143002 2.3985 2 P 0 
L 11.47143002 2.3985 11.45593002 2.414 2 P 0 
L 11.45593002 2.414 11.45593002 2.415 2 P 0 
P 11.53316004 2.412 6 P 0 0;5=4,7=1
P 11.45593002 2.415 25 P 0 0;2,5=0,7=0
P 11.03661004 2.51615 6 P 0 0;5=4,7=1
L 11.03661004 2.51615 11.03661004 2.5027 2 P 0 
L 11.03661004 2.5027 11.04261004 2.4967 2 P 0 
L 11.04261004 2.4967 11.13418996 2.4967 2 P 0 
L 11.13418996 2.4967 11.29596004 2.52523002 2 P 0 
L 11.29596004 2.52523002 11.33301998 2.55118002 2 P 0 
L 11.33301998 2.55118002 11.37201998 2.55805 2 P 0 
L 11.37201998 2.55805 11.40498002 2.55805 2 P 0 
L 11.40498002 2.55805 11.42193002 2.575 2 P 0 
P 11.42193002 2.575 25 P 0 0;2,5=0,7=0
P 8.15 3.66615 6 P 0 0;5=4,7=1
P 8.92441004 5.17001998 6 P 0 0;5=4,7=1
L 1.057 5.027 0.967 5.027 3 P 0 
L 0.967 5.027 0.715 4.775 3 P 0 
L 0.715 4.775 0.715 2.15 3 P 0 
L 0.715 2.15 2.565 0.3 3 P 0 
L 2.565 0.3 3.9 0.3 3 P 0 
L 3.9 0.3 3.955 0.355 3 P 0 
L 3.955 0.355 3.955 0.55 3 P 0 
L 3.955 0.55 3.97 0.565 3 P 0 
L 3.97 0.565 9.135 0.565 3 P 0 
L 9.135 0.565 9.38 0.32 3 P 0 
L 9.38 0.32 9.585 0.32 3 P 0 
L 9.585 0.32 9.7135 0.4485 3 P 0 
L 9.7135 0.4485 9.7135 2.68198002 3 P 0 
L 9.7135 2.68198002 9.88151998 2.85 3 P 0 
L 9.88151998 2.85 9.95743996 2.85 3 P 0 
L 3.91351004 2.62 3.95 2.62 3 P 0 
L 3.95 2.62 3.955 2.615 3 P 0 
L 3.955 2.615 3.955 0.58 3 P 0 
L 3.955 0.58 3.97 0.565 3 P 0 
P 3.91351004 2.62 30 P 0 0;2,5=8,7=0
P 9.95743996 2.85 30 P 0 0;2,5=8,7=0
P 1.057 5.027 8 P 0 0;3,5=1,7=1
P 12.73621004 3.18503996 11 P 0 0;3,5=2,7=0
P 10.68661004 2.11615 6 P 0 0;5=4,7=1
P 10.09 2.17095 6 P 0 0;5=4,7=1
L 10.68661004 2.11615 10.68661004 2.1029 2 P 0 
L 10.68661004 2.1029 10.68041004 2.0967 2 P 0 
L 10.68041004 2.0967 10.62336004 2.0967 2 P 0 
L 10.62336004 2.0967 10.61716004 2.1029 2 P 0 
L 10.61716004 2.1029 10.61716004 2.1342 2 P 0 
L 10.61716004 2.1342 10.60466004 2.1467 2 P 0 
L 10.60466004 2.1467 10.48951004 2.1467 2 P 0 
L 10.48951004 2.1467 10.34313996 2.1209 2 P 0 
L 10.34313996 2.1209 10.14123996 2.1565 2 P 0 
L 10.14123996 2.1565 10.10445 2.1565 2 P 0 
L 10.10445 2.1565 10.09 2.17095 2 P 0 
L 11.65593002 1.695 11.67243002 1.6785 2 P 0 
L 11.67243002 1.6785 11.76966004 1.6785 2 P 0 
L 11.76966004 1.6785 11.78316004 1.692 2 P 0 
P 11.78316004 1.692 6 P 0 0;5=4,7=1
P 11.65593002 1.695 25 P 0 0;2,5=0,7=0
P 12.55905 2.04331004 11 P 0 0;3,5=2,7=0
P 12.81495 2.90945 11 P 0 0;3,5=2,7=0
P 10.63661004 2.01615 6 P 0 0;5=4,7=1
P 10.225 1.92645 6 P 0 0;5=4,7=1
L 10.63661004 2.01615 10.63661004 2.0296 2 P 0 
L 10.63661004 2.0296 10.63061004 2.0356 2 P 0 
L 10.63061004 2.0356 10.54308002 2.0356 2 P 0 
L 10.54308002 2.0356 10.45928996 2.02081998 2 P 0 
L 10.45928996 2.02081998 10.36236004 1.95295 2 P 0 
L 10.36236004 1.95295 10.294 1.9409 2 P 0 
L 10.294 1.9409 10.23945 1.9409 2 P 0 
L 10.23945 1.9409 10.225 1.92645 2 P 0 
L 11.65593002 1.65 11.67333002 1.6674 2 P 0 
L 11.67333002 1.6674 11.76776004 1.6674 2 P 0 
L 11.76776004 1.6674 11.78316004 1.652 2 P 0 
P 11.78316004 1.652 6 P 0 0;5=4,7=1
P 11.65593002 1.65 25 P 0 0;2,5=0,7=0
P 12.63778996 2.08268002 11 P 0 0;3,5=2,7=0
P 1.122 5.417 7 P 0 0;5=6,7=1
L 5.72185 3 5.6492 3 3 P 0 
P 5.6492 3 25 P 0 0;2,5=0,7=0
P 5.72185 3 30 P 0 0;2,5=8,7=0
P 5.855 0.925 7 P 0 0;5=6,7=1
L 5.855 0.925 5.855 2.675 3 P 0 
L 5.855 2.675 5.99 2.81 3 P 0 
L 5.99 2.81 5.99 3.06 3 P 0 
L 5.99 3.06 5.915 3.135 3 P 0 
L 5.915 3.135 5.69 3.135 3 P 0 
L 5.69 3.135 5.6492 3.0942 3 P 0 
L 5.6492 3.0942 5.6492 3 3 P 0 
P 3.88 4.545 8 P 0 0;3,5=1,7=1
L 3.88 4.545 3.77 4.545 3 P 0 
L 3.77 4.545 3.7 4.615 3 P 0 
L 3.7 4.615 3.7 4.65 3 P 0 
L 3.7 4.65 3.65 4.7 3 P 0 
L 3.65 4.7 3.65 5.17 3 P 0 
L 3.65 5.17 3.3154 5.5046 3 P 0 
L 3.3154 5.5046 1.1667 5.5046 3 P 0 
L 1.1667 5.5046 1.159 5.4969 3 P 0 
L 1.159 5.4969 1.159 5.44 3 P 0 
L 1.159 5.44 1.136 5.417 3 P 0 
L 1.136 5.417 1.122 5.417 3 P 0 
P 0.96555 5.78055 8 P 0 0;3,5=1,7=1
P 4.07 4.625 7 P 0 0;5=6,7=1
L 4.07 4.625 4.02175 4.67325 3 P 0 
L 4.02175 4.67325 4.02175 4.77821004 3 P 0 
L 4.02175 4.77821004 3.98066004 4.8193 3 P 0 
L 3.98066004 4.8193 3.94933996 4.8193 3 P 0 
L 3.94933996 4.8193 3.9193 4.84933996 3 P 0 
L 3.9193 4.84933996 3.9193 5.3207 3 P 0 
L 3.9193 5.3207 3.495 5.745 3 P 0 
L 3.495 5.745 1.0011 5.745 3 P 0 
L 1.0011 5.745 0.96555 5.78055 3 P 0 
P 10.58661004 2.71615 6 P 0 0;5=4,7=1
P 10.133 2.928 25 P 0 0;2,5=0,7=0
P 9.91 4.433 8 P 0 0;3,5=1,7=1
L 9.995 2.936 10.023 2.964 3 P 0 
L 10.023 2.964 10.117 2.964 3 P 0 
L 10.117 2.964 10.133 2.948 3 P 0 
L 10.133 2.948 10.133 2.928 3 P 0 
P 9.995 2.936 7 P 0 0;5=6,7=1
L 10.58661004 2.71615 10.58046004 2.71 3 P 0 
L 10.58046004 2.71 10.48498996 2.71 3 P 0 
L 10.48498996 2.71 10.26698996 2.928 3 P 0 
L 10.26698996 2.928 10.133 2.928 3 P 0 
L 11.45593002 2.255 11.47243002 2.2385 2 P 0 
L 11.47243002 2.2385 11.81966004 2.2385 2 P 0 
L 11.81966004 2.2385 11.83316004 2.252 2 P 0 
P 11.83316004 2.252 6 P 0 0;5=4,7=1
P 11.45593002 2.255 25 P 0 0;2,5=0,7=0
P 12.55905 3.61811004 11 P 0 0;3,5=2,7=0
P 12.81495 3.06693002 11 P 0 0;3,5=2,7=0
P 10.58661004 2.06615 6 P 0 0;5=4,7=1
L 10.58661004 2.06615 10.58661004 2.0796 2 P 0 
L 10.58661004 2.0796 10.58061004 2.0856 2 P 0 
L 10.58061004 2.0856 10.52 2.0856 2 P 0 
L 10.52 2.0856 10.17791004 2.02525 2 P 0 
L 10.17791004 2.02525 10.14533002 2.031 2 P 0 
L 10.14533002 2.031 10.10445 2.031 2 P 0 
L 10.10445 2.031 10.09 2.01655 2 P 0 
P 10.09 2.01655 6 P 0 0;5=4,7=1
P 8.1 3.81615 6 P 0 0;5=4,7=1
P 9.10011004 5.0535 6 P 0 0;5=4,7=1
P 8.1 3.86615 6 P 0 0;5=4,7=1
P 9.14011004 5.0535 6 P 0 0;5=4,7=1
P 3.9599 5.395 8 P 0 0;3,5=1,7=1
P 0.88681004 5.78181004 7 P 0 0;5=6,7=1
L 0.88681004 5.78181004 0.925 5.82 3 P 0 
L 0.925 5.82 1.015 5.82 3 P 0 
L 1.015 5.82 1.035 5.8 3 P 0 
L 1.035 5.8 1.165 5.8 3 P 0 
L 1.165 5.8 1.185 5.82 3 P 0 
L 1.185 5.82 3.47 5.82 3 P 0 
L 3.47 5.82 3.84 5.45 3 P 0 
L 3.84 5.45 3.9048 5.45 3 P 0 
L 3.9048 5.45 3.92295 5.43185 3 P 0 
L 3.92295 5.43185 3.92516998 5.43185 3 P 0 
L 3.92516998 5.43185 3.94675 5.41026998 3 P 0 
L 3.94675 5.41026998 3.94675 5.40805 3 P 0 
L 3.94675 5.40805 3.9598 5.395 3 P 0 
L 3.9598 5.395 3.9599 5.395 3 P 0 
P 12.73621004 2.3189 11 P 0 0;3,5=2,7=0
P 10.63661004 1.91615 6 P 0 0;5=4,7=1
P 10.38371998 1.49328002 6 P 0 0;5=4,7=1
L 10.63661004 1.91615 10.63661004 1.91 2 P 0 
L 10.63661004 1.91 10.64261004 1.904 2 P 0 
L 10.64261004 1.904 10.65266004 1.904 2 P 0 
L 10.65266004 1.904 10.66716004 1.8895 2 P 0 
L 10.66716004 1.8895 10.66716004 1.79746004 2 P 0 
L 10.66716004 1.79746004 10.38371998 1.51401998 2 P 0 
L 10.38371998 1.51401998 10.38371998 1.49328002 2 P 0 
P 8.35 3.81615 6 P 0 0;5=4,7=1
P 9.28185 5.22001998 6 P 0 0;5=4,7=1
P 0.72933002 5.463 8 P 0 0;3,5=1,7=1
L 11.45593002 2.575 11.45593002 2.574 2 P 0 
L 11.45593002 2.574 11.47143002 2.5585 2 P 0 
L 11.47143002 2.5585 11.51966004 2.5585 2 P 0 
L 11.51966004 2.5585 11.53316004 2.572 2 P 0 
P 11.53316004 2.572 6 P 0 0;5=4,7=1
P 11.45593002 2.575 25 P 0 0;2,5=0,7=0
P 12.55905 4.56298996 11 P 0 0;3,5=2,7=0
P 8.35 3.86615 6 P 0 0;5=4,7=1
P 9.24185 5.22001998 6 P 0 0;5=4,7=1
L 4.58268002 2.71615 4.54853002 2.682 3 P 0 
L 4.54853002 2.682 4.125 2.682 3 P 0 
L 4.125 2.682 4.109 2.682 3 P 0 
L 4.109 2.682 4.091 2.7 3 P 0 
P 4.091 2.7 25 P 0 0;2,5=0,7=0
P 4.125 2.682 7 P 0 0;5=6,7=1
P 3.94 4.42 8 P 0 0;3,5=1,7=1
P 5.03 5.4 7 P 0 0;5=6,7=1
P 4.58268002 2.71615 6 P 0 0;5=4,7=1
L 3.94 4.42 3.98 4.46 3 P 0 
L 3.98 4.46 4.075 4.46 3 P 0 
L 4.075 4.46 4.205 4.59 3 P 0 
L 4.205 4.59 4.205 5.245 3 P 0 
L 4.205 5.245 4.24 5.28 3 P 0 
L 4.24 5.28 4.955 5.28 3 P 0 
L 4.955 5.28 5.03 5.355 3 P 0 
L 5.03 5.355 5.03 5.4 3 P 0 
P 8.45 3.81615 6 P 0 0;5=4,7=1
P 9.21098002 4.78291998 6 P 0 0;5=4,7=1
P 8.45 3.86615 6 P 0 0;5=4,7=1
P 9.17098002 4.78291998 6 P 0 0;5=4,7=1
P 3.75998996 0.24001004 8 P 0 0;3,5=1,7=1
P 9.55795 0.26133996 8 P 0 0;3,5=1,7=1
P 3.71203002 0.77535 7 P 0 0;5=6,7=1
P 3.70998996 0.7 7 P 0 0;5=6,7=1
P 9.50795 0.72133002 7 P 0 0;5=6,7=1
P 9.46795 0.82631998 7 P 0 0;5=6,7=1
L 4.02893002 2.59336998 4.03048996 2.59336998 5 P 0 
L 4.03048996 2.59336998 4.03386004 2.59 5 P 0 
L 4.03386004 2.59 4.05686004 2.59 5 P 0 
P 3.99421004 2.59441004 30 P 0 0;2,5=8,7=0
L 3.99421004 2.59441004 4.02788996 2.59441004 5 P 0 
L 4.02788996 2.59441004 4.02893002 2.59336998 5 P 0 
L 4.09086004 2.65 4.09086004 2.637 5 P 0 
L 4.09086004 2.637 4.05686004 2.603 5 P 0 
L 4.05686004 2.603 4.05686004 2.59 5 P 0 
P 4.09086004 2.65 25 P 0 0;2,5=0,7=0
P 4.05686004 2.59 25 P 0 0;2,5=0,7=0
P 4.02893002 2.59336998 7 P 0 0;5=6,7=1
L 11.35061998 2.73 11.39 2.73 5 P 0 
L 11.39 2.73 11.395 2.725 5 P 0 
P 11.35061998 2.73 25 P 0 0;2,5=0,7=0
P 11.395 2.725 8 P 0 0;3,5=1,7=1
L 11.35061998 2.8 11.395 2.8 5 P 0 
P 11.35061998 2.8 25 P 0 0;2,5=0,7=0
P 11.395 2.8 7 P 0 0;5=6,7=1
P 11.61661998 2.905 25 P 0 0;2,5=0,7=0
P 11.58613002 2.905 7 P 0 0;5=6,7=1
L 11.61661998 2.905 11.58613002 2.905 5 P 0 
P 11.61661998 2.785 25 P 0 0;2,5=0,7=0
P 11.58613002 2.785 7 P 0 0;5=6,7=1
L 11.61661998 2.785 11.58613002 2.785 5 P 0 
P 1.33906004 4.60351004 8 P 0 0;3,5=1,7=1
P 3.67 4.45 7 P 0 0;5=6,7=1
P 3.72 4.545 7 P 0 0;5=6,7=1
L 5.387 2.725 5.382 2.73 5 P 0 
L 5.382 2.73 5.34668996 2.73 5 P 0 
P 5.37968996 2.8 7 P 0 0;5=6,7=1
P 5.34668996 2.8 25 P 0 0;2,5=0,7=0
L 5.34668996 2.8 5.37968996 2.8 5 P 0 
P 5.387 2.725 8 P 0 0;3,5=1,7=1
P 5.34668996 2.73 25 P 0 0;2,5=0,7=0
P 5.61268996 2.785 25 P 0 0;2,5=0,7=0
P 5.5822 2.785 7 P 0 0;5=6,7=1
L 5.61268996 2.785 5.5822 2.785 5 P 0 
P 5.61268996 2.905 25 P 0 0;2,5=0,7=0
P 5.5822 2.905 7 P 0 0;5=6,7=1
L 5.61268996 2.905 5.5822 2.905 5 P 0 
P 7.2426 4.69351004 7 P 0 0;5=6,7=1
P 7.2926 4.60351004 7 P 0 0;5=6,7=1
P 9.98 4.51 7 P 0 0;5=6,7=1
P 10.133 2.88 25 P 0 0;2,5=0,7=0
L 10.10078996 2.82 10.07778996 2.82 5 P 0 
L 10.07778996 2.82 10.07441998 2.82336998 5 P 0 
L 10.07441998 2.82336998 10.07286004 2.82336998 5 P 0 
P 10.07286004 2.82336998 7 P 0 0;5=6,7=1
P 10.03813996 2.82441004 30 P 0 0;2,5=8,7=0
P 10.10078996 2.82 25 P 0 0;2,5=0,7=0
L 10.07286004 2.82336998 10.07181998 2.82441004 5 P 0 
L 10.07181998 2.82441004 10.03813996 2.82441004 5 P 0 
L 10.133 2.88 10.133 2.86701004 5 P 0 
L 10.133 2.86701004 10.10078996 2.8348 5 P 0 
L 10.10078996 2.8348 10.10078996 2.82 5 P 0 
P 10.03 4.61 7 P 0 0;5=6,7=1
P 1.23906004 4.69351004 7 P 0 0;5=6,7=1
P 3.89 4.655 7 P 0 0;5=6,7=1
P 3.9899 4.765 7 P 0 0;5=6,7=1
P 4.1049 4.86 7 P 0 0;5=6,7=1
P 4.0599 5.395 7 P 0 0;5=6,7=1
P 3.91 5.51 7 P 0 0;5=6,7=1
P 5.125 5.4 7 P 0 0;5=6,7=1
P 1.37925 5.78 7 P 0 0;5=6,7=1
P 1.45798996 5.78 7 P 0 0;5=6,7=1
P 1.42 5.78 7 P 0 0;5=6,7=1
P 1.335 5.78 7 P 0 0;5=6,7=1
L 11.45593002 1.615 11.47243002 1.5985 2 P 0 
L 11.47243002 1.5985 11.51966004 1.5985 2 P 0 
L 11.51966004 1.5985 11.53316004 1.612 2 P 0 
P 12.63778996 2.55511998 11 P 0 0;3,5=2,7=0
P 11.53316004 1.612 6 P 0 0;5=4,7=1
P 11.45593002 1.615 25 P 0 0;2,5=0,7=0
P 8.4 3.76615 6 P 0 0;5=4,7=1
P 9.28185 4.642 6 P 0 0;5=4,7=1
P 12.73621004 4.36613996 11 P 0 0;3,5=2,7=0
P 10.63661004 2.41615 6 P 0 0;5=4,7=1
P 9.975 2.66445 6 P 0 0;5=4,7=1
L 10.63661004 2.41615 10.63661004 2.424 2 P 0 
L 10.63661004 2.424 10.64261004 2.43 2 P 0 
L 10.64261004 2.43 10.65366004 2.43 2 P 0 
L 10.65366004 2.43 10.66716004 2.4435 2 P 0 
L 10.66716004 2.4435 10.66716004 2.5342 2 P 0 
L 10.66716004 2.5342 10.65466004 2.5467 2 P 0 
L 10.65466004 2.5467 10.56103002 2.5467 2 P 0 
L 10.56103002 2.5467 10.50368002 2.604 2 P 0 
L 10.50368002 2.604 10.394 2.604 2 P 0 
L 10.394 2.604 10.348 2.65 2 P 0 
L 10.348 2.65 9.98945 2.65 2 P 0 
L 9.98945 2.65 9.975 2.66445 2 P 0 
P 8.4 3.81615 6 P 0 0;5=4,7=1
P 9.24185 4.642 6 P 0 0;5=4,7=1
L 11.45593002 2.53 11.47333002 2.5474 2 P 0 
L 11.47333002 2.5474 11.51776004 2.5474 2 P 0 
L 11.51776004 2.5474 11.53316004 2.532 2 P 0 
P 11.53316004 2.532 6 P 0 0;5=4,7=1
P 11.45593002 2.53 25 P 0 0;2,5=0,7=0
P 12.63778996 4.60236998 11 P 0 0;3,5=2,7=0
P 8.45 3.66615 6 P 0 0;5=4,7=1
P 9.42358002 4.78291998 6 P 0 0;5=4,7=1
P 0.95951004 5.4595 8 P 0 0;3,5=1,7=1
P 8.45 3.71615 6 P 0 0;5=4,7=1
P 9.38358002 4.78291998 6 P 0 0;5=4,7=1
P 8.4 3.61615 6 P 0 0;5=4,7=1
P 9.49445 4.587 6 P 0 0;5=4,7=1
P 8.4 3.66615 6 P 0 0;5=4,7=1
P 9.45445 4.587 6 P 0 0;5=4,7=1
L 9.07353996 4.42 9.11853996 4.42 3 P 0 
L 9.11853996 4.42 9.16353996 4.465 3 P 0 
L 9.16353996 4.465 9.16353996 4.508 3 P 0 
P 9.16353996 4.508 25 P 0 0;2,5=0,7=0
P 9.07353996 4.42 7 P 0 0;5=6,7=1
P 7.1926 5.15351004 8 P 0 0;3,5=1,7=1
L 7.1926 5.15351004 7.23111004 5.115 3 P 0 
L 7.23111004 5.115 7.29301004 5.115 3 P 0 
L 7.29301004 5.115 7.40083996 5.00716998 3 P 0 
L 7.40083996 5.00716998 7.40083996 4.49916004 3 P 0 
L 7.40083996 4.49916004 7.5457 4.3543 3 P 0 
L 7.5457 4.3543 8.0223 4.3543 3 P 0 
L 8.0223 4.3543 8.1453 4.4773 3 P 0 
L 8.1453 4.4773 9.0067 4.4773 3 P 0 
L 9.0067 4.4773 9.064 4.42 3 P 0 
L 9.064 4.42 9.07353996 4.42 3 P 0 
P 8.1 3.66615 6 P 0 0;5=4,7=1
P 8.74578996 4.667 6 P 0 0;5=4,7=1
P 8.1 3.71615 6 P 0 0;5=4,7=1
P 8.78578996 4.667 6 P 0 0;5=4,7=1
P 8.2 3.66615 6 P 0 0;5=4,7=1
P 8.81665 4.78291998 6 P 0 0;5=4,7=1
P 8.2 3.71615 6 P 0 0;5=4,7=1
P 8.85665 4.78291998 6 P 0 0;5=4,7=1
P 8.05 3.76615 6 P 0 0;5=4,7=1
P 8.89061998 4.667 6 P 0 0;5=4,7=1
P 8.05 3.81615 6 P 0 0;5=4,7=1
P 8.93061998 4.667 6 P 0 0;5=4,7=1
P 9.02925 4.667 6 P 0 0;5=4,7=1
P 8.2 3.81615 6 P 0 0;5=4,7=1
P 9.06925 4.667 6 P 0 0;5=4,7=1
P 8.2 3.86615 6 P 0 0;5=4,7=1
P 5.31268996 2.73 25 P 0 0;2,5=0,7=0
P 5.42768996 2.73 25 P 0 0;2,5=0,7=0
P 4.68268002 2.71615 6 P 0 0;5=4,7=1
L 5.31268996 2.73 5.27 2.73 3 P 0 
P 5.27 2.73 8 P 0 0;3,5=5,7=1
L 5.42768996 2.73 5.42768996 2.7573 3 P 0 
L 5.42768996 2.7573 5.41998996 2.765 3 P 0 
L 5.41998996 2.765 5.32088996 2.765 3 P 0 
L 5.32088996 2.765 5.31268996 2.7568 3 P 0 
L 5.31268996 2.7568 5.31268996 2.73 3 P 0 
L 5.27 2.73 5.1819 2.73 3 P 0 
L 5.1819 2.73 5.09305 2.64115 3 P 0 
L 5.09305 2.64115 4.86485 2.64115 3 P 0 
L 4.86485 2.64115 4.81485 2.69115 3 P 0 
L 4.81485 2.69115 4.70768002 2.69115 3 P 0 
L 4.70768002 2.69115 4.68268002 2.71615 3 P 0 
L 5.27 2.8 5.2019 2.8 3 P 0 
L 5.2019 2.8 5.09305 2.69115 3 P 0 
L 5.09305 2.69115 5.00768002 2.69115 3 P 0 
L 5.00768002 2.69115 4.98268002 2.71615 3 P 0 
L 5.42768996 2.8 5.42768996 2.82415 3 P 0 
L 5.42768996 2.82415 5.41998996 2.83185 3 P 0 
L 5.41998996 2.83185 5.32038996 2.83185 3 P 0 
L 5.32038996 2.83185 5.31268996 2.82415 3 P 0 
L 5.31268996 2.82415 5.31268996 2.8 3 P 0 
L 5.27 2.8 5.31268996 2.8 3 P 0 
P 4.98268002 2.71615 6 P 0 0;5=4,7=1
P 5.31268996 2.8 25 P 0 0;2,5=0,7=0
P 5.42768996 2.8 25 P 0 0;2,5=0,7=0
P 5.27 2.8 8 P 0 0;3,5=5,7=1
L 1.9 2.48 1.8769 2.48 3 P 0 
L 1.8769 2.48 1.875 2.4781 3 P 0 
L 1.875 2.4781 1.85421004 2.4781 3 P 0 
L 1.9 2.48 1.92885 2.48 3 P 0 
L 1.92885 2.48 1.94 2.49115 3 P 0 
L 1.94 2.49115 2.12106004 2.49115 3 P 0 
L 2.12106004 2.49115 2.14606004 2.51615 3 P 0 
P 1.85421004 2.4781 25 P 0 0;2,5=0,7=0
P 2.14606004 2.51615 6 P 0 0;5=4,7=1
P 1.9 2.48 8 P 0 0;3,5=5,7=1
P 8.45 3.41615 6 P 0 0;5=4,7=1
P 8.18811004 5.0535 6 P 0 0;5=4,7=1
L 4.07408002 4.01978996 3.77886998 4.315 3 P 0 
L 3.77886998 4.315 3.027 4.315 3 P 0 
L 3.027 4.315 2.907 4.435 3 P 0 
L 2.907 4.435 2.145 4.435 3 P 0 
L 2.145 4.435 1.823 4.113 3 P 0 
L 1.823 4.113 1.823 3.61 3 P 0 
P 1.823 3.61 25 P 0 0;2,5=0,7=0
P 5.03268002 3.81615 6 P 0 0;5=4,7=1
P 4.07408002 4.01978996 8 P 0 0;3,5=1,7=1
P 8.45 3.46615 6 P 0 0;5=4,7=1
P 8.14811004 5.0535 6 P 0 0;5=4,7=1
P 5.03268002 2.16615 6 P 0 0;5=4,7=1
P 3.9099 5.395 8 P 0 0;3,5=1,7=1
P 8.45 3.26615 6 P 0 0;5=4,7=1
P 8.40071004 5.115 6 P 0 0;5=4,7=1
P 8.45 3.31615 6 P 0 0;5=4,7=1
P 8.36071004 5.115 6 P 0 0;5=4,7=1
P 8.35 3.26615 6 P 0 0;5=4,7=1
P 8.40071004 4.742 6 P 0 0;5=4,7=1
P 8.35 3.31615 6 P 0 0;5=4,7=1
P 8.36071004 4.742 6 P 0 0;5=4,7=1
P 8.3 3.56615 6 P 0 0;5=4,7=1
L 8.3 3.56615 8.275 3.54115 3 P 0 
L 8.275 3.54115 8.275 3.40578996 3 P 0 
L 8.275 3.40578996 8.26036004 3.39115 3 P 0 
L 8.26036004 3.39115 7.98478996 3.39115 3 P 0 
L 7.98478996 3.39115 7.96393996 3.412 3 P 0 
L 7.96393996 3.412 7.96393996 3.465 3 P 0 
L 7.96393996 3.465 7.91893996 3.51 3 P 0 
L 7.91893996 3.51 7.90393996 3.51 3 P 0 
P 7.86093996 3.51 25 P 0 0;2,5=0,7=0
L 7.86093996 3.51 7.90393996 3.51 3 P 0 
P 7.90393996 3.51 8 P 0 0;3,5=5,7=1
P 8.05 3.31615 6 P 0 0;5=4,7=1
P 7.58118996 5.169 6 P 0 0;5=4,7=1
P 8.25 3.56615 6 P 0 0;5=4,7=1
L 8.25 3.56615 8.225 3.54115 3 P 0 
L 8.225 3.54115 7.96278996 3.54115 3 P 0 
L 7.96278996 3.54115 7.94393996 3.56 3 P 0 
L 7.94393996 3.56 7.90393996 3.56 3 P 0 
P 7.90393996 3.56 8 P 0 0;3,5=5,7=1
P 7.86093996 3.56 25 P 0 0;2,5=0,7=0
L 7.90393996 3.56 7.86093996 3.56 3 P 0 
P 8.05 3.36615 6 P 0 0;5=4,7=1
P 7.62118996 5.169 6 P 0 0;5=4,7=1
P 2.24606004 2.86615 6 P 0 0;5=4,7=1
P 2.63685 2.82 25 P 0 0;2,5=0,7=0
L 2.63685 2.82 2.61685 2.84 2 P 0 
L 2.61685 2.84 2.5617 2.84 2 P 0 
L 2.5617 2.84 2.5573 2.8356 2 P 0 
L 2.5573 2.8356 2.27801004 2.8356 2 P 0 
L 2.27801004 2.8356 2.26551004 2.8481 2 P 0 
L 2.26551004 2.8481 2.26551004 2.86015 2 P 0 
L 2.26551004 2.86015 2.25951004 2.86615 2 P 0 
L 2.25951004 2.86615 2.24606004 2.86615 2 P 0 
L 7.82415 2.4781 7.78 2.4781 5 P 0 
L 0.61698002 2.045 0.66 2.045 5 P 0 
P 5.59 4.475 8 P 0 0;3,5=5,7=1
P 8.05 2.61615 6 P 0 0;5=4,7=1
P 8.05 2.66615 6 P 0 0;5=4,7=1
P 8.1 2.46615 6 P 0 0;5=4,7=1
P 8.1 2.41615 6 P 0 0;5=4,7=1
P 8.2 2.46615 6 P 0 0;5=4,7=1
P 8.2 2.41615 6 P 0 0;5=4,7=1
P 8.15 2.41615 6 P 0 0;5=4,7=1
P 8.15 2.36615 6 P 0 0;5=4,7=1
P 8.05 2.41615 6 P 0 0;5=4,7=1
P 8.05 2.36615 6 P 0 0;5=4,7=1
P 8.2 2.31615 6 P 0 0;5=4,7=1
P 8.2 2.26615 6 P 0 0;5=4,7=1
P 8.15 2.26615 6 P 0 0;5=4,7=1
P 8.15 2.21615 6 P 0 0;5=4,7=1
P 8.1 2.31615 6 P 0 0;5=4,7=1
P 8.1 2.26615 6 P 0 0;5=4,7=1
P 8.05 2.26615 6 P 0 0;5=4,7=1
P 8.05 2.21615 6 P 0 0;5=4,7=1
P 8.1 2.11615 6 P 0 0;5=4,7=1
P 8.1 2.06615 6 P 0 0;5=4,7=1
P 8.2 2.11615 6 P 0 0;5=4,7=1
P 8.2 2.06615 6 P 0 0;5=4,7=1
P 8.15 2.06615 6 P 0 0;5=4,7=1
P 8.15 2.01615 6 P 0 0;5=4,7=1
P 8.05 2.06615 6 P 0 0;5=4,7=1
P 8.05 2.01615 6 P 0 0;5=4,7=1
P 8.2 1.96615 6 P 0 0;5=4,7=1
P 8.2 1.91615 6 P 0 0;5=4,7=1
P 8.15 1.91615 6 P 0 0;5=4,7=1
P 8.15 1.86615 6 P 0 0;5=4,7=1
P 8.1 1.96615 6 P 0 0;5=4,7=1
P 8.1 1.91615 6 P 0 0;5=4,7=1
P 8.05 1.91615 6 P 0 0;5=4,7=1
P 8.05 1.86615 6 P 0 0;5=4,7=1
P 8.1 3.16615 6 P 0 0;5=4,7=1
P 8.1 3.11615 6 P 0 0;5=4,7=1
P 8.2 3.16615 6 P 0 0;5=4,7=1
P 8.2 3.11615 6 P 0 0;5=4,7=1
P 8.15 3.11615 6 P 0 0;5=4,7=1
P 8.15 3.06615 6 P 0 0;5=4,7=1
P 8.05 3.11615 6 P 0 0;5=4,7=1
P 8.05 3.06615 6 P 0 0;5=4,7=1
P 8.2 3.01615 6 P 0 0;5=4,7=1
P 8.2 2.96615 6 P 0 0;5=4,7=1
P 8.15 2.96615 6 P 0 0;5=4,7=1
P 8.15 2.91615 6 P 0 0;5=4,7=1
P 8.1 3.01615 6 P 0 0;5=4,7=1
P 8.1 2.96615 6 P 0 0;5=4,7=1
P 8.05 2.96615 6 P 0 0;5=4,7=1
P 8.05 2.91615 6 P 0 0;5=4,7=1
P 8 2.81615 6 P 0 0;5=4,7=1
P 8 2.76615 6 P 0 0;5=4,7=1
P 8.15 2.81615 6 P 0 0;5=4,7=1
P 8.15 2.76615 6 P 0 0;5=4,7=1
P 8.2 2.76615 6 P 0 0;5=4,7=1
P 8.2 2.71615 6 P 0 0;5=4,7=1
P 8.1 2.76615 6 P 0 0;5=4,7=1
P 8.1 2.71615 6 P 0 0;5=4,7=1
P 8.15 2.66615 6 P 0 0;5=4,7=1
P 8.15 2.61615 6 P 0 0;5=4,7=1
P 8.2 2.61615 6 P 0 0;5=4,7=1
P 8.2 2.56615 6 P 0 0;5=4,7=1
P 8.1 2.61615 6 P 0 0;5=4,7=1
P 8.1 2.56615 6 P 0 0;5=4,7=1
P 8.35 2.56615 6 P 0 0;5=4,7=1
P 8.35 2.61615 6 P 0 0;5=4,7=1
P 8.35 2.46615 6 P 0 0;5=4,7=1
P 8.35 2.41615 6 P 0 0;5=4,7=1
P 8.45 2.46615 6 P 0 0;5=4,7=1
P 8.45 2.41615 6 P 0 0;5=4,7=1
P 8.5 2.41615 6 P 0 0;5=4,7=1
P 8.5 2.36615 6 P 0 0;5=4,7=1
P 8.4 2.41615 6 P 0 0;5=4,7=1
P 8.4 2.36615 6 P 0 0;5=4,7=1
P 8.45 2.31615 6 P 0 0;5=4,7=1
P 8.45 2.26615 6 P 0 0;5=4,7=1
P 8.5 2.26615 6 P 0 0;5=4,7=1
P 8.5 2.21615 6 P 0 0;5=4,7=1
P 8.4 2.26615 6 P 0 0;5=4,7=1
P 8.4 2.21615 6 P 0 0;5=4,7=1
P 8.35 2.31615 6 P 0 0;5=4,7=1
P 8.35 2.26615 6 P 0 0;5=4,7=1
P 8.35 2.11615 6 P 0 0;5=4,7=1
P 8.35 2.06615 6 P 0 0;5=4,7=1
P 8.45 2.11615 6 P 0 0;5=4,7=1
P 8.45 2.06615 6 P 0 0;5=4,7=1
P 8.5 2.06615 6 P 0 0;5=4,7=1
P 8.5 2.01615 6 P 0 0;5=4,7=1
P 8.4 2.06615 6 P 0 0;5=4,7=1
P 8.4 2.01615 6 P 0 0;5=4,7=1
P 8.45 1.96615 6 P 0 0;5=4,7=1
P 8.45 1.91615 6 P 0 0;5=4,7=1
P 8.5 1.91615 6 P 0 0;5=4,7=1
P 8.5 1.86615 6 P 0 0;5=4,7=1
P 8.4 1.91615 6 P 0 0;5=4,7=1
P 8.4 1.86615 6 P 0 0;5=4,7=1
P 8.35 1.96615 6 P 0 0;5=4,7=1
P 8.35 1.91615 6 P 0 0;5=4,7=1
P 8.35 3.16615 6 P 0 0;5=4,7=1
P 8.35 3.11615 6 P 0 0;5=4,7=1
P 8.45 3.16615 6 P 0 0;5=4,7=1
P 8.45 3.11615 6 P 0 0;5=4,7=1
P 8.5 3.11615 6 P 0 0;5=4,7=1
P 8.5 3.06615 6 P 0 0;5=4,7=1
P 8.4 3.11615 6 P 0 0;5=4,7=1
P 8.4 3.06615 6 P 0 0;5=4,7=1
P 8.45 3.01615 6 P 0 0;5=4,7=1
P 8.45 2.96615 6 P 0 0;5=4,7=1
P 8.5 2.96615 6 P 0 0;5=4,7=1
P 8.5 2.91615 6 P 0 0;5=4,7=1
P 8.4 2.96615 6 P 0 0;5=4,7=1
P 8.4 2.91615 6 P 0 0;5=4,7=1
P 8.35 3.01615 6 P 0 0;5=4,7=1
P 8.35 2.96615 6 P 0 0;5=4,7=1
P 8.4 2.81615 6 P 0 0;5=4,7=1
P 8.4 2.76615 6 P 0 0;5=4,7=1
P 8.5 2.81615 6 P 0 0;5=4,7=1
P 8.5 2.76615 6 P 0 0;5=4,7=1
P 8.45 2.76615 6 P 0 0;5=4,7=1
P 8.45 2.71615 6 P 0 0;5=4,7=1
P 8.35 2.76615 6 P 0 0;5=4,7=1
P 8.35 2.71615 6 P 0 0;5=4,7=1
P 8.5 2.66615 6 P 0 0;5=4,7=1
P 8.5 2.61615 6 P 0 0;5=4,7=1
P 8.45 2.61615 6 P 0 0;5=4,7=1
P 8.45 2.56615 6 P 0 0;5=4,7=1
P 8.4 2.66615 6 P 0 0;5=4,7=1
P 8.4 2.61615 6 P 0 0;5=4,7=1
P 2.04606004 2.61615 6 P 0 0;5=4,7=1
P 2.04606004 2.66615 6 P 0 0;5=4,7=1
P 2.09606004 2.46615 6 P 0 0;5=4,7=1
P 2.09606004 2.41615 6 P 0 0;5=4,7=1
P 2.19606004 2.46615 6 P 0 0;5=4,7=1
P 2.19606004 2.41615 6 P 0 0;5=4,7=1
P 2.14606004 2.41615 6 P 0 0;5=4,7=1
P 2.14606004 2.36615 6 P 0 0;5=4,7=1
P 2.04606004 2.41615 6 P 0 0;5=4,7=1
P 2.04606004 2.36615 6 P 0 0;5=4,7=1
P 2.19606004 2.31615 6 P 0 0;5=4,7=1
P 2.19606004 2.26615 6 P 0 0;5=4,7=1
P 2.14606004 2.26615 6 P 0 0;5=4,7=1
P 2.14606004 2.21615 6 P 0 0;5=4,7=1
P 2.09606004 2.31615 6 P 0 0;5=4,7=1
P 2.09606004 2.26615 6 P 0 0;5=4,7=1
P 2.04606004 2.26615 6 P 0 0;5=4,7=1
P 2.04606004 2.21615 6 P 0 0;5=4,7=1
P 2.09606004 2.11615 6 P 0 0;5=4,7=1
P 2.09606004 2.06615 6 P 0 0;5=4,7=1
P 2.19606004 2.11615 6 P 0 0;5=4,7=1
P 2.19606004 2.06615 6 P 0 0;5=4,7=1
P 2.14606004 2.06615 6 P 0 0;5=4,7=1
P 2.14606004 2.01615 6 P 0 0;5=4,7=1
P 2.04606004 2.06615 6 P 0 0;5=4,7=1
P 2.04606004 2.01615 6 P 0 0;5=4,7=1
P 2.19606004 1.96615 6 P 0 0;5=4,7=1
P 2.19606004 1.91615 6 P 0 0;5=4,7=1
P 2.14606004 1.91615 6 P 0 0;5=4,7=1
P 2.14606004 1.86615 6 P 0 0;5=4,7=1
P 2.09606004 1.96615 6 P 0 0;5=4,7=1
P 2.09606004 1.91615 6 P 0 0;5=4,7=1
P 2.04606004 1.91615 6 P 0 0;5=4,7=1
P 2.04606004 1.86615 6 P 0 0;5=4,7=1
P 2.09606004 3.16615 6 P 0 0;5=4,7=1
P 2.09606004 3.11615 6 P 0 0;5=4,7=1
P 2.19606004 3.16615 6 P 0 0;5=4,7=1
P 2.19606004 3.11615 6 P 0 0;5=4,7=1
P 2.14606004 3.11615 6 P 0 0;5=4,7=1
P 2.14606004 3.06615 6 P 0 0;5=4,7=1
P 2.04606004 3.11615 6 P 0 0;5=4,7=1
P 2.04606004 3.06615 6 P 0 0;5=4,7=1
P 2.19606004 3.01615 6 P 0 0;5=4,7=1
P 2.19606004 2.96615 6 P 0 0;5=4,7=1
P 2.14606004 2.96615 6 P 0 0;5=4,7=1
P 2.14606004 2.91615 6 P 0 0;5=4,7=1
P 2.09606004 3.01615 6 P 0 0;5=4,7=1
P 2.09606004 2.96615 6 P 0 0;5=4,7=1
P 2.04606004 2.96615 6 P 0 0;5=4,7=1
P 2.04606004 2.91615 6 P 0 0;5=4,7=1
P 1.99606004 2.81615 6 P 0 0;5=4,7=1
P 1.99606004 2.76615 6 P 0 0;5=4,7=1
P 2.14606004 2.81615 6 P 0 0;5=4,7=1
P 2.14606004 2.76615 6 P 0 0;5=4,7=1
P 2.19606004 2.76615 6 P 0 0;5=4,7=1
P 2.19606004 2.71615 6 P 0 0;5=4,7=1
P 2.09606004 2.76615 6 P 0 0;5=4,7=1
P 2.09606004 2.71615 6 P 0 0;5=4,7=1
P 2.14606004 2.66615 6 P 0 0;5=4,7=1
P 2.14606004 2.61615 6 P 0 0;5=4,7=1
P 2.19606004 2.61615 6 P 0 0;5=4,7=1
P 2.19606004 2.56615 6 P 0 0;5=4,7=1
P 2.09606004 2.61615 6 P 0 0;5=4,7=1
P 2.09606004 2.56615 6 P 0 0;5=4,7=1
P 2.34606004 2.56615 6 P 0 0;5=4,7=1
P 2.34606004 2.61615 6 P 0 0;5=4,7=1
P 2.34606004 2.46615 6 P 0 0;5=4,7=1
P 2.34606004 2.41615 6 P 0 0;5=4,7=1
P 2.44606004 2.46615 6 P 0 0;5=4,7=1
P 2.44606004 2.41615 6 P 0 0;5=4,7=1
P 2.49606004 2.41615 6 P 0 0;5=4,7=1
P 2.49606004 2.36615 6 P 0 0;5=4,7=1
P 2.39606004 2.41615 6 P 0 0;5=4,7=1
P 2.39606004 2.36615 6 P 0 0;5=4,7=1
P 2.44606004 2.31615 6 P 0 0;5=4,7=1
P 2.44606004 2.26615 6 P 0 0;5=4,7=1
P 2.49606004 2.26615 6 P 0 0;5=4,7=1
P 2.49606004 2.21615 6 P 0 0;5=4,7=1
P 2.39606004 2.26615 6 P 0 0;5=4,7=1
P 2.39606004 2.21615 6 P 0 0;5=4,7=1
P 2.34606004 2.31615 6 P 0 0;5=4,7=1
P 2.34606004 2.26615 6 P 0 0;5=4,7=1
P 2.34606004 2.11615 6 P 0 0;5=4,7=1
P 2.34606004 2.06615 6 P 0 0;5=4,7=1
P 2.44606004 2.11615 6 P 0 0;5=4,7=1
P 2.44606004 2.06615 6 P 0 0;5=4,7=1
P 2.49606004 2.06615 6 P 0 0;5=4,7=1
P 2.49606004 2.01615 6 P 0 0;5=4,7=1
P 2.39606004 2.06615 6 P 0 0;5=4,7=1
P 2.39606004 2.01615 6 P 0 0;5=4,7=1
P 2.44606004 1.96615 6 P 0 0;5=4,7=1
P 2.44606004 1.91615 6 P 0 0;5=4,7=1
P 2.49606004 1.91615 6 P 0 0;5=4,7=1
P 2.49606004 1.86615 6 P 0 0;5=4,7=1
P 2.39606004 1.91615 6 P 0 0;5=4,7=1
P 2.39606004 1.86615 6 P 0 0;5=4,7=1
P 2.34606004 1.96615 6 P 0 0;5=4,7=1
P 2.34606004 1.91615 6 P 0 0;5=4,7=1
P 2.34606004 3.16615 6 P 0 0;5=4,7=1
P 2.34606004 3.11615 6 P 0 0;5=4,7=1
P 2.44606004 3.16615 6 P 0 0;5=4,7=1
P 2.44606004 3.11615 6 P 0 0;5=4,7=1
P 2.49606004 3.11615 6 P 0 0;5=4,7=1
P 2.49606004 3.06615 6 P 0 0;5=4,7=1
P 2.39606004 3.11615 6 P 0 0;5=4,7=1
P 2.39606004 3.06615 6 P 0 0;5=4,7=1
P 2.44606004 3.01615 6 P 0 0;5=4,7=1
P 2.44606004 2.96615 6 P 0 0;5=4,7=1
P 2.49606004 2.96615 6 P 0 0;5=4,7=1
P 2.49606004 2.91615 6 P 0 0;5=4,7=1
P 2.39606004 2.96615 6 P 0 0;5=4,7=1
P 2.39606004 2.91615 6 P 0 0;5=4,7=1
P 2.34606004 3.01615 6 P 0 0;5=4,7=1
P 2.34606004 2.96615 6 P 0 0;5=4,7=1
P 2.39606004 2.81615 6 P 0 0;5=4,7=1
P 2.39606004 2.76615 6 P 0 0;5=4,7=1
P 2.49606004 2.81615 6 P 0 0;5=4,7=1
P 2.49606004 2.76615 6 P 0 0;5=4,7=1
P 2.44606004 2.76615 6 P 0 0;5=4,7=1
P 2.44606004 2.71615 6 P 0 0;5=4,7=1
P 2.34606004 2.76615 6 P 0 0;5=4,7=1
P 2.34606004 2.71615 6 P 0 0;5=4,7=1
P 2.49606004 2.66615 6 P 0 0;5=4,7=1
P 2.49606004 2.61615 6 P 0 0;5=4,7=1
P 2.44606004 2.61615 6 P 0 0;5=4,7=1
P 2.44606004 2.56615 6 P 0 0;5=4,7=1
P 2.39606004 2.66615 6 P 0 0;5=4,7=1
P 2.39606004 2.61615 6 P 0 0;5=4,7=1
P 8.94061998 4.70573996 7 P 0 0;5=6,7=1
P 9.01925 4.70573996 7 P 0 0;5=6,7=1
P 9.07925 4.70573996 7 P 0 0;5=6,7=1
P 8.73578996 4.70573996 7 P 0 0;5=6,7=1
P 8.79578996 4.70573996 7 P 0 0;5=6,7=1
P 8.86665 4.74418002 7 P 0 0;5=6,7=1
P 8.80665 4.74418002 7 P 0 0;5=6,7=1
P 9.43358002 4.74418002 7 P 0 0;5=6,7=1
P 9.51531004 4.68098996 7 P 0 0;5=6,7=1
P 9.57531004 4.68098996 7 P 0 0;5=6,7=1
P 9.44445 4.62573996 7 P 0 0;5=6,7=1
P 9.50445 4.62573996 7 P 0 0;5=6,7=1
P 9.23185 4.68073996 7 P 0 0;5=6,7=1
P 9.29185 4.68073996 7 P 0 0;5=6,7=1
P 9.16098002 4.74418002 7 P 0 0;5=6,7=1
P 9.37358002 4.74418002 7 P 0 0;5=6,7=1
P 9.22098002 4.74418002 7 P 0 0;5=6,7=1
P 9.51531004 5.17873996 7 P 0 0;5=6,7=1
P 9.57531004 5.17873996 7 P 0 0;5=6,7=1
P 9.43358002 5.18128002 7 P 0 0;5=6,7=1
P 9.23185 5.18128002 7 P 0 0;5=6,7=1
P 9.29185 5.18128002 7 P 0 0;5=6,7=1
P 9.37358002 5.18128002 7 P 0 0;5=6,7=1
P 9.36271004 5.14223996 7 P 0 0;5=6,7=1
P 9.30271004 5.14223996 7 P 0 0;5=6,7=1
P 9.15011004 5.09223996 7 P 0 0;5=6,7=1
P 9.09011004 5.09223996 7 P 0 0;5=6,7=1
P 9.07925 5.20373996 7 P 0 0;5=6,7=1
P 9.01925 5.20373996 7 P 0 0;5=6,7=1
P 8.93441004 5.20876004 7 P 0 0;5=6,7=1
P 8.73578996 5.17873996 7 P 0 0;5=6,7=1
P 8.79578996 5.17873996 7 P 0 0;5=6,7=1
P 8.87441004 5.20876004 7 P 0 0;5=6,7=1
P 7.64205 4.74418002 7 P 0 0;5=6,7=1
P 7.70205 4.74418002 7 P 0 0;5=6,7=1
P 7.63118996 4.66826004 7 P 0 0;5=6,7=1
P 7.57118996 4.66826004 7 P 0 0;5=6,7=1
P 7.91465 4.61826004 7 P 0 0;5=6,7=1
P 7.78378996 4.74418002 7 P 0 0;5=6,7=1
P 7.84378996 4.74418002 7 P 0 0;5=6,7=1
P 7.85465 4.61826004 7 P 0 0;5=6,7=1
P 8.06725 4.74418002 7 P 0 0;5=6,7=1
P 8.12725 4.74418002 7 P 0 0;5=6,7=1
P 8.02206998 4.62815 7 P 0 0;5=6,7=1
P 8.08206998 4.62815 7 P 0 0;5=6,7=1
P 8.41071004 4.70326004 7 P 0 0;5=6,7=1
P 8.35071004 4.70326004 7 P 0 0;5=6,7=1
P 8.20898002 4.74418002 7 P 0 0;5=6,7=1
P 8.26898002 4.74418002 7 P 0 0;5=6,7=1
P 8.21208996 4.62826004 7 P 0 0;5=6,7=1
P 8.27208996 4.62826004 7 P 0 0;5=6,7=1
P 8.19811004 5.09223996 7 P 0 0;5=6,7=1
P 8.12725 5.13026004 7 P 0 0;5=6,7=1
P 8.06725 5.13026004 7 P 0 0;5=6,7=1
P 7.91465 5.13026004 7 P 0 0;5=6,7=1
P 7.92551004 5.09223996 7 P 0 0;5=6,7=1
P 7.98551004 5.09223996 7 P 0 0;5=6,7=1
P 7.85465 5.13026004 7 P 0 0;5=6,7=1
P 7.64203996 5.09223996 7 P 0 0;5=6,7=1
P 7.70203996 5.09223996 7 P 0 0;5=6,7=1
P 7.57118996 5.13026004 7 P 0 0;5=6,7=1
P 7.63118996 5.13026004 7 P 0 0;5=6,7=1
P 2.73225 4.70573996 7 P 0 0;5=6,7=1
P 2.79225 4.70573996 7 P 0 0;5=6,7=1
P 3.22831004 5.18128002 7 P 0 0;5=6,7=1
P 3.28831004 5.18128002 7 P 0 0;5=6,7=1
P 3.01571004 5.20373996 7 P 0 0;5=6,7=1
P 3.07571004 5.20373996 7 P 0 0;5=6,7=1
P 2.73225 5.17873996 7 P 0 0;5=6,7=1
P 2.79225 5.17873996 7 P 0 0;5=6,7=1
P 1.56765 4.66826004 7 P 0 0;5=6,7=1
P 1.62765 4.66826004 7 P 0 0;5=6,7=1
P 1.56765 5.13026004 7 P 0 0;5=6,7=1
P 1.62765 5.13026004 7 P 0 0;5=6,7=1
P 1.91111004 5.13026004 7 P 0 0;5=6,7=1
P 1.85111004 5.13026004 7 P 0 0;5=6,7=1
P 5.08268002 2.76615 6 P 0 0;5=4,7=1
P 5.03268002 2.76615 6 P 0 0;5=4,7=1
P 5.03268002 2.71615 6 P 0 0;5=4,7=1
P 4.93268002 2.76615 6 P 0 0;5=4,7=1
P 4.98268002 2.76615 6 P 0 0;5=4,7=1
P 4.93268002 2.71615 6 P 0 0;5=4,7=1
P 5.08268002 2.66615 6 P 0 0;5=4,7=1
P 4.98268002 2.66615 6 P 0 0;5=4,7=1
P 5.03268002 2.56615 6 P 0 0;5=4,7=1
P 4.93268002 2.56615 6 P 0 0;5=4,7=1
P 4.98268002 2.46615 6 P 0 0;5=4,7=1
P 4.98268002 2.51615 6 P 0 0;5=4,7=1
P 4.93268002 2.51615 6 P 0 0;5=4,7=1
P 5.08268002 2.51615 6 P 0 0;5=4,7=1
P 5.08268002 2.46615 6 P 0 0;5=4,7=1
P 5.03268002 2.21615 6 P 0 0;5=4,7=1
P 4.93268002 2.21615 6 P 0 0;5=4,7=1
P 4.98268002 2.31615 6 P 0 0;5=4,7=1
P 4.93268002 2.36615 6 P 0 0;5=4,7=1
P 5.08268002 2.31615 6 P 0 0;5=4,7=1
P 5.08268002 2.16615 6 P 0 0;5=4,7=1
P 4.93268002 2.16615 6 P 0 0;5=4,7=1
P 4.98268002 2.16615 6 P 0 0;5=4,7=1
P 4.93268002 1.96615 6 P 0 0;5=4,7=1
P 5.03268002 1.96615 6 P 0 0;5=4,7=1
P 5.03268002 2.11615 6 P 0 0;5=4,7=1
P 4.93268002 2.11615 6 P 0 0;5=4,7=1
P 4.98268002 2.01615 6 P 0 0;5=4,7=1
P 5.08268002 2.01615 6 P 0 0;5=4,7=1
P 4.98268002 1.86615 6 P 0 0;5=4,7=1
P 5.08268002 1.86615 6 P 0 0;5=4,7=1
P 4.78268002 3.81615 6 P 0 0;5=4,7=1
P 4.78268002 3.66615 6 P 0 0;5=4,7=1
P 4.73268002 3.81615 6 P 0 0;5=4,7=1
P 4.73268002 3.66615 6 P 0 0;5=4,7=1
P 4.68268002 3.81615 6 P 0 0;5=4,7=1
P 4.68268002 3.66615 6 P 0 0;5=4,7=1
P 4.78268002 3.51615 6 P 0 0;5=4,7=1
P 4.73268002 3.51615 6 P 0 0;5=4,7=1
P 4.68268002 3.51615 6 P 0 0;5=4,7=1
P 4.78268002 3.36615 6 P 0 0;5=4,7=1
P 4.73268002 3.36615 6 P 0 0;5=4,7=1
P 4.78268002 3.21615 6 P 0 0;5=4,7=1
P 4.73268002 3.21615 6 P 0 0;5=4,7=1
P 4.68268002 3.36615 6 P 0 0;5=4,7=1
P 4.68268002 3.21615 6 P 0 0;5=4,7=1
P 4.78268002 3.06615 6 P 0 0;5=4,7=1
P 4.73268002 3.06615 6 P 0 0;5=4,7=1
P 4.68268002 3.06615 6 P 0 0;5=4,7=1
P 4.78268002 2.91615 6 P 0 0;5=4,7=1
P 4.73268002 2.91615 6 P 0 0;5=4,7=1
P 4.68268002 2.91615 6 P 0 0;5=4,7=1
P 4.88268002 2.76615 6 P 0 0;5=4,7=1
P 4.88268002 2.66615 6 P 0 0;5=4,7=1
P 4.78268002 2.46615 6 P 0 0;5=4,7=1
P 4.88268002 2.56615 6 P 0 0;5=4,7=1
P 4.88268002 2.61615 6 P 0 0;5=4,7=1
P 4.68268002 2.46615 6 P 0 0;5=4,7=1
P 4.88268002 2.46615 6 P 0 0;5=4,7=1
P 4.88268002 2.51615 6 P 0 0;5=4,7=1
P 4.78268002 2.41615 6 P 0 0;5=4,7=1
P 4.88268002 2.41615 6 P 0 0;5=4,7=1
P 4.78268002 2.36615 6 P 0 0;5=4,7=1
P 4.78268002 2.31615 6 P 0 0;5=4,7=1
P 4.78268002 2.26615 6 P 0 0;5=4,7=1
P 4.78268002 2.21615 6 P 0 0;5=4,7=1
P 4.73268002 2.36615 6 P 0 0;5=4,7=1
P 4.68268002 2.31615 6 P 0 0;5=4,7=1
P 4.73268002 2.21615 6 P 0 0;5=4,7=1
P 4.88268002 2.21615 6 P 0 0;5=4,7=1
P 4.88268002 2.26615 6 P 0 0;5=4,7=1
P 4.88268002 2.31615 6 P 0 0;5=4,7=1
P 4.88268002 2.36615 6 P 0 0;5=4,7=1
P 4.73268002 2.16615 6 P 0 0;5=4,7=1
P 4.68268002 2.16615 6 P 0 0;5=4,7=1
P 4.78268002 1.96615 6 P 0 0;5=4,7=1
P 4.78268002 2.06615 6 P 0 0;5=4,7=1
P 4.78268002 2.01615 6 P 0 0;5=4,7=1
P 4.88268002 1.96615 6 P 0 0;5=4,7=1
P 4.88268002 2.06615 6 P 0 0;5=4,7=1
P 4.88268002 2.01615 6 P 0 0;5=4,7=1
P 4.78268002 2.11615 6 P 0 0;5=4,7=1
P 4.88268002 2.11615 6 P 0 0;5=4,7=1
P 4.73268002 2.11615 6 P 0 0;5=4,7=1
P 4.68268002 2.01615 6 P 0 0;5=4,7=1
P 4.73268002 1.96615 6 P 0 0;5=4,7=1
P 4.78268002 1.86615 6 P 0 0;5=4,7=1
P 4.88268002 1.86615 6 P 0 0;5=4,7=1
P 4.68268002 1.86615 6 P 0 0;5=4,7=1
P 4.63268002 3.81615 6 P 0 0;5=4,7=1
P 4.63268002 3.66615 6 P 0 0;5=4,7=1
P 4.58268002 3.81615 6 P 0 0;5=4,7=1
P 4.58268002 3.66615 6 P 0 0;5=4,7=1
P 4.63268002 3.51615 6 P 0 0;5=4,7=1
P 4.58268002 3.51615 6 P 0 0;5=4,7=1
P 4.63268002 3.36615 6 P 0 0;5=4,7=1
P 4.58268002 3.36615 6 P 0 0;5=4,7=1
P 4.63268002 3.21615 6 P 0 0;5=4,7=1
P 4.58268002 3.21615 6 P 0 0;5=4,7=1
P 4.63268002 3.06615 6 P 0 0;5=4,7=1
P 4.58268002 3.06615 6 P 0 0;5=4,7=1
P 4.63268002 2.91615 6 P 0 0;5=4,7=1
P 4.58268002 2.91615 6 P 0 0;5=4,7=1
P 4.58268002 2.46615 6 P 0 0;5=4,7=1
P 4.63268002 2.21615 6 P 0 0;5=4,7=1
P 4.58268002 2.31615 6 P 0 0;5=4,7=1
P 4.63268002 2.36615 6 P 0 0;5=4,7=1
P 4.58268002 2.01615 6 P 0 0;5=4,7=1
P 4.63268002 2.11615 6 P 0 0;5=4,7=1
P 4.63268002 1.96615 6 P 0 0;5=4,7=1
P 4.58268002 1.86615 6 P 0 0;5=4,7=1
P 2.04606004 3.41615 6 P 0 0;5=4,7=1
P 2.09606004 3.51615 6 P 0 0;5=4,7=1
P 7.82415 2.4781 25 P 0 0;2,5=0,7=0
L 1.82021004 2.4781 1.792 2.4781 5 P 0 
P 3.37003996 5.18128002 7 P 0 0;5=6,7=1
P 3.43003996 5.18128002 7 P 0 0;5=6,7=1
P 3.29916998 5.14223996 7 P 0 0;5=6,7=1
P 3.35916998 5.14223996 7 P 0 0;5=6,7=1
P 2.93708002 4.70573996 7 P 0 0;5=6,7=1
P 3.07571004 4.70573996 7 P 0 0;5=6,7=1
P 3.01571004 4.70573996 7 P 0 0;5=6,7=1
P 2.87708002 4.70573996 7 P 0 0;5=6,7=1
P 2.93086998 5.20876004 7 P 0 0;5=6,7=1
P 2.87086998 5.20876004 7 P 0 0;5=6,7=1
P 2.80311004 4.74418002 7 P 0 0;5=6,7=1
P 2.86311004 4.74418002 7 P 0 0;5=6,7=1
P 3.08656998 5.09223996 7 P 0 0;5=6,7=1
P 3.14656998 5.09223996 7 P 0 0;5=6,7=1
P 2.26855 4.62826004 7 P 0 0;5=6,7=1
P 2.20855 4.62826004 7 P 0 0;5=6,7=1
P 2.26543996 4.74418002 7 P 0 0;5=6,7=1
P 2.20543996 4.74418002 7 P 0 0;5=6,7=1
P 2.34716998 4.70326004 7 P 0 0;5=6,7=1
P 2.07853002 4.62815 7 P 0 0;5=6,7=1
P 2.01853002 4.62815 7 P 0 0;5=6,7=1
P 2.12371004 4.74418002 7 P 0 0;5=6,7=1
P 2.06371004 4.74418002 7 P 0 0;5=6,7=1
P 2.19456998 5.09223996 7 P 0 0;5=6,7=1
P 2.13456998 5.09223996 7 P 0 0;5=6,7=1
P 2.12371004 5.13026004 7 P 0 0;5=6,7=1
P 2.06371004 5.13026004 7 P 0 0;5=6,7=1
P 1.6985 5.09223996 7 P 0 0;5=6,7=1
P 1.6385 5.09223996 7 P 0 0;5=6,7=1
P 1.85111004 4.61826004 7 P 0 0;5=6,7=1
P 1.63851004 4.74418002 7 P 0 0;5=6,7=1
P 1.69851004 4.74418002 7 P 0 0;5=6,7=1
P 1.98196998 5.09223996 7 P 0 0;5=6,7=1
P 1.92196998 5.09223996 7 P 0 0;5=6,7=1
P 1.84025 4.74418002 7 P 0 0;5=6,7=1
P 1.78025 4.74418002 7 P 0 0;5=6,7=1
P 11.03661004 2.71615 6 P 0 0;5=4,7=1
P 10.93661004 2.71615 6 P 0 0;5=4,7=1
P 11.03661004 2.76615 6 P 0 0;5=4,7=1
P 10.98661004 2.76615 6 P 0 0;5=4,7=1
P 10.93661004 2.76615 6 P 0 0;5=4,7=1
P 11.08661004 2.76615 6 P 0 0;5=4,7=1
P 11.03661004 2.56615 6 P 0 0;5=4,7=1
P 10.93661004 2.56615 6 P 0 0;5=4,7=1
P 10.98661004 2.66615 6 P 0 0;5=4,7=1
P 10.98661004 2.51615 6 P 0 0;5=4,7=1
P 10.93661004 2.51615 6 P 0 0;5=4,7=1
P 11.08661004 2.66615 6 P 0 0;5=4,7=1
P 11.08661004 2.51615 6 P 0 0;5=4,7=1
P 11.08661004 2.46615 6 P 0 0;5=4,7=1
P 10.98661004 2.46615 6 P 0 0;5=4,7=1
P 11.08661004 2.31615 6 P 0 0;5=4,7=1
P 10.93661004 2.36615 6 P 0 0;5=4,7=1
P 10.98661004 2.31615 6 P 0 0;5=4,7=1
P 10.93661004 2.21615 6 P 0 0;5=4,7=1
P 11.03661004 2.21615 6 P 0 0;5=4,7=1
P 11.03661004 2.11615 6 P 0 0;5=4,7=1
P 10.93661004 2.11615 6 P 0 0;5=4,7=1
P 10.98661004 2.01615 6 P 0 0;5=4,7=1
P 10.93661004 1.96615 6 P 0 0;5=4,7=1
P 11.03661004 1.96615 6 P 0 0;5=4,7=1
P 11.08661004 2.01615 6 P 0 0;5=4,7=1
P 10.98661004 2.16615 6 P 0 0;5=4,7=1
P 10.93661004 2.16615 6 P 0 0;5=4,7=1
P 11.08661004 2.16615 6 P 0 0;5=4,7=1
P 10.98661004 1.86615 6 P 0 0;5=4,7=1
P 11.08661004 1.86615 6 P 0 0;5=4,7=1
P 10.73661004 2.71615 6 P 0 0;5=4,7=1
P 10.73661004 2.76615 6 P 0 0;5=4,7=1
P 10.88661004 2.76615 6 P 0 0;5=4,7=1
P 10.78661004 2.76615 6 P 0 0;5=4,7=1
P 10.73661004 2.56615 6 P 0 0;5=4,7=1
P 10.68661004 2.66615 6 P 0 0;5=4,7=1
P 10.73661004 2.51615 6 P 0 0;5=4,7=1
P 10.68661004 2.51615 6 P 0 0;5=4,7=1
P 10.88661004 2.61615 6 P 0 0;5=4,7=1
P 10.88661004 2.56615 6 P 0 0;5=4,7=1
P 10.88661004 2.51615 6 P 0 0;5=4,7=1
P 10.78661004 2.56615 6 P 0 0;5=4,7=1
P 10.78661004 2.61615 6 P 0 0;5=4,7=1
P 10.78661004 2.66615 6 P 0 0;5=4,7=1
P 10.78661004 2.51615 6 P 0 0;5=4,7=1
P 10.78661004 2.46615 6 P 0 0;5=4,7=1
P 10.68661004 2.46615 6 P 0 0;5=4,7=1
P 10.88661004 2.46615 6 P 0 0;5=4,7=1
P 10.78661004 2.21615 6 P 0 0;5=4,7=1
P 10.78661004 2.26615 6 P 0 0;5=4,7=1
P 10.78661004 2.31615 6 P 0 0;5=4,7=1
P 10.78661004 2.36615 6 P 0 0;5=4,7=1
P 10.68661004 2.31615 6 P 0 0;5=4,7=1
P 10.73661004 2.36615 6 P 0 0;5=4,7=1
P 10.73661004 2.21615 6 P 0 0;5=4,7=1
P 10.78661004 2.41615 6 P 0 0;5=4,7=1
P 10.88661004 2.36615 6 P 0 0;5=4,7=1
P 10.88661004 2.31615 6 P 0 0;5=4,7=1
P 10.88661004 2.26615 6 P 0 0;5=4,7=1
P 10.88661004 2.21615 6 P 0 0;5=4,7=1
P 10.73661004 1.96615 6 P 0 0;5=4,7=1
P 10.68661004 2.01615 6 P 0 0;5=4,7=1
P 10.73661004 2.11615 6 P 0 0;5=4,7=1
P 10.78661004 2.11615 6 P 0 0;5=4,7=1
P 10.78661004 2.01615 6 P 0 0;5=4,7=1
P 10.78661004 1.96615 6 P 0 0;5=4,7=1
P 10.78661004 2.06615 6 P 0 0;5=4,7=1
P 10.68661004 2.16615 6 P 0 0;5=4,7=1
P 10.73661004 2.16615 6 P 0 0;5=4,7=1
P 10.88661004 2.01615 6 P 0 0;5=4,7=1
P 10.88661004 2.06615 6 P 0 0;5=4,7=1
P 10.88661004 2.11615 6 P 0 0;5=4,7=1
P 10.88661004 1.96615 6 P 0 0;5=4,7=1
P 10.78661004 1.91615 6 P 0 0;5=4,7=1
P 10.68661004 1.86615 6 P 0 0;5=4,7=1
P 10.78661004 1.86615 6 P 0 0;5=4,7=1
P 10.88661004 1.86615 6 P 0 0;5=4,7=1
P 10.63661004 2.71615 6 P 0 0;5=4,7=1
P 10.63661004 2.76615 6 P 0 0;5=4,7=1
P 10.63661004 2.56615 6 P 0 0;5=4,7=1
P 10.58661004 2.66615 6 P 0 0;5=4,7=1
P 10.63661004 2.51615 6 P 0 0;5=4,7=1
P 10.58661004 2.51615 6 P 0 0;5=4,7=1
P 10.58661004 2.46615 6 P 0 0;5=4,7=1
P 10.63661004 2.36615 6 P 0 0;5=4,7=1
P 10.58661004 2.31615 6 P 0 0;5=4,7=1
P 10.58661004 2.01615 6 P 0 0;5=4,7=1
P 10.63661004 1.96615 6 P 0 0;5=4,7=1
P 10.63661004 2.11615 6 P 0 0;5=4,7=1
P 10.58661004 1.86615 6 P 0 0;5=4,7=1
L 1.95146004 5.377 1.92346004 5.377 5 P 0 
P 1.92346004 5.377 7 P 0 0;5=6,7=1
L 2.11646004 5.377 2.14346004 5.377 5 P 0 
P 2.14346004 5.377 7 P 0 0;5=6,7=1
L 7.955 5.377 7.927 5.377 5 P 0 
P 7.927 5.377 7 P 0 0;5=6,7=1
L 8.12 5.377 8.147 5.377 5 P 0 
P 8.147 5.377 7 P 0 0;5=6,7=1
P 3.43003996 4.74418002 7 P 0 0;5=6,7=1
P 3.51176998 4.68098996 7 P 0 0;5=6,7=1
P 3.57176998 4.68098996 7 P 0 0;5=6,7=1
P 3.21743996 4.74418002 7 P 0 0;5=6,7=1
P 3.37003996 4.74418002 7 P 0 0;5=6,7=1
P 3.09646004 5.332 25 P 0 0;2,5=0,7=0
P 3.23146004 5.332 25 P 0 0;2,5=0,7=0
L 3.38146004 5.332 3.41 5.332 5 P 0 
P 3.38146004 5.332 25 P 0 0;2,5=0,7=0
P 3.41 5.332 7 P 0 0;5=6,7=1
L 9.1 5.332 9.07 5.332 5 P 0 
L 9.385 5.332 9.415 5.332 5 P 0 
L 9.235 5.332 9.265 5.332 5 P 0 
P 5.38048002 1.5957 7 P 0 0;5=6,7=1
P 5.38048002 1.7891 7 P 0 0;5=6,7=1
P 5.38048002 1.732 7 P 0 0;5=6,7=1
P 5.38048002 1.6528 7 P 0 0;5=6,7=1
P 5.53531004 1.8603 7 P 0 0;5=6,7=1
P 5.53531004 1.8032 7 P 0 0;5=6,7=1
P 5.53531004 2.2727 7 P 0 0;5=6,7=1
P 5.53531004 2.1373 7 P 0 0;5=6,7=1
P 5.53531004 1.9964 7 P 0 0;5=6,7=1
P 5.38048002 2.3403 7 P 0 0;5=6,7=1
P 5.38048002 2.2832 7 P 0 0;5=6,7=1
P 5.38048002 2.2049 7 P 0 0;5=6,7=1
P 5.38048002 2.1478 7 P 0 0;5=6,7=1
P 5.38048002 2.0642 7 P 0 0;5=6,7=1
P 5.38048002 2.0071 7 P 0 0;5=6,7=1
P 5.38048002 1.9288 7 P 0 0;5=6,7=1
P 5.38048002 1.8717 7 P 0 0;5=6,7=1
P 5.53531004 2.351 7 P 0 0;5=6,7=1
P 5.38048002 2.4757 7 P 0 0;5=6,7=1
P 5.38048002 2.4186 7 P 0 0;5=6,7=1
P 5.53531004 2.4902 7 P 0 0;5=6,7=1
P 5.53531004 2.6825 7 P 0 0;5=6,7=1
P 5.53531004 2.6254 7 P 0 0;5=6,7=1
P 5.38048002 2.5578 7 P 0 0;5=6,7=1
P 5.38048002 2.6149 7 P 0 0;5=6,7=1
L 6.385 5.07 6.40123996 5.07 5 P 0 
L 6.40123996 5.07 6.42418996 5.04705 5 P 0 
P 10.43 1.3341 7 P 0 0;5=6,7=1
P 10.43 1.277 7 P 0 0;5=6,7=1
P 10.4159 1.43 7 P 0 0;5=6,7=1
P 10.473 1.43 7 P 0 0;5=6,7=1
P 10.37313996 1.55336004 7 P 0 0;5=6,7=1
P 10.41451004 1.51198002 7 P 0 0;5=6,7=1
P 10.295 1.713 7 P 0 0;5=6,7=1
P 10.295 1.6559 7 P 0 0;5=6,7=1
P 10.26 1.9179 7 P 0 0;5=6,7=1
P 10.29525 1.877 7 P 0 0;5=6,7=1
P 10.29525 1.8199 7 P 0 0;5=6,7=1
P 10.26 1.975 7 P 0 0;5=6,7=1
P 10.125 2.0651 7 P 0 0;5=6,7=1
P 10.125 2.1224 7 P 0 0;5=6,7=1
P 10.125 2.1795 7 P 0 0;5=6,7=1
P 10.01 2.2481 7 P 0 0;5=6,7=1
P 10.01 2.191 7 P 0 0;5=6,7=1
P 10.01 2.38435 7 P 0 0;5=6,7=1
P 10.01 2.32725 7 P 0 0;5=6,7=1
P 10.125 2.3168 7 P 0 0;5=6,7=1
P 10.125 2.2597 7 P 0 0;5=6,7=1
P 10.125 2.4519 7 P 0 0;5=6,7=1
P 10.125 2.3948 7 P 0 0;5=6,7=1
P 10.01 2.51945 7 P 0 0;5=6,7=1
P 10.01 2.46235 7 P 0 0;5=6,7=1
P 10.125 2.587 7 P 0 0;5=6,7=1
P 10.125 2.5299 7 P 0 0;5=6,7=1
P 10.01 2.673 7 P 0 0;5=6,7=1
P 10.01 2.6159 7 P 0 0;5=6,7=1
P 11.74316004 1.7035 7 P 0 0;5=6,7=1
P 11.74316004 1.6405 7 P 0 0;5=6,7=1
P 11.69316004 1.4805 7 P 0 0;5=6,7=1
P 11.69316004 1.5435 7 P 0 0;5=6,7=1
P 11.49316004 1.5605 7 P 0 0;5=6,7=1
P 11.49316004 1.6235 7 P 0 0;5=6,7=1
P 11.49316004 1.4635 7 P 0 0;5=6,7=1
P 11.49366004 1.401 7 P 0 0;5=6,7=1
P 11.69316004 2.6005 7 P 0 0;5=6,7=1
P 11.69316004 2.5035 7 P 0 0;5=6,7=1
P 11.69316004 2.4405 7 P 0 0;5=6,7=1
P 11.69316004 2.3435 7 P 0 0;5=6,7=1
P 11.69316004 2.2805 7 P 0 0;5=6,7=1
P 11.69316004 2.1835 7 P 0 0;5=6,7=1
P 11.69316004 1.9605 7 P 0 0;5=6,7=1
P 11.69316004 2.0235 7 P 0 0;5=6,7=1
P 11.69316004 2.1205 7 P 0 0;5=6,7=1
P 11.69316004 1.8005 7 P 0 0;5=6,7=1
P 11.69316004 1.8635 7 P 0 0;5=6,7=1
P 11.49316004 2.5205 7 P 0 0;5=6,7=1
P 11.49316004 2.5835 7 P 0 0;5=6,7=1
P 11.49316004 2.4235 7 P 0 0;5=6,7=1
P 11.49316004 2.3605 7 P 0 0;5=6,7=1
P 11.79316004 2.2635 7 P 0 0;5=6,7=1
P 11.79316004 2.2005 7 P 0 0;5=6,7=1
P 11.49316004 1.9435 7 P 0 0;5=6,7=1
P 11.49316004 2.1035 7 P 0 0;5=6,7=1
P 11.49316004 2.0405 7 P 0 0;5=6,7=1
P 11.49316004 1.8805 7 P 0 0;5=6,7=1
P 11.49366004 1.721 7 P 0 0;5=6,7=1
P 11.49316004 1.7835 7 P 0 0;5=6,7=1
P 10.125 2.7451 7 P 0 0;5=6,7=1
P 10.125 2.688 7 P 0 0;5=6,7=1
L 11.845 2.85 11.80693002 2.85 5 P 0 
P 12.30798002 2.155 25 P 0 0;2,5=0,7=0
P 12.34 2.19 7 P 0 0;5=6,7=1
L 5.46168996 2.8 5.46168996 2.73 5 P 0 
P 9.415 5.332 7 P 0 0;5=6,7=1
P 9.265 5.332 7 P 0 0;5=6,7=1
P 9.07 5.332 7 P 0 0;5=6,7=1
P 4.7 5.54928996 7 P 0 0;5=6,7=1
P 4.81 5.375 7 P 0 0;5=6,7=1
P 4.96 5.375 7 P 0 0;5=6,7=1
P 5.16 5.645 7 P 0 0;5=6,7=1
P 5.04441004 5.605 7 P 0 0;5=6,7=1
P 4.92 5.7 7 P 0 0;5=6,7=1
P 9.91 4.7 7 P 0 0;5=6,7=1
P 3.57 4.45 7 P 0 0;5=6,7=1
P 10.465 5.195 7 P 0 0;5=6,7=1
P 10.515 5.32 7 P 0 0;5=6,7=1
P 10.465 5.275 7 P 0 0;5=6,7=1
P 12.025 4.915 7 P 0 0;5=6,7=1
P 12.12 4.965 7 P 0 0;5=6,7=1
P 12.185 4.915 7 P 0 0;5=6,7=1
P 3.72 4.45 7 P 0 0;5=6,7=1
P 3.66 4.63 7 P 0 0;5=6,7=1
P 3.77 4.86 7 P 0 0;5=6,7=1
P 9.96 4.69 7 P 0 0;5=6,7=1
P 10.03 4.51 7 P 0 0;5=6,7=1
P 3.835 4.6 7 P 0 0;5=6,7=1
P 3.9865 4.635 7 P 0 0;5=6,7=1
P 4.14 4.655 7 P 0 0;5=6,7=1
L 5.917 2.97 5.917 2.9452 7 P 0 
L 5.917 2.9452 5.9192 2.943 7 P 0 
P 4.1049 4.7649 7 P 0 0;5=6,7=1
P 1.28051004 5.78 7 P 0 0;5=6,7=1
P 3.87 5.125 7 P 0 0;5=6,7=1
L 9.95743996 2.87558996 9.995 2.87558996 5 P 0 
P 0.4826 5.8976 7 P 0 0;5=6,7=1
P 0.84953002 5.17 7 P 0 0;5=6,7=1
P 0.955 5.325 7 P 0 0;5=6,7=1
P 1.31 5.355 7 P 0 0;5=6,7=1
P 1.20176998 5.78 7 P 0 0;5=6,7=1
L 6.34948996 4.99705 6.31295 4.99705 7 P 0 
P 6.34948996 4.99705 25 P 0 0;2,5=0,7=0
P 6.31295 4.99705 7 P 0 0;5=6,7=1
L 6.837 5 6.87 5 7 P 0 
P 6.837 5 25 P 0 0;2,5=0,7=0
P 6.87 5 7 P 0 0;5=6,7=1
P 6.27208996 4.7202 27 P 0 0;2,5=11,7=0
P 6.27208996 4.6402 27 P 0 0;2,5=11,7=0
P 6.27208996 4.8802 27 P 0 0;2,5=11,7=0
P 6.27208996 4.8002 27 P 0 0;2,5=11,7=0
P 9.64796004 0.79643002 7 P 0 0;5=6,7=1
P 9.40795 0.26133002 7 P 0 0;5=6,7=1
P 3.60998996 0.24 7 P 0 0;5=6,7=1
P 3.65998996 0.345 7 P 0 0;5=6,7=1
P 3.86 0.7751 8 P 0 0;3,5=1,7=1
P 6.905 4.94705 7 P 0 0;5=6,7=1
P 6.905 4.88705 7 P 0 0;5=6,7=1
P 6.91118996 4.81705 27 P 0 0;2,5=11,7=0
P 6.955 4.8 7 P 0 0;5=6,7=1
P 6.955 4.84 7 P 0 0;5=6,7=1
P 6.91118996 4.73868002 27 P 0 0;2,5=11,7=0
P 6.955 4.72 7 P 0 0;5=6,7=1
P 6.955 4.76 7 P 0 0;5=6,7=1
P 6.59708996 5.0502 7 P 0 0;5=6,7=1
P 6.65218996 4.77 7 P 0 0;5=6,7=1
P 6.62118996 4.95641998 7 P 0 0;5=12,7=1
P 6.6015 4.93673996 7 P 0 0;5=12,7=1
P 6.64088002 4.93673996 7 P 0 0;5=12,7=1
P 6.62118996 4.91705 7 P 0 0;5=12,7=1
P 6.62118996 4.87768002 7 P 0 0;5=12,7=1
P 6.6015 4.89736004 7 P 0 0;5=12,7=1
P 6.64088002 4.89736004 7 P 0 0;5=12,7=1
P 6.66208996 4.6252 27 P 0 0;2,5=11,7=0
P 6.66208996 4.7052 27 P 0 0;2,5=11,7=0
P 6.62 4.69 7 P 0 0;5=6,7=1
P 6.62 4.725 7 P 0 0;5=6,7=1
P 6.385 5.07 7 P 0 0;5=6,7=1
P 5.53593996 4.55505 7 P 0 0;5=6,7=1
P 5.99708996 4.5552 27 P 0 0;2,5=11,7=0
P 5.91708996 4.5552 27 P 0 0;2,5=11,7=0
P 6.07708996 4.5552 27 P 0 0;2,5=11,7=0
P 6.05708996 4.5102 7 P 0 0;5=6,7=1
P 6.01708996 4.5102 7 P 0 0;5=6,7=1
P 5.97708996 4.5102 7 P 0 0;5=6,7=1
P 5.93708996 4.5102 7 P 0 0;5=6,7=1
P 5.89708996 4.5102 7 P 0 0;5=6,7=1
P 6.09708996 4.5102 7 P 0 0;5=6,7=1
P 5.83708996 4.5552 27 P 0 0;2,5=11,7=0
P 5.75708996 4.5552 27 P 0 0;2,5=11,7=0
P 5.67708996 4.5552 27 P 0 0;2,5=11,7=0
P 5.61708996 4.5102 7 P 0 0;5=6,7=1
P 5.65708996 4.5102 7 P 0 0;5=6,7=1
P 5.85708996 4.5102 7 P 0 0;5=6,7=1
P 5.81708996 4.5102 7 P 0 0;5=6,7=1
P 5.77708996 4.5102 7 P 0 0;5=6,7=1
P 5.73708996 4.5102 7 P 0 0;5=6,7=1
P 5.69708996 4.5102 7 P 0 0;5=6,7=1
P 5.59778996 4.5552 27 P 0 0;2,5=11,7=0
P 5.57708996 4.5102 7 P 0 0;5=6,7=1
P 0.036 0.10868002 7 P 0 0;5=6,7=1
P 0.036 0.15868002 7 P 0 0;5=6,7=1
P 0.036 0.20868002 7 P 0 0;5=6,7=1
P 0.22873996 0.036 7 P 0 0;5=6,7=1
P 0.17873996 0.036 7 P 0 0;5=6,7=1
P 0.12873996 0.036 7 P 0 0;5=6,7=1
P 0.07873996 0.036 7 P 0 0;5=6,7=1
P 0.47873996 0.036 7 P 0 0;5=6,7=1
P 0.42873996 0.036 7 P 0 0;5=6,7=1
P 0.37873996 0.036 7 P 0 0;5=6,7=1
P 0.32873996 0.036 7 P 0 0;5=6,7=1
P 0.27873996 0.036 7 P 0 0;5=6,7=1
P 0.77873996 0.036 7 P 0 0;5=6,7=1
P 0.72873996 0.036 7 P 0 0;5=6,7=1
P 0.67873996 0.036 7 P 0 0;5=6,7=1
P 0.62873996 0.036 7 P 0 0;5=6,7=1
P 0.57873996 0.036 7 P 0 0;5=6,7=1
P 0.52873996 0.036 7 P 0 0;5=6,7=1
P 1.02873996 0.036 7 P 0 0;5=6,7=1
P 0.97873996 0.036 7 P 0 0;5=6,7=1
P 0.92873996 0.036 7 P 0 0;5=6,7=1
P 0.87873996 0.036 7 P 0 0;5=6,7=1
P 0.82873996 0.036 7 P 0 0;5=6,7=1
P 1.27873996 0.036 7 P 0 0;5=6,7=1
P 1.22873996 0.036 7 P 0 0;5=6,7=1
P 1.17873996 0.036 7 P 0 0;5=6,7=1
P 1.12873996 0.036 7 P 0 0;5=6,7=1
P 1.07873996 0.036 7 P 0 0;5=6,7=1
P 1.52873996 0.036 7 P 0 0;5=6,7=1
P 1.47873996 0.036 7 P 0 0;5=6,7=1
P 1.42873996 0.036 7 P 0 0;5=6,7=1
P 1.37873996 0.036 7 P 0 0;5=6,7=1
P 1.32873996 0.036 7 P 0 0;5=6,7=1
P 1.82873996 0.036 7 P 0 0;5=6,7=1
P 1.77873996 0.036 7 P 0 0;5=6,7=1
P 1.72873996 0.036 7 P 0 0;5=6,7=1
P 1.67873996 0.036 7 P 0 0;5=6,7=1
P 1.62873996 0.036 7 P 0 0;5=6,7=1
P 1.57873996 0.036 7 P 0 0;5=6,7=1
P 2.07873996 0.036 7 P 0 0;5=6,7=1
P 2.02873996 0.036 7 P 0 0;5=6,7=1
P 1.97873996 0.036 7 P 0 0;5=6,7=1
P 1.92873996 0.036 7 P 0 0;5=6,7=1
P 1.87873996 0.036 7 P 0 0;5=6,7=1
P 2.32873996 0.036 7 P 0 0;5=6,7=1
P 2.27873996 0.036 7 P 0 0;5=6,7=1
P 2.22873996 0.036 7 P 0 0;5=6,7=1
P 2.17873996 0.036 7 P 0 0;5=6,7=1
P 2.12873996 0.036 7 P 0 0;5=6,7=1
P 2.62873996 0.036 7 P 0 0;5=6,7=1
P 2.57873996 0.036 7 P 0 0;5=6,7=1
P 2.52873996 0.036 7 P 0 0;5=6,7=1
P 2.47873996 0.036 7 P 0 0;5=6,7=1
P 2.42873996 0.036 7 P 0 0;5=6,7=1
P 2.37873996 0.036 7 P 0 0;5=6,7=1
P 2.87873996 0.036 7 P 0 0;5=6,7=1
P 2.82873996 0.036 7 P 0 0;5=6,7=1
P 2.77873996 0.036 7 P 0 0;5=6,7=1
P 2.72873996 0.036 7 P 0 0;5=6,7=1
P 2.67873996 0.036 7 P 0 0;5=6,7=1
P 3.12873996 0.036 7 P 0 0;5=6,7=1
P 3.07873996 0.036 7 P 0 0;5=6,7=1
P 3.02873996 0.036 7 P 0 0;5=6,7=1
P 2.97873996 0.036 7 P 0 0;5=6,7=1
P 2.92873996 0.036 7 P 0 0;5=6,7=1
P 3.37873996 0.036 7 P 0 0;5=6,7=1
P 3.32873996 0.036 7 P 0 0;5=6,7=1
P 3.27873996 0.036 7 P 0 0;5=6,7=1
P 3.22873996 0.036 7 P 0 0;5=6,7=1
P 3.17873996 0.036 7 P 0 0;5=6,7=1
P 3.67873996 0.036 7 P 0 0;5=6,7=1
P 3.62873996 0.036 7 P 0 0;5=6,7=1
P 3.57873996 0.036 7 P 0 0;5=6,7=1
P 3.52873996 0.036 7 P 0 0;5=6,7=1
P 3.47873996 0.036 7 P 0 0;5=6,7=1
P 3.42873996 0.036 7 P 0 0;5=6,7=1
P 3.92873996 0.036 7 P 0 0;5=6,7=1
P 3.87873996 0.036 7 P 0 0;5=6,7=1
P 3.82873996 0.036 7 P 0 0;5=6,7=1
P 3.77873996 0.036 7 P 0 0;5=6,7=1
P 3.72873996 0.036 7 P 0 0;5=6,7=1
P 4.17873996 0.036 7 P 0 0;5=6,7=1
P 4.12873996 0.036 7 P 0 0;5=6,7=1
P 4.07873996 0.036 7 P 0 0;5=6,7=1
P 4.02873996 0.036 7 P 0 0;5=6,7=1
P 3.97873996 0.036 7 P 0 0;5=6,7=1
P 4.42873996 0.036 7 P 0 0;5=6,7=1
P 4.37873996 0.036 7 P 0 0;5=6,7=1
P 4.32873996 0.036 7 P 0 0;5=6,7=1
P 4.27873996 0.036 7 P 0 0;5=6,7=1
P 4.22873996 0.036 7 P 0 0;5=6,7=1
P 4.72873996 0.036 7 P 0 0;5=6,7=1
P 4.67873996 0.036 7 P 0 0;5=6,7=1
P 4.62873996 0.036 7 P 0 0;5=6,7=1
P 4.57873996 0.036 7 P 0 0;5=6,7=1
P 4.52873996 0.036 7 P 0 0;5=6,7=1
P 4.47873996 0.036 7 P 0 0;5=6,7=1
P 4.81833996 0.21825 7 P 0 0;5=6,7=1
P 4.81833996 0.16825 7 P 0 0;5=6,7=1
P 4.81833996 0.11825 7 P 0 0;5=6,7=1
P 4.81703996 0.06826004 7 P 0 0;5=6,7=1
P 4.77873996 0.03611998 7 P 0 0;5=6,7=1
P 6.80731004 0.036 7 P 0 0;5=6,7=1
P 6.75731004 0.036 7 P 0 0;5=6,7=1
P 6.70731004 0.036 7 P 0 0;5=6,7=1
P 6.65731004 0.03676004 7 P 0 0;5=6,7=1
P 6.62298996 0.07311998 7 P 0 0;5=6,7=1
P 6.62261998 0.12311998 7 P 0 0;5=6,7=1
P 6.62261998 0.17311998 7 P 0 0;5=6,7=1
P 6.62261998 0.22311998 7 P 0 0;5=6,7=1
P 7.00731004 0.036 7 P 0 0;5=6,7=1
P 6.95731004 0.036 7 P 0 0;5=6,7=1
P 6.90731004 0.036 7 P 0 0;5=6,7=1
P 6.85731004 0.036 7 P 0 0;5=6,7=1
P 0.036 0.25868002 7 P 0 0;5=6,7=1
P 0.036 0.30868002 7 P 0 0;5=6,7=1
P 0.036 0.35868002 7 P 0 0;5=6,7=1
P 0.036 0.40868002 7 P 0 0;5=6,7=1
P 0.036 0.45868002 7 P 0 0;5=6,7=1
P 4.96803996 0.46906998 7 P 0 0;5=6,7=1
P 4.91805 0.46808002 7 P 0 0;5=6,7=1
P 4.87108996 0.45088996 7 P 0 0;5=6,7=1
P 4.83591004 0.41536004 7 P 0 0;5=6,7=1
P 4.81918996 0.36823996 7 P 0 0;5=6,7=1
P 4.81833996 0.31825 7 P 0 0;5=6,7=1
P 4.81833996 0.26825 7 P 0 0;5=6,7=1
P 5.21803996 0.46906998 7 P 0 0;5=6,7=1
P 5.16803996 0.46906998 7 P 0 0;5=6,7=1
P 5.11803996 0.46906998 7 P 0 0;5=6,7=1
P 5.06803996 0.46906998 7 P 0 0;5=6,7=1
P 5.01803996 0.46906998 7 P 0 0;5=6,7=1
P 5.51803996 0.46906998 7 P 0 0;5=6,7=1
P 5.46803996 0.46906998 7 P 0 0;5=6,7=1
P 5.41803996 0.46906998 7 P 0 0;5=6,7=1
P 5.36803996 0.46906998 7 P 0 0;5=6,7=1
P 5.31803996 0.46906998 7 P 0 0;5=6,7=1
P 5.26803996 0.46906998 7 P 0 0;5=6,7=1
P 5.76803996 0.46906998 7 P 0 0;5=6,7=1
P 5.71803996 0.46906998 7 P 0 0;5=6,7=1
P 5.66803996 0.46906998 7 P 0 0;5=6,7=1
P 5.61803996 0.46906998 7 P 0 0;5=6,7=1
P 5.56803996 0.46906998 7 P 0 0;5=6,7=1
P 6.01803996 0.46906998 7 P 0 0;5=6,7=1
P 5.96803996 0.46906998 7 P 0 0;5=6,7=1
P 5.91803996 0.46906998 7 P 0 0;5=6,7=1
P 5.86803996 0.46906998 7 P 0 0;5=6,7=1
P 5.81803996 0.46906998 7 P 0 0;5=6,7=1
P 6.31803996 0.46906998 7 P 0 0;5=6,7=1
P 6.26803996 0.46906998 7 P 0 0;5=6,7=1
P 6.21803996 0.46906998 7 P 0 0;5=6,7=1
P 6.16803996 0.46906998 7 P 0 0;5=6,7=1
P 6.11803996 0.46906998 7 P 0 0;5=6,7=1
P 6.06803996 0.46906998 7 P 0 0;5=6,7=1
P 6.56568002 0.45345 7 P 0 0;5=6,7=1
P 6.51803002 0.46861998 7 P 0 0;5=6,7=1
P 6.46803996 0.46906998 7 P 0 0;5=6,7=1
P 6.41803996 0.46906998 7 P 0 0;5=6,7=1
P 6.36803996 0.46906998 7 P 0 0;5=6,7=1
P 6.62261998 0.27311998 7 P 0 0;5=6,7=1
P 6.62261998 0.32311998 7 P 0 0;5=6,7=1
P 6.62106998 0.3731 7 P 0 0;5=6,7=1
P 6.60233996 0.41946004 7 P 0 0;5=6,7=1
P 0.036 0.50868002 7 P 0 0;5=6,7=1
P 0.036 0.55868002 7 P 0 0;5=6,7=1
P 5.40386004 2.96 27 P 0 0;2,5=11,7=0
P 5.40386004 3.04 27 P 0 0;2,5=11,7=0
P 5.40386004 3.12 27 P 0 0;2,5=11,7=0
P 11.40778996 3.04 27 P 0 0;2,5=11,7=0
P 11.40778996 3.12 27 P 0 0;2,5=11,7=0
P 11.40778996 2.96 27 P 0 0;2,5=11,7=0
P 11.80693002 2.85 30 P 0 0;2,5=8,7=0
P 11.845 2.85 7 P 0 0;5=6,7=1
P 8.98115 2.7861 7 P 0 0;5=6,7=1
P 8.98115 2.8989 7 P 0 0;5=6,7=1
L 5.46168996 2.73 5.49221004 2.73 5 P 0 
L 11.61661998 2.855 11.58613002 2.855 5 P 0 
P 11.58613002 2.855 7 P 0 0;5=6,7=1
L 11.47061998 2.8 11.50361998 2.8 5 P 0 
P 11.50361998 2.8 7 P 0 0;5=6,7=1
L 11.47061998 2.73 11.50361998 2.73 5 P 0 
P 11.50361998 2.73 7 P 0 0;5=6,7=1
L 10.13478996 2.82 10.13478996 2.797 5 P 0 
L 10.13478996 2.797 10.11778996 2.78 5 P 0 
L 5.61268996 2.855 5.5822 2.855 5 P 0 
L 4.09086004 2.59 4.09086004 2.567 5 P 0 
L 4.09086004 2.567 4.07386004 2.55 5 P 0 
L 5.6152 3 5.5722 3 5 P 0 
P 5.6152 3 25 P 0 0;2,5=0,7=0
P 5.5722 3 7 P 0 0;5=6,7=1
L 5.72185 3.02558996 5.75778996 3.02558996 5 P 0 
P 5.72185 3.02558996 30 P 0 0;2,5=8,7=0
P 5.75778996 3.02558996 7 P 0 0;5=6,7=1
P 5.9192 2.943 7 P 0 0;5=6,7=1
P 4.07386004 2.55 7 P 0 0;5=6,7=1
L 3.91351004 2.64558996 3.86826998 2.64558996 5 P 0 
P 3.86826998 2.64558996 7 P 0 0;5=6,7=1
P 9.95743996 2.87558996 30 P 0 0;2,5=8,7=0
P 9.995 2.87558996 7 P 0 0;5=6,7=1
P 10.11778996 2.78 7 P 0 0;5=6,7=1
P 7.2426 4.60351004 7 P 0 0;5=6,7=1
P 7.3401 4.85601004 7 P 0 0;5=6,7=1
P 7.1926 5.04351004 7 P 0 0;5=6,7=1
P 0.66 2.045 8 P 0 0;3,5=1,7=1
P 1.792 2.4781 7 P 0 0;5=6,7=1
P 2.97721004 2.8989 7 P 0 0;5=6,7=1
P 2.97721004 2.7861 7 P 0 0;5=6,7=1
P 2.9422 2.925 7 P 0 0;5=6,7=1
P 8.94278996 2.925 7 P 0 0;5=6,7=1
P 5.5822 2.855 7 P 0 0;5=6,7=1
L 5.84968996 2.85 5.803 2.85 5 P 0 
P 5.84968996 2.85 7 P 0 0;5=6,7=1
P 0.65348996 1.85608996 7 P 0 0;5=6,7=1
P 0.65348996 1.91628996 7 P 0 0;5=6,7=1
P 0.09448996 4.60236998 11 P 0 0;3,5=2,7=0
P 0.35038996 4.20866004 11 P 0 0;5=2,7=0
P 0.09448996 4.2874 11 P 0 0;5=2,7=0
P 0.09448996 4.12991998 11 P 0 0;5=2,7=0
P 0.17323002 4.16928996 11 P 0 0;5=2,7=0
P 0.27165 4.09055 11 P 0 0;5=2,7=0
P 0.27165 3.93306998 11 P 0 0;5=2,7=0
P 0.35038996 4.05118002 11 P 0 0;5=2,7=0
P 0.35038996 3.8937 11 P 0 0;5=2,7=0
P 0.09448996 3.97243996 11 P 0 0;5=2,7=0
P 0.09448996 3.81496004 11 P 0 0;5=2,7=0
P 0.17323002 4.01181004 11 P 0 0;5=2,7=0
P 0.17323002 3.85433002 11 P 0 0;5=2,7=0
P 0.27165 3.77558996 11 P 0 0;5=2,7=0
P 0.27165 3.61811004 11 P 0 0;5=2,7=0
P 0.35038996 3.73621998 11 P 0 0;5=2,7=0
P 0.35038996 3.57873996 11 P 0 0;5=2,7=0
P 0.09448996 3.65748002 11 P 0 0;5=2,7=0
P 0.09448996 3.5 11 P 0 0;5=2,7=0
P 0.17323002 3.69685 11 P 0 0;5=2,7=0
P 0.17323002 3.53936998 11 P 0 0;5=2,7=0
P 0.27165 3.46063002 11 P 0 0;5=2,7=0
P 0.35038996 3.42126004 11 P 0 0;5=2,7=0
P 0.27165 3.30315 11 P 0 0;5=2,7=0
P 0.27165 3.22441004 11 P 0 0;5=2,7=0
P 0.17323002 3.38188996 11 P 0 0;5=2,7=0
P 0.17323002 3.30315 11 P 0 0;5=2,7=0
P 0.35038996 3.1063 11 P 0 0;5=2,7=0
P 0.35038996 2.94881998 11 P 0 0;5=2,7=0
P 0.27165 3.06693002 11 P 0 0;5=2,7=0
P 0.27165 2.90945 11 P 0 0;5=2,7=0
P 0.17323002 3.14566998 11 P 0 0;5=2,7=0
P 0.17323002 2.98818996 11 P 0 0;5=2,7=0
P 0.09448996 3.18503996 11 P 0 0;5=2,7=0
P 0.09448996 3.02756004 11 P 0 0;5=2,7=0
P 0.35038996 2.79133996 11 P 0 0;5=2,7=0
P 0.27165 2.75196998 11 P 0 0;5=2,7=0
P 0.35038996 2.63386004 11 P 0 0;5=2,7=0
P 0.17323002 2.83071004 11 P 0 0;5=2,7=0
P 0.09448996 2.87008002 11 P 0 0;5=2,7=0
P 0.09448996 2.7126 11 P 0 0;5=2,7=0
P 0.35038996 2.39763996 11 P 0 0;5=2,7=0
P 0.27165 2.51575 11 P 0 0;5=2,7=0
P 0.27165 2.35826998 11 P 0 0;5=2,7=0
P 0.17323002 2.59448996 11 P 0 0;5=2,7=0
P 0.17323002 2.43701004 11 P 0 0;5=2,7=0
P 0.09448996 2.47638002 11 P 0 0;5=2,7=0
P 0.09448996 2.3189 11 P 0 0;5=2,7=0
P 0.35038996 2.24016004 11 P 0 0;5=2,7=0
P 0.35038996 2.08268002 11 P 0 0;5=2,7=0
P 0.35038996 2.00393996 11 P 0 0;5=2,7=0
P 0.27165 2.20078996 11 P 0 0;5=2,7=0
P 0.17323002 2.27953002 11 P 0 0;5=2,7=0
P 0.09448996 2.16141998 11 P 0 0;5=2,7=0
P 0.09448996 2.08268002 11 P 0 0;5=2,7=0
P 0.17323002 1.96456998 11 P 0 0;5=2,7=0
P 0.09448996 1.84646004 11 P 0 0;5=2,7=0
P 0.09448996 4.44488002 11 P 0 0;5=2,7=0
P 12.63778996 2.00393996 11 P 0 0;5=2,7=0
P 12.55905 2.12205 11 P 0 0;5=2,7=0
P 12.55905 1.88583002 11 P 0 0;5=2,7=0
P 12.81495 2.12205 11 P 0 0;5=2,7=0
P 12.81495 2.04331004 11 P 0 0;5=2,7=0
P 12.73621004 2.39763996 11 P 0 0;5=2,7=0
P 12.73621004 2.24016004 11 P 0 0;5=2,7=0
P 12.63778996 2.3189 11 P 0 0;5=2,7=0
P 12.55905 2.35826998 11 P 0 0;5=2,7=0
P 12.55905 2.20078996 11 P 0 0;5=2,7=0
P 12.81495 2.43701004 11 P 0 0;5=2,7=0
P 12.81495 2.27953002 11 P 0 0;5=2,7=0
P 12.73621004 2.55511998 11 P 0 0;5=2,7=0
P 12.63778996 2.63386004 11 P 0 0;5=2,7=0
P 12.63778996 2.47638002 11 P 0 0;5=2,7=0
P 12.55905 2.51575 11 P 0 0;5=2,7=0
P 12.81495 2.67323002 11 P 0 0;5=2,7=0
P 12.73621004 2.94881998 11 P 0 0;5=2,7=0
P 12.73621004 2.79133996 11 P 0 0;5=2,7=0
P 12.63778996 3.02756004 11 P 0 0;5=2,7=0
P 12.63778996 2.87008002 11 P 0 0;5=2,7=0
P 12.55905 2.90945 11 P 0 0;5=2,7=0
P 12.55905 2.75196998 11 P 0 0;5=2,7=0
P 12.81495 2.98818996 11 P 0 0;5=2,7=0
P 12.81495 2.83071004 11 P 0 0;5=2,7=0
P 12.73621004 3.26378002 11 P 0 0;5=2,7=0
P 12.73621004 3.1063 11 P 0 0;5=2,7=0
P 12.63778996 3.18503996 11 P 0 0;5=2,7=0
P 12.55905 3.22441004 11 P 0 0;5=2,7=0
P 12.55905 3.06693002 11 P 0 0;5=2,7=0
P 12.81495 3.14566998 11 P 0 0;5=2,7=0
P 12.55905 3.53936998 11 P 0 0;5=2,7=0
P 12.63778996 3.57873996 11 P 0 0;5=2,7=0
P 12.63778996 3.42126004 11 P 0 0;5=2,7=0
P 12.73621004 3.5 11 P 0 0;5=2,7=0
P 12.73621004 3.34251998 11 P 0 0;5=2,7=0
P 12.63778996 3.34251998 11 P 0 0;5=2,7=0
P 12.81495 3.61811004 11 P 0 0;5=2,7=0
P 12.81495 3.46063002 11 P 0 0;5=2,7=0
P 12.55905 3.85433002 11 P 0 0;5=2,7=0
P 12.55905 3.69685 11 P 0 0;5=2,7=0
P 12.63778996 3.8937 11 P 0 0;5=2,7=0
P 12.63778996 3.73621998 11 P 0 0;5=2,7=0
P 12.73621004 3.81496004 11 P 0 0;5=2,7=0
P 12.73621004 3.65748002 11 P 0 0;5=2,7=0
P 12.81495 3.93306998 11 P 0 0;5=2,7=0
P 12.81495 3.77558996 11 P 0 0;5=2,7=0
P 12.55905 4.16928996 11 P 0 0;5=2,7=0
P 12.55905 4.01181004 11 P 0 0;5=2,7=0
P 12.63778996 4.20866004 11 P 0 0;5=2,7=0
P 12.63778996 4.05118002 11 P 0 0;5=2,7=0
P 12.73621004 4.12991998 11 P 0 0;5=2,7=0
P 12.73621004 3.97243996 11 P 0 0;5=2,7=0
P 12.81495 4.09055 11 P 0 0;5=2,7=0
P 12.55905 4.48425 11 P 0 0;5=2,7=0
P 12.55905 4.32676998 11 P 0 0;5=2,7=0
P 12.63778996 4.52361998 11 P 0 0;5=2,7=0
P 12.63778996 4.36613996 11 P 0 0;5=2,7=0
P 12.73621004 4.44488002 11 P 0 0;5=2,7=0
P 12.73621004 4.2874 11 P 0 0;5=2,7=0
P 12.81495 4.40551004 11 P 0 0;5=2,7=0
P 12.81495 4.24803002 11 P 0 0;5=2,7=0
P 12.55905 4.64173996 11 P 0 0;5=2,7=0
P 12.81495 4.56298996 11 P 0 0;5=2,7=0
P 0.27165 4.40551004 11 P 0 0;5=2,7=0
P 0.35038996 4.52361998 11 P 0 0;5=2,7=0
P 0.17323002 4.48425 11 P 0 0;5=2,7=0
P 0.27165 4.24803002 11 P 0 0;5=2,7=0
P 0.35038996 4.36613996 11 P 0 0;5=2,7=0
P 0.17323002 4.32676998 11 P 0 0;5=2,7=0
P 5.49221004 2.73 7 P 0 0;5=6,7=1
P 5.803 2.85 30 P 0 0;2,5=8,7=0
P 5.61268996 2.855 25 P 0 0;2,5=0,7=0
P 5.44886004 2.9414 7 P 0 0;5=6,7=1
P 5.44886004 3.0214 7 P 0 0;5=6,7=1
P 5.44886004 3.0564 7 P 0 0;5=6,7=1
P 5.44886004 3.1014 7 P 0 0;5=6,7=1
P 5.44886004 3.1364 7 P 0 0;5=6,7=1
P 5.44886004 3.2164 7 P 0 0;5=6,7=1
P 5.44886004 3.1814 7 P 0 0;5=6,7=1
P 5.44886004 2.9764 7 P 0 0;5=6,7=1
P 5.44886004 3.2614 7 P 0 0;5=6,7=1
P 5.44886004 3.2964 7 P 0 0;5=6,7=1
P 10.33998996 4.9231 7 P 0 0;5=6,7=1
P 10.38498996 4.9231 8 P 0 0;3,5=1,7=1
P 10.77498996 4.9231 7 P 0 0;5=6,7=1
P 10.72998996 4.9231 7 P 0 0;5=6,7=1
P 10.30498996 4.9431 7 P 0 0;5=6,7=1
P 10.26498996 4.9431 7 P 0 0;5=6,7=1
P 10.30498996 5.0281 7 P 0 0;5=6,7=1
P 10.30498996 5.0731 7 P 0 0;5=6,7=1
P 10.30498996 4.9831 7 P 0 0;5=6,7=1
P 10.26498996 5.0281 7 P 0 0;5=6,7=1
P 10.26498996 5.0731 7 P 0 0;5=6,7=1
P 10.26498996 4.9831 7 P 0 0;5=6,7=1
P 10.26498996 5.1181 7 P 0 0;5=6,7=1
P 10.30498996 5.1181 7 P 0 0;5=6,7=1
P 10.34498996 5.1181 7 P 0 0;5=6,7=1
P 10.42498996 4.9431 7 P 0 0;5=6,7=1
P 10.46498996 4.9431 7 P 0 0;5=6,7=1
P 10.38498996 5.1181 7 P 0 0;5=6,7=1
P 10.46498996 5.1181 7 P 0 0;5=6,7=1
P 10.42498996 5.1181 7 P 0 0;5=6,7=1
P 10.42498996 4.9831 7 P 0 0;5=6,7=1
P 10.42498996 5.0731 7 P 0 0;5=6,7=1
P 10.42498996 5.0281 7 P 0 0;5=6,7=1
P 10.46498996 4.9831 7 P 0 0;5=6,7=1
P 10.46498996 5.0731 7 P 0 0;5=6,7=1
P 10.46498996 5.0281 7 P 0 0;5=6,7=1
P 10.85498996 4.9431 7 P 0 0;5=6,7=1
P 10.81498996 4.9431 7 P 0 0;5=6,7=1
P 10.65498996 4.9431 7 P 0 0;5=6,7=1
P 10.69498996 4.9431 7 P 0 0;5=6,7=1
P 10.85498996 5.0281 7 P 0 0;5=6,7=1
P 10.85498996 5.0731 7 P 0 0;5=6,7=1
P 10.85498996 4.9831 7 P 0 0;5=6,7=1
P 10.81498996 5.0281 7 P 0 0;5=6,7=1
P 10.81498996 5.0731 7 P 0 0;5=6,7=1
P 10.81498996 4.9831 7 P 0 0;5=6,7=1
P 10.81498996 5.1181 7 P 0 0;5=6,7=1
P 10.85498996 5.1181 7 P 0 0;5=6,7=1
P 10.73498996 5.1181 7 P 0 0;5=6,7=1
P 10.69498996 5.1181 7 P 0 0;5=6,7=1
P 10.65498996 5.1181 7 P 0 0;5=6,7=1
P 10.77498996 5.1181 7 P 0 0;5=6,7=1
P 10.65498996 4.9831 7 P 0 0;5=6,7=1
P 10.65498996 5.0731 7 P 0 0;5=6,7=1
P 10.65498996 5.0281 7 P 0 0;5=6,7=1
P 10.69498996 4.9831 7 P 0 0;5=6,7=1
P 10.69498996 5.0731 7 P 0 0;5=6,7=1
P 10.69498996 5.0281 7 P 0 0;5=6,7=1
P 1.23906004 4.60351004 7 P 0 0;5=6,7=1
P 1.18906004 5.04351004 7 P 0 0;5=6,7=1
P 1.33656004 4.85601004 7 P 0 0;5=6,7=1
P 10.16606998 2.81 7 P 0 0;5=6,7=1
P 3.91351004 2.64558996 30 P 0 0;2,5=8,7=0
P 4.15221004 2.9281 7 P 0 0;5=6,7=1
P 4.09086004 2.59 25 P 0 0;2,5=0,7=0
P 10.13478996 2.82 25 P 0 0;2,5=0,7=0
P 11.45278996 2.9414 7 P 0 0;5=6,7=1
P 11.45278996 3.0214 7 P 0 0;5=6,7=1
P 11.45278996 3.0564 7 P 0 0;5=6,7=1
P 11.45278996 3.1014 7 P 0 0;5=6,7=1
P 11.45278996 3.1364 7 P 0 0;5=6,7=1
P 11.45278996 3.2164 7 P 0 0;5=6,7=1
P 11.45278996 3.1814 7 P 0 0;5=6,7=1
P 11.45278996 2.9764 7 P 0 0;5=6,7=1
P 11.45278996 3.2614 7 P 0 0;5=6,7=1
P 11.45278996 3.2964 7 P 0 0;5=6,7=1
P 11.47061998 2.73 25 P 0 0;2,5=0,7=0
P 11.47061998 2.8 25 P 0 0;2,5=0,7=0
P 11.61661998 2.855 25 P 0 0;2,5=0,7=0
P 0.09448996 1.45276004 11 P 0 0;5=2,7=0
P 0.27165 1.57086998 11 P 0 0;5=2,7=0
P 0.35038996 1.45276004 11 P 0 0;5=2,7=0
P 12.81495 1.49213002 11 P 0 0;5=2,7=0
P 12.73621004 1.61023996 11 P 0 0;5=2,7=0
P 12.55905 1.49213002 11 P 0 0;5=2,7=0
P 0.27165 1.88583002 11 P 0 0;5=2,7=0
P 12.73621004 1.9252 11 P 0 0;5=2,7=0
P 5.46168996 2.73 25 P 0 0;2,5=0,7=0
P 5.46168996 2.8 25 P 0 0;2,5=0,7=0
P 11.40778996 3.28 27 P 0 0;2,5=11,7=0
P 11.40778996 3.2 27 P 0 0;2,5=11,7=0
P 5.40386004 3.2 27 P 0 0;2,5=11,7=0
P 5.40386004 3.28 27 P 0 0;2,5=11,7=0
P 7.35731004 0.036 7 P 0 0;5=6,7=1
P 7.60731004 0.036 7 P 0 0;5=6,7=1
P 7.55731004 0.036 7 P 0 0;5=6,7=1
P 7.50731004 0.036 7 P 0 0;5=6,7=1
P 7.45731004 0.036 7 P 0 0;5=6,7=1
P 7.40731004 0.036 7 P 0 0;5=6,7=1
P 7.85731004 0.036 7 P 0 0;5=6,7=1
P 7.80731004 0.036 7 P 0 0;5=6,7=1
P 7.75731004 0.036 7 P 0 0;5=6,7=1
P 7.70731004 0.036 7 P 0 0;5=6,7=1
P 7.65731004 0.036 7 P 0 0;5=6,7=1
P 8.15731004 0.036 7 P 0 0;5=6,7=1
P 8.10731004 0.036 7 P 0 0;5=6,7=1
P 8.05731004 0.036 7 P 0 0;5=6,7=1
P 8.00731004 0.036 7 P 0 0;5=6,7=1
P 7.95731004 0.036 7 P 0 0;5=6,7=1
P 7.90731004 0.036 7 P 0 0;5=6,7=1
P 8.40731004 0.036 7 P 0 0;5=6,7=1
P 8.35731004 0.036 7 P 0 0;5=6,7=1
P 8.30731004 0.036 7 P 0 0;5=6,7=1
P 8.25731004 0.036 7 P 0 0;5=6,7=1
P 8.20731004 0.036 7 P 0 0;5=6,7=1
P 8.65731004 0.036 7 P 0 0;5=6,7=1
P 8.60731004 0.036 7 P 0 0;5=6,7=1
P 8.55731004 0.036 7 P 0 0;5=6,7=1
P 8.50731004 0.036 7 P 0 0;5=6,7=1
P 8.45731004 0.036 7 P 0 0;5=6,7=1
P 8.90731004 0.036 7 P 0 0;5=6,7=1
P 8.85731004 0.036 7 P 0 0;5=6,7=1
P 8.80731004 0.036 7 P 0 0;5=6,7=1
P 8.75731004 0.036 7 P 0 0;5=6,7=1
P 8.70731004 0.036 7 P 0 0;5=6,7=1
P 9.20731004 0.036 7 P 0 0;5=6,7=1
P 9.15731004 0.036 7 P 0 0;5=6,7=1
P 9.10731004 0.036 7 P 0 0;5=6,7=1
P 9.05731004 0.036 7 P 0 0;5=6,7=1
P 9.00731004 0.036 7 P 0 0;5=6,7=1
P 8.95731004 0.036 7 P 0 0;5=6,7=1
P 9.45731004 0.036 7 P 0 0;5=6,7=1
P 9.40731004 0.036 7 P 0 0;5=6,7=1
P 9.35731004 0.036 7 P 0 0;5=6,7=1
P 9.30731004 0.036 7 P 0 0;5=6,7=1
P 9.25731004 0.036 7 P 0 0;5=6,7=1
P 9.70731004 0.036 7 P 0 0;5=6,7=1
P 9.65731004 0.036 7 P 0 0;5=6,7=1
P 9.60731004 0.036 7 P 0 0;5=6,7=1
P 9.55731004 0.036 7 P 0 0;5=6,7=1
P 9.50731004 0.036 7 P 0 0;5=6,7=1
P 10.00731004 0.036 7 P 0 0;5=6,7=1
P 9.95731004 0.036 7 P 0 0;5=6,7=1
P 9.90731004 0.036 7 P 0 0;5=6,7=1
P 9.85731004 0.036 7 P 0 0;5=6,7=1
P 9.80731004 0.036 7 P 0 0;5=6,7=1
P 9.75731004 0.036 7 P 0 0;5=6,7=1
P 10.25731004 0.036 7 P 0 0;5=6,7=1
P 10.20731004 0.036 7 P 0 0;5=6,7=1
P 10.15731004 0.036 7 P 0 0;5=6,7=1
P 10.10731004 0.036 7 P 0 0;5=6,7=1
P 10.05731004 0.036 7 P 0 0;5=6,7=1
P 10.50731004 0.036 7 P 0 0;5=6,7=1
P 10.45731004 0.036 7 P 0 0;5=6,7=1
P 10.40731004 0.036 7 P 0 0;5=6,7=1
P 10.35731004 0.036 7 P 0 0;5=6,7=1
P 10.30731004 0.036 7 P 0 0;5=6,7=1
P 10.75731004 0.036 7 P 0 0;5=6,7=1
P 10.70731004 0.036 7 P 0 0;5=6,7=1
P 10.65731004 0.036 7 P 0 0;5=6,7=1
P 10.60731004 0.036 7 P 0 0;5=6,7=1
P 10.55731004 0.036 7 P 0 0;5=6,7=1
P 11.05731004 0.036 7 P 0 0;5=6,7=1
P 11.00731004 0.036 7 P 0 0;5=6,7=1
P 10.95731004 0.036 7 P 0 0;5=6,7=1
P 10.90731004 0.036 7 P 0 0;5=6,7=1
P 10.85731004 0.036 7 P 0 0;5=6,7=1
P 10.80731004 0.036 7 P 0 0;5=6,7=1
P 11.30731004 0.036 7 P 0 0;5=6,7=1
P 11.25731004 0.036 7 P 0 0;5=6,7=1
P 11.20731004 0.036 7 P 0 0;5=6,7=1
P 11.15731004 0.036 7 P 0 0;5=6,7=1
P 11.10731004 0.036 7 P 0 0;5=6,7=1
P 11.55731004 0.036 7 P 0 0;5=6,7=1
P 11.50731004 0.036 7 P 0 0;5=6,7=1
P 11.45731004 0.036 7 P 0 0;5=6,7=1
P 11.40731004 0.036 7 P 0 0;5=6,7=1
P 11.35731004 0.036 7 P 0 0;5=6,7=1
P 11.80731004 0.036 7 P 0 0;5=6,7=1
P 11.75731004 0.036 7 P 0 0;5=6,7=1
P 11.70731004 0.036 7 P 0 0;5=6,7=1
P 11.65731004 0.036 7 P 0 0;5=6,7=1
P 11.60731004 0.036 7 P 0 0;5=6,7=1
P 12.10731004 0.036 7 P 0 0;5=6,7=1
P 12.05731004 0.036 7 P 0 0;5=6,7=1
P 12.00731004 0.036 7 P 0 0;5=6,7=1
P 11.95731004 0.036 7 P 0 0;5=6,7=1
P 11.90731004 0.036 7 P 0 0;5=6,7=1
P 11.85731004 0.036 7 P 0 0;5=6,7=1
P 12.35731004 0.036 7 P 0 0;5=6,7=1
P 12.30731004 0.036 7 P 0 0;5=6,7=1
P 12.25731004 0.036 7 P 0 0;5=6,7=1
P 12.20731004 0.036 7 P 0 0;5=6,7=1
P 12.15731004 0.036 7 P 0 0;5=6,7=1
P 12.60731004 0.036 7 P 0 0;5=6,7=1
P 12.55731004 0.036 7 P 0 0;5=6,7=1
P 12.50731004 0.036 7 P 0 0;5=6,7=1
P 12.45731004 0.036 7 P 0 0;5=6,7=1
P 12.40731004 0.036 7 P 0 0;5=6,7=1
P 12.8892 0.22596004 7 P 0 0;5=6,7=1
P 12.8892 0.17596004 7 P 0 0;5=6,7=1
P 12.8892 0.12596004 7 P 0 0;5=6,7=1
P 12.88911004 0.07596004 7 P 0 0;5=6,7=1
P 12.85728996 0.03738996 7 P 0 0;5=6,7=1
P 12.80731004 0.036 7 P 0 0;5=6,7=1
P 12.75731004 0.036 7 P 0 0;5=6,7=1
P 12.70731004 0.036 7 P 0 0;5=6,7=1
P 12.65731004 0.036 7 P 0 0;5=6,7=1
P 12.8892 0.47596004 7 P 0 0;5=6,7=1
P 12.8892 0.42596004 7 P 0 0;5=6,7=1
P 12.8892 0.37596004 7 P 0 0;5=6,7=1
P 12.8892 0.32596004 7 P 0 0;5=6,7=1
P 12.8892 0.27596004 7 P 0 0;5=6,7=1
P 12.8892 0.62596004 7 P 0 0;5=6,7=1
P 12.8892 0.57596004 7 P 0 0;5=6,7=1
P 12.8892 0.52596004 7 P 0 0;5=6,7=1
P 0.036 1.00868002 7 P 0 0;5=6,7=1
P 0.036 1.05868002 7 P 0 0;5=6,7=1
P 0.036 1.10868002 7 P 0 0;5=6,7=1
P 0.036 1.15868002 7 P 0 0;5=6,7=1
P 0.036 1.20868002 7 P 0 0;5=6,7=1
P 0.036 1.25868002 7 P 0 0;5=6,7=1
P 0.036 1.30868002 7 P 0 0;5=6,7=1
P 0.036 1.35868002 7 P 0 0;5=6,7=1
P 0.036 1.40868002 7 P 0 0;5=6,7=1
P 0.036 1.45868002 7 P 0 0;5=6,7=1
P 0.036 1.50868002 7 P 0 0;5=6,7=1
P 0.036 1.55868002 7 P 0 0;5=6,7=1
P 0.036 1.60868002 7 P 0 0;5=6,7=1
P 0.036 1.65868002 7 P 0 0;5=6,7=1
P 0.036 1.70868002 7 P 0 0;5=6,7=1
P 0.036 1.75868002 7 P 0 0;5=6,7=1
P 0.036 1.80868002 7 P 0 0;5=6,7=1
P 0.036 1.85868002 7 P 0 0;5=6,7=1
P 0.036 1.90868002 7 P 0 0;5=6,7=1
P 0.036 1.95868002 7 P 0 0;5=6,7=1
P 0.036 2.00868002 7 P 0 0;5=6,7=1
P 0.036 2.05868002 7 P 0 0;5=6,7=1
P 0.036 2.10868002 7 P 0 0;5=6,7=1
P 0.036 2.15868002 7 P 0 0;5=6,7=1
P 0.036 2.20868002 7 P 0 0;5=6,7=1
P 0.036 2.25868002 7 P 0 0;5=6,7=1
P 0.036 2.30868002 7 P 0 0;5=6,7=1
P 0.036 2.35868002 7 P 0 0;5=6,7=1
P 0.036 2.40868002 7 P 0 0;5=6,7=1
P 0.036 2.45868002 7 P 0 0;5=6,7=1
P 0.036 2.50868002 7 P 0 0;5=6,7=1
P 0.036 2.55868002 7 P 0 0;5=6,7=1
P 0.036 2.60868002 7 P 0 0;5=6,7=1
P 0.036 2.65868002 7 P 0 0;5=6,7=1
P 0.036 2.70868002 7 P 0 0;5=6,7=1
P 0.036 2.75868002 7 P 0 0;5=6,7=1
P 0.036 2.80868002 7 P 0 0;5=6,7=1
P 0.036 2.85868002 7 P 0 0;5=6,7=1
P 0.036 2.90868002 7 P 0 0;5=6,7=1
P 0.036 2.95868002 7 P 0 0;5=6,7=1
P 0.036 3.00868002 7 P 0 0;5=6,7=1
P 0.036 3.05868002 7 P 0 0;5=6,7=1
P 0.036 3.10868002 7 P 0 0;5=6,7=1
P 0.036 3.15868002 7 P 0 0;5=6,7=1
P 0.036 3.20868002 7 P 0 0;5=6,7=1
P 0.036 3.25868002 7 P 0 0;5=6,7=1
P 0.036 3.30868002 7 P 0 0;5=6,7=1
P 0.036 3.35868002 7 P 0 0;5=6,7=1
P 0.036 3.40868002 7 P 0 0;5=6,7=1
P 0.036 3.45868002 7 P 0 0;5=6,7=1
P 0.036 3.50868002 7 P 0 0;5=6,7=1
P 0.036 3.55868002 7 P 0 0;5=6,7=1
P 0.036 3.60868002 7 P 0 0;5=6,7=1
P 0.036 3.65868002 7 P 0 0;5=6,7=1
P 0.036 3.70868002 7 P 0 0;5=6,7=1
P 0.036 3.75868002 7 P 0 0;5=6,7=1
P 0.036 3.80868002 7 P 0 0;5=6,7=1
P 0.036 3.85868002 7 P 0 0;5=6,7=1
P 0.036 3.90868002 7 P 0 0;5=6,7=1
P 0.036 3.95868002 7 P 0 0;5=6,7=1
P 0.036 4.00868002 7 P 0 0;5=6,7=1
P 0.036 4.05868002 7 P 0 0;5=6,7=1
P 0.036 4.10868002 7 P 0 0;5=6,7=1
P 0.036 4.15868002 7 P 0 0;5=6,7=1
P 0.036 4.20868002 7 P 0 0;5=6,7=1
P 0.036 4.25868002 7 P 0 0;5=6,7=1
P 0.036 4.30868002 7 P 0 0;5=6,7=1
P 0.036 4.35868002 7 P 0 0;5=6,7=1
P 0.036 4.40868002 7 P 0 0;5=6,7=1
P 0.036 4.45868002 7 P 0 0;5=6,7=1
P 0.036 4.50868002 7 P 0 0;5=6,7=1
P 0.036 4.55868002 7 P 0 0;5=6,7=1
P 0.036 4.60868002 7 P 0 0;5=6,7=1
P 0.036 4.65868002 7 P 0 0;5=6,7=1
P 0.036 4.70868002 7 P 0 0;5=6,7=1
P 0.036 4.75868002 7 P 0 0;5=6,7=1
P 12.8892 1.02596004 7 P 0 0;5=6,7=1
P 12.8892 1.27596004 7 P 0 0;5=6,7=1
P 12.8892 1.22596004 7 P 0 0;5=6,7=1
P 12.8892 1.17596004 7 P 0 0;5=6,7=1
P 12.8892 1.12596004 7 P 0 0;5=6,7=1
P 12.8892 1.07596004 7 P 0 0;5=6,7=1
P 12.8892 1.52596004 7 P 0 0;5=6,7=1
P 12.8892 1.47596004 7 P 0 0;5=6,7=1
P 12.8892 1.42596004 7 P 0 0;5=6,7=1
P 12.8892 1.37596004 7 P 0 0;5=6,7=1
P 12.8892 1.32596004 7 P 0 0;5=6,7=1
P 12.8892 1.77596004 7 P 0 0;5=6,7=1
P 12.8892 1.72596004 7 P 0 0;5=6,7=1
P 12.8892 1.67596004 7 P 0 0;5=6,7=1
P 12.8892 1.62596004 7 P 0 0;5=6,7=1
P 12.8892 1.57596004 7 P 0 0;5=6,7=1
P 12.8892 2.07596004 7 P 0 0;5=6,7=1
P 12.8892 2.02596004 7 P 0 0;5=6,7=1
P 12.8892 1.97596004 7 P 0 0;5=6,7=1
P 12.8892 1.92596004 7 P 0 0;5=6,7=1
P 12.8892 1.87596004 7 P 0 0;5=6,7=1
P 12.8892 1.82596004 7 P 0 0;5=6,7=1
P 12.8892 2.32596004 7 P 0 0;5=6,7=1
P 12.8892 2.27596004 7 P 0 0;5=6,7=1
P 12.8892 2.22596004 7 P 0 0;5=6,7=1
P 12.8892 2.17596004 7 P 0 0;5=6,7=1
P 12.8892 2.57596004 7 P 0 0;5=6,7=1
P 12.8892 2.52596004 7 P 0 0;5=6,7=1
P 12.8892 2.47596004 7 P 0 0;5=6,7=1
P 12.8892 2.42596004 7 P 0 0;5=6,7=1
P 12.8892 2.37596004 7 P 0 0;5=6,7=1
P 12.8892 2.82596004 7 P 0 0;5=6,7=1
P 12.8892 2.77596004 7 P 0 0;5=6,7=1
P 12.8892 2.72596004 7 P 0 0;5=6,7=1
P 12.8892 2.67596004 7 P 0 0;5=6,7=1
P 12.8892 2.62596004 7 P 0 0;5=6,7=1
P 12.8892 3.12596004 7 P 0 0;5=6,7=1
P 12.8892 3.07596004 7 P 0 0;5=6,7=1
P 12.8892 3.02596004 7 P 0 0;5=6,7=1
P 12.8892 2.97596004 7 P 0 0;5=6,7=1
P 12.8892 2.92596004 7 P 0 0;5=6,7=1
P 12.8892 2.87596004 7 P 0 0;5=6,7=1
P 12.8892 3.37596004 7 P 0 0;5=6,7=1
P 12.8892 3.32596004 7 P 0 0;5=6,7=1
P 12.8892 3.27596004 7 P 0 0;5=6,7=1
P 12.8892 3.22596004 7 P 0 0;5=6,7=1
P 12.8892 3.17596004 7 P 0 0;5=6,7=1
P 12.8892 3.62596004 7 P 0 0;5=6,7=1
P 12.8892 3.57596004 7 P 0 0;5=6,7=1
P 12.8892 3.52596004 7 P 0 0;5=6,7=1
P 12.8892 3.47596004 7 P 0 0;5=6,7=1
P 12.8892 3.42596004 7 P 0 0;5=6,7=1
P 12.8892 3.92596004 7 P 0 0;5=6,7=1
P 12.8892 3.87596004 7 P 0 0;5=6,7=1
P 12.8892 3.82596004 7 P 0 0;5=6,7=1
P 12.8892 3.77596004 7 P 0 0;5=6,7=1
P 12.8892 3.72596004 7 P 0 0;5=6,7=1
P 12.8892 3.67596004 7 P 0 0;5=6,7=1
P 12.8892 4.17596004 7 P 0 0;5=6,7=1
P 12.8892 4.12596004 7 P 0 0;5=6,7=1
P 12.8892 4.07596004 7 P 0 0;5=6,7=1
P 12.8892 4.02596004 7 P 0 0;5=6,7=1
P 12.8892 3.97596004 7 P 0 0;5=6,7=1
P 12.8892 4.42596004 7 P 0 0;5=6,7=1
P 12.8892 4.37596004 7 P 0 0;5=6,7=1
P 12.8892 4.32596004 7 P 0 0;5=6,7=1
P 12.8892 4.27596004 7 P 0 0;5=6,7=1
P 12.8892 4.22596004 7 P 0 0;5=6,7=1
P 12.8892 4.67596004 7 P 0 0;5=6,7=1
P 12.8892 4.62596004 7 P 0 0;5=6,7=1
P 12.8892 4.57596004 7 P 0 0;5=6,7=1
P 12.8892 4.52596004 7 P 0 0;5=6,7=1
P 12.8892 4.47596004 7 P 0 0;5=6,7=1
P 12.8892 4.82596004 7 P 0 0;5=6,7=1
P 12.8892 4.77596004 7 P 0 0;5=6,7=1
P 12.8892 4.72596004 7 P 0 0;5=6,7=1
P 0.036 5.25868002 7 P 0 0;5=6,7=1
P 0.036 5.30868002 7 P 0 0;5=6,7=1
P 0.036 5.35868002 7 P 0 0;5=6,7=1
P 0.036 5.40868002 7 P 0 0;5=6,7=1
P 0.036 5.45868002 7 P 0 0;5=6,7=1
P 0.036 5.50868002 7 P 0 0;5=6,7=1
P 0.036 5.55868002 7 P 0 0;5=6,7=1
P 0.036 5.60868002 7 P 0 0;5=6,7=1
P 0.036 5.65868002 7 P 0 0;5=6,7=1
P 0.036 5.70868002 7 P 0 0;5=6,7=1
P 0.036 5.75868002 7 P 0 0;5=6,7=1
P 0.036 5.80868002 7 P 0 0;5=6,7=1
P 0.036 5.85868002 7 P 0 0;5=6,7=1
P 0.036 5.90868002 7 P 0 0;5=6,7=1
P 0.03826998 5.95863002 7 P 0 0;5=6,7=1
P 0.07901004 5.98761998 7 P 0 0;5=6,7=1
P 0.12901004 5.98761998 7 P 0 0;5=6,7=1
P 0.17901004 5.98761998 7 P 0 0;5=6,7=1
P 0.22901004 5.98761998 7 P 0 0;5=6,7=1
P 0.27901004 5.98761998 7 P 0 0;5=6,7=1
P 0.32901004 5.98761998 7 P 0 0;5=6,7=1
P 0.37901004 5.98761998 7 P 0 0;5=6,7=1
P 0.42901004 5.98761998 7 P 0 0;5=6,7=1
P 0.47901004 5.98761998 7 P 0 0;5=6,7=1
P 0.52901004 5.98761998 7 P 0 0;5=6,7=1
P 0.57901004 5.98761998 7 P 0 0;5=6,7=1
P 0.62901004 5.98761998 7 P 0 0;5=6,7=1
P 0.67901004 5.98761998 7 P 0 0;5=6,7=1
P 0.72901004 5.98761998 7 P 0 0;5=6,7=1
P 0.77901004 5.98761998 7 P 0 0;5=6,7=1
P 0.82901004 5.98761998 7 P 0 0;5=6,7=1
P 0.87901004 5.98761998 7 P 0 0;5=6,7=1
P 0.92901004 5.98761998 7 P 0 0;5=6,7=1
P 0.97901004 5.98761998 7 P 0 0;5=6,7=1
P 1.02901004 5.98761998 7 P 0 0;5=6,7=1
P 1.07901004 5.98761998 7 P 0 0;5=6,7=1
P 1.12901004 5.98761998 7 P 0 0;5=6,7=1
P 1.17901004 5.98761998 7 P 0 0;5=6,7=1
P 1.22901004 5.98761998 7 P 0 0;5=6,7=1
P 1.27901004 5.98761998 7 P 0 0;5=6,7=1
P 1.32901004 5.98761998 7 P 0 0;5=6,7=1
P 1.37901004 5.98761998 7 P 0 0;5=6,7=1
P 1.42901004 5.98761998 7 P 0 0;5=6,7=1
P 1.47901004 5.98761998 7 P 0 0;5=6,7=1
P 1.52901004 5.98761998 7 P 0 0;5=6,7=1
P 1.57901004 5.98761998 7 P 0 0;5=6,7=1
P 1.62901004 5.98761998 7 P 0 0;5=6,7=1
P 1.67901004 5.98761998 7 P 0 0;5=6,7=1
P 1.72901004 5.98761998 7 P 0 0;5=6,7=1
P 1.77901004 5.98761998 7 P 0 0;5=6,7=1
P 1.82901004 5.98761998 7 P 0 0;5=6,7=1
P 1.87901004 5.98761998 7 P 0 0;5=6,7=1
P 1.92901004 5.98761998 7 P 0 0;5=6,7=1
P 1.97901004 5.98761998 7 P 0 0;5=6,7=1
P 2.02901004 5.98761998 7 P 0 0;5=6,7=1
P 2.07901004 5.98761998 7 P 0 0;5=6,7=1
P 2.12901004 5.98761998 7 P 0 0;5=6,7=1
P 2.17901004 5.98761998 7 P 0 0;5=6,7=1
P 2.22901004 5.98761998 7 P 0 0;5=6,7=1
P 2.27901004 5.98761998 7 P 0 0;5=6,7=1
P 2.32901004 5.98761998 7 P 0 0;5=6,7=1
P 2.37901004 5.98761998 7 P 0 0;5=6,7=1
P 2.42901004 5.98761998 7 P 0 0;5=6,7=1
P 2.47901004 5.98761998 7 P 0 0;5=6,7=1
P 2.52901004 5.98761998 7 P 0 0;5=6,7=1
P 2.57901004 5.98761998 7 P 0 0;5=6,7=1
P 2.62901004 5.98761998 7 P 0 0;5=6,7=1
P 2.67901004 5.98761998 7 P 0 0;5=6,7=1
P 2.72901004 5.98761998 7 P 0 0;5=6,7=1
P 2.77901004 5.98761998 7 P 0 0;5=6,7=1
P 2.82901004 5.98761998 7 P 0 0;5=6,7=1
P 2.87901004 5.98761998 7 P 0 0;5=6,7=1
P 2.92901004 5.98761998 7 P 0 0;5=6,7=1
P 2.97901004 5.98761998 7 P 0 0;5=6,7=1
P 3.02901004 5.98761998 7 P 0 0;5=6,7=1
P 3.07901004 5.98761998 7 P 0 0;5=6,7=1
P 3.12901004 5.98761998 7 P 0 0;5=6,7=1
P 3.17901004 5.98761998 7 P 0 0;5=6,7=1
P 3.22901004 5.98761998 7 P 0 0;5=6,7=1
P 3.27901004 5.98761998 7 P 0 0;5=6,7=1
P 3.32901004 5.98761998 7 P 0 0;5=6,7=1
P 3.37901004 5.98761998 7 P 0 0;5=6,7=1
P 3.42901004 5.98761998 7 P 0 0;5=6,7=1
P 3.47901004 5.98761998 7 P 0 0;5=6,7=1
P 3.52901004 5.98761998 7 P 0 0;5=6,7=1
P 3.57901004 5.98761998 7 P 0 0;5=6,7=1
P 3.62901004 5.98761998 7 P 0 0;5=6,7=1
P 3.67901004 5.98761998 7 P 0 0;5=6,7=1
P 3.72901004 5.98761998 7 P 0 0;5=6,7=1
P 3.77901004 5.98761998 7 P 0 0;5=6,7=1
P 3.82901004 5.98761998 7 P 0 0;5=6,7=1
P 3.87901004 5.98761998 7 P 0 0;5=6,7=1
P 3.92901004 5.98761998 7 P 0 0;5=6,7=1
P 3.97901004 5.98761998 7 P 0 0;5=6,7=1
P 4.02901004 5.98761998 7 P 0 0;5=6,7=1
P 4.07901004 5.98761998 7 P 0 0;5=6,7=1
P 4.12901004 5.98761998 7 P 0 0;5=6,7=1
P 4.17901004 5.98761998 7 P 0 0;5=6,7=1
P 4.22901004 5.98761998 7 P 0 0;5=6,7=1
P 4.27901004 5.98761998 7 P 0 0;5=6,7=1
P 4.32901004 5.98761998 7 P 0 0;5=6,7=1
P 4.37901004 5.98761998 7 P 0 0;5=6,7=1
P 4.42901004 5.98761998 7 P 0 0;5=6,7=1
P 4.47901004 5.98761998 7 P 0 0;5=6,7=1
P 4.52901004 5.98761998 7 P 0 0;5=6,7=1
P 4.57901004 5.98761998 7 P 0 0;5=6,7=1
P 4.62901004 5.98761998 7 P 0 0;5=6,7=1
P 4.67901004 5.98761998 7 P 0 0;5=6,7=1
P 4.72901004 5.98761998 7 P 0 0;5=6,7=1
P 4.77901004 5.98761998 7 P 0 0;5=6,7=1
P 4.82901004 5.98761998 7 P 0 0;5=6,7=1
P 4.87901004 5.98761998 7 P 0 0;5=6,7=1
P 4.92901004 5.98761998 7 P 0 0;5=6,7=1
P 4.97901004 5.98761998 7 P 0 0;5=6,7=1
P 5.02901004 5.98761998 7 P 0 0;5=6,7=1
P 5.07901004 5.98761998 7 P 0 0;5=6,7=1
P 5.12901004 5.98761998 7 P 0 0;5=6,7=1
P 5.17901004 5.98761998 7 P 0 0;5=6,7=1
P 5.22901004 5.98761998 7 P 0 0;5=6,7=1
P 5.27901004 5.98761998 7 P 0 0;5=6,7=1
P 5.32901004 5.98761998 7 P 0 0;5=6,7=1
P 5.37901004 5.98761998 7 P 0 0;5=6,7=1
P 5.42901004 5.98761998 7 P 0 0;5=6,7=1
P 5.47901004 5.98761998 7 P 0 0;5=6,7=1
P 5.52901004 5.98761998 7 P 0 0;5=6,7=1
P 5.57901004 5.98761998 7 P 0 0;5=6,7=1
P 5.62901004 5.98761998 7 P 0 0;5=6,7=1
P 5.67901004 5.98761998 7 P 0 0;5=6,7=1
P 5.72901004 5.98761998 7 P 0 0;5=6,7=1
P 5.77901004 5.98761998 7 P 0 0;5=6,7=1
P 5.82901004 5.98761998 7 P 0 0;5=6,7=1
P 5.87901004 5.98761998 7 P 0 0;5=6,7=1
P 5.92901004 5.98761998 7 P 0 0;5=6,7=1
P 5.97901004 5.98761998 7 P 0 0;5=6,7=1
P 6.02901004 5.98761998 7 P 0 0;5=6,7=1
P 6.07901004 5.98761998 7 P 0 0;5=6,7=1
P 6.12901004 5.98761998 7 P 0 0;5=6,7=1
P 6.17901004 5.98761998 7 P 0 0;5=6,7=1
P 6.22901004 5.98761998 7 P 0 0;5=6,7=1
P 6.27901004 5.98761998 7 P 0 0;5=6,7=1
P 6.32901004 5.98761998 7 P 0 0;5=6,7=1
P 6.37901004 5.98761998 7 P 0 0;5=6,7=1
P 6.42901004 5.98761998 7 P 0 0;5=6,7=1
P 6.47901004 5.98761998 7 P 0 0;5=6,7=1
P 6.52901004 5.98761998 7 P 0 0;5=6,7=1
P 6.57901004 5.98761998 7 P 0 0;5=6,7=1
P 6.62901004 5.98761998 7 P 0 0;5=6,7=1
P 6.67901004 5.98761998 7 P 0 0;5=6,7=1
P 6.72901004 5.98761998 7 P 0 0;5=6,7=1
P 6.77901004 5.98761998 7 P 0 0;5=6,7=1
P 6.82901004 5.98761998 7 P 0 0;5=6,7=1
P 6.87901004 5.98761998 7 P 0 0;5=6,7=1
P 6.92901004 5.98761998 7 P 0 0;5=6,7=1
P 6.97901004 5.98761998 7 P 0 0;5=6,7=1
P 12.8892 5.47596004 7 P 0 0;5=6,7=1
P 12.8892 5.42596004 7 P 0 0;5=6,7=1
P 12.8892 5.37596004 7 P 0 0;5=6,7=1
P 12.8892 5.32596004 7 P 0 0;5=6,7=1
P 12.8892 5.27596004 7 P 0 0;5=6,7=1
P 12.8892 5.72596004 7 P 0 0;5=6,7=1
P 12.8892 5.67596004 7 P 0 0;5=6,7=1
P 12.8892 5.62596004 7 P 0 0;5=6,7=1
P 12.8892 5.57596004 7 P 0 0;5=6,7=1
P 12.8892 5.52596004 7 P 0 0;5=6,7=1
P 7.37901004 5.98761998 7 P 0 0;5=6,7=1
P 7.42901004 5.98761998 7 P 0 0;5=6,7=1
P 7.47901004 5.98761998 7 P 0 0;5=6,7=1
P 7.52901004 5.98761998 7 P 0 0;5=6,7=1
P 7.57901004 5.98761998 7 P 0 0;5=6,7=1
P 7.62901004 5.98761998 7 P 0 0;5=6,7=1
P 7.67901004 5.98761998 7 P 0 0;5=6,7=1
P 7.72901004 5.98761998 7 P 0 0;5=6,7=1
P 7.77901004 5.98761998 7 P 0 0;5=6,7=1
P 7.82901004 5.98761998 7 P 0 0;5=6,7=1
P 7.87901004 5.98761998 7 P 0 0;5=6,7=1
P 7.92901004 5.98761998 7 P 0 0;5=6,7=1
P 7.97901004 5.98761998 7 P 0 0;5=6,7=1
P 8.02901004 5.98761998 7 P 0 0;5=6,7=1
P 8.07901004 5.98761998 7 P 0 0;5=6,7=1
P 8.12901004 5.98761998 7 P 0 0;5=6,7=1
P 8.17901004 5.98761998 7 P 0 0;5=6,7=1
P 8.22901004 5.98761998 7 P 0 0;5=6,7=1
P 8.27901004 5.98761998 7 P 0 0;5=6,7=1
P 8.32901004 5.98761998 7 P 0 0;5=6,7=1
P 8.37901004 5.98761998 7 P 0 0;5=6,7=1
P 8.42901004 5.98761998 7 P 0 0;5=6,7=1
P 8.47901004 5.98761998 7 P 0 0;5=6,7=1
P 8.52901004 5.98761998 7 P 0 0;5=6,7=1
P 8.57901004 5.98761998 7 P 0 0;5=6,7=1
P 8.62901004 5.98761998 7 P 0 0;5=6,7=1
P 8.67901004 5.98761998 7 P 0 0;5=6,7=1
P 8.72901004 5.98761998 7 P 0 0;5=6,7=1
P 8.77901004 5.98761998 7 P 0 0;5=6,7=1
P 8.82901004 5.98761998 7 P 0 0;5=6,7=1
P 8.87901004 5.98761998 7 P 0 0;5=6,7=1
P 8.92901004 5.98761998 7 P 0 0;5=6,7=1
P 8.97901004 5.98761998 7 P 0 0;5=6,7=1
P 9.02901004 5.98761998 7 P 0 0;5=6,7=1
P 9.07901004 5.98761998 7 P 0 0;5=6,7=1
P 9.12901004 5.98761998 7 P 0 0;5=6,7=1
P 9.17901004 5.98761998 7 P 0 0;5=6,7=1
P 9.22901004 5.98761998 7 P 0 0;5=6,7=1
P 9.27901004 5.98761998 7 P 0 0;5=6,7=1
P 9.32901004 5.98761998 7 P 0 0;5=6,7=1
P 9.37901004 5.98761998 7 P 0 0;5=6,7=1
P 9.42901004 5.98761998 7 P 0 0;5=6,7=1
P 9.47901004 5.98761998 7 P 0 0;5=6,7=1
P 9.52901004 5.98761998 7 P 0 0;5=6,7=1
P 9.57901004 5.98761998 7 P 0 0;5=6,7=1
P 9.62901004 5.98761998 7 P 0 0;5=6,7=1
P 9.67901004 5.98761998 7 P 0 0;5=6,7=1
P 9.72901004 5.98761998 7 P 0 0;5=6,7=1
P 9.77901004 5.98761998 7 P 0 0;5=6,7=1
P 9.82901004 5.98761998 7 P 0 0;5=6,7=1
P 9.87901004 5.98761998 7 P 0 0;5=6,7=1
P 9.92901004 5.98761998 7 P 0 0;5=6,7=1
P 9.97901004 5.98761998 7 P 0 0;5=6,7=1
P 10.02901004 5.98761998 7 P 0 0;5=6,7=1
P 10.07901004 5.98761998 7 P 0 0;5=6,7=1
P 10.12901004 5.98761998 7 P 0 0;5=6,7=1
P 10.17901004 5.98761998 7 P 0 0;5=6,7=1
P 10.22901004 5.98761998 7 P 0 0;5=6,7=1
P 10.27901004 5.98761998 7 P 0 0;5=6,7=1
P 10.32901004 5.98761998 7 P 0 0;5=6,7=1
P 10.37901004 5.98761998 7 P 0 0;5=6,7=1
P 10.42901004 5.98761998 7 P 0 0;5=6,7=1
P 10.47901004 5.98761998 7 P 0 0;5=6,7=1
P 10.52901004 5.98761998 7 P 0 0;5=6,7=1
P 10.57901004 5.98761998 7 P 0 0;5=6,7=1
P 10.62901004 5.98761998 7 P 0 0;5=6,7=1
P 10.67901004 5.98761998 7 P 0 0;5=6,7=1
P 10.72901004 5.98761998 7 P 0 0;5=6,7=1
P 10.77901004 5.98761998 7 P 0 0;5=6,7=1
P 10.82901004 5.98761998 7 P 0 0;5=6,7=1
P 10.87901004 5.98761998 7 P 0 0;5=6,7=1
P 10.92901004 5.98761998 7 P 0 0;5=6,7=1
P 10.97901004 5.98761998 7 P 0 0;5=6,7=1
P 11.02901004 5.98761998 7 P 0 0;5=6,7=1
P 11.07901004 5.98761998 7 P 0 0;5=6,7=1
P 11.12901004 5.98761998 7 P 0 0;5=6,7=1
P 11.17901004 5.98761998 7 P 0 0;5=6,7=1
P 11.22901004 5.98761998 7 P 0 0;5=6,7=1
P 11.27901004 5.98761998 7 P 0 0;5=6,7=1
P 11.32901004 5.98761998 7 P 0 0;5=6,7=1
P 11.37901004 5.98761998 7 P 0 0;5=6,7=1
P 11.42901004 5.98761998 7 P 0 0;5=6,7=1
P 11.47901004 5.98761998 7 P 0 0;5=6,7=1
P 11.52901004 5.98761998 7 P 0 0;5=6,7=1
P 11.57901004 5.98761998 7 P 0 0;5=6,7=1
P 11.62901004 5.98761998 7 P 0 0;5=6,7=1
P 11.67901004 5.98761998 7 P 0 0;5=6,7=1
P 11.72901004 5.98761998 7 P 0 0;5=6,7=1
P 11.77901004 5.98761998 7 P 0 0;5=6,7=1
P 11.82901004 5.98761998 7 P 0 0;5=6,7=1
P 11.87901004 5.98761998 7 P 0 0;5=6,7=1
P 11.92901004 5.98761998 7 P 0 0;5=6,7=1
P 11.97901004 5.98761998 7 P 0 0;5=6,7=1
P 12.02901004 5.98761998 7 P 0 0;5=6,7=1
P 12.07901004 5.98761998 7 P 0 0;5=6,7=1
P 12.12901004 5.98761998 7 P 0 0;5=6,7=1
P 12.17901004 5.98761998 7 P 0 0;5=6,7=1
P 12.22901004 5.98761998 7 P 0 0;5=6,7=1
P 12.27901004 5.98761998 7 P 0 0;5=6,7=1
P 12.32901004 5.98761998 7 P 0 0;5=6,7=1
P 12.37901004 5.98761998 7 P 0 0;5=6,7=1
P 12.42901004 5.98761998 7 P 0 0;5=6,7=1
P 12.47901004 5.98761998 7 P 0 0;5=6,7=1
P 12.52901004 5.98761998 7 P 0 0;5=6,7=1
P 12.57901004 5.98761998 7 P 0 0;5=6,7=1
P 12.62901004 5.98761998 7 P 0 0;5=6,7=1
P 12.67901004 5.98761998 7 P 0 0;5=6,7=1
P 12.72901004 5.98761998 7 P 0 0;5=6,7=1
P 12.77901004 5.98761998 7 P 0 0;5=6,7=1
P 12.82901004 5.98761998 7 P 0 0;5=6,7=1
P 12.87726004 5.97451004 7 P 0 0;5=6,7=1
P 12.8892 5.92596004 7 P 0 0;5=6,7=1
P 12.8892 5.87596004 7 P 0 0;5=6,7=1
P 12.8892 5.82596004 7 P 0 0;5=6,7=1
P 12.8892 5.77596004 7 P 0 0;5=6,7=1
P 4.33605 4.9231 7 P 0 0;5=6,7=1
P 4.38105 4.9231 7 P 0 0;5=6,7=1
P 4.30105 4.9431 7 P 0 0;5=6,7=1
P 4.42105 4.9431 7 P 0 0;5=6,7=1
P 4.46105 4.9431 7 P 0 0;5=6,7=1
P 4.26105 4.9431 7 P 0 0;5=6,7=1
P 4.72605 4.9231 7 P 0 0;5=6,7=1
P 4.65105 4.9431 7 P 0 0;5=6,7=1
P 4.69105 4.9431 7 P 0 0;5=6,7=1
P 4.85105 4.9431 7 P 0 0;5=6,7=1
P 4.81105 4.9431 7 P 0 0;5=6,7=1
P 4.77105 4.9231 7 P 0 0;5=6,7=1
P 4.30105 5.0281 7 P 0 0;5=6,7=1
P 4.30105 5.0731 7 P 0 0;5=6,7=1
P 4.30105 4.9831 7 P 0 0;5=6,7=1
P 4.34105 5.1181 7 P 0 0;5=6,7=1
P 4.38105 5.1181 7 P 0 0;5=6,7=1
P 4.46105 5.1181 7 P 0 0;5=6,7=1
P 4.42105 5.1181 7 P 0 0;5=6,7=1
P 4.42105 4.9831 7 P 0 0;5=6,7=1
P 4.42105 5.0731 7 P 0 0;5=6,7=1
P 4.42105 5.0281 7 P 0 0;5=6,7=1
P 4.46105 4.9831 7 P 0 0;5=6,7=1
P 4.46105 5.0731 7 P 0 0;5=6,7=1
P 4.46105 5.0281 7 P 0 0;5=6,7=1
P 4.26105 5.0281 7 P 0 0;5=6,7=1
P 4.26105 5.0731 7 P 0 0;5=6,7=1
P 4.26105 4.9831 7 P 0 0;5=6,7=1
P 4.73105 5.1181 7 P 0 0;5=6,7=1
P 4.69105 5.1181 7 P 0 0;5=6,7=1
P 4.65105 5.1181 7 P 0 0;5=6,7=1
P 4.65105 4.9831 7 P 0 0;5=6,7=1
P 4.65105 5.0731 7 P 0 0;5=6,7=1
P 4.65105 5.0281 7 P 0 0;5=6,7=1
P 4.69105 4.9831 7 P 0 0;5=6,7=1
P 4.69105 5.0731 7 P 0 0;5=6,7=1
P 4.69105 5.0281 7 P 0 0;5=6,7=1
P 4.85105 5.0281 7 P 0 0;5=6,7=1
P 4.85105 5.0731 7 P 0 0;5=6,7=1
P 4.85105 4.9831 7 P 0 0;5=6,7=1
P 4.81105 5.0281 7 P 0 0;5=6,7=1
P 4.81105 5.0731 7 P 0 0;5=6,7=1
P 4.81105 4.9831 7 P 0 0;5=6,7=1
P 4.81105 5.1181 7 P 0 0;5=6,7=1
P 4.85105 5.1181 7 P 0 0;5=6,7=1
P 4.77105 5.1181 7 P 0 0;5=6,7=1
P 4.30105 5.1181 7 P 0 0;5=6,7=1
P 4.26105 5.1181 7 P 0 0;5=6,7=1
P 9.45795 0.36633002 7 P 0 0;5=6,7=1
P 6.62 4.645 7 P 0 0;5=6,7=1
P 6.62 4.61 7 P 0 0;5=6,7=1
P 6.605 4.77 7 P 0 0;5=6,7=1
P 6.315 4.9 7 P 0 0;5=6,7=1
P 6.315 4.865 7 P 0 0;5=6,7=1
P 6.315 4.82 7 P 0 0;5=6,7=1
P 6.315 4.785 7 P 0 0;5=6,7=1
P 6.315 4.705 7 P 0 0;5=6,7=1
P 6.315 4.74 7 P 0 0;5=6,7=1
P 6.315 4.66 7 P 0 0;5=6,7=1
P 6.315 4.625 7 P 0 0;5=6,7=1
P 1.51673002 5.78 7 P 0 0;5=6,7=1
P 1.12303002 5.46016004 7 P 0 0;5=6,7=1
P 1.20176998 5.46016004 7 P 0 0;5=6,7=1
P 1.51673002 5.46016004 7 P 0 0;5=6,7=1
P 1.36 5.355 7 P 0 0;5=6,7=1
P 1.41 5.355 7 P 0 0;5=6,7=1
P 1.46 5.355 7 P 0 0;5=6,7=1
P 1.305 5.885 7 P 0 0;5=6,7=1
P 1.355 5.885 7 P 0 0;5=6,7=1
P 1.405 5.885 7 P 0 0;5=6,7=1
P 1.455 5.885 7 P 0 0;5=6,7=1
P 0.705 5.355 7 P 0 0;5=6,7=1
P 0.7 5.267 8 P 0 0;3,5=1,7=1
P 0.73 5.175 7 P 0 0;5=6,7=1
P 1.03 5.065 7 P 0 0;5=6,7=1
P 1.28051004 5.46016004 7 P 0 0;5=6,7=1
P 5.917 2.97 25 P 0 0;2,5=0,7=0
P 12.215 4.915 7 P 0 0;5=6,7=1
P 12.055 4.915 7 P 0 0;5=6,7=1
P 10.465 5.245 7 P 0 0;5=6,7=1
P 10.465 5.165 7 P 0 0;5=6,7=1
P 11.7719 4.80998996 7 P 0 0;5=6,7=1
P 11.7719 4.85498996 7 P 0 0;5=6,7=1
P 11.7719 4.90498996 7 P 0 0;5=6,7=1
P 11.7719 4.94998996 7 P 0 0;5=6,7=1
P 11.9719 4.94998996 7 P 0 0;5=6,7=1
P 11.9719 4.80998996 7 P 0 0;5=6,7=1
P 11.9719 4.85498996 7 P 0 0;5=6,7=1
P 11.9719 4.90498996 7 P 0 0;5=6,7=1
P 11.9219 4.94998996 7 P 0 0;5=6,7=1
P 11.9219 4.80998996 7 P 0 0;5=6,7=1
P 11.8719 4.94998996 7 P 0 0;5=6,7=1
P 11.8719 4.80998996 7 P 0 0;5=6,7=1
P 11.8219 4.80998996 7 P 0 0;5=6,7=1
P 11.8219 4.94998996 7 P 0 0;5=6,7=1
P 0.61698002 2.045 25 P 0 0;2,5=0,7=0
P 1.82021004 2.4781 25 P 0 0;2,5=0,7=0
L 12.34 2.19 12.325 2.19 5 P 0 
L 12.325 2.19 12.30798002 2.17298002 5 P 0 
L 12.30798002 2.17298002 12.30798002 2.155 5 P 0 
P 11.69316004 2.6635 7 P 0 0;5=6,7=1
P 10.125 2.008 7 P 0 0;5=6,7=1
P 6.42418996 5.04705 25 P 0 0;2,5=0,7=0
P 5.53531004 1.6642 7 P 0 0;5=6,7=1
P 5.53531004 1.7213 7 P 0 0;5=6,7=1
P 5.53531004 2.0802 7 P 0 0;5=6,7=1
P 5.53531004 1.9393 7 P 0 0;5=6,7=1
P 5.53531004 2.2156 7 P 0 0;5=6,7=1
P 5.53531004 2.4081 7 P 0 0;5=6,7=1
P 5.53531004 2.5473 7 P 0 0;5=6,7=1
P 9.1 5.332 25 P 0 0;2,5=0,7=0
P 9.235 5.332 25 P 0 0;2,5=0,7=0
P 9.385 5.332 25 P 0 0;2,5=0,7=0
P 2.86855 4.92 7 P 0 0;5=6,7=1
P 2.79768002 4.92 7 P 0 0;5=6,7=1
P 3.08113996 4.92 7 P 0 0;5=6,7=1
P 3.36461004 4.926 7 P 0 0;5=6,7=1
P 3.22288002 4.92 7 P 0 0;5=6,7=1
P 3.50633996 4.92 7 P 0 0;5=6,7=1
P 3.43546998 4.928 7 P 0 0;5=6,7=1
P 3.15398002 4.81401998 7 P 0 0;5=6,7=1
P 3.22288002 4.81401998 7 P 0 0;5=6,7=1
P 3.36461004 4.81401998 7 P 0 0;5=6,7=1
P 3.43546998 4.81401998 7 P 0 0;5=6,7=1
P 3.50633996 4.81401998 7 P 0 0;5=6,7=1
P 3.22288002 5.023 7 P 0 0;5=6,7=1
P 3.50633996 5.023 7 P 0 0;5=6,7=1
P 3.43546998 5.023 7 P 0 0;5=6,7=1
P 3.14 4.92 7 P 0 0;5=6,7=1
P 3.275 4.92 7 P 0 0;5=6,7=1
L 3.23146004 5.332 3.26 5.332 5 P 0 
P 3.26 5.332 7 P 0 0;5=6,7=1
L 3.09646004 5.332 3.06791998 5.332 5 P 0 
P 3.06791998 5.332 7 P 0 0;5=6,7=1
P 3.51176998 5.17873996 7 P 0 0;5=6,7=1
P 3.57176998 5.17873996 7 P 0 0;5=6,7=1
P 3.15743996 4.74418002 7 P 0 0;5=6,7=1
P 1.63308002 4.92 7 P 0 0;5=6,7=1
P 1.84568002 4.92 7 P 0 0;5=6,7=1
P 1.77481004 4.92 7 P 0 0;5=6,7=1
P 1.70395 4.92 7 P 0 0;5=6,7=1
P 2.12913996 4.92 7 P 0 0;5=6,7=1
P 2.05828002 4.92 7 P 0 0;5=6,7=1
P 1.98741004 4.92 7 P 0 0;5=6,7=1
P 1.91653996 4.92 7 P 0 0;5=6,7=1
P 2.34173996 4.92 7 P 0 0;5=6,7=1
P 2.27086998 4.92 7 P 0 0;5=6,7=1
P 2.20001004 4.926 7 P 0 0;5=6,7=1
P 2.34173996 4.81 7 P 0 0;5=6,7=1
P 2.27086998 4.81 7 P 0 0;5=6,7=1
P 2.20001004 4.81 7 P 0 0;5=6,7=1
P 1.63173002 4.81526998 7 P 0 0;5=6,7=1
P 1.7 4.812 7 P 0 0;5=6,7=1
P 1.84568002 4.81 7 P 0 0;5=6,7=1
P 1.776 4.812 7 P 0 0;5=6,7=1
P 2.12913996 4.81 7 P 0 0;5=6,7=1
P 1.99 4.81 7 P 0 0;5=6,7=1
P 1.92 4.81 7 P 0 0;5=6,7=1
P 2.40716998 5.15373996 7 P 0 0;5=6,7=1
P 2.34716998 5.15373996 7 P 0 0;5=6,7=1
P 2.11646004 5.377 25 P 0 0;2,5=0,7=0
P 1.95146004 5.377 25 P 0 0;2,5=0,7=0
P 10.58661004 2.16615 6 P 0 0;5=4,7=1
P 10.63661004 2.16615 6 P 0 0;5=4,7=1
P 10.63661004 2.21615 6 P 0 0;5=4,7=1
P 10.88661004 1.91615 6 P 0 0;5=4,7=1
P 10.88661004 2.41615 6 P 0 0;5=4,7=1
P 10.88661004 2.66615 6 P 0 0;5=4,7=1
P 11.03661004 2.41615 6 P 0 0;5=4,7=1
P 11.03661004 2.36615 6 P 0 0;5=4,7=1
P 1.91111004 4.61826004 7 P 0 0;5=6,7=1
P 2.40716998 4.70326004 7 P 0 0;5=6,7=1
P 2.945 4.92 7 P 0 0;5=6,7=1
P 3.01028002 4.92 7 P 0 0;5=6,7=1
P 7.78 2.4781 8 P 0 0;3,5=1,7=1
P 2.24606004 3.86615 6 P 0 0;5=4,7=1
P 2.49606004 3.86615 6 P 0 0;5=4,7=1
P 2.24606004 3.81615 6 P 0 0;5=4,7=1
P 2.19606004 3.76615 6 P 0 0;5=4,7=1
P 2.24606004 3.76615 6 P 0 0;5=4,7=1
P 2.29606004 3.76615 6 P 0 0;5=4,7=1
P 2.49606004 3.71615 6 P 0 0;5=4,7=1
P 2.49606004 3.56615 6 P 0 0;5=4,7=1
P 2.44606004 3.56615 6 P 0 0;5=4,7=1
P 2.39606004 3.56615 6 P 0 0;5=4,7=1
P 2.29606004 3.61615 6 P 0 0;5=4,7=1
P 2.24606004 3.71615 6 P 0 0;5=4,7=1
P 2.24606004 3.66615 6 P 0 0;5=4,7=1
P 2.24606004 3.61615 6 P 0 0;5=4,7=1
P 2.19606004 3.61615 6 P 0 0;5=4,7=1
P 2.19606004 3.56615 6 P 0 0;5=4,7=1
P 2.14606004 3.56615 6 P 0 0;5=4,7=1
P 2.04606004 3.56615 6 P 0 0;5=4,7=1
P 1.99606004 3.56615 6 P 0 0;5=4,7=1
P 2.04606004 3.51615 6 P 0 0;5=4,7=1
P 2.04606004 3.46615 6 P 0 0;5=4,7=1
P 2.19606004 3.51615 6 P 0 0;5=4,7=1
P 2.24606004 3.51615 6 P 0 0;5=4,7=1
P 2.29606004 3.51615 6 P 0 0;5=4,7=1
P 2.49606004 3.41615 6 P 0 0;5=4,7=1
P 2.44606004 3.36615 6 P 0 0;5=4,7=1
P 2.24606004 3.46615 6 P 0 0;5=4,7=1
P 2.24606004 3.41615 6 P 0 0;5=4,7=1
P 2.29606004 3.36615 6 P 0 0;5=4,7=1
P 2.24606004 3.36615 6 P 0 0;5=4,7=1
P 2.19606004 3.36615 6 P 0 0;5=4,7=1
P 1.99606004 3.41615 6 P 0 0;5=4,7=1
P 2.09606004 3.36615 6 P 0 0;5=4,7=1
P 2.24606004 3.31615 6 P 0 0;5=4,7=1
P 2.24606004 3.26615 6 P 0 0;5=4,7=1
P 2.29606004 3.21615 6 P 0 0;5=4,7=1
P 2.24606004 3.21615 6 P 0 0;5=4,7=1
P 2.19606004 3.21615 6 P 0 0;5=4,7=1
P 2.09606004 3.21615 6 P 0 0;5=4,7=1
P 2.14606004 3.16615 6 P 0 0;5=4,7=1
P 2.04606004 3.16615 6 P 0 0;5=4,7=1
P 2.24606004 3.16615 6 P 0 0;5=4,7=1
P 2.29606004 3.16615 6 P 0 0;5=4,7=1
P 2.34606004 3.21615 6 P 0 0;5=4,7=1
P 2.44606004 3.21615 6 P 0 0;5=4,7=1
P 2.49606004 3.21615 6 P 0 0;5=4,7=1
P 2.49606004 3.26615 6 P 0 0;5=4,7=1
P 2.49606004 3.16615 6 P 0 0;5=4,7=1
P 2.39606004 3.16615 6 P 0 0;5=4,7=1
P 2.29606004 3.06615 6 P 0 0;5=4,7=1
P 2.29606004 3.11615 6 P 0 0;5=4,7=1
P 2.29606004 2.96615 6 P 0 0;5=4,7=1
P 2.29606004 3.01615 6 P 0 0;5=4,7=1
P 2.24606004 3.06615 6 P 0 0;5=4,7=1
P 2.24606004 3.11615 6 P 0 0;5=4,7=1
P 2.24606004 2.96615 6 P 0 0;5=4,7=1
P 2.24606004 3.01615 6 P 0 0;5=4,7=1
P 2.34606004 2.86615 6 P 0 0;5=4,7=1
P 2.34606004 2.91615 6 P 0 0;5=4,7=1
P 2.29606004 2.76615 6 P 0 0;5=4,7=1
P 2.29606004 2.81615 6 P 0 0;5=4,7=1
P 2.24606004 2.76615 6 P 0 0;5=4,7=1
P 2.24606004 2.81615 6 P 0 0;5=4,7=1
P 2.19606004 2.81615 6 P 0 0;5=4,7=1
P 2.09606004 2.81615 6 P 0 0;5=4,7=1
P 2.09606004 2.86615 6 P 0 0;5=4,7=1
P 2.19606004 3.06615 6 P 0 0;5=4,7=1
P 2.14606004 3.01615 6 P 0 0;5=4,7=1
P 2.09606004 3.06615 6 P 0 0;5=4,7=1
P 2.04606004 3.01615 6 P 0 0;5=4,7=1
P 2.09606004 2.91615 6 P 0 0;5=4,7=1
P 2.14606004 2.86615 6 P 0 0;5=4,7=1
P 2.04606004 2.86615 6 P 0 0;5=4,7=1
P 2.19606004 2.91615 6 P 0 0;5=4,7=1
P 2.24606004 2.91615 6 P 0 0;5=4,7=1
P 2.29606004 2.91615 6 P 0 0;5=4,7=1
P 2.39606004 3.01615 6 P 0 0;5=4,7=1
P 2.34606004 3.06615 6 P 0 0;5=4,7=1
P 2.44606004 3.06615 6 P 0 0;5=4,7=1
P 2.49606004 3.01615 6 P 0 0;5=4,7=1
P 2.44606004 2.91615 6 P 0 0;5=4,7=1
P 2.44606004 2.86615 6 P 0 0;5=4,7=1
P 2.39606004 2.86615 6 P 0 0;5=4,7=1
P 2.34606004 2.81615 6 P 0 0;5=4,7=1
P 2.44606004 2.81615 6 P 0 0;5=4,7=1
P 2.49606004 2.86615 6 P 0 0;5=4,7=1
P 2.49606004 2.71615 6 P 0 0;5=4,7=1
P 2.44606004 2.66615 6 P 0 0;5=4,7=1
P 2.39606004 2.71615 6 P 0 0;5=4,7=1
P 2.34606004 2.66615 6 P 0 0;5=4,7=1
P 2.29606004 2.71615 6 P 0 0;5=4,7=1
P 2.29606004 2.66615 6 P 0 0;5=4,7=1
P 2.24606004 2.71615 6 P 0 0;5=4,7=1
P 2.24606004 2.66615 6 P 0 0;5=4,7=1
P 2.19606004 2.66615 6 P 0 0;5=4,7=1
P 2.14606004 2.71615 6 P 0 0;5=4,7=1
P 2.09606004 2.66615 6 P 0 0;5=4,7=1
P 2.04606004 2.71615 6 P 0 0;5=4,7=1
P 2.04606004 2.56615 6 P 0 0;5=4,7=1
P 2.04606004 2.51615 6 P 0 0;5=4,7=1
P 2.04606004 2.46615 6 P 0 0;5=4,7=1
P 2.09606004 2.51615 6 P 0 0;5=4,7=1
P 2.14606004 2.56615 6 P 0 0;5=4,7=1
P 2.24606004 2.61615 6 P 0 0;5=4,7=1
P 2.24606004 2.56615 6 P 0 0;5=4,7=1
P 2.29606004 2.61615 6 P 0 0;5=4,7=1
P 2.29606004 2.56615 6 P 0 0;5=4,7=1
P 2.34606004 2.51615 6 P 0 0;5=4,7=1
P 2.29606004 2.51615 6 P 0 0;5=4,7=1
P 2.24606004 2.51615 6 P 0 0;5=4,7=1
P 2.19606004 2.51615 6 P 0 0;5=4,7=1
P 2.14606004 2.46615 6 P 0 0;5=4,7=1
P 2.24606004 2.46615 6 P 0 0;5=4,7=1
P 2.29606004 2.46615 6 P 0 0;5=4,7=1
P 2.29606004 2.41615 6 P 0 0;5=4,7=1
P 2.24606004 2.41615 6 P 0 0;5=4,7=1
P 2.24606004 2.36615 6 P 0 0;5=4,7=1
P 2.19606004 2.36615 6 P 0 0;5=4,7=1
P 2.29606004 2.36615 6 P 0 0;5=4,7=1
P 2.39606004 2.46615 6 P 0 0;5=4,7=1
P 2.39606004 2.51615 6 P 0 0;5=4,7=1
P 2.39606004 2.56615 6 P 0 0;5=4,7=1
P 2.44606004 2.51615 6 P 0 0;5=4,7=1
P 2.49606004 2.56615 6 P 0 0;5=4,7=1
P 2.49606004 2.51615 6 P 0 0;5=4,7=1
P 2.49606004 2.46615 6 P 0 0;5=4,7=1
P 2.44606004 2.36615 6 P 0 0;5=4,7=1
P 2.49606004 2.31615 6 P 0 0;5=4,7=1
P 2.39606004 2.31615 6 P 0 0;5=4,7=1
P 2.34606004 2.36615 6 P 0 0;5=4,7=1
P 2.29606004 2.31615 6 P 0 0;5=4,7=1
P 2.24606004 2.31615 6 P 0 0;5=4,7=1
P 2.04606004 2.31615 6 P 0 0;5=4,7=1
P 2.04606004 2.16615 6 P 0 0;5=4,7=1
P 2.04606004 2.11615 6 P 0 0;5=4,7=1
P 2.04606004 1.96615 6 P 0 0;5=4,7=1
P 2.09606004 2.01615 6 P 0 0;5=4,7=1
P 2.14606004 1.96615 6 P 0 0;5=4,7=1
P 2.09606004 1.86615 6 P 0 0;5=4,7=1
P 2.19606004 1.86615 6 P 0 0;5=4,7=1
P 2.24606004 1.86615 6 P 0 0;5=4,7=1
P 2.29606004 1.86615 6 P 0 0;5=4,7=1
P 2.34606004 1.86615 6 P 0 0;5=4,7=1
P 2.24606004 1.91615 6 P 0 0;5=4,7=1
P 2.29606004 1.91615 6 P 0 0;5=4,7=1
P 2.24606004 1.96615 6 P 0 0;5=4,7=1
P 2.29606004 1.96615 6 P 0 0;5=4,7=1
P 2.19606004 2.01615 6 P 0 0;5=4,7=1
P 2.24606004 2.01615 6 P 0 0;5=4,7=1
P 2.29606004 2.01615 6 P 0 0;5=4,7=1
P 2.34606004 2.01615 6 P 0 0;5=4,7=1
P 2.39606004 1.96615 6 P 0 0;5=4,7=1
P 2.44606004 2.01615 6 P 0 0;5=4,7=1
P 2.49606004 1.96615 6 P 0 0;5=4,7=1
P 2.44606004 1.86615 6 P 0 0;5=4,7=1
P 2.49606004 2.11615 6 P 0 0;5=4,7=1
P 2.44606004 2.16615 6 P 0 0;5=4,7=1
P 2.49606004 2.16615 6 P 0 0;5=4,7=1
P 2.44606004 2.21615 6 P 0 0;5=4,7=1
P 2.39606004 2.16615 6 P 0 0;5=4,7=1
P 2.39606004 2.11615 6 P 0 0;5=4,7=1
P 2.34606004 2.16615 6 P 0 0;5=4,7=1
P 2.34606004 2.21615 6 P 0 0;5=4,7=1
P 2.29606004 2.21615 6 P 0 0;5=4,7=1
P 2.29606004 2.16615 6 P 0 0;5=4,7=1
P 2.29606004 2.06615 6 P 0 0;5=4,7=1
P 2.29606004 2.11615 6 P 0 0;5=4,7=1
P 2.24606004 2.11615 6 P 0 0;5=4,7=1
P 2.24606004 2.16615 6 P 0 0;5=4,7=1
P 2.24606004 2.06615 6 P 0 0;5=4,7=1
P 2.24606004 2.21615 6 P 0 0;5=4,7=1
P 2.29606004 2.26615 6 P 0 0;5=4,7=1
P 2.24606004 2.26615 6 P 0 0;5=4,7=1
P 2.19606004 2.21615 6 P 0 0;5=4,7=1
P 2.19606004 2.16615 6 P 0 0;5=4,7=1
P 2.14606004 2.11615 6 P 0 0;5=4,7=1
P 2.14606004 2.16615 6 P 0 0;5=4,7=1
P 2.09606004 2.21615 6 P 0 0;5=4,7=1
P 2.09606004 2.16615 6 P 0 0;5=4,7=1
P 2.09606004 2.36615 6 P 0 0;5=4,7=1
P 2.14606004 2.31615 6 P 0 0;5=4,7=1
P 1.99606004 2.71615 6 P 0 0;5=4,7=1
P 1.99606004 2.86615 6 P 0 0;5=4,7=1
P 2.04606004 2.81615 6 P 0 0;5=4,7=1
P 2.04606004 2.76615 6 P 0 0;5=4,7=1
P 3.29373996 5.023 7 P 0 0;5=6,7=1
P 2.14606004 3.26615 6 P 0 0;5=4,7=1
P 2.04606004 3.26615 6 P 0 0;5=4,7=1
P 2.04606004 3.21615 6 P 0 0;5=4,7=1
P 2.14606004 3.21615 6 P 0 0;5=4,7=1
P 2.39606004 3.21615 6 P 0 0;5=4,7=1
P 2.39606004 3.26615 6 P 0 0;5=4,7=1
P 2.29606004 3.26615 6 P 0 0;5=4,7=1
P 2.29606004 3.31615 6 P 0 0;5=4,7=1
P 2.34606004 3.36615 6 P 0 0;5=4,7=1
P 2.14606004 3.41615 6 P 0 0;5=4,7=1
P 2.09606004 3.61615 6 P 0 0;5=4,7=1
P 2.29606004 3.46615 6 P 0 0;5=4,7=1
P 2.29606004 3.41615 6 P 0 0;5=4,7=1
P 2.39606004 3.41615 6 P 0 0;5=4,7=1
P 2.34606004 3.51615 6 P 0 0;5=4,7=1
P 2.34606004 3.61615 6 P 0 0;5=4,7=1
P 2.34606004 3.56615 6 P 0 0;5=4,7=1
P 2.44606004 3.51615 6 P 0 0;5=4,7=1
P 2.44606004 3.61615 6 P 0 0;5=4,7=1
P 2.14606004 3.71615 6 P 0 0;5=4,7=1
P 2.04606004 3.71615 6 P 0 0;5=4,7=1
P 2.09606004 3.76615 6 P 0 0;5=4,7=1
P 2.14606004 3.86615 6 P 0 0;5=4,7=1
P 2.04606004 3.86615 6 P 0 0;5=4,7=1
P 2.29606004 3.71615 6 P 0 0;5=4,7=1
P 2.29606004 3.66615 6 P 0 0;5=4,7=1
P 2.39606004 3.71615 6 P 0 0;5=4,7=1
P 2.34606004 3.76615 6 P 0 0;5=4,7=1
P 2.29606004 3.81615 6 P 0 0;5=4,7=1
P 2.39606004 3.86615 6 P 0 0;5=4,7=1
P 2.29606004 3.86615 6 P 0 0;5=4,7=1
P 2.44606004 3.76615 6 P 0 0;5=4,7=1
P 2.19606004 2.86615 6 P 0 0;5=4,7=1
P 3.36461004 5.023 7 P 0 0;5=6,7=1
P 3.29373996 4.81401998 7 P 0 0;5=6,7=1
P 3.01028002 4.81401998 7 P 0 0;5=6,7=1
P 2.94141004 4.81401998 7 P 0 0;5=6,7=1
P 2.86555 4.81401998 7 P 0 0;5=6,7=1
P 2.79768002 4.81401998 7 P 0 0;5=6,7=1
P 3.15201004 5.023 7 P 0 0;5=6,7=1
P 3.08113996 5.023 7 P 0 0;5=6,7=1
P 3.01028002 5.023 7 P 0 0;5=6,7=1
P 2.93941004 5.023 7 P 0 0;5=6,7=1
P 2.86855 5.023 7 P 0 0;5=6,7=1
P 2.79768002 5.023 7 P 0 0;5=6,7=1
P 1.70395 5.023 7 P 0 0;5=6,7=1
P 1.63308002 5.023 7 P 0 0;5=6,7=1
P 1.77481004 5.023 7 P 0 0;5=6,7=1
P 1.91653996 5.023 7 P 0 0;5=6,7=1
P 1.84568002 5.023 7 P 0 0;5=6,7=1
P 1.98741004 5.023 7 P 0 0;5=6,7=1
P 2.05828002 5.023 7 P 0 0;5=6,7=1
P 2.12913996 5.023 7 P 0 0;5=6,7=1
P 2.20001004 5.023 7 P 0 0;5=6,7=1
P 2.27086998 5.023 7 P 0 0;5=6,7=1
P 2.34173996 5.023 7 P 0 0;5=6,7=1
P 1.56221004 5.023 7 P 0 0;5=6,7=1
P 1.56221004 4.81401998 7 P 0 0;5=6,7=1
P 2.06086998 4.81 7 P 0 0;5=6,7=1
P 2.41261004 5.023 7 P 0 0;5=6,7=1
P 2.41261004 4.81401998 7 P 0 0;5=6,7=1
P 2.72681004 5.023 7 P 0 0;5=6,7=1
P 2.72681004 4.81401998 7 P 0 0;5=6,7=1
P 3.57721004 4.81401998 7 P 0 0;5=6,7=1
P 3.57721004 5.023 7 P 0 0;5=6,7=1
P 4.88268002 1.91615 6 P 0 0;5=4,7=1
P 4.78268002 1.91615 6 P 0 0;5=4,7=1
P 5.03268002 2.36615 6 P 0 0;5=4,7=1
P 5.03268002 2.41615 6 P 0 0;5=4,7=1
P 4.88268002 3.66615 6 P 0 0;5=4,7=1
P 4.83268002 3.66615 6 P 0 0;5=4,7=1
P 5.03268002 3.66615 6 P 0 0;5=4,7=1
P 4.93268002 3.66615 6 P 0 0;5=4,7=1
P 4.98268002 3.66615 6 P 0 0;5=4,7=1
P 4.88268002 3.51615 6 P 0 0;5=4,7=1
P 4.83268002 3.51615 6 P 0 0;5=4,7=1
P 5.03268002 3.51615 6 P 0 0;5=4,7=1
P 4.93268002 3.51615 6 P 0 0;5=4,7=1
P 4.98268002 3.51615 6 P 0 0;5=4,7=1
P 4.88268002 3.81615 6 P 0 0;5=4,7=1
P 4.83268002 3.81615 6 P 0 0;5=4,7=1
P 4.93268002 3.81615 6 P 0 0;5=4,7=1
P 4.98268002 3.81615 6 P 0 0;5=4,7=1
P 4.88268002 3.36615 6 P 0 0;5=4,7=1
P 4.83268002 3.36615 6 P 0 0;5=4,7=1
P 5.03268002 3.36615 6 P 0 0;5=4,7=1
P 4.93268002 3.36615 6 P 0 0;5=4,7=1
P 4.98268002 3.36615 6 P 0 0;5=4,7=1
P 4.83268002 3.21615 6 P 0 0;5=4,7=1
P 4.88268002 3.21615 6 P 0 0;5=4,7=1
P 4.98268002 3.21615 6 P 0 0;5=4,7=1
P 4.93268002 3.21615 6 P 0 0;5=4,7=1
P 5.03268002 3.21615 6 P 0 0;5=4,7=1
P 4.83268002 3.06615 6 P 0 0;5=4,7=1
P 4.88268002 3.06615 6 P 0 0;5=4,7=1
P 4.98268002 3.06615 6 P 0 0;5=4,7=1
P 4.93268002 3.06615 6 P 0 0;5=4,7=1
P 5.03268002 3.06615 6 P 0 0;5=4,7=1
P 4.83268002 2.91615 6 P 0 0;5=4,7=1
P 4.88268002 2.91615 6 P 0 0;5=4,7=1
P 4.98268002 2.91615 6 P 0 0;5=4,7=1
P 4.93268002 2.91615 6 P 0 0;5=4,7=1
P 5.03268002 2.91615 6 P 0 0;5=4,7=1
P 4.78268002 2.51615 6 P 0 0;5=4,7=1
P 4.73268002 2.51615 6 P 0 0;5=4,7=1
P 4.68268002 2.51615 6 P 0 0;5=4,7=1
P 4.63268002 2.51615 6 P 0 0;5=4,7=1
P 4.58268002 2.51615 6 P 0 0;5=4,7=1
P 4.63268002 2.56615 6 P 0 0;5=4,7=1
P 4.73268002 2.56615 6 P 0 0;5=4,7=1
P 4.78268002 2.56615 6 P 0 0;5=4,7=1
P 4.78268002 2.61615 6 P 0 0;5=4,7=1
P 4.78268002 2.66615 6 P 0 0;5=4,7=1
P 4.68268002 2.66615 6 P 0 0;5=4,7=1
P 4.58268002 2.66615 6 P 0 0;5=4,7=1
P 4.73268002 2.71615 6 P 0 0;5=4,7=1
P 4.63268002 2.71615 6 P 0 0;5=4,7=1
P 4.63268002 2.76615 6 P 0 0;5=4,7=1
P 4.73268002 2.76615 6 P 0 0;5=4,7=1
P 4.78268002 2.76615 6 P 0 0;5=4,7=1
P 4.63268002 2.16615 6 P 0 0;5=4,7=1
P 4.78268002 2.16615 6 P 0 0;5=4,7=1
P 10.63661004 2.91615 6 P 0 0;5=4,7=1
P 10.58661004 2.91615 6 P 0 0;5=4,7=1
P 10.63661004 3.06615 6 P 0 0;5=4,7=1
P 10.58661004 3.06615 6 P 0 0;5=4,7=1
P 10.63661004 3.36615 6 P 0 0;5=4,7=1
P 10.58661004 3.36615 6 P 0 0;5=4,7=1
P 10.63661004 3.21615 6 P 0 0;5=4,7=1
P 10.58661004 3.21615 6 P 0 0;5=4,7=1
P 10.58661004 3.66615 6 P 0 0;5=4,7=1
P 10.63661004 3.51615 6 P 0 0;5=4,7=1
P 10.58661004 3.51615 6 P 0 0;5=4,7=1
P 10.63661004 3.81615 6 P 0 0;5=4,7=1
P 10.63661004 3.66615 6 P 0 0;5=4,7=1
P 10.58661004 3.81615 6 P 0 0;5=4,7=1
P 10.83661004 2.91615 6 P 0 0;5=4,7=1
P 10.78661004 2.91615 6 P 0 0;5=4,7=1
P 10.73661004 2.91615 6 P 0 0;5=4,7=1
P 10.68661004 2.91615 6 P 0 0;5=4,7=1
P 10.88661004 2.91615 6 P 0 0;5=4,7=1
P 10.88661004 3.06615 6 P 0 0;5=4,7=1
P 10.83661004 3.06615 6 P 0 0;5=4,7=1
P 10.78661004 3.06615 6 P 0 0;5=4,7=1
P 10.73661004 3.06615 6 P 0 0;5=4,7=1
P 10.68661004 3.06615 6 P 0 0;5=4,7=1
P 10.88661004 3.21615 6 P 0 0;5=4,7=1
P 10.83661004 3.21615 6 P 0 0;5=4,7=1
P 10.83661004 3.36615 6 P 0 0;5=4,7=1
P 10.88661004 3.36615 6 P 0 0;5=4,7=1
P 10.78661004 3.36615 6 P 0 0;5=4,7=1
P 10.73661004 3.36615 6 P 0 0;5=4,7=1
P 10.78661004 3.21615 6 P 0 0;5=4,7=1
P 10.73661004 3.21615 6 P 0 0;5=4,7=1
P 10.68661004 3.36615 6 P 0 0;5=4,7=1
P 10.68661004 3.21615 6 P 0 0;5=4,7=1
P 10.83661004 3.51615 6 P 0 0;5=4,7=1
P 10.88661004 3.51615 6 P 0 0;5=4,7=1
P 10.83661004 3.66615 6 P 0 0;5=4,7=1
P 10.78661004 3.66615 6 P 0 0;5=4,7=1
P 10.73661004 3.66615 6 P 0 0;5=4,7=1
P 10.68661004 3.66615 6 P 0 0;5=4,7=1
P 10.78661004 3.51615 6 P 0 0;5=4,7=1
P 10.73661004 3.51615 6 P 0 0;5=4,7=1
P 10.68661004 3.51615 6 P 0 0;5=4,7=1
P 10.83661004 3.81615 6 P 0 0;5=4,7=1
P 10.88661004 3.81615 6 P 0 0;5=4,7=1
P 10.88661004 3.66615 6 P 0 0;5=4,7=1
P 10.78661004 3.81615 6 P 0 0;5=4,7=1
P 10.73661004 3.81615 6 P 0 0;5=4,7=1
P 10.68661004 3.81615 6 P 0 0;5=4,7=1
P 11.03661004 2.91615 6 P 0 0;5=4,7=1
P 10.93661004 2.91615 6 P 0 0;5=4,7=1
P 10.98661004 2.91615 6 P 0 0;5=4,7=1
P 11.03661004 3.06615 6 P 0 0;5=4,7=1
P 10.93661004 3.06615 6 P 0 0;5=4,7=1
P 10.98661004 3.06615 6 P 0 0;5=4,7=1
P 11.03661004 3.21615 6 P 0 0;5=4,7=1
P 10.93661004 3.21615 6 P 0 0;5=4,7=1
P 10.98661004 3.21615 6 P 0 0;5=4,7=1
P 10.98661004 3.36615 6 P 0 0;5=4,7=1
P 10.93661004 3.36615 6 P 0 0;5=4,7=1
P 11.03661004 3.36615 6 P 0 0;5=4,7=1
P 10.98661004 3.51615 6 P 0 0;5=4,7=1
P 10.93661004 3.51615 6 P 0 0;5=4,7=1
P 11.03661004 3.51615 6 P 0 0;5=4,7=1
P 10.98661004 3.66615 6 P 0 0;5=4,7=1
P 10.93661004 3.66615 6 P 0 0;5=4,7=1
P 11.03661004 3.66615 6 P 0 0;5=4,7=1
P 10.98661004 3.81615 6 P 0 0;5=4,7=1
P 10.93661004 3.81615 6 P 0 0;5=4,7=1
P 3.07691004 4.81401998 7 P 0 0;5=6,7=1
P 8.1 1.86615 6 P 0 0;5=4,7=1
P 8.15 2.16615 6 P 0 0;5=4,7=1
P 8.15 2.11615 6 P 0 0;5=4,7=1
P 8.15 1.96615 6 P 0 0;5=4,7=1
P 8.1 2.01615 6 P 0 0;5=4,7=1
P 8.05 1.96615 6 P 0 0;5=4,7=1
P 8.05 2.11615 6 P 0 0;5=4,7=1
P 8.05 2.16615 6 P 0 0;5=4,7=1
P 8.15 2.31615 6 P 0 0;5=4,7=1
P 8.1 2.36615 6 P 0 0;5=4,7=1
P 8.1 2.16615 6 P 0 0;5=4,7=1
P 8.1 2.21615 6 P 0 0;5=4,7=1
P 8.05 2.31615 6 P 0 0;5=4,7=1
P 8.15 2.46615 6 P 0 0;5=4,7=1
P 8.15 2.56615 6 P 0 0;5=4,7=1
P 8.1 2.51615 6 P 0 0;5=4,7=1
P 8.05 2.46615 6 P 0 0;5=4,7=1
P 8.05 2.51615 6 P 0 0;5=4,7=1
P 8.05 2.56615 6 P 0 0;5=4,7=1
P 8.1 2.66615 6 P 0 0;5=4,7=1
P 8.05 2.76615 6 P 0 0;5=4,7=1
P 8.05 2.81615 6 P 0 0;5=4,7=1
P 8 2.86615 6 P 0 0;5=4,7=1
P 8 2.71615 6 P 0 0;5=4,7=1
P 8.05 2.71615 6 P 0 0;5=4,7=1
P 8.15 2.71615 6 P 0 0;5=4,7=1
P 8.05 2.86615 6 P 0 0;5=4,7=1
P 8.15 2.86615 6 P 0 0;5=4,7=1
P 8.1 2.91615 6 P 0 0;5=4,7=1
P 8.1 2.86615 6 P 0 0;5=4,7=1
P 8.1 2.81615 6 P 0 0;5=4,7=1
P 8.05 3.01615 6 P 0 0;5=4,7=1
P 8.1 3.06615 6 P 0 0;5=4,7=1
P 8.15 3.01615 6 P 0 0;5=4,7=1
P 8.15 3.16615 6 P 0 0;5=4,7=1
P 8.05 3.16615 6 P 0 0;5=4,7=1
P 8 3.41615 6 P 0 0;5=4,7=1
P 8.05 3.41615 6 P 0 0;5=4,7=1
P 8.1 3.36615 6 P 0 0;5=4,7=1
P 8.1 3.21615 6 P 0 0;5=4,7=1
P 8.15 3.56615 6 P 0 0;5=4,7=1
P 8.05 3.56615 6 P 0 0;5=4,7=1
P 8 3.56615 6 P 0 0;5=4,7=1
P 8.05 3.51615 6 P 0 0;5=4,7=1
P 8.05 3.46615 6 P 0 0;5=4,7=1
P 8.1 3.51615 6 P 0 0;5=4,7=1
P 8.35 1.86615 6 P 0 0;5=4,7=1
P 8.3 1.86615 6 P 0 0;5=4,7=1
P 8.25 1.86615 6 P 0 0;5=4,7=1
P 8.2 1.86615 6 P 0 0;5=4,7=1
P 8.25 2.06615 6 P 0 0;5=4,7=1
P 8.25 2.16615 6 P 0 0;5=4,7=1
P 8.25 2.11615 6 P 0 0;5=4,7=1
P 8.3 2.11615 6 P 0 0;5=4,7=1
P 8.3 2.06615 6 P 0 0;5=4,7=1
P 8.4 2.11615 6 P 0 0;5=4,7=1
P 8.4 2.16615 6 P 0 0;5=4,7=1
P 8.4 1.96615 6 P 0 0;5=4,7=1
P 8.35 2.01615 6 P 0 0;5=4,7=1
P 8.3 2.01615 6 P 0 0;5=4,7=1
P 8.25 2.01615 6 P 0 0;5=4,7=1
P 8.2 2.01615 6 P 0 0;5=4,7=1
P 8.3 1.96615 6 P 0 0;5=4,7=1
P 8.25 1.96615 6 P 0 0;5=4,7=1
P 8.3 1.91615 6 P 0 0;5=4,7=1
P 8.25 1.91615 6 P 0 0;5=4,7=1
P 8.2 2.16615 6 P 0 0;5=4,7=1
P 8.2 2.21615 6 P 0 0;5=4,7=1
P 8.25 2.26615 6 P 0 0;5=4,7=1
P 8.3 2.26615 6 P 0 0;5=4,7=1
P 8.25 2.21615 6 P 0 0;5=4,7=1
P 8.3 2.16615 6 P 0 0;5=4,7=1
P 8.3 2.21615 6 P 0 0;5=4,7=1
P 8.35 2.21615 6 P 0 0;5=4,7=1
P 8.35 2.16615 6 P 0 0;5=4,7=1
P 8.25 2.31615 6 P 0 0;5=4,7=1
P 8.3 2.31615 6 P 0 0;5=4,7=1
P 8.35 2.36615 6 P 0 0;5=4,7=1
P 8.4 2.31615 6 P 0 0;5=4,7=1
P 8.3 2.36615 6 P 0 0;5=4,7=1
P 8.2 2.36615 6 P 0 0;5=4,7=1
P 8.25 2.36615 6 P 0 0;5=4,7=1
P 8.25 2.41615 6 P 0 0;5=4,7=1
P 8.3 2.41615 6 P 0 0;5=4,7=1
P 8.4 2.56615 6 P 0 0;5=4,7=1
P 8.4 2.51615 6 P 0 0;5=4,7=1
P 8.4 2.46615 6 P 0 0;5=4,7=1
P 8.3 2.46615 6 P 0 0;5=4,7=1
P 8.25 2.46615 6 P 0 0;5=4,7=1
P 8.2 2.51615 6 P 0 0;5=4,7=1
P 8.25 2.51615 6 P 0 0;5=4,7=1
P 8.3 2.51615 6 P 0 0;5=4,7=1
P 8.35 2.51615 6 P 0 0;5=4,7=1
P 8.3 2.56615 6 P 0 0;5=4,7=1
P 8.3 2.61615 6 P 0 0;5=4,7=1
P 8.25 2.56615 6 P 0 0;5=4,7=1
P 8.25 2.61615 6 P 0 0;5=4,7=1
P 8.2 2.66615 6 P 0 0;5=4,7=1
P 8.25 2.66615 6 P 0 0;5=4,7=1
P 8.3 2.66615 6 P 0 0;5=4,7=1
P 8.35 2.66615 6 P 0 0;5=4,7=1
P 8.25 2.71615 6 P 0 0;5=4,7=1
P 8.3 2.71615 6 P 0 0;5=4,7=1
P 8.4 2.71615 6 P 0 0;5=4,7=1
P 8.35 2.81615 6 P 0 0;5=4,7=1
P 8.4 2.86615 6 P 0 0;5=4,7=1
P 8.3 2.91615 6 P 0 0;5=4,7=1
P 8.25 2.91615 6 P 0 0;5=4,7=1
P 8.2 2.91615 6 P 0 0;5=4,7=1
P 8.2 2.81615 6 P 0 0;5=4,7=1
P 8.25 2.81615 6 P 0 0;5=4,7=1
P 8.25 2.76615 6 P 0 0;5=4,7=1
P 8.3 2.81615 6 P 0 0;5=4,7=1
P 8.3 2.76615 6 P 0 0;5=4,7=1
P 8.35 2.91615 6 P 0 0;5=4,7=1
P 8.35 2.86615 6 P 0 0;5=4,7=1
P 8.35 3.06615 6 P 0 0;5=4,7=1
P 8.4 3.01615 6 P 0 0;5=4,7=1
P 8.2 3.06615 6 P 0 0;5=4,7=1
P 8.25 3.01615 6 P 0 0;5=4,7=1
P 8.25 2.96615 6 P 0 0;5=4,7=1
P 8.25 3.11615 6 P 0 0;5=4,7=1
P 8.25 3.06615 6 P 0 0;5=4,7=1
P 8.3 3.01615 6 P 0 0;5=4,7=1
P 8.3 2.96615 6 P 0 0;5=4,7=1
P 8.3 3.11615 6 P 0 0;5=4,7=1
P 8.3 3.06615 6 P 0 0;5=4,7=1
P 8.25 3.16615 6 P 0 0;5=4,7=1
P 8.3 3.16615 6 P 0 0;5=4,7=1
P 8.4 3.16615 6 P 0 0;5=4,7=1
P 8.25 3.41615 6 P 0 0;5=4,7=1
P 8.3 3.36615 6 P 0 0;5=4,7=1
P 8.25 3.36615 6 P 0 0;5=4,7=1
P 8.2 3.36615 6 P 0 0;5=4,7=1
P 8.25 3.31615 6 P 0 0;5=4,7=1
P 8.25 3.26615 6 P 0 0;5=4,7=1
P 8.3 3.21615 6 P 0 0;5=4,7=1
P 8.25 3.21615 6 P 0 0;5=4,7=1
P 8.2 3.21615 6 P 0 0;5=4,7=1
P 8.35 3.21615 6 P 0 0;5=4,7=1
P 8.4 3.56615 6 P 0 0;5=4,7=1
P 8.3 3.61615 6 P 0 0;5=4,7=1
P 8.25 3.66615 6 P 0 0;5=4,7=1
P 8.25 3.61615 6 P 0 0;5=4,7=1
P 8.2 3.61615 6 P 0 0;5=4,7=1
P 8.2 3.56615 6 P 0 0;5=4,7=1
P 8.2 3.51615 6 P 0 0;5=4,7=1
P 8.25 3.51615 6 P 0 0;5=4,7=1
P 8.3 3.51615 6 P 0 0;5=4,7=1
P 8.25 3.46615 6 P 0 0;5=4,7=1
P 8.25 3.86615 6 P 0 0;5=4,7=1
P 8.25 3.81615 6 P 0 0;5=4,7=1
P 8.2 3.76615 6 P 0 0;5=4,7=1
P 8.25 3.76615 6 P 0 0;5=4,7=1
P 8.3 3.76615 6 P 0 0;5=4,7=1
P 8.25 3.71615 6 P 0 0;5=4,7=1
P 8.45 1.86615 6 P 0 0;5=4,7=1
P 8.5 2.16615 6 P 0 0;5=4,7=1
P 8.5 2.11615 6 P 0 0;5=4,7=1
P 8.5 1.96615 6 P 0 0;5=4,7=1
P 8.45 2.01615 6 P 0 0;5=4,7=1
P 8.45 2.21615 6 P 0 0;5=4,7=1
P 8.45 2.16615 6 P 0 0;5=4,7=1
P 8.5 2.31615 6 P 0 0;5=4,7=1
P 8.45 2.36615 6 P 0 0;5=4,7=1
P 8.5 2.46615 6 P 0 0;5=4,7=1
P 8.5 2.51615 6 P 0 0;5=4,7=1
P 8.5 2.56615 6 P 0 0;5=4,7=1
P 8.45 2.51615 6 P 0 0;5=4,7=1
P 8.45 2.66615 6 P 0 0;5=4,7=1
P 8.5 2.71615 6 P 0 0;5=4,7=1
P 8.5 2.86615 6 P 0 0;5=4,7=1
P 8.45 2.81615 6 P 0 0;5=4,7=1
P 8.45 2.86615 6 P 0 0;5=4,7=1
P 8.45 2.91615 6 P 0 0;5=4,7=1
P 8.5 3.01615 6 P 0 0;5=4,7=1
P 8.45 3.06615 6 P 0 0;5=4,7=1
P 8.5 3.16615 6 P 0 0;5=4,7=1
P 8.5 3.41615 6 P 0 0;5=4,7=1
P 8.45 3.36615 6 P 0 0;5=4,7=1
P 8.45 3.21615 6 P 0 0;5=4,7=1
P 8.5 3.21615 6 P 0 0;5=4,7=1
P 8.5 3.26615 6 P 0 0;5=4,7=1
P 8.5 3.56615 6 P 0 0;5=4,7=1
P 8.45 3.56615 6 P 0 0;5=4,7=1
P 8.5 3.86615 6 P 0 0;5=4,7=1
P 8.5 3.71615 6 P 0 0;5=4,7=1
P 8.2 2.86615 6 P 0 0;5=4,7=1
P 8.05 3.26615 6 P 0 0;5=4,7=1
P 8.05 3.21615 6 P 0 0;5=4,7=1
P 8.3 3.26615 6 P 0 0;5=4,7=1
P 8.3 3.31615 6 P 0 0;5=4,7=1
P 8.35 3.36615 6 P 0 0;5=4,7=1
P 8.15 3.26615 6 P 0 0;5=4,7=1
P 8.15 3.21615 6 P 0 0;5=4,7=1
P 8.4 3.21615 6 P 0 0;5=4,7=1
P 8.4 3.26615 6 P 0 0;5=4,7=1
P 8.1 3.61615 6 P 0 0;5=4,7=1
P 8.3 3.46615 6 P 0 0;5=4,7=1
P 8.3 3.41615 6 P 0 0;5=4,7=1
P 8.35 3.51615 6 P 0 0;5=4,7=1
P 8.35 3.61615 6 P 0 0;5=4,7=1
P 8.35 3.56615 6 P 0 0;5=4,7=1
P 8.15 3.41615 6 P 0 0;5=4,7=1
P 8.45 3.51615 6 P 0 0;5=4,7=1
P 8.45 3.61615 6 P 0 0;5=4,7=1
P 8.4 3.41615 6 P 0 0;5=4,7=1
P 8.05 3.71615 6 P 0 0;5=4,7=1
P 8.1 3.76615 6 P 0 0;5=4,7=1
P 8.05 3.86615 6 P 0 0;5=4,7=1
P 8.3 3.71615 6 P 0 0;5=4,7=1
P 8.3 3.66615 6 P 0 0;5=4,7=1
P 8.35 3.76615 6 P 0 0;5=4,7=1
P 8.3 3.81615 6 P 0 0;5=4,7=1
P 8.3 3.86615 6 P 0 0;5=4,7=1
P 8.15 3.71615 6 P 0 0;5=4,7=1
P 8.15 3.86615 6 P 0 0;5=4,7=1
P 8.45 3.76615 6 P 0 0;5=4,7=1
P 8.4 3.71615 6 P 0 0;5=4,7=1
P 8.4 3.86615 6 P 0 0;5=4,7=1
P 7.955 5.377 25 P 0 0;2,5=0,7=0
P 8.12 5.377 25 P 0 0;2,5=0,7=0
P 3.28831004 4.68073996 7 P 0 0;5=6,7=1
P 3.22831004 4.68073996 7 P 0 0;5=6,7=1
P 3.50091004 4.62573996 7 P 0 0;5=6,7=1
P 3.44091004 4.62573996 7 P 0 0;5=6,7=1
P 7.56575 5.023 7 P 0 0;5=6,7=1
P 7.63661998 5.023 7 P 0 0;5=6,7=1
P 7.84921998 5.023 7 P 0 0;5=6,7=1
P 7.77835 5.023 7 P 0 0;5=6,7=1
P 7.70748996 5.023 7 P 0 0;5=6,7=1
P 7.92008002 5.023 7 P 0 0;5=6,7=1
P 8.06181998 5.023 7 P 0 0;5=6,7=1
P 8.13268002 5.023 7 P 0 0;5=6,7=1
P 7.99095 5.023 7 P 0 0;5=6,7=1
P 8.34528002 5.023 7 P 0 0;5=6,7=1
P 8.27441004 5.023 7 P 0 0;5=6,7=1
P 8.20355 5.023 7 P 0 0;5=6,7=1
P 8.41615 5.023 7 P 0 0;5=6,7=1
P 7.63661998 4.92 7 P 0 0;5=6,7=1
P 7.84921998 4.9207 7 P 0 0;5=6,7=1
P 7.70748996 4.9207 7 P 0 0;5=6,7=1
P 7.77835 4.9207 7 P 0 0;5=6,7=1
P 7.99095 4.9207 7 P 0 0;5=6,7=1
P 7.92008002 4.9207 7 P 0 0;5=6,7=1
P 8.06181998 4.9207 7 P 0 0;5=6,7=1
P 8.13268002 4.9207 7 P 0 0;5=6,7=1
P 8.27441004 4.9207 7 P 0 0;5=6,7=1
P 8.20355 4.9267 7 P 0 0;5=6,7=1
P 8.34528002 4.9207 7 P 0 0;5=6,7=1
P 7.63526998 4.81526998 7 P 0 0;5=6,7=1
P 7.84921998 4.81 7 P 0 0;5=6,7=1
P 7.77953996 4.812 7 P 0 0;5=6,7=1
P 7.70353996 4.812 7 P 0 0;5=6,7=1
P 8.13268002 4.81 7 P 0 0;5=6,7=1
P 8.06441004 4.81 7 P 0 0;5=6,7=1
P 7.99353996 4.81 7 P 0 0;5=6,7=1
P 7.92353996 4.81 7 P 0 0;5=6,7=1
P 8.27441004 4.81 7 P 0 0;5=6,7=1
P 8.34528002 4.81 7 P 0 0;5=6,7=1
P 8.20355 4.81 7 P 0 0;5=6,7=1
P 8.41615 4.81401998 7 P 0 0;5=6,7=1
P 8.86908996 4.81401998 7 P 0 0;5=6,7=1
P 8.73035 4.81401998 7 P 0 0;5=6,7=1
P 8.80121998 4.81401998 7 P 0 0;5=6,7=1
P 8.94495 4.81401998 7 P 0 0;5=6,7=1
P 9.08045 4.81401998 7 P 0 0;5=6,7=1
P 9.01381998 4.81401998 7 P 0 0;5=6,7=1
P 9.36815 4.81401998 7 P 0 0;5=6,7=1
P 9.29728002 4.81401998 7 P 0 0;5=6,7=1
P 9.22641998 4.81401998 7 P 0 0;5=6,7=1
P 9.15751998 4.81401998 7 P 0 0;5=6,7=1
P 9.43901004 4.81401998 7 P 0 0;5=6,7=1
P 9.50988002 4.81401998 7 P 0 0;5=6,7=1
P 9.58075 4.81401998 7 P 0 0;5=6,7=1
P 8.80121998 5.023 7 P 0 0;5=6,7=1
P 8.73035 5.023 7 P 0 0;5=6,7=1
P 8.87208996 5.023 7 P 0 0;5=6,7=1
P 9.08468002 5.023 7 P 0 0;5=6,7=1
P 9.01381998 5.023 7 P 0 0;5=6,7=1
P 8.94295 5.023 7 P 0 0;5=6,7=1
P 8.87208996 4.92 7 P 0 0;5=6,7=1
P 8.80121998 4.92 7 P 0 0;5=6,7=1
P 9.01381998 4.92 7 P 0 0;5=6,7=1
P 9.08468002 4.92 7 P 0 0;5=6,7=1
P 9.22641998 4.92 7 P 0 0;5=6,7=1
P 9.36815 4.926 7 P 0 0;5=6,7=1
P 9.50988002 4.92 7 P 0 0;5=6,7=1
P 9.43901004 4.928 7 P 0 0;5=6,7=1
P 9.36815 5.023 7 P 0 0;5=6,7=1
P 9.29728002 5.023 7 P 0 0;5=6,7=1
P 9.22641998 5.023 7 P 0 0;5=6,7=1
P 9.15555 5.023 7 P 0 0;5=6,7=1
P 9.50988002 5.023 7 P 0 0;5=6,7=1
P 9.43901004 5.023 7 P 0 0;5=6,7=1
P 9.58075 5.023 7 P 0 0;5=6,7=1
P 8.94853996 4.92 7 P 0 0;5=6,7=1
P 9.27853996 4.92 7 P 0 0;5=6,7=1
P 9.14353996 4.92 7 P 0 0;5=6,7=1
P 8.13811004 5.09223996 7 P 0 0;5=6,7=1
P 8.35071004 5.15373996 7 P 0 0;5=6,7=1
P 8.41071004 5.15373996 7 P 0 0;5=6,7=1
P 7.56575 4.81401998 7 P 0 0;5=6,7=1
P 8.88061998 4.70573996 7 P 0 0;5=6,7=1
P 2.45985 4.77875 12 P 0 0;5=13,7=0
P 1.51496998 4.77875 12 P 0 0;5=13,7=0
P 2.44016998 5.05826998 12 P 0 0;5=13,7=0
P 1.53465 5.05826998 12 P 0 0;5=13,7=0
P 3.60476998 4.77875 12 P 0 0;5=13,7=0
P 2.67956998 4.77875 12 P 0 0;5=13,7=0
P 3.60476998 5.05826998 12 P 0 0;5=13,7=0
P 2.69925 5.05826998 12 P 0 0;5=13,7=0
P 8.46338996 4.77875 12 P 0 0;5=13,7=0
P 7.51851004 4.77875 12 P 0 0;5=13,7=0
P 8.44371004 5.05826998 12 P 0 0;5=13,7=0
P 7.53818996 5.05826998 12 P 0 0;5=13,7=0
P 9.60831004 4.77875 12 P 0 0;5=13,7=0
P 8.68311004 4.77875 12 P 0 0;5=13,7=0
P 9.60831004 5.05826998 12 P 0 0;5=13,7=0
P 8.70278996 5.05826998 12 P 0 0;5=13,7=0
P 10.82676998 5.49685 14 P 0 0;5=14,7=0
P 10.99213002 5.49685 14 P 0 0;5=14,7=0
P 11.15748002 5.49685 14 P 0 0;5=14,7=0
P 11.32283996 5.49685 14 P 0 0;5=14,7=0
P 11.48818996 5.49685 14 P 0 0;5=14,7=0
P 11.65353996 5.49685 14 P 0 0;5=14,7=0
P 11.8189 5.49685 14 P 0 0;5=14,7=0
P 11.98425 5.49685 14 P 0 0;5=14,7=0
P 12.14961004 5.49685 28 P 0 0;3,5=15,7=0
P 10.83662215 1.50786998 31 P 0 0;5=16,7=0
P 10.83661772 1.50788002 32 P 0 0;5=16,7=0
P 8.24999774 1.50788002 32 P 0 0;5=16,7=0
P 8.25000217 1.50786998 31 P 0 0;5=16,7=0
P 6.96457215 1.52755994 31 P 0 0;5=16,7=0
P 6.96456772 1.52755994 32 P 0 0;5=16,7=0
P 6.96457215 4.20471998 31 P 0 0;5=16,7=0
P 6.96456772 4.20473002 32 P 0 0;5=16,7=0
P 8.25000217 4.22440994 31 P 0 0;5=16,7=0
P 8.24999774 4.22440994 32 P 0 0;5=16,7=0
P 10.83662215 4.22440994 31 P 0 0;5=16,7=0
P 10.83661772 4.22440994 32 P 0 0;5=16,7=0
P 12.12205217 4.20471998 31 P 0 0;5=16,7=0
P 12.12204774 4.20473002 32 P 0 0;5=16,7=0
P 12.12204774 1.52755994 32 P 0 0;5=16,7=0
P 12.12205217 1.52755994 31 P 0 0;5=16,7=0
P 11.99213002 4.20473002 7 P 0 0;5=6,7=0
P 12.03018002 4.11286004 7 P 0 0;5=6,7=0
P 12.03018002 4.2966 7 P 0 0;5=6,7=0
P 12.21391998 4.11286004 7 P 0 0;5=6,7=0
P 12.25196998 4.20473002 7 P 0 0;5=6,7=0
P 12.21391998 4.2966 7 P 0 0;5=6,7=0
P 10.7067 4.22441004 7 P 0 0;5=6,7=0
P 10.74475 4.13253996 7 P 0 0;5=6,7=0
P 10.74475 4.31628002 7 P 0 0;5=6,7=0
P 10.92848996 4.13253996 7 P 0 0;5=6,7=0
P 10.96653996 4.22441004 7 P 0 0;5=6,7=0
P 10.92848996 4.31628002 7 P 0 0;5=6,7=0
P 8.12008002 4.22441004 7 P 0 0;5=6,7=0
P 8.15813002 4.13253996 7 P 0 0;5=6,7=0
P 8.15813002 4.31628002 7 P 0 0;5=6,7=0
P 8.34186998 4.13253996 7 P 0 0;5=6,7=0
P 8.37991998 4.22441004 7 P 0 0;5=6,7=0
P 8.34186998 4.31628002 7 P 0 0;5=6,7=0
P 6.83465 4.20473002 7 P 0 0;5=6,7=0
P 6.8727 4.11286004 7 P 0 0;5=6,7=0
P 6.8727 4.2966 7 P 0 0;5=6,7=0
P 7.05643996 4.11286004 7 P 0 0;5=6,7=0
P 7.09448996 4.20473002 7 P 0 0;5=6,7=0
P 7.05643996 4.2966 7 P 0 0;5=6,7=0
P 6.83465 1.52756004 7 P 0 0;5=6,7=0
P 6.8727 1.43568996 7 P 0 0;5=6,7=0
P 6.8727 1.61943002 7 P 0 0;5=6,7=0
P 7.05643996 1.43568996 7 P 0 0;5=6,7=0
P 7.09448996 1.52756004 7 P 0 0;5=6,7=0
P 7.05643996 1.61943002 7 P 0 0;5=6,7=0
P 8.15813002 1.416 7 P 0 0;5=6,7=0
P 8.12008002 1.50786998 7 P 0 0;5=6,7=0
P 8.15813002 1.59975 7 P 0 0;5=6,7=0
P 8.34186998 1.416 7 P 0 0;5=6,7=0
P 8.34186998 1.59975 7 P 0 0;5=6,7=0
P 8.37991998 1.50786998 7 P 0 0;5=6,7=0
P 10.74475 1.59975 7 P 0 0;5=6,7=0
P 10.92848996 1.59975 7 P 0 0;5=6,7=0
P 10.96653996 1.50786998 7 P 0 0;5=6,7=0
P 10.92848996 1.416 7 P 0 0;5=6,7=0
P 10.74475 1.416 7 P 0 0;5=6,7=0
P 10.7067 1.50786998 7 P 0 0;5=6,7=0
P 12.2126 1.43701004 7 P 0 0;5=6,7=0
P 12.25196998 1.52756004 7 P 0 0;5=6,7=0
P 12.2126 1.61811004 7 P 0 0;5=6,7=0
P 12.0315 1.61811004 7 P 0 0;5=6,7=0
P 11.99213002 1.52756004 7 P 0 0;5=6,7=0
P 12.0315 1.43701004 7 P 0 0;5=6,7=0
P 4.83268219 1.50786998 31 P 0 0;5=16,7=0
P 4.83267776 1.50788002 32 P 0 0;5=16,7=0
P 2.24605778 1.50788002 32 P 0 0;5=16,7=0
P 2.2460622 1.50786998 31 P 0 0;5=16,7=0
P 0.96063219 1.52755994 31 P 0 0;5=16,7=0
P 0.96062776 1.52755994 32 P 0 0;5=16,7=0
P 0.96063219 4.20471998 31 P 0 0;5=16,7=0
P 0.96062776 4.20473002 32 P 0 0;5=16,7=0
P 2.2460622 4.22440994 31 P 0 0;5=16,7=0
P 2.24605778 4.22440994 32 P 0 0;5=16,7=0
P 4.83268219 4.22440994 31 P 0 0;5=16,7=0
P 4.83267776 4.22440994 32 P 0 0;5=16,7=0
P 6.1181122 4.20471998 31 P 0 0;5=16,7=0
P 6.11810778 4.20473002 32 P 0 0;5=16,7=0
P 6.11810778 1.52755994 32 P 0 0;5=16,7=0
P 6.1181122 1.52755994 31 P 0 0;5=16,7=0
P 5.98818996 4.20473002 7 P 0 0;5=6,7=0
P 6.02623996 4.11286004 7 P 0 0;5=6,7=0
P 6.02623996 4.2966 7 P 0 0;5=6,7=0
P 6.20998002 4.11286004 7 P 0 0;5=6,7=0
P 6.24803002 4.20473002 7 P 0 0;5=6,7=0
P 6.20998002 4.2966 7 P 0 0;5=6,7=0
P 4.70276004 4.22441004 7 P 0 0;5=6,7=0
P 4.74081004 4.13253996 7 P 0 0;5=6,7=0
P 4.74081004 4.31628002 7 P 0 0;5=6,7=0
P 4.92455 4.13253996 7 P 0 0;5=6,7=0
P 4.9626 4.22441004 7 P 0 0;5=6,7=0
P 4.92455 4.31628002 7 P 0 0;5=6,7=0
P 2.11613996 4.22441004 7 P 0 0;5=6,7=0
P 2.15418996 4.13253996 7 P 0 0;5=6,7=0
P 2.15418996 4.31628002 7 P 0 0;5=6,7=0
P 2.33793002 4.13253996 7 P 0 0;5=6,7=0
P 2.37598002 4.22441004 7 P 0 0;5=6,7=0
P 2.33793002 4.31628002 7 P 0 0;5=6,7=0
P 0.83071004 4.20473002 7 P 0 0;5=6,7=0
P 0.86876004 4.11286004 7 P 0 0;5=6,7=0
P 0.86876004 4.2966 7 P 0 0;5=6,7=0
P 1.0525 4.11286004 7 P 0 0;5=6,7=0
P 1.09055 4.20473002 7 P 0 0;5=6,7=0
P 1.0525 4.2966 7 P 0 0;5=6,7=0
P 0.83071004 1.52756004 7 P 0 0;5=6,7=0
P 0.86876004 1.43568996 7 P 0 0;5=6,7=0
P 0.86876004 1.61943002 7 P 0 0;5=6,7=0
P 1.0525 1.43568996 7 P 0 0;5=6,7=0
P 1.09055 1.52756004 7 P 0 0;5=6,7=0
P 1.0525 1.61943002 7 P 0 0;5=6,7=0
P 2.15418996 1.416 7 P 0 0;5=6,7=0
P 2.11613996 1.50786998 7 P 0 0;5=6,7=0
P 2.15418996 1.59975 7 P 0 0;5=6,7=0
P 2.33793002 1.416 7 P 0 0;5=6,7=0
P 2.33793002 1.59975 7 P 0 0;5=6,7=0
P 2.37598002 1.50786998 7 P 0 0;5=6,7=0
P 4.74081004 1.59975 7 P 0 0;5=6,7=0
P 4.92455 1.59975 7 P 0 0;5=6,7=0
P 4.9626 1.50786998 7 P 0 0;5=6,7=0
P 4.92455 1.416 7 P 0 0;5=6,7=0
P 4.74081004 1.416 7 P 0 0;5=6,7=0
P 4.70276004 1.50786998 7 P 0 0;5=6,7=0
P 6.20866004 1.43701004 7 P 0 0;5=6,7=0
P 6.24803002 1.52756004 7 P 0 0;5=6,7=0
P 6.20866004 1.61811004 7 P 0 0;5=6,7=0
P 6.02756004 1.61811004 7 P 0 0;5=6,7=0
P 5.98818996 1.52756004 7 P 0 0;5=6,7=0
P 6.02756004 1.43701004 7 P 0 0;5=6,7=0
P 12.59646998 0.8189 7 P 0 0;5=6,7=0
P 12.5571 0.72835 7 P 0 0;5=6,7=0
P 12.59646998 0.6378 7 P 0 0;5=6,7=0
P 12.68702215 0.72835 31 P 0 0;5=16,7=0
P 12.77756998 0.6378 7 P 0 0;5=6,7=0
P 12.81693996 0.72835 7 P 0 0;5=6,7=0
P 12.77756998 0.8189 7 P 0 0;5=6,7=0
P 12.68701772 0.72835 32 P 0 0;5=16,7=0
P 12.59646998 5.24803002 7 P 0 0;5=6,7=0
P 12.5571 5.15748002 7 P 0 0;5=6,7=0
P 12.59646998 5.06693002 7 P 0 0;5=6,7=0
P 12.68702215 5.15748002 31 P 0 0;5=16,7=0
P 12.77756998 5.06693002 7 P 0 0;5=6,7=0
P 12.81693996 5.15748002 7 P 0 0;5=6,7=0
P 12.77756998 5.24803002 7 P 0 0;5=6,7=0
P 12.68701772 5.15748002 32 P 0 0;5=16,7=0
P 0.1319 5.20866004 7 P 0 0;5=6,7=0
P 0.09253002 5.11811004 7 P 0 0;5=6,7=0
P 0.1319 5.02756004 7 P 0 0;5=6,7=0
P 0.22245217 5.11810994 31 P 0 0;5=16,7=0
P 0.313 5.02756004 7 P 0 0;5=6,7=0
P 0.35236998 5.11811004 7 P 0 0;5=6,7=0
P 0.313 5.20866004 7 P 0 0;5=6,7=0
P 0.22244774 5.11810994 32 P 0 0;5=16,7=0
P 0.1319 0.77953002 7 P 0 0;5=6,7=0
P 0.09253002 0.68898002 7 P 0 0;5=6,7=0
P 0.1319 0.59843002 7 P 0 0;5=6,7=0
P 0.22245217 0.68898002 31 P 0 0;5=16,7=0
P 0.313 0.59843002 7 P 0 0;5=6,7=0
P 0.35236998 0.68898002 7 P 0 0;5=6,7=0
P 0.313 0.77953002 7 P 0 0;5=6,7=0
P 0.22244774 0.68898002 32 P 0 0;5=16,7=0
P 10.80498996 5.56656004 7 P 0 0;5=6,7=1
P 10.84498996 5.56656004 7 P 0 0;5=6,7=1
P 10.80498996 5.42656004 7 P 0 0;5=6,7=1
P 10.84498996 5.42656004 7 P 0 0;5=6,7=1
P 11.01035 5.42656004 7 P 0 0;5=6,7=1
P 10.97035 5.42656004 7 P 0 0;5=6,7=1
P 11.01035 5.56656004 7 P 0 0;5=6,7=1
P 10.97035 5.56656004 7 P 0 0;5=6,7=1
P 11.17571004 5.42656004 7 P 0 0;5=6,7=1
P 11.13571004 5.42656004 7 P 0 0;5=6,7=1
P 11.17571004 5.56656004 7 P 0 0;5=6,7=1
P 11.13571004 5.56656004 7 P 0 0;5=6,7=1
P 11.34106998 5.42656004 7 P 0 0;5=6,7=1
P 11.30106998 5.42656004 7 P 0 0;5=6,7=1
P 11.34106998 5.56656004 7 P 0 0;5=6,7=1
P 11.30106998 5.56656004 7 P 0 0;5=6,7=1
P 11.50643002 5.42656004 7 P 0 0;5=6,7=1
P 11.46643002 5.42656004 7 P 0 0;5=6,7=1
P 11.50643002 5.56656004 7 P 0 0;5=6,7=1
P 11.46643002 5.56656004 7 P 0 0;5=6,7=1
P 11.67178996 5.42656004 7 P 0 0;5=6,7=1
P 11.63178996 5.42656004 7 P 0 0;5=6,7=1
P 11.67178996 5.56656004 7 P 0 0;5=6,7=1
P 11.63178996 5.56656004 7 P 0 0;5=6,7=1
P 11.83715 5.42656004 7 P 0 0;5=6,7=1
P 11.79715 5.42656004 7 P 0 0;5=6,7=1
P 11.83715 5.56656004 7 P 0 0;5=6,7=1
P 11.79715 5.56656004 7 P 0 0;5=6,7=1
P 12.00251004 5.42656004 7 P 0 0;5=6,7=1
P 11.96251004 5.42656004 7 P 0 0;5=6,7=1
P 12.00251004 5.56656004 7 P 0 0;5=6,7=1
P 11.96251004 5.56656004 7 P 0 0;5=6,7=1
P 12.16786998 5.42656004 7 P 0 0;5=6,7=1
P 12.12786998 5.42656004 7 P 0 0;5=6,7=1
P 12.16786998 5.56656004 7 P 0 0;5=6,7=1
P 12.12786998 5.56656004 7 P 0 0;5=6,7=1
P 6.645 4.83 8 P 0 0;3,5=5,7=1
P 4.755 5.03 8 P 0 0;3,5=5,7=1
P 7.32283996 0.23621998 7 P 0 0;5=6,7=0
P 7.28016998 0.33921998 7 P 0 0;5=6,7=0
P 7.17716801 0.23621998 33 P 0 0;5=17,7=0
P 7.28016998 0.13321998 7 P 0 0;5=6,7=0
P 7.17717195 0.23621998 34 P 0 0;5=17,7=0
P 7.07416998 0.13321998 7 P 0 0;5=6,7=0
P 7.0315 0.23621998 7 P 0 0;5=6,7=0
P 7.07416998 0.33921998 7 P 0 0;5=6,7=0
P 7.32283996 5.7874 7 P 0 0;5=6,7=0
P 7.28016998 5.8904 7 P 0 0;5=6,7=0
P 7.17716801 5.7874 33 P 0 0;5=17,7=0
P 7.28016998 5.6844 7 P 0 0;5=6,7=0
P 7.17717195 5.7874 34 P 0 0;5=17,7=0
P 7.07416998 5.6844 7 P 0 0;5=6,7=0
P 7.0315 5.7874 7 P 0 0;5=6,7=0
P 7.07416998 5.8904 7 P 0 0;5=6,7=0
S P 0
OB 4.26 4.905 I
OS 4.25 4.915
OS 4.25 5.135
OS 4.265 5.15
OS 4.855 5.15
OS 4.87 5.135
OS 4.87 4.915
OS 4.86 4.905
OS 4.26 4.905
OE
SE
S P 0
OB 10.78 5.565 I
OS 10.8 5.585
OS 12.19 5.585
OS 12.205 5.57
OS 12.205 5.42
OS 12.19 5.405
OS 10.8 5.405
OS 10.78 5.425
OS 10.78 5.565
OE
SE
S P 0
OB 6.96118996063 4.7093 I
OS 6.89018996063 4.7093
OS 6.88618996063 4.7133
OS 6.88618996063 4.84505
OS 6.89318996063 4.85205
OS 6.96618996063 4.85205
OS 6.97118996063 4.84705
OS 6.97118996063 4.7193
OS 6.96118996063 4.7093
OE
SE
S P 0
OB 6.57918996063 4.60405 I
OS 6.57918996063 4.95705
OS 6.58918996063 4.96705
OS 6.62495 4.96705
OS 6.68643996063 4.90556003937
OS 6.68643996063 4.60205
OS 6.68143996063 4.59705
OS 6.58618996063 4.59705
OS 6.57918996063 4.60405
OE
SE
S P 0
OB 6.24708996063 4.9102 I
OS 6.25208996063 4.9152
OS 6.32708996063 4.9152
OS 6.33708996063 4.9052
OS 6.33708996063 4.6152
OS 6.32908996063 4.6072
OS 6.25508996063 4.6072
OS 6.24708996063 4.6152
OS 6.24708996063 4.9102
OE
SE
S P 0
OB 6.10808996063 4.5742 I
OS 6.10808996063 4.5062
OS 6.06188996063 4.46
OS 5.575 4.46
OS 5.56208996063 4.47291003937
OS 5.56208996063 4.5702
OS 5.57208996063 4.5802
OS 6.10208996063 4.5802
OS 6.10808996063 4.5742
OE
SE
S P 0
OB 11.38778996063 2.93 I
OS 11.38178996063 2.936
OS 11.38178996063 3.305
OS 11.38678996063 3.31
OS 11.45778996063 3.31
OS 11.46278996063 3.305
OS 11.46278996063 2.94
OS 11.45278996063 2.93
OS 11.38778996063 2.93
OE
SE
S P 0
OB 5.38386003937 2.93 I
OS 5.37786003937 2.936
OS 5.37786003937 3.305
OS 5.38286003937 3.31
OS 5.45386003937 3.31
OS 5.45886003937 3.305
OS 5.45886003937 2.94
OS 5.44886003937 2.93
OS 5.38386003937 2.93
OE
SE
L 2.24606004 3.56615 2.22106004 3.54115 3 P 0 
L 2.22106004 3.54115 1.95885 3.54115 3 P 0 
L 1.95885 3.54115 1.94 3.56 3 P 0 
L 1.94 3.56 1.9 3.56 3 P 0 
L 1.9 3.56 1.857 3.56 3 P 0 
P 1.857 3.56 25 P 0 0;2,5=0,7=0
P 2.24606004 3.56615 6 P 0 0;5=4,7=1
P 1.9 3.56 8 P 0 0;3,5=5,7=1
P 8.2 3.26615 6 P 0 0;5=4,7=1
P 7.65203996 5.0535 6 P 0 0;5=4,7=1
P 2.29606004 2.86615 6 P 0 0;5=4,7=1
P 2.63685 2.87 25 P 0 0;2,5=0,7=0
L 2.63685 2.87 2.61795 2.8511 2 P 0 
L 2.61795 2.8511 2.5571 2.8511 2 P 0 
L 2.5571 2.8511 2.5527 2.8467 2 P 0 
L 2.5527 2.8467 2.28261004 2.8467 2 P 0 
L 2.28261004 2.8467 2.27661004 2.8527 2 P 0 
L 2.27661004 2.8527 2.27661004 2.86015 2 P 0 
L 2.27661004 2.86015 2.28261004 2.86615 2 P 0 
L 2.28261004 2.86615 2.29606004 2.86615 2 P 0 
P 1.857 3.51 25 P 0 0;2,5=0,7=0
P 2.29606004 3.56615 6 P 0 0;5=4,7=1
L 1.857 3.51 1.9 3.51 3 P 0 
P 1.9 3.51 8 P 0 0;3,5=5,7=1
L 2.29606004 3.56615 2.27106004 3.54115 3 P 0 
L 2.27106004 3.54115 2.27106004 3.40578996 3 P 0 
L 2.27106004 3.40578996 2.25641998 3.39115 3 P 0 
L 2.25641998 3.39115 1.98085 3.39115 3 P 0 
L 1.98085 3.39115 1.96 3.412 3 P 0 
L 1.96 3.412 1.96 3.465 3 P 0 
L 1.96 3.465 1.915 3.51 3 P 0 
L 1.915 3.51 1.9 3.51 3 P 0 
P 7.69203996 5.0535 6 P 0 0;5=4,7=1
P 8.2 3.31615 6 P 0 0;5=4,7=1
P 1.33906004 4.69351004 8 P 0 0;3,5=1,7=1
P 1.31906004 4.94151004 25 P 0 0;2,5=0,7=0
P 1.823 3.56 25 P 0 0;2,5=0,7=0
L 1.31906004 4.94151004 1.307 4.92945 3 P 0 
L 1.307 4.92945 1.307 4.88701004 3 P 0 
L 1.307 4.88701004 1.289 4.86901004 3 P 0 
L 1.289 4.86901004 1.289 4.80601004 3 P 0 
L 1.289 4.80601004 1.327 4.76801004 3 P 0 
L 1.327 4.76801004 1.327 4.70556998 3 P 0 
L 1.327 4.70556998 1.33906004 4.69351004 3 P 0 
L 1.33906004 4.69351004 1.327 4.68145 3 P 0 
L 1.327 4.68145 1.327 4.646 3 P 0 
L 1.327 4.646 1.30066004 4.61966004 3 P 0 
L 1.30066004 4.61966004 1.30066004 3.98835 3 P 0 
L 1.30066004 3.98835 1.74241004 3.5466 3 P 0 
L 1.74241004 3.5466 1.8096 3.5466 3 P 0 
L 1.8096 3.5466 1.823 3.56 3 P 0 
P 0.80806998 5.46193996 8 P 0 0;3,5=1,7=1
L 0.80806998 5.46193996 0.90213002 5.556 3 P 0 
L 0.90213002 5.556 3.37568002 5.556 3 P 0 
L 3.37568002 5.556 3.733 5.19868002 3 P 0 
L 3.733 5.19868002 3.733 5.075 3 P 0 
P 3.733 5.075 7 P 0 0;5=6,7=1
L 1.26906004 4.94151004 1.2813 4.92926998 3 P 0 
L 1.2813 4.92926998 1.2813 4.89766004 3 P 0 
L 1.2813 4.89766004 1.2633 4.87966004 3 P 0 
L 1.2633 4.87966004 1.2633 4.79536004 3 P 0 
L 1.2633 4.79536004 1.3013 4.75736004 3 P 0 
L 1.3013 4.75736004 1.3013 4.70575 3 P 0 
L 1.3013 4.70575 1.28906004 4.69351004 3 P 0 
P 1.28906004 4.69351004 8 P 0 0;3,5=1,7=1
P 1.26906004 4.94151004 25 P 0 0;2,5=0,7=0
P 1.823 3.51 25 P 0 0;2,5=0,7=0
L 1.28906004 4.69351004 1.3013 4.68126998 3 P 0 
L 1.3013 4.68126998 1.3013 4.65665 3 P 0 
L 1.3013 4.65665 1.27496004 4.63031004 3 P 0 
L 1.27496004 4.63031004 1.27496004 3.9777 3 P 0 
L 1.27496004 3.9777 1.73176004 3.5209 3 P 0 
L 1.73176004 3.5209 1.8121 3.5209 3 P 0 
L 1.8121 3.5209 1.823 3.51 3 P 0 
P 8.2 3.41615 6 P 0 0;5=4,7=1
P 7.86465 5.169 6 P 0 0;5=4,7=1
P 3.94 4.765 8 P 0 0;3,5=1,7=1
P 2.34606004 3.26615 6 P 0 0;5=4,7=1
P 2.39716998 4.742 6 P 0 0;5=4,7=1
P 8.2 3.46615 6 P 0 0;5=4,7=1
P 7.90465 5.169 6 P 0 0;5=4,7=1
L 2.06646004 5.343 2.06646004 5.29 3 P 0 
P 2.06646004 5.343 25 P 0 0;2,5=0,7=0
L 2.06646004 5.343 2.11646004 5.343 3 P 0 
P 2.11646004 5.343 25 P 0 0;2,5=0,7=0
P 2.06646004 5.29 8 P 0 0;3,5=1,7=1
P 2.34606004 3.31615 6 P 0 0;5=4,7=1
P 2.35716998 4.742 6 P 0 0;5=4,7=1
L 3.11 4.508 3.11 4.475 3 P 0 
L 3.11 4.475 3.105 4.47 3 P 0 
P 1.33906004 5.15351004 8 P 0 0;3,5=1,7=1
P 3.105 4.47 7 P 0 0;5=6,7=1
P 3.11 4.508 25 P 0 0;2,5=0,7=0
L 1.33906004 5.15351004 1.33906004 5.09728002 3 P 0 
L 1.33906004 5.09728002 1.42 5.01633996 3 P 0 
L 1.42 5.01633996 1.42 4.50856998 3 P 0 
L 1.42 4.50856998 1.52756998 4.401 3 P 0 
L 1.52756998 4.401 2.03111004 4.401 3 P 0 
L 2.03111004 4.401 2.13311004 4.503 3 P 0 
L 2.13311004 4.503 3.02335 4.503 3 P 0 
L 3.02335 4.503 3.05635 4.47 3 P 0 
L 3.05635 4.47 3.105 4.47 3 P 0 
P 8 3.46615 6 P 0 0;5=4,7=1
P 7.93551004 5.0535 6 P 0 0;5=4,7=1
L 2.00146004 5.343 2.00146004 5.29 3 P 0 
L 2.00146004 5.343 1.95146004 5.343 3 P 0 
P 2.00146004 5.343 25 P 0 0;2,5=0,7=0
P 1.95146004 5.343 25 P 0 0;2,5=0,7=0
P 2.00146004 5.29 8 P 0 0;3,5=1,7=1
P 2.25855 4.667 6 P 0 0;5=4,7=1
P 2.39606004 3.31615 6 P 0 0;5=4,7=1
P 3.16 4.508 25 P 0 0;2,5=0,7=0
L 3.07 4.42 3.115 4.42 3 P 0 
L 3.115 4.42 3.16 4.465 3 P 0 
L 3.16 4.465 3.16 4.508 3 P 0 
P 1.18906004 5.15351004 8 P 0 0;3,5=1,7=1
P 3.07 4.42 7 P 0 0;5=6,7=1
L 3.07 4.42 3.0127 4.4773 3 P 0 
L 3.0127 4.4773 2.14376004 4.4773 3 P 0 
L 2.14376004 4.4773 2.04176004 4.3753 3 P 0 
L 2.04176004 4.3753 1.51691998 4.3753 3 P 0 
L 1.51691998 4.3753 1.3943 4.49791998 3 P 0 
L 1.3943 4.49791998 1.3943 5.00568996 3 P 0 
L 1.3943 5.00568996 1.28498996 5.115 3 P 0 
L 1.28498996 5.115 1.22756998 5.115 3 P 0 
L 1.22756998 5.115 1.18906004 5.15351004 3 P 0 
P 8 3.51615 6 P 0 0;5=4,7=1
P 7.97551004 5.0535 6 P 0 0;5=4,7=1
P 2.21855 4.667 6 P 0 0;5=4,7=1
P 2.39606004 3.36615 6 P 0 0;5=4,7=1
P 8.11725 5.169 6 P 0 0;5=4,7=1
P 8.4 3.46615 6 P 0 0;5=4,7=1
L 3.635 0.715 3.635 2.65001004 3 P 0 
L 3.635 2.65001004 3.83998996 2.855 3 P 0 
L 3.83998996 2.855 4.522 2.855 3 P 0 
L 4.522 2.855 4.53585 2.84115 3 P 0 
L 4.53585 2.84115 4.59303996 2.84115 3 P 0 
L 4.59303996 2.84115 4.59318996 2.841 3 P 0 
L 4.59318996 2.841 4.60783002 2.841 3 P 0 
L 4.60783002 2.841 4.63268002 2.81615 3 P 0 
P 3.635 0.715 8 P 0 0;3,5=1,7=1
P 4.63268002 2.81615 6 P 0 0;5=4,7=1
P 2.44606004 3.26615 6 P 0 0;5=4,7=1
P 2.39716998 5.115 6 P 0 0;5=4,7=1
P 8.07725 5.169 6 P 0 0;5=4,7=1
P 8.4 3.51615 6 P 0 0;5=4,7=1
P 2.44606004 3.31615 6 P 0 0;5=4,7=1
P 2.35716998 5.115 6 P 0 0;5=4,7=1
P 8.5 3.46615 6 P 0 0;5=4,7=1
P 8.07206998 4.66688996 6 P 0 0;5=4,7=1
P 2.25543996 4.78291998 6 P 0 0;5=4,7=1
P 2.49606004 3.31615 6 P 0 0;5=4,7=1
P 8.5 3.51615 6 P 0 0;5=4,7=1
P 8.03206998 4.66688996 6 P 0 0;5=4,7=1
P 4.02 4.42 8 P 0 0;3,5=1,7=1
P 4.58268002 2.76615 6 P 0 0;5=4,7=1
P 2.21543996 4.78291998 6 P 0 0;5=4,7=1
P 2.49606004 3.36615 6 P 0 0;5=4,7=1
P 8.35 3.41615 6 P 0 0;5=4,7=1
P 8.11725 4.78291998 6 P 0 0;5=4,7=1
L 5.56 2.82 5.63848996 2.82 3 P 0 
L 5.63848996 2.82 5.64668996 2.8118 3 P 0 
L 5.64668996 2.8118 5.64668996 2.785 3 P 0 
P 4.78268002 2.71615 6 P 0 0;5=4,7=1
P 5.71638002 2.82441004 30 P 0 0;2,5=8,7=0
P 5.64668996 2.785 25 P 0 0;2,5=0,7=0
L 5.64668996 2.785 5.66468996 2.785 3 P 0 
L 5.66468996 2.785 5.7041 2.82441004 3 P 0 
L 5.7041 2.82441004 5.71638002 2.82441004 3 P 0 
P 5.56 2.82 8 P 0 0;3,5=5,7=1
L 4.78268002 2.71615 4.83683996 2.71615 3 P 0 
L 4.83683996 2.71615 4.86183996 2.69115 3 P 0 
L 4.86183996 2.69115 4.95015 2.69115 3 P 0 
L 4.95015 2.69115 4.95768002 2.69868002 3 P 0 
L 4.95768002 2.69868002 4.95768002 2.72651004 3 P 0 
L 4.95768002 2.72651004 4.97231998 2.74115 3 P 0 
L 4.97231998 2.74115 5.09303996 2.74115 3 P 0 
L 5.09303996 2.74115 5.2294 2.87751004 3 P 0 
L 5.2294 2.87751004 5.4775 2.87751004 3 P 0 
L 5.4775 2.87751004 5.53501004 2.82 3 P 0 
L 5.53501004 2.82 5.56 2.82 3 P 0 
P 2.11371004 4.78291998 6 P 0 0;5=4,7=1
P 2.34606004 3.41615 6 P 0 0;5=4,7=1
P 8.35 3.46615 6 P 0 0;5=4,7=1
P 8.07725 4.78291998 6 P 0 0;5=4,7=1
P 5.08268002 2.71615 6 P 0 0;5=4,7=1
P 4.06 4.86 8 P 0 0;3,5=1,7=1
P 2.07371004 4.78291998 6 P 0 0;5=4,7=1
P 2.34606004 3.46615 6 P 0 0;5=4,7=1
P 2.18456998 5.0535 6 P 0 0;5=4,7=1
P 2.44606004 3.41615 6 P 0 0;5=4,7=1
P 10.93661004 2.41615 6 P 0 0;5=4,7=1
P 11.62193002 2.61 25 P 0 0;2,5=0,7=0
L 10.93661004 2.41615 10.93661004 2.4296 2 P 0 
L 10.93661004 2.4296 10.94261004 2.4356 2 P 0 
L 10.94261004 2.4356 10.95466004 2.4356 2 P 0 
L 10.95466004 2.4356 10.96716004 2.4481 2 P 0 
L 10.96716004 2.4481 10.96716004 2.5296 2 P 0 
L 10.96716004 2.5296 10.97316004 2.5356 2 P 0 
L 10.97316004 2.5356 11.08956998 2.5356 2 P 0 
L 11.08956998 2.5356 11.23643996 2.56151004 2 P 0 
L 11.23643996 2.56151004 11.31176004 2.61423996 2 P 0 
L 11.31176004 2.61423996 11.38098002 2.62645 2 P 0 
L 11.38098002 2.62645 11.60448002 2.62645 2 P 0 
L 11.60448002 2.62645 11.62093002 2.61 2 P 0 
L 11.62093002 2.61 11.62193002 2.61 2 P 0 
P 2.14456998 5.0535 6 P 0 0;5=4,7=1
P 2.44606004 3.46615 6 P 0 0;5=4,7=1
P 10.93661004 2.46615 6 P 0 0;5=4,7=1
P 11.62193002 2.655 25 P 0 0;2,5=0,7=0
L 10.93661004 2.46615 10.93661004 2.4527 2 P 0 
L 10.93661004 2.4527 10.94261004 2.4467 2 P 0 
L 10.94261004 2.4467 10.95006004 2.4467 2 P 0 
L 10.95006004 2.4467 10.95606004 2.4527 2 P 0 
L 10.95606004 2.4527 10.95606004 2.5342 2 P 0 
L 10.95606004 2.5342 10.96856004 2.5467 2 P 0 
L 10.96856004 2.5467 11.08858996 2.5467 2 P 0 
L 11.08858996 2.5467 11.23208996 2.57201998 2 P 0 
L 11.23208996 2.57201998 11.3074 2.62475 2 P 0 
L 11.3074 2.62475 11.38 2.63755 2 P 0 
L 11.38 2.63755 11.60448002 2.63755 2 P 0 
L 11.60448002 2.63755 11.62193002 2.655 2 P 0 
P 8.5 3.31615 6 P 0 0;5=4,7=1
P 8.25898002 4.78291998 6 P 0 0;5=4,7=1
P 4.88268002 2.71615 6 P 0 0;5=4,7=1
L 5.71638002 2.87558996 5.70661998 2.87558996 3 P 0 
L 5.70661998 2.87558996 5.67721004 2.905 3 P 0 
L 5.67721004 2.905 5.64668996 2.905 3 P 0 
P 5.71638002 2.87558996 30 P 0 0;2,5=8,7=0
P 5.64668996 2.905 25 P 0 0;2,5=0,7=0
P 5.56 2.955 8 P 0 0;3,5=5,7=1
L 5.64668996 2.905 5.64668996 2.94331004 3 P 0 
L 5.64668996 2.94331004 5.635 2.955 3 P 0 
L 5.635 2.955 5.56 2.955 3 P 0 
L 5.56 2.955 5.535 2.955 3 P 0 
L 5.535 2.955 5.48955 2.90955 3 P 0 
L 5.48955 2.90955 5.21145 2.90955 3 P 0 
L 5.21145 2.90955 5.09305 2.79115 3 P 0 
L 5.09305 2.79115 4.92231998 2.79115 3 P 0 
L 4.92231998 2.79115 4.90768002 2.77651004 3 P 0 
L 4.90768002 2.77651004 4.90768002 2.74115 3 P 0 
L 4.90768002 2.74115 4.88268002 2.71615 3 P 0 
P 2.06853002 4.66688996 6 P 0 0;5=4,7=1
P 2.49606004 3.46615 6 P 0 0;5=4,7=1
P 8.5 3.36615 6 P 0 0;5=4,7=1
P 8.21898002 4.78291998 6 P 0 0;5=4,7=1
P 2.02853002 4.66688996 6 P 0 0;5=4,7=1
P 2.49606004 3.51615 6 P 0 0;5=4,7=1
P 8.4 3.31615 6 P 0 0;5=4,7=1
P 8.26208996 4.667 6 P 0 0;5=4,7=1
P 2.11371004 5.169 6 P 0 0;5=4,7=1
P 2.39606004 3.46615 6 P 0 0;5=4,7=1
P 8.4 3.36615 6 P 0 0;5=4,7=1
P 8.22208996 4.667 6 P 0 0;5=4,7=1
P 3.84 0.69 8 P 0 0;3,5=1,7=1
P 4.68268002 2.76615 6 P 0 0;5=4,7=1
L 3.84 0.69 3.84 0.705 3 P 0 
L 3.84 0.705 3.815 0.73 3 P 0 
L 3.815 0.73 3.815 2.67088996 3 P 0 
L 3.815 2.67088996 3.90411004 2.76 3 P 0 
L 3.90411004 2.76 4.435 2.76 3 P 0 
L 4.435 2.76 4.45385 2.74115 3 P 0 
L 4.45385 2.74115 4.65768002 2.74115 3 P 0 
L 4.65768002 2.74115 4.68268002 2.76615 3 P 0 
P 2.07371004 5.169 6 P 0 0;5=4,7=1
P 2.39606004 3.51615 6 P 0 0;5=4,7=1
P 3.56 0.49 8 P 0 0;3,5=1,7=1
P 4.73268002 2.81615 6 P 0 0;5=4,7=1
L 3.56 0.49 3.56 2.665 3 P 0 
L 3.56 2.665 3.86 2.965 3 P 0 
L 3.86 2.965 4.17 2.965 3 P 0 
L 4.17 2.965 4.212 2.923 3 P 0 
L 4.212 2.923 4.526 2.923 3 P 0 
L 4.526 2.923 4.55785 2.89115 3 P 0 
L 4.55785 2.89115 4.65768002 2.89115 3 P 0 
L 4.65768002 2.89115 4.73268002 2.81615 3 P 0 
P 1.57765 5.169 6 P 0 0;5=4,7=1
P 2.04606004 3.31615 6 P 0 0;5=4,7=1
L 7.3426 5.15351004 7.3426 5.10176004 3 P 0 
L 7.3426 5.10176004 7.42653996 5.01781998 3 P 0 
L 7.42653996 5.01781998 7.42653996 4.50981004 3 P 0 
L 7.42653996 4.50981004 7.55635 4.38 3 P 0 
L 7.55635 4.38 8.01165 4.38 3 P 0 
L 8.01165 4.38 8.13465 4.503 3 P 0 
L 8.13465 4.503 9.01735 4.503 3 P 0 
L 9.01735 4.503 9.05035 4.47 3 P 0 
L 9.05035 4.47 9.10853996 4.47 3 P 0 
P 9.10853996 4.47 7 P 0 0;5=6,7=1
P 7.3426 5.15351004 8 P 0 0;3,5=1,7=1
P 9.11353996 4.508 25 P 0 0;2,5=0,7=0
L 9.11353996 4.508 9.11353996 4.475 3 P 0 
L 9.11353996 4.475 9.10853996 4.47 3 P 0 
P 3.785 0.69 8 P 0 0;3,5=1,7=1
P 4.78268002 2.81615 6 P 0 0;5=4,7=1
L 3.785 0.69 3.785 2.68161004 3 P 0 
L 3.785 2.68161004 3.88938996 2.786 3 P 0 
L 3.88938996 2.786 4.53621004 2.786 3 P 0 
L 4.53621004 2.786 4.54136004 2.79115 3 P 0 
L 4.54136004 2.79115 4.75768002 2.79115 3 P 0 
L 4.75768002 2.79115 4.78268002 2.81615 3 P 0 
P 1.61765 5.169 6 P 0 0;5=4,7=1
P 2.04606004 3.36615 6 P 0 0;5=4,7=1
P 8.1 3.26615 6 P 0 0;5=4,7=1
P 7.58118996 4.707 6 P 0 0;5=4,7=1
P 2.09606004 3.26615 6 P 0 0;5=4,7=1
P 1.57765 4.707 6 P 0 0;5=4,7=1
P 5.08268002 1.96615 6 P 0 0;5=4,7=1
L 5.46358002 1.8533 5.44663002 1.83635 2 P 0 
L 5.44663002 1.83635 5.21765 1.83635 2 P 0 
L 5.21765 1.83635 5.134 1.92 2 P 0 
L 5.134 1.92 5.134 1.92798996 2 P 0 
L 5.134 1.92798996 5.11528996 1.9467 2 P 0 
L 5.11528996 1.9467 5.08868002 1.9467 2 P 0 
L 5.08868002 1.9467 5.08268002 1.9527 2 P 0 
L 5.08268002 1.9527 5.08268002 1.96615 2 P 0 
P 5.46358002 1.8533 25 P 0 0;2,5=0,7=0
P 8.1 3.31615 6 P 0 0;5=4,7=1
P 7.62118996 4.707 6 P 0 0;5=4,7=1
P 3.75998996 0.345 8 P 0 0;3,5=1,7=1
P 4.68268002 2.81615 6 P 0 0;5=4,7=1
L 4.68268002 2.81615 4.63283002 2.866 3 P 0 
L 4.63283002 2.866 4.54501004 2.866 3 P 0 
L 4.54501004 2.866 4.53031004 2.8807 3 P 0 
L 4.53031004 2.8807 3.82068996 2.8807 3 P 0 
L 3.82068996 2.8807 3.6 2.66001004 3 P 0 
L 3.6 2.66001004 3.6 0.73211998 3 P 0 
L 3.6 0.73211998 3.59815 0.73026998 3 P 0 
L 3.59815 0.73026998 3.59815 0.69973002 3 P 0 
L 3.59815 0.69973002 3.6 0.69788002 3 P 0 
L 3.6 0.69788002 3.6 0.50711998 3 P 0 
L 3.6 0.50711998 3.59815 0.50526998 3 P 0 
L 3.59815 0.50526998 3.59815 0.47473002 3 P 0 
L 3.59815 0.47473002 3.6 0.47288002 3 P 0 
L 3.6 0.47288002 3.6 0.405 3 P 0 
L 3.6 0.405 3.61 0.395 3 P 0 
L 3.61 0.395 3.70998996 0.395 3 P 0 
L 3.70998996 0.395 3.75998996 0.345 3 P 0 
P 2.09606004 3.31615 6 P 0 0;5=4,7=1
P 1.61765 4.707 6 P 0 0;5=4,7=1
L 7.42603996 5.15895 7.42603996 5.07395 7 P 0 
L 7.42603996 5.07395 7.45853996 5.04145 7 P 0 
L 7.45853996 5.04145 7.45853996 4.605 7 P 0 
L 7.45853996 4.605 7.50153996 4.562 7 P 0 
L 7.50153996 4.562 7.82853996 4.562 7 P 0 
P 0.58 5.591 8 P 0 0;3,5=1,7=1
L 1.38906004 5.15351004 1.38906004 5.10238996 7 P 0 
L 1.38906004 5.10238996 1.455 5.03645 7 P 0 
L 1.455 5.03645 1.455 4.605 7 P 0 
L 1.455 4.605 1.498 4.562 7 P 0 
L 1.498 4.562 1.825 4.562 7 P 0 
L 1.88 4.562 1.825 4.562 7 P 0 
L 2.00146004 5.377 2.00146004 5.41653996 7 P 0 
L 2.00146004 5.41653996 2.001 5.417 7 P 0 
L 2.06646004 5.417 2.001 5.417 7 P 0 
L 2.06646004 5.417 2.06646004 5.377 7 P 0 
L 3.14146004 5.385 2.32746004 5.385 7 P 0 
L 2.32746004 5.385 2.29546004 5.417 7 P 0 
L 2.29546004 5.417 2.06646004 5.417 7 P 0 
L 3.14146004 5.385 3.14146004 5.332 7 P 0 
P 2.06646004 5.377 25 P 0 0;2,5=0,7=0
P 3.33646004 5.332 25 P 0 0;2,5=0,7=0
P 3.18646004 5.332 25 P 0 0;2,5=0,7=0
L 3.19146004 5.385 3.14146004 5.385 7 P 0 
P 3.14146004 5.332 25 P 0 0;2,5=0,7=0
L 3.19146004 5.385 3.31646004 5.385 7 P 0 
L 3.31646004 5.385 3.33646004 5.365 7 P 0 
L 3.33646004 5.365 3.33646004 5.332 7 P 0 
L 3.19146004 5.385 3.18646004 5.38 7 P 0 
L 3.18646004 5.38 3.18646004 5.332 7 P 0 
P 2.00146004 5.377 25 P 0 0;2,5=0,7=0
L 8.005 5.417 7.451 5.417 7 P 0 
L 7.451 5.417 7.42603996 5.39203996 7 P 0 
L 7.42603996 5.39203996 7.42603996 5.15895 7 P 0 
L 8.005 5.417 8.07 5.417 7 P 0 
L 8.07 5.377 8.07 5.417 7 P 0 
L 8.07 5.417 8.299 5.417 7 P 0 
L 8.299 5.417 8.331 5.385 7 P 0 
L 8.331 5.385 9.145 5.385 7 P 0 
L 9.145 5.385 9.195 5.385 7 P 0 
P 9.34 5.332 25 P 0 0;2,5=0,7=0
P 9.19 5.332 25 P 0 0;2,5=0,7=0
P 11.65061998 2.855 25 P 0 0;2,5=0,7=0
P 11.72031004 2.85 30 P 0 0;2,5=8,7=0
P 11.67761998 2.85 7 P 0 0;5=6,7=1
L 11.72031004 2.85 11.67761998 2.85 5 P 0 
L 11.65061998 2.855 11.67261998 2.855 5 P 0 
L 11.67261998 2.855 11.67761998 2.85 5 P 0 
P 11.865 4.455 8 P 0 0;3,5=1,7=1
L 9.195 5.385 9.34 5.385 7 P 0 
P 9.145 5.332 25 P 0 0;2,5=0,7=0
L 9.34 5.332 9.34 5.385 7 P 0 
L 9.19 5.332 9.19 5.38 7 P 0 
L 9.19 5.38 9.195 5.385 7 P 0 
L 9.145 5.332 9.145 5.385 7 P 0 
P 8.005 5.377 25 P 0 0;2,5=0,7=0
L 8.005 5.377 8.005 5.417 5 P 0 
P 8.07 5.377 25 P 0 0;2,5=0,7=0
P 5.71638002 2.85 30 P 0 0;2,5=8,7=0
P 5.67368996 2.85 7 P 0 0;5=6,7=1
P 5.64668996 2.855 25 P 0 0;2,5=0,7=0
L 5.64668996 2.855 5.66868996 2.855 5 P 0 
L 5.66868996 2.855 5.67368996 2.85 5 P 0 
L 5.71638002 2.85 5.67368996 2.85 5 P 0 
P 5.855 3.07 7 P 0 0;5=6,7=1
P 5.883 3.07 25 P 0 0;2,5=0,7=0
L 5.883 3.07 5.855 3.07 5 P 0 
P 5.883 2.97 25 P 0 0;2,5=0,7=0
L 5.80255 2.97441004 5.83778996 2.97441004 5 P 0 
L 5.83778996 2.97441004 5.8422 2.97 5 P 0 
L 5.8422 2.97 5.8522 2.97 5 P 0 
P 5.8522 2.97 7 P 0 0;5=6,7=1
P 5.80255 2.97441004 30 P 0 0;2,5=8,7=0
L 5.883 2.97 5.8522 2.97 7 P 0 
P 7.2926 5.15351004 7 P 0 0;5=6,7=1
P 7.2426 5.15351004 7 P 0 0;5=6,7=1
P 7.1926 4.95351004 7 P 0 0;5=6,7=1
P 7.42603996 5.15895 8 P 0 0;3,5=1,7=1
P 3.94 4.655 7 P 0 0;5=6,7=1
P 3.77 4.765 7 P 0 0;5=6,7=1
P 4.14 4.745 7 P 0 0;5=6,7=1
P 4.76 5.375 7 P 0 0;5=6,7=1
P 4.96 5.5 7 P 0 0;5=6,7=1
P 5.16 5.555 7 P 0 0;5=6,7=1
P 4.892 5.767 7 P 0 0;5=6,7=1
P 5.088 5.767 7 P 0 0;5=6,7=1
P 0.91 5.075 7 P 0 0;5=6,7=1
P 1.03 4.96 7 P 0 0;5=6,7=1
P 1.03 5.155 7 P 0 0;5=6,7=1
P 1.38906004 5.15351004 8 P 0 0;3,5=1,7=1
P 1.23906004 5.15351004 7 P 0 0;5=6,7=1
P 1.28906004 5.15351004 7 P 0 0;5=6,7=1
P 1.18906004 4.95351004 7 P 0 0;5=6,7=1
P 0.83 5.355 7 P 0 0;5=6,7=1
P 0.9 5.355 7 P 0 0;5=6,7=1
P 0.755 5.355 7 P 0 0;5=6,7=1
P 0.73 5.205 7 P 0 0;5=6,7=1
P 0.81016004 5.17 7 P 0 0;5=6,7=1
P 1.094 5.356 8 P 0 0;3,5=1,7=1
P 1.044 5.448 7 P 0 0;5=6,7=1
P 1.4 5.46 7 P 0 0;5=6,7=1
P 1.32 5.46 7 P 0 0;5=6,7=1
P 1.43798996 5.46016004 7 P 0 0;5=6,7=1
P 1.35925 5.46016004 7 P 0 0;5=6,7=1
P 0.89 5.885 7 P 0 0;5=6,7=1
P 0.81 5.885 7 P 0 0;5=6,7=1
P 0.73 5.885 7 P 0 0;5=6,7=1
P 0.97 5.885 7 P 0 0;5=6,7=1
P 1.04 5.885 7 P 0 0;5=6,7=1
P 1.12 5.885 7 P 0 0;5=6,7=1
L 2.001 5.417 1.622 5.417 7 P 0 
L 1.622 5.417 1.38906004 5.18406004 7 P 0 
L 1.38906004 5.18406004 1.38906004 5.15351004 7 P 0 
P 1.825 4.562 25 P 0 0;2,5=0,7=0
P 1.88 4.562 25 P 0 0;2,5=0,7=0
L 7.88353996 4.562 7.82853996 4.562 7 P 0 
P 7.88353996 4.562 25 P 0 0;2,5=0,7=0
P 7.82853996 4.562 25 P 0 0;2,5=0,7=0
L 11.865 4.455 12.185 4.455 7 P 0 
L 12.185 4.455 12.275 4.545 7 P 0 
L 12.275 4.545 12.275 5.05 7 P 0 
L 12.275 5.05 12.565 5.34 7 P 0 
L 12.565 5.34 12.565 5.885 7 P 0 
L 12.565 5.885 12.52 5.93 7 P 0 
L 12.52 5.93 9.465 5.93 7 P 0 
L 9.465 5.93 9.34 5.805 7 P 0 
L 9.34 5.805 9.34 5.385 7 P 0 
P 8.15 3.31615 6 P 0 0;5=4,7=1
P 7.65205 4.78291998 6 P 0 0;5=4,7=1
P 5.917 3.02 25 P 0 0;2,5=0,7=0
L 5.917 3.07 5.917 3.02 3 P 0 
P 5.917 3.07 25 P 0 0;2,5=0,7=0
P 11.80693002 2.82441004 30 P 0 0;2,5=8,7=0
P 5.803 2.82441004 30 P 0 0;2,5=8,7=0
P 11.235 3.3 7 P 0 0;5=6,7=1
L 11.235 3.3 11.28 3.345 3 P 0 
L 11.28 3.345 11.867 3.345 3 P 0 
L 11.867 3.345 11.905 3.307 3 P 0 
L 11.905 3.307 11.905 3.195 3 P 0 
L 11.905 3.195 11.765 3.055 3 P 0 
L 11.765 3.055 11.765 2.83291004 3 P 0 
L 11.765 2.83291004 11.7735 2.82441004 3 P 0 
L 11.7735 2.82441004 11.80693002 2.82441004 3 P 0 
P 5.815 0.925 8 P 0 0;3,5=1,7=1
L 5.803 2.82441004 5.81558996 2.82441004 3 P 0 
L 5.81558996 2.82441004 5.826 2.814 3 P 0 
L 5.826 2.814 5.949 2.814 3 P 0 
L 5.949 2.814 5.9622 2.8272 3 P 0 
L 5.9622 2.8272 5.9622 3.01 3 P 0 
L 5.9622 3.01 5.9522 3.02 3 P 0 
L 5.9522 3.02 5.917 3.02 3 P 0 
L 5.815 0.925 5.815 2.685 3 P 0 
L 5.815 2.685 5.79 2.71 3 P 0 
L 5.79 2.71 5.79 2.815 3 P 0 
L 5.79 2.815 5.79941004 2.82441004 3 P 0 
L 5.79941004 2.82441004 5.803 2.82441004 3 P 0 
P 3.635 0.49 8 P 0 0;3,5=1,7=1
P 4.58268002 2.81615 6 P 0 0;5=4,7=1
L 3.635 0.49 3.655 0.49 3 P 0 
L 3.655 0.49 3.74815 0.58315 3 P 0 
L 3.74815 0.58315 3.74815 2.70816004 3 P 0 
L 3.74815 2.70816004 3.86498996 2.825 3 P 0 
L 3.86498996 2.825 4.514 2.825 3 P 0 
L 4.514 2.825 4.52285 2.81615 3 P 0 
L 4.52285 2.81615 4.58268002 2.81615 3 P 0 
P 2.19606004 3.26615 6 P 0 0;5=4,7=1
P 1.6485 5.0535 6 P 0 0;5=4,7=1
P 8.15 3.36615 6 P 0 0;5=4,7=1
P 7.69205 4.78291998 6 P 0 0;5=4,7=1
P 2.19606004 3.31615 6 P 0 0;5=4,7=1
P 1.6885 5.0535 6 P 0 0;5=4,7=1
P 8.1 3.41615 6 P 0 0;5=4,7=1
P 7.79378996 4.78291998 6 P 0 0;5=4,7=1
P 2.14606004 3.31615 6 P 0 0;5=4,7=1
P 1.64851004 4.78291998 6 P 0 0;5=4,7=1
P 8.1 3.46615 6 P 0 0;5=4,7=1
P 7.83378996 4.78291998 6 P 0 0;5=4,7=1
P 2.14606004 3.36615 6 P 0 0;5=4,7=1
P 1.68851004 4.78291998 6 P 0 0;5=4,7=1
P 0.73 4.96 8 P 0 0;3,5=1,7=1
P 3.795 4.6 7 P 0 0;5=6,7=1
L 0.73 4.96 0.77 5 3 P 0 
L 0.77 5 0.77 5.3 3 P 0 
L 0.77 5.3 0.795 5.325 3 P 0 
L 0.795 5.325 0.795 5.385 3 P 0 
L 0.795 5.385 0.9403 5.5303 3 P 0 
L 0.9403 5.5303 3.3397 5.5303 3 P 0 
L 3.3397 5.5303 3.69 5.18 3 P 0 
L 3.69 5.18 3.69 4.705 3 P 0 
L 3.69 4.705 3.7325 4.6625 3 P 0 
L 3.7325 4.6625 3.7325 4.6275 3 P 0 
L 3.7325 4.6275 3.76 4.6 3 P 0 
L 3.76 4.6 3.795 4.6 3 P 0 
P 4.86 5.375 7 P 0 0;5=6,7=1
P 6.57318996 5.09705 25 P 0 0;2,5=0,7=0
L 6.57318996 5.09705 6.57318996 5.52001004 3 P 0 
L 6.57318996 5.52001004 6.3882 5.705 3 P 0 
L 6.3882 5.705 5.0282 5.705 3 P 0 
L 5.0282 5.705 4.86 5.5368 3 P 0 
L 4.86 5.5368 4.86 5.375 3 P 0 
L 3.795 4.6 3.795 4.6215 3 P 0 
L 3.795 4.6215 3.8085 4.635 3 P 0 
L 3.8085 4.635 3.855 4.635 3 P 0 
L 3.855 4.635 3.9 4.59 3 P 0 
L 3.9 4.59 3.985 4.59 3 P 0 
L 3.985 4.59 4 4.575 3 P 0 
L 4 4.575 4.085 4.575 3 P 0 
L 4.085 4.575 4.10185 4.59185 3 P 0 
L 4.10185 4.59185 4.10185 4.65 3 P 0 
L 4.10185 4.65 4.0575 4.69435 3 P 0 
L 4.0575 4.69435 4.0575 4.7825 3 P 0 
L 4.0575 4.7825 4.02185 4.81815 3 P 0 
L 4.02185 4.81815 4.02185 5.16185 3 P 0 
L 4.02185 5.16185 4.2 5.34 3 P 0 
L 4.2 5.34 4.825 5.34 3 P 0 
L 4.825 5.34 4.86 5.375 3 P 0 
P 8.15 3.46615 6 P 0 0;5=4,7=1
P 7.86465 4.657 6 P 0 0;5=4,7=1
P 2.09606004 3.41615 6 P 0 0;5=4,7=1
P 1.79025 4.78291998 6 P 0 0;5=4,7=1
P 8.15 3.51615 6 P 0 0;5=4,7=1
P 7.90465 4.657 6 P 0 0;5=4,7=1
P 2.09606004 3.46615 6 P 0 0;5=4,7=1
P 1.83025 4.78291998 6 P 0 0;5=4,7=1
P 2.19606004 3.41615 6 P 0 0;5=4,7=1
P 1.86111004 5.169 6 P 0 0;5=4,7=1
P 2.19606004 3.46615 6 P 0 0;5=4,7=1
P 1.90111004 5.169 6 P 0 0;5=4,7=1
P 6.72708996 4.5652 7 P 0 0;5=6,7=1
P 6.76208996 4.5652 7 P 0 0;5=6,7=1
P 6.79708996 4.5652 7 P 0 0;5=6,7=1
P 6.83708996 4.5652 8 P 0 0;3,5=1,7=1
P 6.90208996 4.5652 7 P 0 0;5=6,7=1
P 6.87208996 4.5652 7 P 0 0;5=6,7=1
P 10.99998996 4.9531 7 P 0 0;5=6,7=1
P 11.03998996 4.9531 7 P 0 0;5=6,7=1
P 10.99998996 4.9131 7 P 0 0;5=6,7=1
P 11.03998996 4.9131 7 P 0 0;5=6,7=1
P 11.21998996 4.9531 7 P 0 0;5=6,7=1
P 11.17998996 4.9531 7 P 0 0;5=6,7=1
P 11.13498996 4.9531 7 P 0 0;5=6,7=1
P 11.08498996 4.9531 7 P 0 0;5=6,7=1
P 11.21998996 4.9131 7 P 0 0;5=6,7=1
P 11.17998996 4.9131 7 P 0 0;5=6,7=1
P 11.08498996 4.9131 7 P 0 0;5=6,7=1
P 11.13498996 4.9131 7 P 0 0;5=6,7=1
P 10.99998996 5.1631 7 P 0 0;5=6,7=1
P 11.03998996 5.1631 7 P 0 0;5=6,7=1
P 10.99998996 5.1231 7 P 0 0;5=6,7=1
P 10.99998996 5.0381 7 P 0 0;5=6,7=1
P 10.99998996 5.0831 7 P 0 0;5=6,7=1
P 10.99998996 4.9931 7 P 0 0;5=6,7=1
P 11.03998996 4.9931 7 P 0 0;5=6,7=1
P 11.03998996 5.0831 7 P 0 0;5=6,7=1
P 11.03998996 5.0381 7 P 0 0;5=6,7=1
P 11.03998996 5.1231 7 P 0 0;5=6,7=1
P 11.21998996 5.1631 7 P 0 0;5=6,7=1
P 11.17998996 5.1631 7 P 0 0;5=6,7=1
P 11.08498996 5.1631 7 P 0 0;5=6,7=1
P 11.13498996 5.1631 7 P 0 0;5=6,7=1
P 11.21998996 5.1231 7 P 0 0;5=6,7=1
P 11.21998996 5.0381 7 P 0 0;5=6,7=1
P 11.21998996 5.0831 7 P 0 0;5=6,7=1
P 11.21998996 4.9931 7 P 0 0;5=6,7=1
P 11.17998996 4.9931 7 P 0 0;5=6,7=1
P 11.17998996 5.1231 7 P 0 0;5=6,7=1
P 11.17998996 5.0831 7 P 0 0;5=6,7=1
P 11.17998996 5.0381 7 P 0 0;5=6,7=1
P 11.13498996 5.1231 7 P 0 0;5=6,7=1
P 11.08498996 5.1231 7 P 0 0;5=6,7=1
P 11.6269 4.90498996 7 P 0 0;5=6,7=1
P 11.6269 4.85498996 7 P 0 0;5=6,7=1
P 11.4269 4.80998996 7 P 0 0;5=6,7=1
P 11.4269 4.85498996 7 P 0 0;5=6,7=1
P 11.4269 4.90498996 7 P 0 0;5=6,7=1
P 11.4269 4.94998996 7 P 0 0;5=6,7=1
P 11.4769 4.94998996 7 P 0 0;5=6,7=1
P 11.4769 4.80998996 7 P 0 0;5=6,7=1
P 11.5269 4.94998996 7 P 0 0;5=6,7=1
P 11.5269 4.80998996 7 P 0 0;5=6,7=1
P 11.5769 4.94998996 7 P 0 0;5=6,7=1
P 11.6269 4.94998996 7 P 0 0;5=6,7=1
P 11.6269 4.80998996 7 P 0 0;5=6,7=1
P 11.5769 4.80998996 7 P 0 0;5=6,7=1
P 10.82676998 5.71338996 14 P 0 0;3,5=14,7=0
P 10.99213002 5.71338996 14 P 0 0;5=14,7=0
P 11.15748002 5.71338996 14 P 0 0;3,5=14,7=0
P 11.32283996 5.71338996 14 P 0 0;5=14,7=0
P 11.48818996 5.71338996 14 P 0 0;3,5=14,7=0
P 11.65353996 5.71338996 14 P 0 0;5=14,7=0
P 11.8189 5.71338996 14 P 0 0;3,5=14,7=0
P 11.98425 5.71338996 14 P 0 0;5=14,7=0
P 12.14961004 5.71338996 14 P 0 0;3,5=14,7=0
P 10.80498996 5.7831 7 P 0 0;5=6,7=1
P 10.84498996 5.7831 7 P 0 0;5=6,7=1
P 10.80498996 5.6431 7 P 0 0;5=6,7=1
P 10.84498996 5.6431 7 P 0 0;5=6,7=1
P 11.01035 5.6431 7 P 0 0;5=6,7=1
P 10.97035 5.6431 7 P 0 0;5=6,7=1
P 11.01035 5.7831 7 P 0 0;5=6,7=1
P 10.97035 5.7831 7 P 0 0;5=6,7=1
P 11.17571004 5.6431 7 P 0 0;5=6,7=1
P 11.13571004 5.6431 7 P 0 0;5=6,7=1
P 11.17571004 5.7831 7 P 0 0;5=6,7=1
P 11.13571004 5.7831 7 P 0 0;5=6,7=1
P 11.34106998 5.6431 7 P 0 0;5=6,7=1
P 11.30106998 5.6431 7 P 0 0;5=6,7=1
P 11.34106998 5.7831 7 P 0 0;5=6,7=1
P 11.30106998 5.7831 7 P 0 0;5=6,7=1
P 11.50643002 5.6431 7 P 0 0;5=6,7=1
P 11.46643002 5.6431 7 P 0 0;5=6,7=1
P 11.50643002 5.7831 7 P 0 0;5=6,7=1
P 11.46643002 5.7831 7 P 0 0;5=6,7=1
P 11.67178996 5.6431 7 P 0 0;5=6,7=1
P 11.63178996 5.6431 7 P 0 0;5=6,7=1
P 11.67178996 5.7831 7 P 0 0;5=6,7=1
P 11.63178996 5.7831 7 P 0 0;5=6,7=1
P 11.83715 5.6431 7 P 0 0;5=6,7=1
P 11.79715 5.6431 7 P 0 0;5=6,7=1
P 11.83715 5.7831 7 P 0 0;5=6,7=1
P 11.79715 5.7831 7 P 0 0;5=6,7=1
P 12.00251004 5.6431 7 P 0 0;5=6,7=1
P 11.96251004 5.6431 7 P 0 0;5=6,7=1
P 12.00251004 5.7831 7 P 0 0;5=6,7=1
P 11.96251004 5.7831 7 P 0 0;5=6,7=1
P 12.16786998 5.6431 7 P 0 0;5=6,7=1
P 12.12786998 5.6431 7 P 0 0;5=6,7=1
P 12.16786998 5.7831 7 P 0 0;5=6,7=1
P 12.12786998 5.7831 7 P 0 0;5=6,7=1
P 11.295 4.88 8 P 0 0;3,5=5,7=1
S P 0
OB 11.31405 4.78405 I
OS 11.195 4.9031
OS 10.99498996063 4.9031
OS 10.98998996063 4.9081
OS 10.98998996063 5.12
OS 10.95498996063 5.155
OS 10.582 5.155
OS 10.567 5.17
OS 10.567 5.836
OS 10.616 5.885
OS 12.49 5.885
OS 12.52 5.855
OS 12.52 5.365
OS 12.175 5.02
OS 11.730969980315 5.02
OS 11.7 4.989030019685
OS 11.7 4.825
OS 11.65905 4.78405
OS 11.31405 4.78405
OE
OB 10.79585 5.394980019685 H
OS 12.19415 5.394980019685
OS 12.215019980315 5.41585
OS 12.215019980315 5.57415
OS 12.19415 5.595019980315
OS 10.79585 5.595019980315
OS 10.769980019685 5.56915
OS 10.769980019685 5.42085
OS 10.79585 5.394980019685
OE
OB 12.415380019685 5.695280019685 H
OC 12.415380019685 5.695280019685 12.33465 5.695280019685 N
OE
SE
S P 0
OB 4.97 4.9 I
OS 4.955 4.915
OS 4.955 5.195
OS 4.975 5.215
OS 5.24 5.215
OS 5.26 5.195
OS 5.26 4.91
OS 5.25 4.9
OS 4.97 4.9
OE
SE
P 5.03605 5.1631 7 P 0 0;5=6,7=1
P 5.03605 4.9931 7 P 0 0;5=6,7=1
P 5.03605 5.0831 7 P 0 0;5=6,7=1
P 5.03605 5.0381 7 P 0 0;5=6,7=1
P 5.03605 5.1231 7 P 0 0;5=6,7=1
P 5.21605 5.1631 7 P 0 0;5=6,7=1
P 5.17605 5.1631 7 P 0 0;5=6,7=1
P 5.08105 5.1631 7 P 0 0;5=6,7=1
P 5.13105 5.1631 7 P 0 0;5=6,7=1
P 5.21605 5.1231 7 P 0 0;5=6,7=1
P 5.21605 5.0381 7 P 0 0;5=6,7=1
P 5.21605 5.0831 7 P 0 0;5=6,7=1
P 5.21605 4.9931 7 P 0 0;5=6,7=1
P 5.17605 4.9931 7 P 0 0;5=6,7=1
P 5.17605 5.1231 7 P 0 0;5=6,7=1
P 5.17605 5.0831 7 P 0 0;5=6,7=1
P 5.17605 5.0381 7 P 0 0;5=6,7=1
P 5.13105 5.1231 7 P 0 0;5=6,7=1
P 5.08105 5.1231 7 P 0 0;5=6,7=1
P 4.99605 5.1631 7 P 0 0;5=6,7=1
P 4.99605 5.1231 7 P 0 0;5=6,7=1
P 4.99605 5.0381 7 P 0 0;5=6,7=1
P 4.99605 5.0831 7 P 0 0;5=6,7=1
P 4.99605 4.9931 7 P 0 0;5=6,7=1
P 5.03605 4.9531 7 P 0 0;5=6,7=1
P 5.03605 4.9131 7 P 0 0;5=6,7=1
P 5.21605 4.9531 7 P 0 0;5=6,7=1
P 5.17605 4.9531 7 P 0 0;5=6,7=1
P 5.13105 4.9531 7 P 0 0;5=6,7=1
P 5.08105 4.9531 7 P 0 0;5=6,7=1
P 5.21605 4.9131 7 P 0 0;5=6,7=1
P 5.17605 4.9131 7 P 0 0;5=6,7=1
P 5.08105 4.9131 7 P 0 0;5=6,7=1
P 5.13105 4.9131 7 P 0 0;5=6,7=1
P 4.99605 4.9531 7 P 0 0;5=6,7=1
P 4.99605 4.9131 7 P 0 0;5=6,7=1
P 5.105 5.05 8 P 0 0;3,5=5,7=1
P 6.34948996 5.03 7 P 0 0;5=6,7=1
P 2.74225 5.14 6 P 0 0;5=4,7=1
P 2.04606004 3.61615 6 P 0 0;5=4,7=1
P 2.14606004 3.46615 6 P 0 0;5=4,7=1
P 1.86111004 4.657 6 P 0 0;5=4,7=1
P 2.78225 5.14 6 P 0 0;5=4,7=1
P 2.04606004 3.66615 6 P 0 0;5=4,7=1
P 2.14606004 3.51615 6 P 0 0;5=4,7=1
P 1.90111004 4.657 6 P 0 0;5=4,7=1
P 1.93196998 5.0535 6 P 0 0;5=4,7=1
P 1.99606004 3.46615 6 P 0 0;5=4,7=1
P 4.58268002 2.56615 6 P 0 0;5=4,7=1
P 1.97196998 5.0535 6 P 0 0;5=4,7=1
P 1.99606004 3.51615 6 P 0 0;5=4,7=1
P 2.88086998 5.17001998 6 P 0 0;5=4,7=1
P 2.14606004 3.61615 6 P 0 0;5=4,7=1
P 2.34606004 3.66615 6 P 0 0;5=4,7=1
P 3.56176998 4.71973002 6 P 0 0;5=4,7=1
P 2.92086998 5.17001998 6 P 0 0;5=4,7=1
P 2.14606004 3.66615 6 P 0 0;5=4,7=1
P 2.34606004 3.71615 6 P 0 0;5=4,7=1
P 3.52176998 4.71973002 6 P 0 0;5=4,7=1
P 2.39606004 3.61615 6 P 0 0;5=4,7=1
P 3.49091004 4.587 6 P 0 0;5=4,7=1
P 2.39606004 3.66615 6 P 0 0;5=4,7=1
P 3.45091004 4.587 6 P 0 0;5=4,7=1
P 2.49606004 3.61615 6 P 0 0;5=4,7=1
P 3.56176998 5.14 6 P 0 0;5=4,7=1
P 2.49606004 3.66615 6 P 0 0;5=4,7=1
P 3.52176998 5.14 6 P 0 0;5=4,7=1
P 2.44606004 3.66615 6 P 0 0;5=4,7=1
P 3.42003996 4.78291998 6 P 0 0;5=4,7=1
P 4.30605 4.6631 7 P 0 0;5=6,7=1
P 4.34105 4.6431 7 P 0 0;5=6,7=1
P 4.38605 4.6431 7 P 0 0;5=6,7=1
P 4.42605 4.6631 7 P 0 0;5=6,7=1
P 4.46605 4.6631 7 P 0 0;5=6,7=1
P 4.30605 4.7031 7 P 0 0;5=6,7=1
P 4.42605 4.7031 7 P 0 0;5=6,7=1
P 4.46605 4.7031 7 P 0 0;5=6,7=1
P 4.26605 4.6631 7 P 0 0;5=6,7=1
P 4.26605 4.7031 7 P 0 0;5=6,7=1
P 4.65605 4.6631 7 P 0 0;5=6,7=1
P 4.69605 4.6631 7 P 0 0;5=6,7=1
P 4.65605 4.7031 7 P 0 0;5=6,7=1
P 4.69605 4.7031 7 P 0 0;5=6,7=1
P 4.73105 4.6431 7 P 0 0;5=6,7=1
P 4.81605 4.6631 7 P 0 0;5=6,7=1
P 4.85605 4.6631 7 P 0 0;5=6,7=1
P 4.81605 4.7031 7 P 0 0;5=6,7=1
P 4.85605 4.7031 7 P 0 0;5=6,7=1
P 4.77605 4.6431 7 P 0 0;5=6,7=1
P 5.17605 4.7131 7 P 0 0;5=6,7=1
P 5.17605 4.6731 7 P 0 0;5=6,7=1
P 5.08105 4.6731 7 P 0 0;5=6,7=1
P 5.13105 4.6731 7 P 0 0;5=6,7=1
P 5.03605 4.6731 7 P 0 0;5=6,7=1
P 5.03605 4.7131 7 P 0 0;5=6,7=1
P 4.30605 4.7481 7 P 0 0;5=6,7=1
P 4.30605 4.7931 7 P 0 0;5=6,7=1
P 4.30605 4.8381 7 P 0 0;5=6,7=1
P 4.38605 4.8381 7 P 0 0;5=6,7=1
P 4.34605 4.8381 7 P 0 0;5=6,7=1
P 4.46605 4.8381 7 P 0 0;5=6,7=1
P 4.42605 4.8381 7 P 0 0;5=6,7=1
P 4.42605 4.7931 7 P 0 0;5=6,7=1
P 4.42605 4.7481 7 P 0 0;5=6,7=1
P 4.46605 4.7931 7 P 0 0;5=6,7=1
P 4.46605 4.7481 7 P 0 0;5=6,7=1
P 4.26605 4.7481 7 P 0 0;5=6,7=1
P 4.26605 4.7931 7 P 0 0;5=6,7=1
P 4.26605 4.8381 7 P 0 0;5=6,7=1
P 4.65605 4.8381 7 P 0 0;5=6,7=1
P 4.65605 4.7931 7 P 0 0;5=6,7=1
P 4.65605 4.7481 7 P 0 0;5=6,7=1
P 4.69605 4.8381 7 P 0 0;5=6,7=1
P 4.69605 4.7931 7 P 0 0;5=6,7=1
P 4.69605 4.7481 7 P 0 0;5=6,7=1
P 4.73605 4.8381 7 P 0 0;5=6,7=1
P 4.81605 4.8381 7 P 0 0;5=6,7=1
P 4.81605 4.7931 7 P 0 0;5=6,7=1
P 4.81605 4.7481 7 P 0 0;5=6,7=1
P 4.85605 4.8381 7 P 0 0;5=6,7=1
P 4.85605 4.7931 7 P 0 0;5=6,7=1
P 4.85605 4.7481 7 P 0 0;5=6,7=1
P 4.77605 4.8381 7 P 0 0;5=6,7=1
P 5.08105 4.8431 7 P 0 0;5=6,7=1
P 5.13105 4.8431 7 P 0 0;5=6,7=1
P 5.17605 4.8431 7 P 0 0;5=6,7=1
P 5.17605 4.8031 7 P 0 0;5=6,7=1
P 5.17605 4.7581 7 P 0 0;5=6,7=1
P 5.03605 4.8431 7 P 0 0;5=6,7=1
P 5.03605 4.8031 7 P 0 0;5=6,7=1
P 5.03605 4.7581 7 P 0 0;5=6,7=1
P 4.58268002 2.96615 6 P 0 0;5=4,7=1
P 4.63268002 2.96615 6 P 0 0;5=4,7=1
P 4.63268002 3.11615 6 P 0 0;5=4,7=1
P 4.58268002 3.01615 6 P 0 0;5=4,7=1
P 4.58268002 3.11615 6 P 0 0;5=4,7=1
P 4.63268002 3.01615 6 P 0 0;5=4,7=1
P 4.63268002 3.31615 6 P 0 0;5=4,7=1
P 4.58268002 3.26615 6 P 0 0;5=4,7=1
P 4.58268002 3.31615 6 P 0 0;5=4,7=1
P 4.63268002 3.26615 6 P 0 0;5=4,7=1
P 4.63268002 3.16615 6 P 0 0;5=4,7=1
P 4.58268002 3.16615 6 P 0 0;5=4,7=1
P 4.58268002 3.46615 6 P 0 0;5=4,7=1
P 4.63268002 3.41615 6 P 0 0;5=4,7=1
P 4.63268002 3.46615 6 P 0 0;5=4,7=1
P 4.58268002 3.41615 6 P 0 0;5=4,7=1
P 4.58268002 3.61615 6 P 0 0;5=4,7=1
P 4.58268002 3.56615 6 P 0 0;5=4,7=1
P 4.63268002 3.61615 6 P 0 0;5=4,7=1
P 4.63268002 3.56615 6 P 0 0;5=4,7=1
P 4.58268002 3.71615 6 P 0 0;5=4,7=1
P 4.63268002 3.71615 6 P 0 0;5=4,7=1
P 4.58268002 3.76615 6 P 0 0;5=4,7=1
P 4.58268002 3.86615 6 P 0 0;5=4,7=1
P 4.63268002 3.76615 6 P 0 0;5=4,7=1
P 4.63268002 3.86615 6 P 0 0;5=4,7=1
P 4.68268002 2.96615 6 P 0 0;5=4,7=1
P 4.73268002 2.96615 6 P 0 0;5=4,7=1
P 4.78268002 2.96615 6 P 0 0;5=4,7=1
P 4.68268002 3.11615 6 P 0 0;5=4,7=1
P 4.68268002 3.01615 6 P 0 0;5=4,7=1
P 4.73268002 3.11615 6 P 0 0;5=4,7=1
P 4.73268002 3.01615 6 P 0 0;5=4,7=1
P 4.78268002 3.11615 6 P 0 0;5=4,7=1
P 4.78268002 3.01615 6 P 0 0;5=4,7=1
P 4.73268002 3.31615 6 P 0 0;5=4,7=1
P 4.73268002 3.26615 6 P 0 0;5=4,7=1
P 4.68268002 3.26615 6 P 0 0;5=4,7=1
P 4.68268002 3.31615 6 P 0 0;5=4,7=1
P 4.78268002 3.26615 6 P 0 0;5=4,7=1
P 4.78268002 3.31615 6 P 0 0;5=4,7=1
P 4.73268002 3.16615 6 P 0 0;5=4,7=1
P 4.68268002 3.16615 6 P 0 0;5=4,7=1
P 4.78268002 3.16615 6 P 0 0;5=4,7=1
P 4.73268002 3.41615 6 P 0 0;5=4,7=1
P 4.68268002 3.41615 6 P 0 0;5=4,7=1
P 4.68268002 3.46615 6 P 0 0;5=4,7=1
P 4.73268002 3.46615 6 P 0 0;5=4,7=1
P 4.78268002 3.46615 6 P 0 0;5=4,7=1
P 4.78268002 3.41615 6 P 0 0;5=4,7=1
P 4.73268002 3.56615 6 P 0 0;5=4,7=1
P 4.73268002 3.61615 6 P 0 0;5=4,7=1
P 4.68268002 3.56615 6 P 0 0;5=4,7=1
P 4.68268002 3.61615 6 P 0 0;5=4,7=1
P 4.78268002 3.61615 6 P 0 0;5=4,7=1
P 4.78268002 3.56615 6 P 0 0;5=4,7=1
P 4.73268002 3.71615 6 P 0 0;5=4,7=1
P 4.68268002 3.71615 6 P 0 0;5=4,7=1
P 4.78268002 3.71615 6 P 0 0;5=4,7=1
P 4.73268002 3.76615 6 P 0 0;5=4,7=1
P 4.73268002 3.86615 6 P 0 0;5=4,7=1
P 4.68268002 3.76615 6 P 0 0;5=4,7=1
P 4.68268002 3.86615 6 P 0 0;5=4,7=1
P 4.78268002 3.76615 6 P 0 0;5=4,7=1
P 4.78268002 3.86615 6 P 0 0;5=4,7=1
P 4.88268002 3.86615 6 P 0 0;5=4,7=1
P 4.83268002 3.86615 6 P 0 0;5=4,7=1
P 5.03268002 3.86615 6 P 0 0;5=4,7=1
P 4.93268002 3.86615 6 P 0 0;5=4,7=1
P 4.98268002 3.86615 6 P 0 0;5=4,7=1
P 4.88268002 3.76615 6 P 0 0;5=4,7=1
P 4.83268002 3.76615 6 P 0 0;5=4,7=1
P 5.03268002 3.76615 6 P 0 0;5=4,7=1
P 4.93268002 3.76615 6 P 0 0;5=4,7=1
P 4.98268002 3.76615 6 P 0 0;5=4,7=1
P 4.88268002 3.71615 6 P 0 0;5=4,7=1
P 4.83268002 3.71615 6 P 0 0;5=4,7=1
P 5.03268002 3.71615 6 P 0 0;5=4,7=1
P 4.93268002 3.71615 6 P 0 0;5=4,7=1
P 4.98268002 3.71615 6 P 0 0;5=4,7=1
P 4.88268002 3.61615 6 P 0 0;5=4,7=1
P 4.83268002 3.61615 6 P 0 0;5=4,7=1
P 5.03268002 3.61615 6 P 0 0;5=4,7=1
P 4.93268002 3.61615 6 P 0 0;5=4,7=1
P 4.98268002 3.61615 6 P 0 0;5=4,7=1
P 4.88268002 3.56615 6 P 0 0;5=4,7=1
P 4.83268002 3.56615 6 P 0 0;5=4,7=1
P 5.03268002 3.56615 6 P 0 0;5=4,7=1
P 4.93268002 3.56615 6 P 0 0;5=4,7=1
P 4.98268002 3.56615 6 P 0 0;5=4,7=1
P 4.88268002 3.46615 6 P 0 0;5=4,7=1
P 4.83268002 3.46615 6 P 0 0;5=4,7=1
P 5.03268002 3.46615 6 P 0 0;5=4,7=1
P 4.93268002 3.46615 6 P 0 0;5=4,7=1
P 4.98268002 3.46615 6 P 0 0;5=4,7=1
P 4.88268002 3.41615 6 P 0 0;5=4,7=1
P 4.83268002 3.41615 6 P 0 0;5=4,7=1
P 5.03268002 3.41615 6 P 0 0;5=4,7=1
P 4.93268002 3.41615 6 P 0 0;5=4,7=1
P 4.98268002 3.41615 6 P 0 0;5=4,7=1
P 4.88268002 3.31615 6 P 0 0;5=4,7=1
P 4.83268002 3.31615 6 P 0 0;5=4,7=1
P 5.03268002 3.31615 6 P 0 0;5=4,7=1
P 4.93268002 3.31615 6 P 0 0;5=4,7=1
P 4.98268002 3.31615 6 P 0 0;5=4,7=1
P 4.83268002 3.26615 6 P 0 0;5=4,7=1
P 4.88268002 3.26615 6 P 0 0;5=4,7=1
P 4.98268002 3.26615 6 P 0 0;5=4,7=1
P 4.93268002 3.26615 6 P 0 0;5=4,7=1
P 5.03268002 3.26615 6 P 0 0;5=4,7=1
P 4.83268002 3.16615 6 P 0 0;5=4,7=1
P 4.88268002 3.16615 6 P 0 0;5=4,7=1
P 4.98268002 3.16615 6 P 0 0;5=4,7=1
P 4.93268002 3.16615 6 P 0 0;5=4,7=1
P 5.03268002 3.16615 6 P 0 0;5=4,7=1
P 4.83268002 3.11615 6 P 0 0;5=4,7=1
P 4.88268002 3.11615 6 P 0 0;5=4,7=1
P 4.98268002 3.11615 6 P 0 0;5=4,7=1
P 4.93268002 3.11615 6 P 0 0;5=4,7=1
P 5.03268002 3.11615 6 P 0 0;5=4,7=1
P 4.83268002 3.01615 6 P 0 0;5=4,7=1
P 4.88268002 3.01615 6 P 0 0;5=4,7=1
P 4.98268002 3.01615 6 P 0 0;5=4,7=1
P 4.93268002 3.01615 6 P 0 0;5=4,7=1
P 5.03268002 3.01615 6 P 0 0;5=4,7=1
P 4.83268002 2.96615 6 P 0 0;5=4,7=1
P 4.88268002 2.96615 6 P 0 0;5=4,7=1
P 4.98268002 2.96615 6 P 0 0;5=4,7=1
P 4.93268002 2.96615 6 P 0 0;5=4,7=1
P 5.03268002 2.96615 6 P 0 0;5=4,7=1
P 4.41 4.21 8 P 0 0;3,5=5,7=1
S P 0
OB 4.29998996063 2.958 I
OS 4.25605 3.00193996063
OS 4.25605 4.8381
OS 4.26605 4.8481
OS 5.18105 4.8481
OS 5.22106003937 4.80808996063
OS 5.22106003937 3.033
OS 5.14606003937 2.958
OS 4.29998996063 2.958
OE
OB 4.5987 3.06615 H
OC 4.5987 3.06615 4.582680019685 3.06615 N
OE
OB 4.6487 3.06615 H
OC 4.6487 3.06615 4.632680019685 3.06615 N
OE
OB 4.5987 3.21615 H
OC 4.5987 3.21615 4.582680019685 3.21615 N
OE
OB 4.6487 3.21615 H
OC 4.6487 3.21615 4.632680019685 3.21615 N
OE
OB 4.5987 3.36615 H
OC 4.5987 3.36615 4.582680019685 3.36615 N
OE
OB 4.6487 3.36615 H
OC 4.6487 3.36615 4.632680019685 3.36615 N
OE
OB 4.5987 3.51615 H
OC 4.5987 3.51615 4.582680019685 3.51615 N
OE
OB 4.6487 3.51615 H
OC 4.6487 3.51615 4.632680019685 3.51615 N
OE
OB 4.5987 3.66615 H
OC 4.5987 3.66615 4.582680019685 3.66615 N
OE
OB 4.5987 3.81615 H
OC 4.5987 3.81615 4.582680019685 3.81615 N
OE
OB 4.6487 3.66615 H
OC 4.6487 3.66615 4.632680019685 3.66615 N
OE
OB 4.6487 3.81615 H
OC 4.6487 3.81615 4.632680019685 3.81615 N
OE
OB 4.8987 3.06615 H
OC 4.8987 3.06615 4.882680019685 3.06615 N
OE
OB 4.8487 3.06615 H
OC 4.8487 3.06615 4.832680019685 3.06615 N
OE
OB 4.6987 3.06615 H
OC 4.6987 3.06615 4.682680019685 3.06615 N
OE
OB 4.7487 3.06615 H
OC 4.7487 3.06615 4.732680019685 3.06615 N
OE
OB 4.7987 3.06615 H
OC 4.7987 3.06615 4.782680019685 3.06615 N
OE
OB 4.8987 3.21615 H
OC 4.8987 3.21615 4.882680019685 3.21615 N
OE
OB 4.8487 3.21615 H
OC 4.8487 3.21615 4.832680019685 3.21615 N
OE
OB 4.8487 3.36615 H
OC 4.8487 3.36615 4.832680019685 3.36615 N
OE
OB 4.8987 3.36615 H
OC 4.8987 3.36615 4.882680019685 3.36615 N
OE
OB 4.6987 3.21615 H
OC 4.6987 3.21615 4.682680019685 3.21615 N
OE
OB 4.6987 3.36615 H
OC 4.6987 3.36615 4.682680019685 3.36615 N
OE
OB 4.7487 3.21615 H
OC 4.7487 3.21615 4.732680019685 3.21615 N
OE
OB 4.7987 3.21615 H
OC 4.7987 3.21615 4.782680019685 3.21615 N
OE
OB 4.7487 3.36615 H
OC 4.7487 3.36615 4.732680019685 3.36615 N
OE
OB 4.7987 3.36615 H
OC 4.7987 3.36615 4.782680019685 3.36615 N
OE
OB 4.8487 3.51615 H
OC 4.8487 3.51615 4.832680019685 3.51615 N
OE
OB 4.8987 3.51615 H
OC 4.8987 3.51615 4.882680019685 3.51615 N
OE
OB 4.6987 3.51615 H
OC 4.6987 3.51615 4.682680019685 3.51615 N
OE
OB 4.7487 3.51615 H
OC 4.7487 3.51615 4.732680019685 3.51615 N
OE
OB 4.7987 3.51615 H
OC 4.7987 3.51615 4.782680019685 3.51615 N
OE
OB 4.8487 3.81615 H
OC 4.8487 3.81615 4.832680019685 3.81615 N
OE
OB 4.8987 3.81615 H
OC 4.8987 3.81615 4.882680019685 3.81615 N
OE
OB 4.8487 3.66615 H
OC 4.8487 3.66615 4.832680019685 3.66615 N
OE
OB 4.8987 3.66615 H
OC 4.8987 3.66615 4.882680019685 3.66615 N
OE
OB 4.6987 3.66615 H
OC 4.6987 3.66615 4.682680019685 3.66615 N
OE
OB 4.6987 3.81615 H
OC 4.6987 3.81615 4.682680019685 3.81615 N
OE
OB 4.7487 3.66615 H
OC 4.7487 3.66615 4.732680019685 3.66615 N
OE
OB 4.7487 3.81615 H
OC 4.7487 3.81615 4.732680019685 3.81615 N
OE
OB 4.7987 3.66615 H
OC 4.7987 3.66615 4.782680019685 3.66615 N
OE
OB 4.7987 3.81615 H
OC 4.7987 3.81615 4.782680019685 3.81615 N
OE
OB 5.0487 3.06615 H
OC 5.0487 3.06615 5.032680019685 3.06615 N
OE
OB 4.9487 3.06615 H
OC 4.9487 3.06615 4.932680019685 3.06615 N
OE
OB 4.9987 3.06615 H
OC 4.9987 3.06615 4.982680019685 3.06615 N
OE
OB 5.0487 3.21615 H
OC 5.0487 3.21615 5.032680019685 3.21615 N
OE
OB 4.9487 3.21615 H
OC 4.9487 3.21615 4.932680019685 3.21615 N
OE
OB 4.9987 3.21615 H
OC 4.9987 3.21615 4.982680019685 3.21615 N
OE
OB 4.9987 3.36615 H
OC 4.9987 3.36615 4.982680019685 3.36615 N
OE
OB 4.9487 3.36615 H
OC 4.9487 3.36615 4.932680019685 3.36615 N
OE
OB 5.0487 3.36615 H
OC 5.0487 3.36615 5.032680019685 3.36615 N
OE
OB 4.9987 3.51615 H
OC 4.9987 3.51615 4.982680019685 3.51615 N
OE
OB 4.9487 3.51615 H
OC 4.9487 3.51615 4.932680019685 3.51615 N
OE
OB 5.0487 3.51615 H
OC 5.0487 3.51615 5.032680019685 3.51615 N
OE
OB 4.9987 3.81615 H
OC 4.9987 3.81615 4.982680019685 3.81615 N
OE
OB 4.9487 3.81615 H
OC 4.9487 3.81615 4.932680019685 3.81615 N
OE
OB 4.9987 3.66615 H
OC 4.9987 3.66615 4.982680019685 3.66615 N
OE
OB 4.9487 3.66615 H
OC 4.9487 3.66615 4.932680019685 3.66615 N
OE
OB 5.0487 3.66615 H
OC 5.0487 3.66615 5.032680019685 3.66615 N
OE
OB 5.0487 3.81615 H
OC 5.0487 3.81615 5.032680019685 3.81615 N
OE
OB 5.040430019685 4.22441003937 H
OC 5.040430019685 4.22441003937 4.832680019685 4.22441003937 N
OE
SE
P 2.44606004 3.71615 6 P 0 0;5=4,7=1
P 3.38003996 4.78291998 6 P 0 0;5=4,7=1
P 2.19606004 3.81615 6 P 0 0;5=4,7=1
P 3.02571004 4.667 6 P 0 0;5=4,7=1
P 2.19606004 3.86615 6 P 0 0;5=4,7=1
P 3.06571004 4.667 6 P 0 0;5=4,7=1
P 3.27831004 4.642 6 P 0 0;5=4,7=1
P 2.39606004 3.76615 6 P 0 0;5=4,7=1
P 4.73268002 2.66615 6 P 0 0;5=4,7=1
P 10.73661004 2.66615 6 P 0 0;5=4,7=1
P 3.23831004 4.642 6 P 0 0;5=4,7=1
P 2.39606004 3.81615 6 P 0 0;5=4,7=1
P 5.03268002 2.61615 6 P 0 0;5=4,7=1
P 3.34916998 5.1035 6 P 0 0;5=4,7=1
P 2.49606004 3.76615 6 P 0 0;5=4,7=1
P 3.30916998 5.1035 6 P 0 0;5=4,7=1
P 2.49606004 3.81615 6 P 0 0;5=4,7=1
P 11.03661004 2.61615 6 P 0 0;5=4,7=1
P 2.74225 4.667 6 P 0 0;5=4,7=1
P 2.09606004 3.66615 6 P 0 0;5=4,7=1
P 2.44606004 3.81615 6 P 0 0;5=4,7=1
P 3.20743996 4.78291998 6 P 0 0;5=4,7=1
P 2.78225 4.667 6 P 0 0;5=4,7=1
P 2.09606004 3.71615 6 P 0 0;5=4,7=1
P 2.44606004 3.86615 6 P 0 0;5=4,7=1
P 3.16743996 4.78291998 6 P 0 0;5=4,7=1
P 2.34606004 3.81615 6 P 0 0;5=4,7=1
P 3.27831004 5.22001998 6 P 0 0;5=4,7=1
P 2.34606004 3.86615 6 P 0 0;5=4,7=1
P 3.23831004 5.22001998 6 P 0 0;5=4,7=1
P 4.63268002 2.61615 6 P 0 0;5=4,7=1
P 10.98661004 2.61615 6 P 0 0;5=4,7=1
P 2.19606004 3.66615 6 P 0 0;5=4,7=1
P 2.81311004 4.78291998 6 P 0 0;5=4,7=1
P 10.98661004 2.56615 6 P 0 0;5=4,7=1
P 2.19606004 3.71615 6 P 0 0;5=4,7=1
P 2.85311004 4.78291998 6 P 0 0;5=4,7=1
L 0.61698002 1.655 0.64808996 1.655 3 P 0 
P 5.803 2.87558996 30 P 0 0;2,5=8,7=0
P 0.61698002 1.655 25 P 0 0;2,5=0,7=0
P 0.64808996 1.655 7 P 0 0;5=6,7=1
P 5.76 2.66 8 P 0 0;3,5=1,7=1
L 5.76 2.66 5.76 2.865 3 P 0 
L 5.76 2.865 5.77058996 2.87558996 3 P 0 
L 5.77058996 2.87558996 5.803 2.87558996 3 P 0 
P 10.63661004 2.61615 6 P 0 0;5=4,7=1
P 2.09606004 3.81615 6 P 0 0;5=4,7=1
P 3.09656998 5.0535 6 P 0 0;5=4,7=1
P 2.09606004 3.86615 6 P 0 0;5=4,7=1
P 3.13656998 5.0535 6 P 0 0;5=4,7=1
P 2.88708002 4.667 6 P 0 0;5=4,7=1
P 2.04606004 3.76615 6 P 0 0;5=4,7=1
P 10.73661004 2.61615 6 P 0 0;5=4,7=1
P 2.92708002 4.667 6 P 0 0;5=4,7=1
P 2.04606004 3.81615 6 P 0 0;5=4,7=1
P 10.68661004 2.61615 6 P 0 0;5=4,7=1
P 5.03268002 2.46615 6 P 0 0;5=4,7=1
L 5.03268002 2.46615 5.03268002 2.4796 2 P 0 
L 5.03268002 2.4796 5.03868002 2.4856 2 P 0 
L 5.03868002 2.4856 5.1467 2.4856 2 P 0 
L 5.1467 2.4856 5.24095 2.57985 2 P 0 
L 5.24095 2.57985 5.2918 2.57985 2 P 0 
L 5.2918 2.57985 5.30875 2.5629 2 P 0 
P 5.30875 2.5629 25 P 0 0;2,5=0,7=0
P 5.03268002 2.51615 6 P 0 0;5=4,7=1
L 5.03268002 2.51615 5.03268002 2.5027 2 P 0 
L 5.03268002 2.5027 5.03868002 2.4967 2 P 0 
L 5.03868002 2.4967 5.1421 2.4967 2 P 0 
L 5.1421 2.4967 5.23635 2.59095 2 P 0 
L 5.23635 2.59095 5.2918 2.59095 2 P 0 
L 5.2918 2.59095 5.30875 2.6079 2 P 0 
P 5.30875 2.6079 25 P 0 0;2,5=0,7=0
L 5.883 3.02 5.85558996 3.02 3 P 0 
L 5.85558996 3.02 5.85 3.02558996 3 P 0 
L 5.85 3.02558996 5.80255 3.02558996 3 P 0 
P 5.80255 3.02558996 30 P 0 0;2,5=8,7=0
P 5.883 3.02 25 P 0 0;2,5=0,7=0
L 5.795 3.09 5.795 3.03313996 3 P 0 
L 5.795 3.03313996 5.80255 3.02558996 3 P 0 
P 5.795 3.09 8 P 0 0;3,5=5,7=1
P 11.08661004 2.56615 6 P 0 0;5=4,7=1
P 10.68661004 2.56615 6 P 0 0;5=4,7=1
L 9.175 5.255 9.19 5.27 3 P 0 
L 9.19 5.27 9.19 5.298 3 P 0 
L 9.235 5.298 9.19 5.298 3 P 0 
P 9.19 5.298 25 P 0 0;2,5=0,7=0
P 9.235 5.298 25 P 0 0;2,5=0,7=0
P 9.175 5.255 8 P 0 0;3,5=1,7=1
P 4.73268002 2.61615 6 P 0 0;5=4,7=1
L 9.11853996 5.255 9.145 5.28146004 3 P 0 
L 9.145 5.28146004 9.145 5.298 3 P 0 
L 9.1 5.298 9.145 5.298 3 P 0 
P 9.145 5.298 25 P 0 0;2,5=0,7=0
P 9.1 5.298 25 P 0 0;2,5=0,7=0
P 9.11853996 5.255 8 P 0 0;3,5=1,7=1
P 5.30875 2.4687 25 P 0 0;2,5=0,7=0
L 5.08268002 2.41615 5.08268002 2.4027 2 P 0 
L 5.08268002 2.4027 5.08868002 2.3967 2 P 0 
L 5.08868002 2.3967 5.197 2.3967 2 P 0 
L 5.197 2.3967 5.25205 2.45175 2 P 0 
L 5.25205 2.45175 5.2918 2.45175 2 P 0 
L 5.2918 2.45175 5.30875 2.4687 2 P 0 
P 5.08268002 2.41615 6 P 0 0;5=4,7=1
P 10.93661004 2.66615 6 P 0 0;5=4,7=1
P 10.58661004 2.61615 6 P 0 0;5=4,7=1
P 8.15 3.76615 6 P 0 0;5=4,7=1
P 9.02925 5.165 6 P 0 0;5=4,7=1
P 4.98268002 2.21615 6 P 0 0;5=4,7=1
L 4.98268002 2.21615 4.98268002 2.2296 2 P 0 
L 4.98268002 2.2296 4.98868002 2.2356 2 P 0 
L 4.98868002 2.2356 5.0467 2.2356 2 P 0 
L 5.0467 2.2356 5.05213002 2.23016998 2 P 0 
L 5.05213002 2.23016998 5.05213002 2.20348996 2 P 0 
L 5.05213002 2.20348996 5.07001998 2.1856 2 P 0 
L 5.07001998 2.1856 5.2327 2.1856 2 P 0 
L 5.2327 2.1856 5.24845 2.16985 2 P 0 
L 5.24845 2.16985 5.2918 2.16985 2 P 0 
L 5.2918 2.16985 5.30875 2.1529 2 P 0 
P 5.30875 2.1529 25 P 0 0;2,5=0,7=0
P 10.58661004 2.56615 6 P 0 0;5=4,7=1
P 8.15 3.81615 6 P 0 0;5=4,7=1
P 9.06925 5.165 6 P 0 0;5=4,7=1
P 11.03661004 2.66615 6 P 0 0;5=4,7=1
P 4.98268002 2.26615 6 P 0 0;5=4,7=1
L 4.98268002 2.26615 4.98268002 2.2527 2 P 0 
L 4.98268002 2.2527 4.98868002 2.2467 2 P 0 
L 4.98868002 2.2467 5.0513 2.2467 2 P 0 
L 5.0513 2.2467 5.06323002 2.23476998 2 P 0 
L 5.06323002 2.23476998 5.06323002 2.20808996 2 P 0 
L 5.06323002 2.20808996 5.07461998 2.1967 2 P 0 
L 5.07461998 2.1967 5.2373 2.1967 2 P 0 
L 5.2373 2.1967 5.25305 2.18095 2 P 0 
L 5.25305 2.18095 5.2918 2.18095 2 P 0 
L 5.2918 2.18095 5.30875 2.1979 2 P 0 
P 5.30875 2.1979 25 P 0 0;2,5=0,7=0
P 10.93661004 2.61615 6 P 0 0;5=4,7=1
P 5.30875 2.2883 25 P 0 0;2,5=0,7=0
P 5.03268002 2.26615 6 P 0 0;5=4,7=1
L 5.03268002 2.26615 5.03268002 2.2796 2 P 0 
L 5.03268002 2.2796 5.03868002 2.2856 2 P 0 
L 5.03868002 2.2856 5.2456 2.2856 2 P 0 
L 5.2456 2.2856 5.2643 2.3043 2 P 0 
L 5.2643 2.3043 5.29275 2.3043 2 P 0 
L 5.29275 2.3043 5.30875 2.2883 2 P 0 
P 11.08661004 2.61615 6 P 0 0;5=4,7=1
P 5.30875 2.3333 25 P 0 0;2,5=0,7=0
P 5.03268002 2.31615 6 P 0 0;5=4,7=1
L 5.30875 2.3333 5.29085 2.3154 2 P 0 
L 5.29085 2.3154 5.2597 2.3154 2 P 0 
L 5.2597 2.3154 5.241 2.2967 2 P 0 
L 5.241 2.2967 5.03868002 2.2967 2 P 0 
L 5.03868002 2.2967 5.03268002 2.3027 2 P 0 
L 5.03268002 2.3027 5.03268002 2.31615 2 P 0 
P 10.63661004 2.66615 6 P 0 0;5=4,7=1
L 3.775 5.295 3.39 5.68 3 P 0 
L 3.39 5.68 0.83 5.68 3 P 0 
L 0.83 5.68 0.73 5.78 3 P 0 
P 3.775 5.295 8 P 0 0;3,5=1,7=1
P 0.73 5.78 7 P 0 0;5=6,7=1
L 8.07 5.29 8.07 5.343 3 P 0 
P 8.07 5.343 25 P 0 0;2,5=0,7=0
L 8.07 5.343 8.12 5.343 3 P 0 
P 8.12 5.343 25 P 0 0;2,5=0,7=0
P 8.07 5.29 8 P 0 0;3,5=1,7=1
P 3.8399 4.765 8 P 0 0;3,5=1,7=1
P 0.81 5.78 7 P 0 0;5=6,7=1
L 3.8399 4.765 3.835 4.7699 3 P 0 
L 3.835 4.7699 3.835 5.355 3 P 0 
L 3.835 5.355 3.4783 5.7117 3 P 0 
L 3.4783 5.7117 0.8783 5.7117 3 P 0 
L 0.8783 5.7117 0.81 5.78 3 P 0 
L 8.005 5.343 7.955 5.343 3 P 0 
P 7.955 5.343 25 P 0 0;2,5=0,7=0
P 8.005 5.343 25 P 0 0;2,5=0,7=0
L 8.005 5.343 8.005 5.29 3 P 0 
P 8.005 5.29 8 P 0 0;3,5=1,7=1
P 11.08661004 1.91615 6 P 0 0;5=4,7=1
P 11.62193002 1.65 25 P 0 0;2,5=0,7=0
L 11.08661004 1.91615 11.08661004 1.9296 2 P 0 
L 11.08661004 1.9296 11.09261004 1.9356 2 P 0 
L 11.09261004 1.9356 11.10568996 1.9356 2 P 0 
L 11.10568996 1.9356 11.11601004 1.92528002 2 P 0 
L 11.11601004 1.92528002 11.22358996 1.77166998 2 P 0 
L 11.22358996 1.77166998 11.35643996 1.67863996 2 P 0 
L 11.35643996 1.67863996 11.42528002 1.6665 2 P 0 
L 11.42528002 1.6665 11.60543002 1.6665 2 P 0 
L 11.60543002 1.6665 11.62193002 1.65 2 P 0 
L 5.30875 1.7371 5.2918 1.75405 2 P 0 
L 5.2918 1.75405 5.15025 1.75405 2 P 0 
L 5.15025 1.75405 5.05213002 1.85216998 2 P 0 
L 5.05213002 1.85216998 5.05213002 1.9296 2 P 0 
L 5.05213002 1.9296 5.04613002 1.9356 2 P 0 
L 5.04613002 1.9356 4.98868002 1.9356 2 P 0 
L 4.98868002 1.9356 4.98268002 1.9296 2 P 0 
L 4.98268002 1.9296 4.98268002 1.91615 2 P 0 
P 4.98268002 1.91615 6 P 0 0;5=4,7=1
P 5.30875 1.7371 25 P 0 0;2,5=0,7=0
L 5.30875 1.7821 5.2918 1.76515 2 P 0 
L 5.2918 1.76515 5.15485 1.76515 2 P 0 
L 5.15485 1.76515 5.06323002 1.85676998 2 P 0 
L 5.06323002 1.85676998 5.06323002 1.9342 2 P 0 
L 5.06323002 1.9342 5.05073002 1.9467 2 P 0 
L 5.05073002 1.9467 4.98868002 1.9467 2 P 0 
L 4.98868002 1.9467 4.98268002 1.9527 2 P 0 
L 4.98268002 1.9527 4.98268002 1.96615 2 P 0 
P 4.98268002 1.96615 6 P 0 0;5=4,7=1
P 5.30875 1.7821 25 P 0 0;2,5=0,7=0
P 4.93268002 1.86615 6 P 0 0;5=4,7=1
P 5.30875 1.6458 25 P 0 0;2,5=0,7=0
L 5.30875 1.6458 5.2918 1.62885 2 P 0 
L 5.2918 1.62885 5.2607 1.62885 2 P 0 
L 5.2607 1.62885 5.25763002 1.63191998 2 P 0 
L 5.25763002 1.63191998 5.25763002 1.63193002 2 P 0 
L 5.25763002 1.63193002 5.25456004 1.635 2 P 0 
L 5.25456004 1.635 5.23656004 1.635 2 P 0 
L 5.23656004 1.635 5.23348996 1.63193002 2 P 0 
L 5.23348996 1.63193002 5.23348996 1.63191998 2 P 0 
L 5.23348996 1.63191998 5.23041998 1.62885 2 P 0 
L 5.23041998 1.62885 5.21241998 1.62885 2 P 0 
L 5.21241998 1.62885 5.20935 1.63191998 2 P 0 
L 5.20935 1.63191998 5.20935 1.63193002 2 P 0 
L 5.20935 1.63193002 5.20628002 1.635 2 P 0 
L 5.20628002 1.635 5.18828002 1.635 2 P 0 
L 5.18828002 1.635 5.18521004 1.63193002 2 P 0 
L 5.18521004 1.63193002 5.18521004 1.63191998 2 P 0 
L 5.18521004 1.63191998 5.18213996 1.62885 2 P 0 
L 5.18213996 1.62885 5.09785 1.62885 2 P 0 
L 5.09785 1.62885 5.01126998 1.71543002 2 P 0 
L 5.01126998 1.71543002 5.01126998 1.72571004 2 P 0 
L 5.01126998 1.72571004 4.99853996 1.73843996 2 P 0 
L 4.99853996 1.73843996 4.98826004 1.73843996 2 P 0 
L 4.98826004 1.73843996 4.97553002 1.75116998 2 P 0 
L 4.97553002 1.75116998 4.97553002 1.76145 2 P 0 
L 4.97553002 1.76145 4.9628 1.77418002 2 P 0 
L 4.9628 1.77418002 4.95251998 1.77418002 2 P 0 
L 4.95251998 1.77418002 4.91323002 1.81346998 2 P 0 
L 4.91323002 1.81346998 4.91323002 1.88443996 2 P 0 
L 4.91323002 1.88443996 4.92078996 1.892 2 P 0 
L 4.92078996 1.892 4.92928002 1.892 2 P 0 
L 4.92928002 1.892 4.93268002 1.8886 2 P 0 
L 4.93268002 1.8886 4.93268002 1.86615 2 P 0 
P 5.30875 1.6008 25 P 0 0;2,5=0,7=0
P 4.93268002 1.91615 6 P 0 0;5=4,7=1
L 5.30875 1.6008 5.2918 1.61775 2 P 0 
L 5.2918 1.61775 5.09325 1.61775 2 P 0 
L 5.09325 1.61775 4.90213002 1.80886998 2 P 0 
L 4.90213002 1.80886998 4.90213002 1.88903996 2 P 0 
L 4.90213002 1.88903996 4.91618996 1.9031 2 P 0 
L 4.91618996 1.9031 4.92978002 1.9031 2 P 0 
L 4.92978002 1.9031 4.93268002 1.906 2 P 0 
L 4.93268002 1.906 4.93268002 1.91615 2 P 0 
P 5.03268002 1.86615 6 P 0 0;5=4,7=1
P 5.46358002 1.7143 25 P 0 0;2,5=0,7=0
L 5.03268002 1.86615 5.03268002 1.8849 2 P 0 
L 5.03268002 1.8849 5.02668002 1.8909 2 P 0 
L 5.02668002 1.8909 5.01923996 1.8909 2 P 0 
L 5.01923996 1.8909 5.01323996 1.8849 2 P 0 
L 5.01323996 1.8849 5.01323996 1.80776004 2 P 0 
L 5.01323996 1.80776004 5.03018996 1.79081004 2 P 0 
L 5.03018996 1.79081004 5.04041998 1.79081004 2 P 0 
L 5.04041998 1.79081004 5.05291998 1.77831004 2 P 0 
L 5.05291998 1.77831004 5.05291998 1.76808002 2 P 0 
L 5.05291998 1.76808002 5.06565 1.75535 2 P 0 
L 5.06565 1.75535 5.07565 1.75535 2 P 0 
L 5.07565 1.75535 5.08838002 1.74261998 2 P 0 
L 5.08838002 1.74261998 5.08838002 1.73261998 2 P 0 
L 5.08838002 1.73261998 5.12365 1.69735 2 P 0 
L 5.12365 1.69735 5.19696004 1.69735 2 P 0 
L 5.19696004 1.69735 5.20028002 1.70066998 2 P 0 
L 5.20028002 1.70066998 5.20028002 1.70068002 2 P 0 
L 5.20028002 1.70068002 5.2036 1.704 2 P 0 
L 5.2036 1.704 5.2216 1.704 2 P 0 
L 5.2216 1.704 5.22491998 1.70068002 2 P 0 
L 5.22491998 1.70068002 5.22491998 1.70066998 2 P 0 
L 5.22491998 1.70066998 5.22823996 1.69735 2 P 0 
L 5.22823996 1.69735 5.24623996 1.69735 2 P 0 
L 5.24623996 1.69735 5.24956004 1.70066998 2 P 0 
L 5.24956004 1.70066998 5.24956004 1.70068002 2 P 0 
L 5.24956004 1.70068002 5.25288002 1.704 2 P 0 
L 5.25288002 1.704 5.27088002 1.704 2 P 0 
L 5.27088002 1.704 5.2742 1.70068002 2 P 0 
L 5.2742 1.70068002 5.2742 1.70066998 2 P 0 
L 5.2742 1.70066998 5.27751998 1.69735 2 P 0 
L 5.27751998 1.69735 5.44663002 1.69735 2 P 0 
L 5.44663002 1.69735 5.46358002 1.7143 2 P 0 
P 5.08268002 1.91615 6 P 0 0;5=4,7=1
L 5.46358002 1.8083 5.44663002 1.82525 2 P 0 
L 5.44663002 1.82525 5.21305 1.82525 2 P 0 
L 5.21305 1.82525 5.1229 1.9154 2 P 0 
L 5.1229 1.9154 5.1229 1.92338996 2 P 0 
L 5.1229 1.92338996 5.11068996 1.9356 2 P 0 
L 5.11068996 1.9356 5.08868002 1.9356 2 P 0 
L 5.08868002 1.9356 5.08268002 1.9296 2 P 0 
L 5.08268002 1.9296 5.08268002 1.91615 2 P 0 
P 5.46358002 1.8083 25 P 0 0;2,5=0,7=0
P 5.08268002 2.56615 6 P 0 0;5=4,7=1
L 7.90393996 2.48 7.88083996 2.48 3 P 0 
L 7.88083996 2.48 7.87893996 2.4781 3 P 0 
L 7.87893996 2.4781 7.85815 2.4781 3 P 0 
P 7.85815 2.4781 25 P 0 0;2,5=0,7=0
P 7.90393996 2.48 8 P 0 0;3,5=5,7=1
L 7.90393996 2.48 7.93278996 2.48 3 P 0 
L 7.93278996 2.48 7.94393996 2.49115 3 P 0 
L 7.94393996 2.49115 8.125 2.49115 3 P 0 
L 8.125 2.49115 8.15 2.51615 3 P 0 
P 8.15 2.51615 6 P 0 0;5=4,7=1
P 4.98268002 2.61615 6 P 0 0;5=4,7=1
L 11.27 2.73 11.31661998 2.73 3 P 0 
P 10.68661004 2.71615 6 P 0 0;5=4,7=1
L 11.31661998 2.73 11.31661998 2.7568 3 P 0 
L 11.31661998 2.7568 11.32481998 2.765 3 P 0 
L 11.32481998 2.765 11.42361998 2.765 3 P 0 
L 11.42361998 2.765 11.43661998 2.752 3 P 0 
L 11.43661998 2.752 11.43661998 2.73 3 P 0 
P 11.31661998 2.73 25 P 0 0;2,5=0,7=0
P 11.43661998 2.73 25 P 0 0;2,5=0,7=0
L 10.68661004 2.71615 10.71161004 2.69115 3 P 0 
L 10.71161004 2.69115 10.74958996 2.69115 3 P 0 
L 10.74958996 2.69115 10.76158996 2.67915 3 P 0 
L 10.76158996 2.67915 10.76158996 2.67653002 3 P 0 
L 10.76158996 2.67653002 10.76161004 2.67651004 3 P 0 
L 10.76161004 2.67651004 10.76161004 2.65138996 3 P 0 
L 10.76161004 2.65138996 10.77185 2.64115 3 P 0 
L 10.77185 2.64115 11.13585 2.64115 3 P 0 
L 11.13585 2.64115 11.2247 2.73 3 P 0 
L 11.2247 2.73 11.27 2.73 3 P 0 
P 11.27 2.73 8 P 0 0;3,5=5,7=1
L 11.27 2.8 11.31661998 2.8 3 P 0 
P 10.98661004 2.71615 6 P 0 0;5=4,7=1
L 11.31661998 2.8 11.31661998 2.82048002 3 P 0 
L 11.31661998 2.82048002 11.33113996 2.835 3 P 0 
L 11.33113996 2.835 11.41361998 2.835 3 P 0 
L 11.41361998 2.835 11.43661998 2.812 3 P 0 
L 11.43661998 2.812 11.43661998 2.8 3 P 0 
P 11.31661998 2.8 25 P 0 0;2,5=0,7=0
P 11.43661998 2.8 25 P 0 0;2,5=0,7=0
L 10.98661004 2.71615 11.01161004 2.69115 3 P 0 
L 11.01161004 2.69115 11.13585 2.69115 3 P 0 
L 11.13585 2.69115 11.2447 2.8 3 P 0 
L 11.2447 2.8 11.27 2.8 3 P 0 
P 11.27 2.8 8 P 0 0;3,5=5,7=1
L 11.555 2.82 11.505 2.87 3 P 0 
L 11.505 2.87 11.2697 2.87 3 P 0 
L 11.2697 2.87 11.14085 2.74115 3 P 0 
L 11.14085 2.74115 10.9707 2.74115 3 P 0 
L 10.9707 2.74115 10.96161004 2.73206004 3 P 0 
L 10.96161004 2.73206004 10.96161004 2.70578996 3 P 0 
L 10.96161004 2.70578996 10.94696998 2.69115 3 P 0 
L 10.94696998 2.69115 10.85185 2.69115 3 P 0 
L 10.85185 2.69115 10.82685 2.71615 3 P 0 
L 10.82685 2.71615 10.78661004 2.71615 3 P 0 
P 10.78661004 2.71615 6 P 0 0;5=4,7=1
P 11.65061998 2.785 25 P 0 0;2,5=0,7=0
L 11.65061998 2.785 11.66861998 2.785 3 P 0 
L 11.66861998 2.785 11.70803002 2.82441004 3 P 0 
L 11.70803002 2.82441004 11.72031004 2.82441004 3 P 0 
P 11.72031004 2.82441004 30 P 0 0;2,5=8,7=0
L 11.65061998 2.785 11.65061998 2.8089 3 P 0 
L 11.65061998 2.8089 11.63951998 2.82 3 P 0 
L 11.63951998 2.82 11.555 2.82 3 P 0 
P 11.555 2.82 8 P 0 0;3,5=5,7=1
P 4.93268002 2.66615 6 P 0 0;5=4,7=1
P 10.88661004 2.71615 6 P 0 0;5=4,7=1
L 11.56 2.945 11.64211998 2.945 3 P 0 
L 11.64211998 2.945 11.65061998 2.9365 3 P 0 
L 11.65061998 2.9365 11.65061998 2.905 3 P 0 
P 11.65061998 2.905 25 P 0 0;2,5=0,7=0
P 11.72031004 2.87558996 30 P 0 0;2,5=8,7=0
L 11.72031004 2.87558996 11.71055 2.87558996 3 P 0 
L 11.71055 2.87558996 11.68113996 2.905 3 P 0 
L 11.68113996 2.905 11.65061998 2.905 3 P 0 
P 11.56 2.945 8 P 0 0;3,5=5,7=1
L 10.88661004 2.71615 10.91161004 2.74115 3 P 0 
L 10.91161004 2.74115 10.91161004 2.78291004 3 P 0 
L 10.91161004 2.78291004 10.91985 2.79115 3 P 0 
L 10.91985 2.79115 11.13763002 2.79115 3 P 0 
L 11.13763002 2.79115 11.25148002 2.905 3 P 0 
L 11.25148002 2.905 11.495 2.905 3 P 0 
L 11.495 2.905 11.535 2.945 3 P 0 
L 11.535 2.945 11.56 2.945 3 P 0 
P 10.68661004 2.76615 6 P 0 0;5=4,7=1
P 9.64 0.71 8 P 0 0;3,5=1,7=1
L 9.64 0.71 9.685 0.755 3 P 0 
L 9.685 0.755 9.685 2.69378996 3 P 0 
L 9.685 2.69378996 10.00521004 3.014 3 P 0 
L 10.00521004 3.014 10.22601004 3.014 3 P 0 
L 10.22601004 3.014 10.49886004 2.74115 3 P 0 
L 10.49886004 2.74115 10.66161004 2.74115 3 P 0 
L 10.66161004 2.74115 10.68661004 2.76615 3 P 0 
P 10.58661004 2.81615 6 P 0 0;5=4,7=1
L 10.58661004 2.81615 10.56115 2.81615 3 P 0 
L 10.56115 2.81615 10.55 2.805 3 P 0 
L 10.55 2.805 10.52501004 2.805 3 P 0 
L 10.52501004 2.805 10.25901004 3.071 3 P 0 
L 10.25901004 3.071 9.98156998 3.071 3 P 0 
L 9.98156998 3.071 9.545 2.63443002 3 P 0 
L 9.545 2.63443002 9.545 0.60336998 3 P 0 
L 9.545 0.60336998 9.43296004 0.49133002 3 P 0 
P 9.43296004 0.49133002 8 P 0 0;3,5=1,7=1
P 9.43296004 0.73633002 8 P 0 0;3,5=1,7=1
P 10.63661004 2.81615 6 P 0 0;5=4,7=1
L 10.63661004 2.81615 10.61161004 2.84115 3 P 0 
L 10.61161004 2.84115 10.53383996 2.84115 3 P 0 
L 10.53383996 2.84115 10.27548996 3.0995 3 P 0 
L 10.27548996 3.0995 9.96975 3.0995 3 P 0 
L 9.96975 3.0995 9.42071004 2.55046004 3 P 0 
L 9.42071004 2.55046004 9.42071004 0.74858002 3 P 0 
L 9.42071004 0.74858002 9.43296004 0.73633002 3 P 0 
P 4.68268002 2.56615 6 P 0 0;5=4,7=1
P 10.68661004 2.81615 6 P 0 0;5=4,7=1
P 9.55795 0.36633002 8 P 0 0;3,5=1,7=1
L 10.68661004 2.81615 10.63776004 2.865 3 P 0 
L 10.63776004 2.865 10.55501004 2.865 3 P 0 
L 10.55501004 2.865 10.28901004 3.131 3 P 0 
L 10.28901004 3.131 9.96093002 3.131 3 P 0 
L 9.96093002 3.131 9.39221004 2.56228002 3 P 0 
L 9.39221004 2.56228002 9.39221004 0.5092 3 P 0 
L 9.39221004 0.5092 9.39481004 0.5066 3 P 0 
L 9.39481004 0.5066 9.39481004 0.47606004 3 P 0 
L 9.39481004 0.47606004 9.39221004 0.47346004 3 P 0 
L 9.39221004 0.47346004 9.39221004 0.46778996 3 P 0 
L 9.39221004 0.46778996 9.44 0.42 3 P 0 
L 9.44 0.42 9.50428002 0.42 3 P 0 
L 9.50428002 0.42 9.55795 0.36633002 3 P 0 
L 10.73661004 2.81615 10.66161004 2.89115 3 P 0 
L 10.66161004 2.89115 10.56885 2.89115 3 P 0 
L 10.56885 2.89115 10.299 3.161 3 P 0 
L 10.299 3.161 9.95061004 3.161 3 P 0 
L 9.95061004 3.161 9.36371004 2.5741 3 P 0 
L 9.36371004 2.5741 9.36371004 0.49708002 3 P 0 
L 9.36371004 0.49708002 9.35796004 0.49133002 3 P 0 
P 10.73661004 2.81615 6 P 0 0;5=4,7=1
P 9.35796004 0.49133002 8 P 0 0;3,5=1,7=1
P 5.03268002 2.66615 6 P 0 0;5=4,7=1
L 9.58296004 0.71133002 9.58226004 0.71203002 3 P 0 
L 9.58226004 0.71203002 9.58226004 2.63136998 3 P 0 
L 9.58226004 2.63136998 9.99338996 3.0425 3 P 0 
L 9.99338996 3.0425 10.24248996 3.0425 3 P 0 
L 10.24248996 3.0425 10.50998996 2.775 3 P 0 
L 10.50998996 2.775 10.56 2.775 3 P 0 
L 10.56 2.775 10.575 2.79 3 P 0 
L 10.575 2.79 10.5751 2.79 3 P 0 
L 10.5751 2.79 10.57625 2.79115 3 P 0 
L 10.57625 2.79115 10.76161004 2.79115 3 P 0 
L 10.76161004 2.79115 10.78661004 2.81615 3 P 0 
P 10.78661004 2.81615 6 P 0 0;5=4,7=1
P 9.58296004 0.71133002 8 P 0 0;3,5=1,7=1
P 5.08268002 2.61615 6 P 0 0;5=4,7=1
P 11.08661004 1.96615 6 P 0 0;5=4,7=1
P 11.62193002 1.695 25 P 0 0;2,5=0,7=0
L 11.08661004 1.96615 11.08661004 1.9527 2 P 0 
L 11.08661004 1.9527 11.09261004 1.9467 2 P 0 
L 11.09261004 1.9467 11.11028996 1.9467 2 P 0 
L 11.11028996 1.9467 11.12455 1.93243996 2 P 0 
L 11.12455 1.93243996 11.23156004 1.77963996 2 P 0 
L 11.23156004 1.77963996 11.3608 1.68915 2 P 0 
L 11.3608 1.68915 11.42626004 1.6776 2 P 0 
L 11.42626004 1.6776 11.60453002 1.6776 2 P 0 
L 11.60453002 1.6776 11.62193002 1.695 2 P 0 
P 11.03661004 1.86615 6 P 0 0;5=4,7=1
P 11.62193002 1.535 25 P 0 0;2,5=0,7=0
L 11.03661004 1.86615 11.03661004 1.8839 2 P 0 
L 11.03661004 1.8839 11.03061004 1.8899 2 P 0 
L 11.03061004 1.8899 11.02316004 1.8899 2 P 0 
L 11.02316004 1.8899 11.01716004 1.8839 2 P 0 
L 11.01716004 1.8839 11.01716004 1.85015 2 P 0 
L 11.01716004 1.85015 11.00693002 1.83991998 2 P 0 
L 11.00693002 1.83991998 11.00693002 1.81278002 2 P 0 
L 11.00693002 1.81278002 11.02173002 1.79166004 2 P 0 
L 11.02173002 1.79166004 11.03733996 1.78073002 2 P 0 
L 11.03733996 1.78073002 11.0467 1.78238996 2 P 0 
L 11.0467 1.78238996 11.06146998 1.77205 2 P 0 
L 11.06146998 1.77205 11.06311998 1.76268002 2 P 0 
L 11.06311998 1.76268002 11.07788002 1.75235 2 P 0 
L 11.07788002 1.75235 11.08723996 1.75401004 2 P 0 
L 11.08723996 1.75401004 11.10201004 1.74366998 2 P 0 
L 11.10201004 1.74366998 11.10366004 1.7343 2 P 0 
L 11.10366004 1.7343 11.11993002 1.72291998 2 P 0 
L 11.11993002 1.72291998 11.1762 1.64253002 2 P 0 
L 11.1762 1.64253002 11.1858 1.64085 2 P 0 
L 11.1858 1.64085 11.19613996 1.62608996 2 P 0 
L 11.19613996 1.62608996 11.19441998 1.61648996 2 P 0 
L 11.19441998 1.61648996 11.20158002 1.60626998 2 P 0 
L 11.20158002 1.60626998 11.3053 1.53363002 2 P 0 
L 11.3053 1.53363002 11.39623996 1.5176 2 P 0 
L 11.39623996 1.5176 11.5117 1.5176 2 P 0 
L 11.5117 1.5176 11.5168 1.5227 2 P 0 
L 11.5168 1.5227 11.5348 1.5227 2 P 0 
L 11.5348 1.5227 11.5399 1.5176 2 P 0 
L 11.5399 1.5176 11.5579 1.5176 2 P 0 
L 11.5579 1.5176 11.563 1.5227 2 P 0 
L 11.563 1.5227 11.581 1.5227 2 P 0 
L 11.581 1.5227 11.5861 1.5176 2 P 0 
L 11.5861 1.5176 11.60453002 1.5176 2 P 0 
L 11.60453002 1.5176 11.62193002 1.535 2 P 0 
P 11.62193002 1.49 25 P 0 0;2,5=0,7=0
P 11.03661004 1.91615 6 P 0 0;5=4,7=1
L 11.62193002 1.49 11.60543002 1.5065 2 P 0 
L 11.60543002 1.5065 11.39526004 1.5065 2 P 0 
L 11.39526004 1.5065 11.30095 1.52311998 2 P 0 
L 11.30095 1.52311998 11.1936 1.59828996 2 P 0 
L 11.1936 1.59828996 11.11195 1.71493996 2 P 0 
L 11.11195 1.71493996 11.01375 1.78368002 2 P 0 
L 11.01375 1.78368002 10.99583002 1.80926998 2 P 0 
L 10.99583002 1.80926998 10.99583002 1.84451998 2 P 0 
L 10.99583002 1.84451998 11.00606004 1.85475 2 P 0 
L 11.00606004 1.85475 11.00606004 1.8885 2 P 0 
L 11.00606004 1.8885 11.01856004 1.901 2 P 0 
L 11.01856004 1.901 11.03061004 1.901 2 P 0 
L 11.03061004 1.901 11.03661004 1.907 2 P 0 
L 11.03661004 1.907 11.03661004 1.91615 2 P 0 
P 10.93661004 1.86615 6 P 0 0;5=4,7=1
P 11.42193002 1.455 25 P 0 0;2,5=0,7=0
L 10.93661004 1.86615 10.93661004 1.8879 2 P 0 
L 10.93661004 1.8879 10.93061004 1.8939 2 P 0 
L 10.93061004 1.8939 10.92316004 1.8939 2 P 0 
L 10.92316004 1.8939 10.91716004 1.8879 2 P 0 
L 10.91716004 1.8879 10.91716004 1.85016004 2 P 0 
L 10.91716004 1.85016004 10.91696004 1.84901998 2 P 0 
L 10.91696004 1.84901998 10.91696004 1.84415 2 P 0 
L 10.91696004 1.84415 10.91208996 1.81638002 2 P 0 
L 10.91208996 1.81638002 10.91381998 1.80655 2 P 0 
L 10.91381998 1.80655 10.92923002 1.78451004 2 P 0 
L 10.92923002 1.78451004 10.95491004 1.76653002 2 P 0 
L 10.95491004 1.76653002 10.96428996 1.76818996 2 P 0 
L 10.96428996 1.76818996 10.97906004 1.75786004 2 P 0 
L 10.97906004 1.75786004 10.9807 1.74848002 2 P 0 
L 10.9807 1.74848002 11.06685 1.68816998 2 P 0 
L 11.06685 1.68816998 11.14851998 1.57151004 2 P 0 
L 11.14851998 1.57151004 11.16226004 1.56188996 2 P 0 
L 11.16226004 1.56188996 11.16936004 1.56313996 2 P 0 
L 11.16936004 1.56313996 11.18411998 1.55281004 2 P 0 
L 11.18411998 1.55281004 11.18536998 1.54571004 2 P 0 
L 11.18536998 1.54571004 11.24713002 1.50246004 2 P 0 
L 11.24713002 1.50246004 11.25423002 1.50371998 2 P 0 
L 11.25423002 1.50371998 11.26898996 1.49338002 2 P 0 
L 11.26898996 1.49338002 11.27023996 1.48628002 2 P 0 
L 11.27023996 1.48628002 11.28498002 1.47596004 2 P 0 
L 11.28498002 1.47596004 11.29208002 1.47721004 2 P 0 
L 11.29208002 1.47721004 11.30683996 1.46686998 2 P 0 
L 11.30683996 1.46686998 11.30808996 1.45976998 2 P 0 
L 11.30808996 1.45976998 11.32283002 1.44945 2 P 0 
L 11.32283002 1.44945 11.38998002 1.4376 2 P 0 
L 11.38998002 1.4376 11.40453002 1.4376 2 P 0 
L 11.40453002 1.4376 11.42193002 1.455 2 P 0 
P 10.93661004 1.91615 6 P 0 0;5=4,7=1
P 11.42193002 1.41 25 P 0 0;2,5=0,7=0
L 11.42193002 1.41 11.40543002 1.4265 2 P 0 
L 11.40543002 1.4265 11.389 1.4265 2 P 0 
L 11.389 1.4265 11.31848002 1.43893996 2 P 0 
L 11.31848002 1.43893996 11.14053996 1.56353002 2 P 0 
L 11.14053996 1.56353002 11.05886998 1.68018996 2 P 0 
L 11.05886998 1.68018996 10.92125 1.77653996 2 P 0 
L 10.92125 1.77653996 10.90331004 1.80221004 2 P 0 
L 10.90331004 1.80221004 10.90038002 1.81881004 2 P 0 
L 10.90038002 1.81881004 10.90606004 1.85113002 2 P 0 
L 10.90606004 1.85113002 10.90606004 1.8925 2 P 0 
L 10.90606004 1.8925 10.91856004 1.905 2 P 0 
L 10.91856004 1.905 10.93061004 1.905 2 P 0 
L 10.93061004 1.905 10.93661004 1.911 2 P 0 
L 10.93661004 1.911 10.93661004 1.91615 2 P 0 
P 10.98661004 1.91615 6 P 0 0;5=4,7=1
P 11.42193002 1.57 25 P 0 0;2,5=0,7=0
L 11.42193002 1.57 11.40498002 1.58695 2 P 0 
L 11.40498002 1.58695 11.34271004 1.58695 2 P 0 
L 11.34271004 1.58695 11.20526004 1.6832 2 P 0 
L 11.20526004 1.6832 11.14253996 1.77271004 2 P 0 
L 11.14253996 1.77271004 11.08591004 1.81236998 2 P 0 
L 11.08591004 1.81236998 11.05606004 1.84223002 2 P 0 
L 11.05606004 1.84223002 11.05606004 1.9296 2 P 0 
L 11.05606004 1.9296 11.05006004 1.9356 2 P 0 
L 11.05006004 1.9356 10.99261004 1.9356 2 P 0 
L 10.99261004 1.9356 10.98661004 1.9296 2 P 0 
L 10.98661004 1.9296 10.98661004 1.91615 2 P 0 
P 10.98661004 1.96615 6 P 0 0;5=4,7=1
P 11.42193002 1.615 25 P 0 0;2,5=0,7=0
L 11.42193002 1.615 11.40498002 1.59805 2 P 0 
L 11.40498002 1.59805 11.34621998 1.59805 2 P 0 
L 11.34621998 1.59805 11.21323002 1.69116998 2 P 0 
L 11.21323002 1.69116998 11.15051004 1.78068002 2 P 0 
L 11.15051004 1.78068002 11.09308002 1.82091004 2 P 0 
L 11.09308002 1.82091004 11.06716004 1.84683002 2 P 0 
L 11.06716004 1.84683002 11.06716004 1.9342 2 P 0 
L 11.06716004 1.9342 11.05466004 1.9467 2 P 0 
L 11.05466004 1.9467 10.99261004 1.9467 2 P 0 
L 10.99261004 1.9467 10.98661004 1.9527 2 P 0 
L 10.98661004 1.9527 10.98661004 1.96615 2 P 0 
P 4.93268002 2.61615 6 P 0 0;5=4,7=1
P 11.03661004 2.01615 6 P 0 0;5=4,7=1
P 11.62193002 1.81 25 P 0 0;2,5=0,7=0
L 11.62193002 1.81 11.60498002 1.82695 2 P 0 
L 11.60498002 1.82695 11.40808002 1.82695 2 P 0 
L 11.40808002 1.82695 11.35533002 1.83625 2 P 0 
L 11.35533002 1.83625 11.26668996 1.89831998 2 P 0 
L 11.26668996 1.89831998 11.19886998 1.99518002 2 P 0 
L 11.19886998 1.99518002 11.14818996 2.03068996 2 P 0 
L 11.14818996 2.03068996 11.12028996 2.0356 2 P 0 
L 11.12028996 2.0356 11.04261004 2.0356 2 P 0 
L 11.04261004 2.0356 11.03661004 2.0296 2 P 0 
L 11.03661004 2.0296 11.03661004 2.01615 2 P 0 
P 11.03661004 2.06615 6 P 0 0;5=4,7=1
P 11.62193002 1.855 25 P 0 0;2,5=0,7=0
L 11.62193002 1.855 11.60498002 1.83805 2 P 0 
L 11.60498002 1.83805 11.40906004 1.83805 2 P 0 
L 11.40906004 1.83805 11.35968002 1.84676004 2 P 0 
L 11.35968002 1.84676004 11.27466004 1.9063 2 P 0 
L 11.27466004 1.9063 11.27466004 1.90628996 2 P 0 
L 11.27466004 1.90628996 11.20683996 2.00315 2 P 0 
L 11.20683996 2.00315 11.15253996 2.0412 2 P 0 
L 11.15253996 2.0412 11.12126004 2.0467 2 P 0 
L 11.12126004 2.0467 11.04261004 2.0467 2 P 0 
L 11.04261004 2.0467 11.03661004 2.0527 2 P 0 
L 11.03661004 2.0527 11.03661004 2.06615 2 P 0 
P 10.93661004 2.01615 6 P 0 0;5=4,7=1
P 11.42193002 1.73 25 P 0 0;2,5=0,7=0
L 11.42193002 1.73 11.40498002 1.74695 2 P 0 
L 11.40498002 1.74695 11.38901998 1.74695 2 P 0 
L 11.38901998 1.74695 11.3485 1.75408996 2 P 0 
L 11.3485 1.75408996 11.25571004 1.81908996 2 P 0 
L 11.25571004 1.81908996 11.15853002 1.95783996 2 P 0 
L 11.15853002 1.95783996 11.12421998 1.98186004 2 P 0 
L 11.12421998 1.98186004 11.10306004 1.9856 2 P 0 
L 11.10306004 1.9856 11.01856004 1.9856 2 P 0 
L 11.01856004 1.9856 11.00606004 1.9981 2 P 0 
L 11.00606004 1.9981 11.00606004 2.0296 2 P 0 
L 11.00606004 2.0296 11.00006004 2.0356 2 P 0 
L 11.00006004 2.0356 10.94261004 2.0356 2 P 0 
L 10.94261004 2.0356 10.93661004 2.0296 2 P 0 
L 10.93661004 2.0296 10.93661004 2.01615 2 P 0 
P 10.93661004 2.06615 6 P 0 0;5=4,7=1
P 11.42193002 1.775 25 P 0 0;2,5=0,7=0
L 11.42193002 1.775 11.40498002 1.75805 2 P 0 
L 11.40498002 1.75805 11.38998996 1.75805 2 P 0 
L 11.38998996 1.75805 11.35286004 1.7646 2 P 0 
L 11.35286004 1.7646 11.26368002 1.82706004 2 P 0 
L 11.26368002 1.82706004 11.1665 1.96581004 2 P 0 
L 11.1665 1.96581004 11.12858002 1.99236998 2 P 0 
L 11.12858002 1.99236998 11.10403996 1.9967 2 P 0 
L 11.10403996 1.9967 11.02316004 1.9967 2 P 0 
L 11.02316004 1.9967 11.01716004 2.0027 2 P 0 
L 11.01716004 2.0027 11.01716004 2.0342 2 P 0 
L 11.01716004 2.0342 11.00466004 2.0467 2 P 0 
L 11.00466004 2.0467 10.94261004 2.0467 2 P 0 
L 10.94261004 2.0467 10.93661004 2.0527 2 P 0 
L 10.93661004 2.0527 10.93661004 2.06615 2 P 0 
P 10.98661004 2.06615 6 P 0 0;5=4,7=1
P 11.62193002 1.97 25 P 0 0;2,5=0,7=0
L 11.62193002 1.97 11.60498002 1.98695 2 P 0 
L 11.60498002 1.98695 11.401 1.98695 2 P 0 
L 11.401 1.98695 11.20541004 2.1239 2 P 0 
L 11.20541004 2.1239 11.139 2.1356 2 P 0 
L 11.139 2.1356 11.02316004 2.1356 2 P 0 
L 11.02316004 2.1356 11.01716004 2.1296 2 P 0 
L 11.01716004 2.1296 11.01716004 2.0981 2 P 0 
L 11.01716004 2.0981 11.00466004 2.0856 2 P 0 
L 11.00466004 2.0856 10.99261004 2.0856 2 P 0 
L 10.99261004 2.0856 10.98661004 2.0796 2 P 0 
L 10.98661004 2.0796 10.98661004 2.06615 2 P 0 
P 10.98661004 2.11615 6 P 0 0;5=4,7=1
P 11.62193002 2.015 25 P 0 0;2,5=0,7=0
L 11.62193002 2.015 11.60498002 1.99805 2 P 0 
L 11.60498002 1.99805 11.4045 1.99805 2 P 0 
L 11.4045 1.99805 11.20976004 2.13441004 2 P 0 
L 11.20976004 2.13441004 11.13998002 2.1467 2 P 0 
L 11.13998002 2.1467 11.01856004 2.1467 2 P 0 
L 11.01856004 2.1467 11.00606004 2.1342 2 P 0 
L 11.00606004 2.1342 11.00606004 2.1027 2 P 0 
L 11.00606004 2.1027 11.00006004 2.0967 2 P 0 
L 11.00006004 2.0967 10.99261004 2.0967 2 P 0 
L 10.99261004 2.0967 10.98661004 2.1027 2 P 0 
L 10.98661004 2.1027 10.98661004 2.11615 2 P 0 
P 11.08661004 2.06615 6 P 0 0;5=4,7=1
L 11.08661004 2.06615 11.08661004 2.0796 2 P 0 
L 11.08661004 2.0796 11.09261004 2.0856 2 P 0 
L 11.09261004 2.0856 11.13288996 2.0856 2 P 0 
L 11.13288996 2.0856 11.17733996 2.07776998 2 P 0 
L 11.17733996 2.07776998 11.23678996 2.03611004 2 P 0 
L 11.23678996 2.03611004 11.29051998 1.95936998 2 P 0 
L 11.29051998 1.95936998 11.35646998 1.91321004 2 P 0 
L 11.35646998 1.91321004 11.39201998 1.90695 2 P 0 
L 11.39201998 1.90695 11.40498002 1.90695 2 P 0 
L 11.40498002 1.90695 11.42193002 1.89 2 P 0 
P 11.42193002 1.89 25 P 0 0;2,5=0,7=0
P 11.08661004 2.11615 6 P 0 0;5=4,7=1
L 11.08661004 2.11615 11.08661004 2.1027 2 P 0 
L 11.08661004 2.1027 11.09261004 2.0967 2 P 0 
L 11.09261004 2.0967 11.13386998 2.0967 2 P 0 
L 11.13386998 2.0967 11.1817 2.08828002 2 P 0 
L 11.1817 2.08828002 11.24476998 2.04408996 2 P 0 
L 11.24476998 2.04408996 11.2985 1.96735 2 P 0 
L 11.2985 1.96735 11.36081998 1.92371998 2 P 0 
L 11.36081998 1.92371998 11.393 1.91805 2 P 0 
L 11.393 1.91805 11.40498002 1.91805 2 P 0 
L 11.40498002 1.91805 11.42193002 1.935 2 P 0 
P 11.42193002 1.935 25 P 0 0;2,5=0,7=0
L 3.09646004 5.298 3.09646004 5.27353996 3 P 0 
L 3.09646004 5.27353996 3.115 5.255 3 P 0 
L 3.09646004 5.298 3.14146004 5.298 3 P 0 
P 3.14146004 5.298 25 P 0 0;2,5=0,7=0
P 3.09646004 5.298 25 P 0 0;2,5=0,7=0
P 3.115 5.255 8 P 0 0;3,5=1,7=1
P 4.63268002 2.66615 6 P 0 0;5=4,7=1
P 11.08661004 2.21615 6 P 0 0;5=4,7=1
P 11.62193002 2.13 25 P 0 0;2,5=0,7=0
L 11.62193002 2.13 11.60496004 2.14696998 2 P 0 
L 11.60496004 2.14696998 11.4023 2.14696998 2 P 0 
L 11.4023 2.14696998 11.35936004 2.15453996 2 P 0 
L 11.35936004 2.15453996 11.27513996 2.21351004 2 P 0 
L 11.27513996 2.21351004 11.14981998 2.2356 2 P 0 
L 11.14981998 2.2356 11.09261004 2.2356 2 P 0 
L 11.09261004 2.2356 11.08661004 2.2296 2 P 0 
L 11.08661004 2.2296 11.08661004 2.21615 2 P 0 
P 4.98268002 2.56615 6 P 0 0;5=4,7=1
P 11.08661004 2.26615 6 P 0 0;5=4,7=1
P 11.62193002 2.175 25 P 0 0;2,5=0,7=0
L 11.62193002 2.175 11.605 2.15806998 2 P 0 
L 11.605 2.15806998 11.40328002 2.15806998 2 P 0 
L 11.40328002 2.15806998 11.36371004 2.16505 2 P 0 
L 11.36371004 2.16505 11.27948996 2.22401998 2 P 0 
L 11.27948996 2.22401998 11.21441004 2.2355 2 P 0 
L 11.21441004 2.2355 11.2144 2.2355 2 P 0 
L 11.2144 2.2355 11.1508 2.2467 2 P 0 
L 11.1508 2.2467 11.09261004 2.2467 2 P 0 
L 11.09261004 2.2467 11.08661004 2.2527 2 P 0 
L 11.08661004 2.2527 11.08661004 2.26615 2 P 0 
P 11.03661004 2.26615 6 P 0 0;5=4,7=1
L 11.03661004 2.26615 11.03661004 2.2796 2 P 0 
L 11.03661004 2.2796 11.04261004 2.2856 2 P 0 
L 11.04261004 2.2856 11.17416998 2.2856 2 P 0 
L 11.17416998 2.2856 11.3066 2.26223996 2 P 0 
L 11.3066 2.26223996 11.35015 2.23173002 2 P 0 
L 11.35015 2.23173002 11.37731004 2.22695 2 P 0 
L 11.37731004 2.22695 11.40498002 2.22695 2 P 0 
L 11.40498002 2.22695 11.42193002 2.21 2 P 0 
P 11.42193002 2.21 25 P 0 0;2,5=0,7=0
P 2.14606004 3.76615 6 P 0 0;5=4,7=1
P 3.02571004 5.165 6 P 0 0;5=4,7=1
P 11.03661004 2.31615 6 P 0 0;5=4,7=1
L 11.03661004 2.31615 11.03661004 2.3027 2 P 0 
L 11.03661004 2.3027 11.04261004 2.2967 2 P 0 
L 11.04261004 2.2967 11.17515 2.2967 2 P 0 
L 11.17515 2.2967 11.31096004 2.27275 2 P 0 
L 11.31096004 2.27275 11.35451004 2.24223996 2 P 0 
L 11.35451004 2.24223996 11.37828996 2.23805 2 P 0 
L 11.37828996 2.23805 11.40498002 2.23805 2 P 0 
L 11.40498002 2.23805 11.42193002 2.255 2 P 0 
P 11.42193002 2.255 25 P 0 0;2,5=0,7=0
P 11.42193002 2.05 25 P 0 0;2,5=0,7=0
P 10.98661004 2.21615 6 P 0 0;5=4,7=1
L 11.42193002 2.05 11.40498002 2.06695 2 P 0 
L 11.40498002 2.06695 11.3839 2.06695 2 P 0 
L 11.3839 2.06695 11.24348002 2.16528002 2 P 0 
L 11.24348002 2.16528002 11.12823002 2.1856 2 P 0 
L 11.12823002 2.1856 11.07006004 2.1856 2 P 0 
L 11.07006004 2.1856 11.05606004 2.1996 2 P 0 
L 11.05606004 2.1996 11.05606004 2.2296 2 P 0 
L 11.05606004 2.2296 11.05006004 2.2356 2 P 0 
L 11.05006004 2.2356 10.99261004 2.2356 2 P 0 
L 10.99261004 2.2356 10.98661004 2.2296 2 P 0 
L 10.98661004 2.2296 10.98661004 2.21615 2 P 0 
P 11.42193002 2.095 25 P 0 0;2,5=0,7=0
P 10.98661004 2.26615 6 P 0 0;5=4,7=1
L 11.42193002 2.095 11.40498002 2.07805 2 P 0 
L 11.40498002 2.07805 11.38741004 2.07805 2 P 0 
L 11.38741004 2.07805 11.24783002 2.17578996 2 P 0 
L 11.24783002 2.17578996 11.12921004 2.1967 2 P 0 
L 11.12921004 2.1967 11.07466004 2.1967 2 P 0 
L 11.07466004 2.1967 11.06716004 2.2042 2 P 0 
L 11.06716004 2.2042 11.06716004 2.2342 2 P 0 
L 11.06716004 2.2342 11.05466004 2.2467 2 P 0 
L 11.05466004 2.2467 10.99261004 2.2467 2 P 0 
L 10.99261004 2.2467 10.98661004 2.2527 2 P 0 
L 10.98661004 2.2527 10.98661004 2.26615 2 P 0 
L 3.17146004 5.255 3.18646004 5.27 3 P 0 
L 3.18646004 5.27 3.18646004 5.298 3 P 0 
P 3.17146004 5.255 8 P 0 0;3,5=1,7=1
L 3.23146004 5.298 3.18646004 5.298 3 P 0 
P 3.23146004 5.298 25 P 0 0;2,5=0,7=0
P 3.18646004 5.298 25 P 0 0;2,5=0,7=0
P 4.68268002 2.61615 6 P 0 0;5=4,7=1
P 10.93661004 2.26615 6 P 0 0;5=4,7=1
P 11.62193002 2.29 25 P 0 0;2,5=0,7=0
L 10.93661004 2.26615 10.93661004 2.2796 2 P 0 
L 10.93661004 2.2796 10.94261004 2.2856 2 P 0 
L 10.94261004 2.2856 10.95466004 2.2856 2 P 0 
L 10.95466004 2.2856 10.96716004 2.2981 2 P 0 
L 10.96716004 2.2981 10.96716004 2.3294 2 P 0 
L 10.96716004 2.3294 10.97336004 2.3356 2 P 0 
L 10.97336004 2.3356 11.24043002 2.3356 2 P 0 
L 11.24043002 2.3356 11.40573996 2.30645 2 P 0 
L 11.40573996 2.30645 11.60448002 2.30645 2 P 0 
L 11.60448002 2.30645 11.62093002 2.29 2 P 0 
L 11.62093002 2.29 11.62193002 2.29 2 P 0 
P 10.58661004 2.76615 6 P 0 0;5=4,7=1
P 4 5.29 8 P 0 0;3,5=1,7=1
P 10.93661004 2.31615 6 P 0 0;5=4,7=1
P 11.62193002 2.335 25 P 0 0;2,5=0,7=0
L 10.93661004 2.31615 10.93661004 2.3027 2 P 0 
L 10.93661004 2.3027 10.94261004 2.2967 2 P 0 
L 10.94261004 2.2967 10.95006004 2.2967 2 P 0 
L 10.95006004 2.2967 10.95606004 2.3027 2 P 0 
L 10.95606004 2.3027 10.95606004 2.334 2 P 0 
L 10.95606004 2.334 10.96876004 2.3467 2 P 0 
L 10.96876004 2.3467 11.24141004 2.3467 2 P 0 
L 11.24141004 2.3467 11.40671998 2.31755 2 P 0 
L 11.40671998 2.31755 11.60448002 2.31755 2 P 0 
L 11.60448002 2.31755 11.62193002 2.335 2 P 0 
P 10.88661004 2.16615 6 P 0 0;5=4,7=1
L 10.88661004 2.16615 10.87316004 2.16615 2 P 0 
L 10.87316004 2.16615 10.86716004 2.16015 2 P 0 
L 10.86716004 2.16015 10.86716004 2.15166004 2 P 0 
L 10.86716004 2.15166004 10.83418002 1.96471998 2 P 0 
L 10.83418002 1.96471998 10.85 1.875 2 P 0 
L 10.85 1.875 10.84073996 1.82251998 2 P 0 
L 10.84073996 1.82251998 10.84578002 1.79395 2 P 0 
L 10.84578002 1.79395 10.87518002 1.75198002 2 P 0 
L 10.87518002 1.75198002 11.024 1.64776004 2 P 0 
L 11.024 1.64776004 11.10998996 1.52495 2 P 0 
L 11.10998996 1.52495 11.33331998 1.36853996 2 P 0 
L 11.33331998 1.36853996 11.55231998 1.32995 2 P 0 
L 11.55231998 1.32995 11.66686998 1.35015 2 P 0 
L 11.66686998 1.35015 11.66688002 1.35015 2 P 0 
L 11.66688002 1.35015 11.7613 1.41626998 2 P 0 
L 11.7613 1.41626998 11.80821998 1.4507 2 P 0 
L 11.80821998 1.4507 11.87448996 1.54535 2 P 0 
L 11.87448996 1.54535 11.89521998 1.66291004 2 P 0 
L 11.89521998 1.66291004 12.02008002 1.84121998 2 P 0 
L 12.02008002 1.84121998 12.01881998 1.84831998 2 P 0 
L 12.01881998 1.84831998 12.02916004 1.86308002 2 P 0 
L 12.02916004 1.86308002 12.03626004 1.86433002 2 P 0 
L 12.03626004 1.86433002 12.04658002 1.87906998 2 P 0 
L 12.04658002 1.87906998 12.08701998 1.90738996 2 P 0 
L 12.08701998 1.90738996 12.08826998 1.9145 2 P 0 
L 12.08826998 1.9145 12.10303002 1.92483002 2 P 0 
L 12.10303002 1.92483002 12.11013002 1.92358002 2 P 0 
L 12.11013002 1.92358002 12.12486998 1.9339 2 P 0 
L 12.12486998 1.9339 12.12611998 1.941 2 P 0 
L 12.12611998 1.941 12.14088002 1.95133996 2 P 0 
L 12.14088002 1.95133996 12.14798002 1.95008996 2 P 0 
L 12.14798002 1.95008996 12.16271998 1.96041004 2 P 0 
L 12.16271998 1.96041004 12.21791998 1.97013996 2 P 0 
L 12.21791998 1.97013996 12.23591998 1.97013996 2 P 0 
L 12.23591998 1.97013996 12.24101998 1.97523996 2 P 0 
L 12.24101998 1.97523996 12.25901998 1.97523996 2 P 0 
L 12.25901998 1.97523996 12.26411998 1.97013996 2 P 0 
L 12.26411998 1.97013996 12.28556004 1.97013996 2 P 0 
L 12.28556004 1.97013996 12.30501004 1.98958996 2 P 0 
P 12.30501004 1.98958996 25 P 0 0;2,5=0,7=0
P 10.73661004 1.91615 6 P 0 0;5=4,7=1
L 10.73661004 1.91615 10.73661004 1.908 2 P 0 
L 10.73661004 1.908 10.74261004 1.902 2 P 0 
L 10.74261004 1.902 10.75466004 1.902 2 P 0 
L 10.75466004 1.902 10.76716004 1.8895 2 P 0 
L 10.76716004 1.8895 10.76716004 1.85283996 2 P 0 
L 10.76716004 1.85283996 10.772 1.848 2 P 0 
L 10.772 1.848 10.772 1.743 2 P 0 
L 10.772 1.743 10.57 1.541 2 P 0 
L 10.57 1.541 10.57 1.323 2 P 0 
L 10.57 1.323 10.547 1.3 2 P 0 
L 10.547 1.3 10.40945 1.3 2 P 0 
L 10.40945 1.3 10.395 1.28555 2 P 0 
P 10.395 1.28555 6 P 0 0;5=4,7=1
P 12.81495 1.96456998 11 P 0 0;3,5=2,7=0
P 9.42358002 5.22001998 6 P 0 0;5=4,7=1
P 8.67478996 2.82 25 P 0 0;2,5=0,7=0
L 8.98115 2.825 8.9667 2.83945 2 P 0 
L 8.9667 2.83945 8.69423996 2.83945 2 P 0 
L 8.69423996 2.83945 8.67478996 2.82 2 P 0 
P 8.98115 2.825 6 P 0 0;5=4,7=1
P 4.58268002 2.61615 6 P 0 0;5=4,7=1
P 9.38358002 5.22001998 6 P 0 0;5=4,7=1
P 8.67478996 2.87 25 P 0 0;2,5=0,7=0
L 8.98115 2.865 8.9667 2.85055 2 P 0 
L 8.9667 2.85055 8.69423996 2.85055 2 P 0 
L 8.69423996 2.85055 8.67478996 2.87 2 P 0 
P 8.98115 2.865 6 P 0 0;5=4,7=1
P 2.14606004 3.81615 6 P 0 0;5=4,7=1
P 3.06571004 5.165 6 P 0 0;5=4,7=1
P 11.08661004 2.71615 6 P 0 0;5=4,7=1
P 3.985 4.88998996 8 P 0 0;3,5=1,7=1
L 11.65593002 2.655 11.65593002 2.654 2 P 0 
L 11.65593002 2.654 11.67143002 2.6385 2 P 0 
L 11.67143002 2.6385 11.71966004 2.6385 2 P 0 
L 11.71966004 2.6385 11.73316004 2.652 2 P 0 
P 11.73316004 2.652 6 P 0 0;5=4,7=1
P 11.65593002 2.655 25 P 0 0;2,5=0,7=0
P 12.55905 4.40551004 11 P 0 0;3,5=2,7=0
L 11.65593002 2.61 11.67333002 2.6274 2 P 0 
L 11.67333002 2.6274 11.71776004 2.6274 2 P 0 
L 11.71776004 2.6274 11.73316004 2.612 2 P 0 
P 11.73316004 2.612 6 P 0 0;5=4,7=1
P 11.65593002 2.61 25 P 0 0;2,5=0,7=0
P 12.63778996 4.44488002 11 P 0 0;3,5=2,7=0
L 8.64078996 2.87 8.62188996 2.8511 2 P 0 
L 8.62188996 2.8511 8.56103996 2.8511 2 P 0 
L 8.56103996 2.8511 8.55663996 2.8467 2 P 0 
L 8.55663996 2.8467 8.28655 2.8467 2 P 0 
L 8.28655 2.8467 8.28055 2.8527 2 P 0 
L 8.28055 2.8527 8.28055 2.86015 2 P 0 
L 8.28055 2.86015 8.28655 2.86615 2 P 0 
L 8.28655 2.86615 8.3 2.86615 2 P 0 
P 8.64078996 2.87 25 P 0 0;2,5=0,7=0
P 8.3 2.86615 6 P 0 0;5=4,7=1
P 4.83268002 2.16615 6 P 0 0;5=4,7=1
P 0.61698996 1.91181998 25 P 0 0;2,5=0,7=0
L 0.69348996 1.90611998 0.67973996 1.89236998 2 P 0 
L 0.67973996 1.89236998 0.63643996 1.89236998 2 P 0 
L 0.63643996 1.89236998 0.61698996 1.91181998 2 P 0 
P 0.69348996 1.90611998 6 P 0 0;5=4,7=1
L 11.73316004 2.492 11.71966004 2.4785 2 P 0 
L 11.71966004 2.4785 11.67143002 2.4785 2 P 0 
L 11.67143002 2.4785 11.65593002 2.494 2 P 0 
L 11.65593002 2.494 11.65593002 2.495 2 P 0 
P 11.73316004 2.492 6 P 0 0;5=4,7=1
P 11.65593002 2.495 25 P 0 0;2,5=0,7=0
P 12.55905 4.24803002 11 P 0 0;3,5=2,7=0
P 4.88268002 2.16615 6 P 0 0;5=4,7=1
P 0.61698996 1.86181998 25 P 0 0;2,5=0,7=0
L 0.69348996 1.86611998 0.67833996 1.88126998 2 P 0 
L 0.67833996 1.88126998 0.63643996 1.88126998 2 P 0 
L 0.63643996 1.88126998 0.61698996 1.86181998 2 P 0 
P 0.69348996 1.86611998 6 P 0 0;5=4,7=1
L 11.73316004 2.452 11.71776004 2.4674 2 P 0 
L 11.71776004 2.4674 11.67333002 2.4674 2 P 0 
L 11.67333002 2.4674 11.65593002 2.45 2 P 0 
P 11.73316004 2.452 6 P 0 0;5=4,7=1
P 11.65593002 2.45 25 P 0 0;2,5=0,7=0
P 12.63778996 4.2874 11 P 0 0;3,5=2,7=0
L 8.64078996 2.82 8.62078996 2.84 2 P 0 
L 8.62078996 2.84 8.56563996 2.84 2 P 0 
L 8.56563996 2.84 8.56123996 2.8356 2 P 0 
L 8.56123996 2.8356 8.28195 2.8356 2 P 0 
L 8.28195 2.8356 8.26945 2.8481 2 P 0 
L 8.26945 2.8481 8.26945 2.86015 2 P 0 
L 8.26945 2.86015 8.26345 2.86615 2 P 0 
L 8.26345 2.86615 8.25 2.86615 2 P 0 
P 8.64078996 2.82 25 P 0 0;2,5=0,7=0
P 8.25 2.86615 6 P 0 0;5=4,7=1
P 12.55905 3.93306998 11 P 0 0;3,5=2,7=0
P 11.73316004 2.332 6 P 0 0;5=4,7=1
L 11.73316004 2.332 11.71966004 2.3185 2 P 0 
L 11.71966004 2.3185 11.67143002 2.3185 2 P 0 
L 11.67143002 2.3185 11.65593002 2.334 2 P 0 
L 11.65593002 2.334 11.65593002 2.335 2 P 0 
P 11.65593002 2.335 25 P 0 0;2,5=0,7=0
P 12.63778996 3.97243996 11 P 0 0;3,5=2,7=0
P 11.73316004 2.292 6 P 0 0;5=4,7=1
L 11.73316004 2.292 11.71776004 2.3074 2 P 0 
L 11.71776004 2.3074 11.67333002 2.3074 2 P 0 
L 11.67333002 2.3074 11.65593002 2.29 2 P 0 
P 11.65593002 2.29 25 P 0 0;2,5=0,7=0
P 10.83661004 2.16615 6 P 0 0;5=4,7=1
L 10.83661004 2.16615 10.85006004 2.16615 2 P 0 
L 10.85006004 2.16615 10.85606004 2.16015 2 P 0 
L 10.85606004 2.16015 10.85606004 2.15263996 2 P 0 
L 10.85606004 2.15263996 10.8229 1.96471998 2 P 0 
L 10.8229 1.96471998 10.83871998 1.875 2 P 0 
L 10.83871998 1.875 10.82946004 1.82251998 2 P 0 
L 10.82946004 1.82251998 10.83526998 1.78958996 2 P 0 
L 10.83526998 1.78958996 10.86721004 1.74401004 2 P 0 
L 10.86721004 1.74401004 11.01603002 1.63978996 2 P 0 
L 11.01603002 1.63978996 11.10201998 1.51698002 2 P 0 
L 11.10201998 1.51698002 11.32896998 1.35803002 2 P 0 
L 11.32896998 1.35803002 11.55231998 1.31866998 2 P 0 
L 11.55231998 1.31866998 11.67123002 1.33963996 2 P 0 
L 11.67123002 1.33963996 11.76776998 1.40723996 2 P 0 
L 11.76776998 1.40723996 11.81626004 1.44283002 2 P 0 
L 11.81626004 1.44283002 11.885 1.541 2 P 0 
L 11.885 1.541 11.90573002 1.65853996 2 P 0 
L 11.90573002 1.65853996 12.05456998 1.87111004 2 P 0 
L 12.05456998 1.87111004 12.16708002 1.9499 2 P 0 
L 12.16708002 1.9499 12.2189 1.95903996 2 P 0 
L 12.2189 1.95903996 12.28556004 1.95903996 2 P 0 
L 12.28556004 1.95903996 12.30501004 1.93958996 2 P 0 
P 12.30501004 1.93958996 25 P 0 0;2,5=0,7=0
P 11.53316004 2.092 6 P 0 0;5=4,7=1
P 11.45593002 2.095 25 P 0 0;2,5=0,7=0
P 12.55905 3.77558996 11 P 0 0;3,5=2,7=0
L 11.45593002 2.095 11.47243002 2.0785 2 P 0 
L 11.47243002 2.0785 11.51966004 2.0785 2 P 0 
L 11.51966004 2.0785 11.53316004 2.092 2 P 0 
P 11.53316004 2.052 6 P 0 0;5=4,7=1
P 11.45593002 2.05 25 P 0 0;2,5=0,7=0
P 12.63778996 3.81496004 11 P 0 0;3,5=2,7=0
L 11.45593002 2.05 11.47333002 2.0674 2 P 0 
L 11.47333002 2.0674 11.51776004 2.0674 2 P 0 
L 11.51776004 2.0674 11.53316004 2.052 2 P 0 
P 12.81495 3.53936998 11 P 0 0;3,5=2,7=0
P 10.68661004 2.26615 6 P 0 0;5=4,7=1
P 9.975 2.3758 6 P 0 0;5=4,7=1
L 10.68661004 2.26615 10.68661004 2.2527 2 P 0 
L 10.68661004 2.2527 10.68061004 2.2467 2 P 0 
L 10.68061004 2.2467 10.62316004 2.2467 2 P 0 
L 10.62316004 2.2467 10.61716004 2.2527 2 P 0 
L 10.61716004 2.2527 10.61716004 2.28418002 2 P 0 
L 10.61716004 2.28418002 10.60463996 2.2967 2 P 0 
L 10.60463996 2.2967 10.52058996 2.2967 2 P 0 
L 10.52058996 2.2967 10.154 2.36135 2 P 0 
L 10.154 2.36135 9.98945 2.36135 2 P 0 
L 9.98945 2.36135 9.975 2.3758 2 P 0 
P 12.81495 3.38188996 11 P 0 0;3,5=2,7=0
P 10.73661004 2.31615 6 P 0 0;5=4,7=1
P 9.975 2.23955 6 P 0 0;5=4,7=1
L 10.73661004 2.31615 10.73661004 2.3027 2 P 0 
L 10.73661004 2.3027 10.73061004 2.2967 2 P 0 
L 10.73061004 2.2967 10.71876004 2.2967 2 P 0 
L 10.71876004 2.2967 10.70606004 2.284 2 P 0 
L 10.70606004 2.284 10.70606004 2.20385 2 P 0 
L 10.70606004 2.20385 10.69891004 2.1967 2 P 0 
L 10.69891004 2.1967 10.45676004 2.1967 2 P 0 
L 10.45676004 2.1967 10.37173996 2.1817 2 P 0 
L 10.37173996 2.1817 10.12558002 2.2251 2 P 0 
L 10.12558002 2.2251 9.98945 2.2251 2 P 0 
L 9.98945 2.2251 9.975 2.23955 2 P 0 
P 12.81495 2.20078996 11 P 0 0;3,5=2,7=0
P 10.68661004 1.91615 6 P 0 0;5=4,7=1
P 10.42445 1.395 6 P 0 0;5=4,7=1
L 10.68661004 1.91615 10.68661004 1.9339 2 P 0 
L 10.68661004 1.9339 10.69261004 1.9399 2 P 0 
L 10.69261004 1.9399 10.6999 1.9399 2 P 0 
L 10.6999 1.9399 10.70606004 1.93373996 2 P 0 
L 10.70606004 1.93373996 10.70606004 1.85076004 2 P 0 
L 10.70606004 1.85076004 10.7019 1.8466 2 P 0 
L 10.7019 1.8466 10.7019 1.7706 2 P 0 
L 10.7019 1.7706 10.4889 1.5576 2 P 0 
L 10.4889 1.5576 10.4889 1.5409 2 P 0 
L 10.4889 1.5409 10.4838 1.5358 2 P 0 
L 10.4838 1.5358 10.4838 1.5178 2 P 0 
L 10.4838 1.5178 10.4889 1.5127 2 P 0 
L 10.4889 1.5127 10.4889 1.4946 2 P 0 
L 10.4889 1.4946 10.47618002 1.48188002 2 P 0 
L 10.47618002 1.48188002 10.46896004 1.48188002 2 P 0 
L 10.46896004 1.48188002 10.45623002 1.46913996 2 P 0 
L 10.45623002 1.46913996 10.45623002 1.46193002 2 P 0 
L 10.45623002 1.46193002 10.4389 1.4446 2 P 0 
L 10.4389 1.4446 10.4389 1.40945 2 P 0 
L 10.4389 1.40945 10.42445 1.395 2 P 0 
P 12.81495 2.75196998 11 P 0 0;3,5=2,7=0
P 10.73661004 2.01615 6 P 0 0;5=4,7=1
L 10.73661004 2.01615 10.73661004 2.0296 2 P 0 
L 10.73661004 2.0296 10.73061004 2.0356 2 P 0 
L 10.73061004 2.0356 10.67316004 2.0356 2 P 0 
L 10.67316004 2.0356 10.66716004 2.0296 2 P 0 
L 10.66716004 2.0296 10.66716004 1.9981 2 P 0 
L 10.66716004 1.9981 10.65466004 1.9856 2 P 0 
L 10.65466004 1.9856 10.54171998 1.9856 2 P 0 
L 10.54171998 1.9856 10.51603002 1.96761998 2 P 0 
L 10.51603002 1.96761998 10.4871 1.92628996 2 P 0 
L 10.4871 1.92628996 10.38368996 1.85388002 2 P 0 
L 10.38368996 1.85388002 10.32141004 1.8429 2 P 0 
L 10.32141004 1.8429 10.2747 1.8429 2 P 0 
L 10.2747 1.8429 10.26025 1.82845 2 P 0 
P 10.26025 1.82845 6 P 0 0;5=4,7=1
P 12.73621004 3.73621998 11 P 0 0;3,5=2,7=0
P 10.58661004 2.21615 6 P 0 0;5=4,7=1
L 10.58661004 2.21615 10.58661004 2.2296 2 P 0 
L 10.58661004 2.2296 10.58061004 2.2356 2 P 0 
L 10.58061004 2.2356 10.49096004 2.2356 2 P 0 
L 10.49096004 2.2356 10.22386004 2.2827 2 P 0 
L 10.22386004 2.2827 10.10445 2.2827 2 P 0 
L 10.10445 2.2827 10.09 2.26825 2 P 0 
P 10.09 2.26825 6 P 0 0;5=4,7=1
P 10.73661004 2.41615 6 P 0 0;5=4,7=1
L 10.73661004 2.41615 10.73661004 2.4296 2 P 0 
L 10.73661004 2.4296 10.73061004 2.4356 2 P 0 
L 10.73061004 2.4356 10.71856004 2.4356 2 P 0 
L 10.71856004 2.4356 10.70606004 2.4481 2 P 0 
L 10.70606004 2.4481 10.70606004 2.5796 2 P 0 
L 10.70606004 2.5796 10.70006004 2.5856 2 P 0 
L 10.70006004 2.5856 10.57168996 2.5856 2 P 0 
L 10.57168996 2.5856 10.50628996 2.651 2 P 0 
L 10.50628996 2.651 10.457 2.651 2 P 0 
L 10.457 2.651 10.397 2.711 2 P 0 
L 10.397 2.711 10.10445 2.711 2 P 0 
L 10.10445 2.711 10.09 2.69655 2 P 0 
P 10.09 2.69655 6 P 0 0;5=4,7=1
P 12.73621004 4.52361998 11 P 0 0;3,5=2,7=0
P 7.3226 4.94151004 25 P 0 0;2,5=0,7=0
P 7.3426 4.69351004 8 P 0 0;3,5=1,7=1
P 7.82693996 3.56 25 P 0 0;2,5=0,7=0
L 7.3426 4.69351004 7.3707 4.66541004 3 P 0 
L 7.3707 4.66541004 7.3707 3.42528996 3 P 0 
L 7.3707 3.42528996 7.40398996 3.392 3 P 0 
L 7.40398996 3.392 7.472 3.392 3 P 0 
L 7.472 3.392 7.625 3.545 3 P 0 
L 7.625 3.545 7.81193996 3.545 3 P 0 
L 7.81193996 3.545 7.82693996 3.56 3 P 0 
L 7.3226 4.94151004 7.2983 4.91721004 3 P 0 
L 7.2983 4.91721004 7.2983 4.84323996 3 P 0 
L 7.2983 4.84323996 7.327 4.81453996 3 P 0 
L 7.327 4.81453996 7.327 4.70911004 3 P 0 
L 7.327 4.70911004 7.3426 4.69351004 3 P 0 
L 11.65593002 1.535 11.67243002 1.5185 2 P 0 
L 11.67243002 1.5185 11.71966004 1.5185 2 P 0 
L 11.71966004 1.5185 11.73316004 1.532 2 P 0 
P 11.73316004 1.532 6 P 0 0;5=4,7=1
P 11.65593002 1.535 25 P 0 0;2,5=0,7=0
P 12.55905 2.27953002 11 P 0 0;3,5=2,7=0
P 7.2726 4.94151004 25 P 0 0;2,5=0,7=0
P 7.2926 4.69351004 8 P 0 0;3,5=1,7=1
P 7.82693996 3.51 25 P 0 0;2,5=0,7=0
L 7.2926 4.69351004 7.2926 4.68238996 3 P 0 
L 7.2926 4.68238996 7.345 4.62998996 3 P 0 
L 7.345 4.62998996 7.345 3.41463996 3 P 0 
L 7.345 3.41463996 7.39333996 3.3663 3 P 0 
L 7.39333996 3.3663 7.48265 3.3663 3 P 0 
L 7.48265 3.3663 7.63565 3.5193 3 P 0 
L 7.63565 3.5193 7.81763996 3.5193 3 P 0 
L 7.81763996 3.5193 7.82693996 3.51 3 P 0 
L 7.2726 4.94151004 7.2726 4.83258996 3 P 0 
L 7.2726 4.83258996 7.3013 4.80388996 3 P 0 
L 7.3013 4.80388996 7.3013 4.70221004 3 P 0 
L 7.3013 4.70221004 7.2926 4.69351004 3 P 0 
P 12.73621004 3.57873996 11 P 0 0;3,5=2,7=0
P 10.68661004 2.21615 6 P 0 0;5=4,7=1
P 9.975 2.3358 6 P 0 0;5=4,7=1
L 10.68661004 2.21615 10.68661004 2.2296 2 P 0 
L 10.68661004 2.2296 10.68061004 2.2356 2 P 0 
L 10.68061004 2.2356 10.61856004 2.2356 2 P 0 
L 10.61856004 2.2356 10.60606004 2.2481 2 P 0 
L 10.60606004 2.2481 10.60606004 2.27958002 2 P 0 
L 10.60606004 2.27958002 10.60003996 2.2856 2 P 0 
L 10.60003996 2.2856 10.51961004 2.2856 2 P 0 
L 10.51961004 2.2856 10.15301998 2.35025 2 P 0 
L 10.15301998 2.35025 9.98945 2.35025 2 P 0 
L 9.98945 2.35025 9.975 2.3358 2 P 0 
P 12.73621004 3.42126004 11 P 0 0;3,5=2,7=0
P 10.73661004 2.26615 6 P 0 0;5=4,7=1
P 9.975 2.19955 6 P 0 0;5=4,7=1
L 10.73661004 2.26615 10.73661004 2.2796 2 P 0 
L 10.73661004 2.2796 10.73061004 2.2856 2 P 0 
L 10.73061004 2.2856 10.72336004 2.2856 2 P 0 
L 10.72336004 2.2856 10.71716004 2.2794 2 P 0 
L 10.71716004 2.2794 10.71716004 2.19925 2 P 0 
L 10.71716004 2.19925 10.70351004 2.1856 2 P 0 
L 10.70351004 2.1856 10.45773996 2.1856 2 P 0 
L 10.45773996 2.1856 10.37173996 2.17041998 2 P 0 
L 10.37173996 2.17041998 10.1246 2.214 2 P 0 
L 10.1246 2.214 9.98945 2.214 2 P 0 
L 9.98945 2.214 9.975 2.19955 2 P 0 
P 11.73316004 2.172 6 P 0 0;5=4,7=1
P 11.65593002 2.175 25 P 0 0;2,5=0,7=0
P 12.55905 3.46063002 11 P 0 0;3,5=2,7=0
L 11.65593002 2.175 11.67243002 2.1585 2 P 0 
L 11.67243002 2.1585 11.71966004 2.1585 2 P 0 
L 11.71966004 2.1585 11.73316004 2.172 2 P 0 
P 4.98268002 2.36615 6 P 0 0;5=4,7=1
P 5.46358002 2.4953 25 P 0 0;2,5=0,7=0
L 4.98268002 2.36615 4.98268002 2.3796 2 P 0 
L 4.98268002 2.3796 4.98868002 2.3856 2 P 0 
L 4.98868002 2.3856 5.00073002 2.3856 2 P 0 
L 5.00073002 2.3856 5.01323002 2.3981 2 P 0 
L 5.01323002 2.3981 5.01323002 2.4296 2 P 0 
L 5.01323002 2.4296 5.01923002 2.4356 2 P 0 
L 5.01923002 2.4356 5.1726 2.4356 2 P 0 
L 5.1726 2.4356 5.24925 2.51225 2 P 0 
L 5.24925 2.51225 5.44663002 2.51225 2 P 0 
L 5.44663002 2.51225 5.46358002 2.4953 2 P 0 
P 10.73661004 1.86615 6 P 0 0;5=4,7=1
P 10.395 1.32555 6 P 0 0;5=4,7=1
P 12.73621004 2.00393996 11 P 0 0;3,5=2,7=0
L 10.395 1.32555 10.40945 1.3111 2 P 0 
L 10.40945 1.3111 10.44188002 1.3111 2 P 0 
L 10.44188002 1.3111 10.44788002 1.3171 2 P 0 
L 10.44788002 1.3171 10.46588002 1.3171 2 P 0 
L 10.46588002 1.3171 10.47188002 1.3111 2 P 0 
L 10.47188002 1.3111 10.48988002 1.3111 2 P 0 
L 10.48988002 1.3111 10.49588002 1.3171 2 P 0 
L 10.49588002 1.3171 10.51388002 1.3171 2 P 0 
L 10.51388002 1.3171 10.51988002 1.3111 2 P 0 
L 10.51988002 1.3111 10.5424 1.3111 2 P 0 
L 10.5424 1.3111 10.5589 1.3276 2 P 0 
L 10.5589 1.3276 10.5589 1.40808996 2 P 0 
L 10.5589 1.40808996 10.5527 1.41428996 2 P 0 
L 10.5527 1.41428996 10.5527 1.43228996 2 P 0 
L 10.5527 1.43228996 10.5589 1.43848996 2 P 0 
L 10.5589 1.43848996 10.5589 1.45648996 2 P 0 
L 10.5589 1.45648996 10.5527 1.46268996 2 P 0 
L 10.5527 1.46268996 10.5527 1.48068996 2 P 0 
L 10.5527 1.48068996 10.5589 1.48688996 2 P 0 
L 10.5589 1.48688996 10.5589 1.5456 2 P 0 
L 10.5589 1.5456 10.7609 1.7476 2 P 0 
L 10.7609 1.7476 10.7609 1.79268002 2 P 0 
L 10.7609 1.79268002 10.7532 1.80038002 2 P 0 
L 10.7532 1.80038002 10.7532 1.81838002 2 P 0 
L 10.7532 1.81838002 10.7609 1.82608002 2 P 0 
L 10.7609 1.82608002 10.7609 1.8434 2 P 0 
L 10.7609 1.8434 10.75606004 1.84823996 2 P 0 
L 10.75606004 1.84823996 10.75606004 1.8849 2 P 0 
L 10.75606004 1.8849 10.75006004 1.8909 2 P 0 
L 10.75006004 1.8909 10.74261004 1.8909 2 P 0 
L 10.74261004 1.8909 10.73661004 1.8849 2 P 0 
L 10.73661004 1.8849 10.73661004 1.86615 2 P 0 
P 11.73316004 2.132 6 P 0 0;5=4,7=1
P 11.65593002 2.13 25 P 0 0;2,5=0,7=0
P 12.63778996 3.5 11 P 0 0;3,5=2,7=0
L 11.65593002 2.13 11.67333002 2.1474 2 P 0 
L 11.67333002 2.1474 11.71776004 2.1474 2 P 0 
L 11.71776004 2.1474 11.73316004 2.132 2 P 0 
P 3.38003996 5.22001998 6 P 0 0;5=4,7=1
L 2.97721004 2.865 2.96276004 2.85055 2 P 0 
L 2.96276004 2.85055 2.6903 2.85055 2 P 0 
L 2.6903 2.85055 2.67085 2.87 2 P 0 
P 2.67085 2.87 25 P 0 0;2,5=0,7=0
P 2.97721004 2.865 6 P 0 0;5=4,7=1
P 5.46358002 2.5403 25 P 0 0;2,5=0,7=0
L 4.98268002 2.41615 4.98268002 2.4027 2 P 0 
L 4.98268002 2.4027 4.98868002 2.3967 2 P 0 
L 4.98868002 2.3967 4.99613002 2.3967 2 P 0 
L 4.99613002 2.3967 5.00213002 2.4027 2 P 0 
L 5.00213002 2.4027 5.00213002 2.4342 2 P 0 
L 5.00213002 2.4342 5.01463002 2.4467 2 P 0 
L 5.01463002 2.4467 5.168 2.4467 2 P 0 
L 5.168 2.4467 5.24465 2.52335 2 P 0 
L 5.24465 2.52335 5.44663002 2.52335 2 P 0 
L 5.44663002 2.52335 5.46358002 2.5403 2 P 0 
P 4.98268002 2.41615 6 P 0 0;5=4,7=1
P 12.63778996 1.76771998 11 P 0 0;3,5=2,7=0
P 12.342 2.11 25 P 0 0;2,5=0,7=0
L 12.63778996 1.76771998 12.67551004 1.73 3 P 0 
L 12.67551004 1.73 12.753 1.73 3 P 0 
L 12.753 1.73 12.789 1.766 3 P 0 
L 12.789 1.766 12.789 1.839 3 P 0 
L 12.789 1.839 12.768 1.86 3 P 0 
L 12.768 1.86 12.768 1.893 3 P 0 
L 12.768 1.893 12.784 1.909 3 P 0 
L 12.784 1.909 12.784 1.93 3 P 0 
L 12.784 1.93 12.751 1.963 3 P 0 
L 12.751 1.963 12.707 1.963 3 P 0 
L 12.707 1.963 12.696 1.974 3 P 0 
L 12.696 1.974 12.696 2.079 3 P 0 
L 12.696 2.079 12.655 2.12 3 P 0 
L 12.655 2.12 12.61 2.12 3 P 0 
L 12.61 2.12 12.575 2.085 3 P 0 
L 12.575 2.085 12.515 2.085 3 P 0 
L 12.515 2.085 12.49 2.11 3 P 0 
L 12.49 2.11 12.342 2.11 3 P 0 
P 3.42003996 5.22001998 6 P 0 0;5=4,7=1
L 2.97721004 2.825 2.96276004 2.83945 2 P 0 
L 2.96276004 2.83945 2.6903 2.83945 2 P 0 
L 2.6903 2.83945 2.67085 2.82 2 P 0 
P 2.67085 2.82 25 P 0 0;2,5=0,7=0
P 2.97721004 2.825 6 P 0 0;5=4,7=1
P 4.88268002 2.81615 6 P 0 0;5=4,7=1
P 4.93268002 2.81615 6 P 0 0;5=4,7=1
P 4.98268002 2.81615 6 P 0 0;5=4,7=1
P 5.03268002 2.81615 6 P 0 0;5=4,7=1
P 5.08268002 2.81615 6 P 0 0;5=4,7=1
P 11.03661004 2.81615 6 P 0 0;5=4,7=1
P 11.08661004 2.81615 6 P 0 0;5=4,7=1
P 10.98661004 2.81615 6 P 0 0;5=4,7=1
P 10.93661004 2.81615 6 P 0 0;5=4,7=1
P 10.88661004 2.81615 6 P 0 0;5=4,7=1
S P 0
OB 5.34386003937 3.31 I
OS 5.34986003937 3.304
OS 5.34986003937 2.935
OS 5.34486003937 2.93
OS 5.27386003937 2.93
OS 5.26886003937 2.935
OS 5.26886003937 3.3
OS 5.27886003937 3.31
OS 5.34386003937 3.31
OE
SE
P 5.32386004 2.96 27 P 0 0;2,5=11,7=0
P 5.32386004 3.04 27 P 0 0;2,5=11,7=0
P 5.32386004 3.12 27 P 0 0;2,5=11,7=0
P 5.27886004 3.0214 7 P 0 0;5=6,7=1
P 5.27886004 3.0564 7 P 0 0;5=6,7=1
P 5.27886004 3.1014 7 P 0 0;5=6,7=1
P 5.27886004 3.1364 7 P 0 0;5=6,7=1
P 5.27886004 2.9764 7 P 0 0;5=6,7=1
P 5.27886004 2.9414 7 P 0 0;5=6,7=1
P 5.32386004 3.2 27 P 0 0;2,5=11,7=0
P 5.32386004 3.28 27 P 0 0;2,5=11,7=0
P 5.27886004 3.2614 7 P 0 0;5=6,7=1
P 5.27886004 3.2964 7 P 0 0;5=6,7=1
P 5.27886004 3.2164 7 P 0 0;5=6,7=1
P 5.27886004 3.1814 7 P 0 0;5=6,7=1
S P 0
OB 11.34778996063 3.31 I
OS 11.35378996063 3.304
OS 11.35378996063 2.935
OS 11.34878996063 2.93
OS 11.27778996063 2.93
OS 11.27278996063 2.935
OS 11.27278996063 3.3
OS 11.28278996063 3.31
OS 11.34778996063 3.31
OE
SE
P 11.28278996 3.1814 7 P 0 0;5=6,7=1
P 11.28278996 3.2164 7 P 0 0;5=6,7=1
P 11.28278996 3.2964 7 P 0 0;5=6,7=1
P 11.28278996 3.2614 7 P 0 0;5=6,7=1
P 11.32778996 3.2 27 P 0 0;2,5=11,7=0
P 11.32778996 3.28 27 P 0 0;2,5=11,7=0
P 11.28278996 2.9414 7 P 0 0;5=6,7=1
P 11.28278996 2.9764 7 P 0 0;5=6,7=1
P 11.28278996 3.1364 7 P 0 0;5=6,7=1
P 11.28278996 3.1014 7 P 0 0;5=6,7=1
P 11.28278996 3.0564 7 P 0 0;5=6,7=1
P 11.28278996 3.0214 7 P 0 0;5=6,7=1
P 11.32778996 2.96 27 P 0 0;2,5=11,7=0
P 11.32778996 3.12 27 P 0 0;2,5=11,7=0
P 11.32778996 3.04 27 P 0 0;2,5=11,7=0
P 5.59708996 4.7302 7 P 0 0;5=6,7=1
P 5.57708996 4.6802 7 P 0 0;5=6,7=1
P 5.59778996 4.6352 27 P 0 0;2,5=11,7=0
P 5.75708996 4.7302 7 P 0 0;5=6,7=1
P 5.83708996 4.7302 7 P 0 0;5=6,7=1
P 5.69708996 4.6802 7 P 0 0;5=6,7=1
P 5.73708996 4.6802 7 P 0 0;5=6,7=1
P 5.77708996 4.6802 7 P 0 0;5=6,7=1
P 5.81708996 4.6802 7 P 0 0;5=6,7=1
P 5.85708996 4.6802 7 P 0 0;5=6,7=1
P 5.67708996 4.7302 7 P 0 0;5=6,7=1
P 5.65708996 4.6802 7 P 0 0;5=6,7=1
P 5.61708996 4.6802 7 P 0 0;5=6,7=1
P 5.67708996 4.6352 27 P 0 0;2,5=11,7=0
P 5.75708996 4.6352 27 P 0 0;2,5=11,7=0
P 5.83708996 4.6352 27 P 0 0;2,5=11,7=0
P 6.13708996 4.7602 7 P 0 0;5=6,7=1
P 6.09708996 4.6802 7 P 0 0;5=6,7=1
P 6.13708996 4.6402 7 P 0 0;5=6,7=1
P 6.13708996 4.6802 7 P 0 0;5=6,7=1
P 6.13708996 4.7202 7 P 0 0;5=6,7=1
P 5.91708996 4.7302 7 P 0 0;5=6,7=1
P 5.99708996 4.7302 7 P 0 0;5=6,7=1
P 6.07708996 4.7302 7 P 0 0;5=6,7=1
P 5.89708996 4.6802 7 P 0 0;5=6,7=1
P 5.93708996 4.6802 7 P 0 0;5=6,7=1
P 5.97708996 4.6802 7 P 0 0;5=6,7=1
P 6.01708996 4.6802 7 P 0 0;5=6,7=1
P 6.05708996 4.6802 7 P 0 0;5=6,7=1
P 6.07708996 4.6352 27 P 0 0;2,5=11,7=0
P 5.91708996 4.6352 27 P 0 0;2,5=11,7=0
P 5.99708996 4.6352 27 P 0 0;2,5=11,7=0
P 6.19208996 4.7202 27 P 0 0;2,5=11,7=0
P 6.19208996 4.6402 27 P 0 0;2,5=11,7=0
P 5.59708996 4.7702 7 P 0 0;5=6,7=1
P 5.59708996 4.8102 7 P 0 0;5=6,7=1
P 5.75708996 4.8102 7 P 0 0;5=6,7=1
P 5.83708996 4.8102 7 P 0 0;5=6,7=1
P 5.75708996 4.7702 7 P 0 0;5=6,7=1
P 5.83708996 4.7702 7 P 0 0;5=6,7=1
P 5.67708996 4.8102 7 P 0 0;5=6,7=1
P 5.67708996 4.7702 7 P 0 0;5=6,7=1
P 6.13708996 4.9252 7 P 0 0;5=6,7=1
P 6.13708996 4.8402 7 P 0 0;5=6,7=1
P 6.13708996 4.8002 7 P 0 0;5=6,7=1
P 6.13708996 4.8852 7 P 0 0;5=6,7=1
P 5.91708996 4.8102 7 P 0 0;5=6,7=1
P 5.99708996 4.8102 7 P 0 0;5=6,7=1
P 5.91708996 4.7702 7 P 0 0;5=6,7=1
P 5.99708996 4.7702 7 P 0 0;5=6,7=1
P 6.07708996 4.8102 7 P 0 0;5=6,7=1
P 6.07708996 4.7702 7 P 0 0;5=6,7=1
P 6.19208996 4.8802 27 P 0 0;2,5=11,7=0
P 6.19208996 4.8002 27 P 0 0;2,5=11,7=0
P 6.09 4.925 8 P 0 0;3,5=5,7=1
S P 0
OB 6.21708996063 4.6172 I
OS 6.21008996063 4.6102
OS 5.57208996063 4.6102
OS 5.56708996063 4.6152
OS 5.56708996063 4.9252
OS 5.58708996063 4.9452
OS 6.20708996063 4.9452
OS 6.21708996063 4.9352
OS 6.21708996063 4.6172
OE
SE
P 4.93268002 2.26615 6 P 0 0;5=4,7=1
L 4.93268002 2.26615 4.93268002 2.2796 2 P 0 
L 4.93268002 2.2796 4.93868002 2.2856 2 P 0 
L 4.93868002 2.2856 4.95073002 2.2856 2 P 0 
L 4.95073002 2.2856 4.96323002 2.2981 2 P 0 
L 4.96323002 2.2981 4.96323002 2.3296 2 P 0 
L 4.96323002 2.3296 4.96923002 2.3356 2 P 0 
L 4.96923002 2.3356 5.2236 2.3356 2 P 0 
L 5.2236 2.3356 5.26105 2.37305 2 P 0 
L 5.26105 2.37305 5.44663002 2.37305 2 P 0 
L 5.44663002 2.37305 5.46358002 2.3561 2 P 0 
P 5.46358002 2.3561 25 P 0 0;2,5=0,7=0
P 4.93268002 2.31615 6 P 0 0;5=4,7=1
P 5.46358002 2.4011 25 P 0 0;2,5=0,7=0
L 4.93268002 2.31615 4.93268002 2.3027 2 P 0 
L 4.93268002 2.3027 4.93868002 2.2967 2 P 0 
L 4.93868002 2.2967 4.94613002 2.2967 2 P 0 
L 4.94613002 2.2967 4.95213002 2.3027 2 P 0 
L 4.95213002 2.3027 4.95213002 2.3342 2 P 0 
L 4.95213002 2.3342 4.96463002 2.3467 2 P 0 
L 4.96463002 2.3467 5.219 2.3467 2 P 0 
L 5.219 2.3467 5.25645 2.38415 2 P 0 
L 5.25645 2.38415 5.44663002 2.38415 2 P 0 
L 5.44663002 2.38415 5.46358002 2.4011 2 P 0 
P 5.08268002 2.36615 6 P 0 0;5=4,7=1
P 5.30875 2.4237 25 P 0 0;2,5=0,7=0
L 5.08268002 2.36615 5.08268002 2.3796 2 P 0 
L 5.08268002 2.3796 5.08868002 2.3856 2 P 0 
L 5.08868002 2.3856 5.2016 2.3856 2 P 0 
L 5.2016 2.3856 5.25665 2.44065 2 P 0 
L 5.25665 2.44065 5.2918 2.44065 2 P 0 
L 5.2918 2.44065 5.30875 2.4237 2 P 0 
P 12.81495 3.22441004 11 P 0 0;3,5=2,7=0
P 10.68661004 2.06615 6 P 0 0;5=4,7=1
P 10.09 2.13095 6 P 0 0;5=4,7=1
L 10.68661004 2.06615 10.68661004 2.0796 2 P 0 
L 10.68661004 2.0796 10.68061004 2.0856 2 P 0 
L 10.68061004 2.0856 10.61876004 2.0856 2 P 0 
L 10.61876004 2.0856 10.60606004 2.0983 2 P 0 
L 10.60606004 2.0983 10.60606004 2.1296 2 P 0 
L 10.60606004 2.1296 10.60006004 2.1356 2 P 0 
L 10.60006004 2.1356 10.49048996 2.1356 2 P 0 
L 10.49048996 2.1356 10.34313996 2.10961998 2 P 0 
L 10.34313996 2.10961998 10.14026004 2.1454 2 P 0 
L 10.14026004 2.1454 10.10445 2.1454 2 P 0 
L 10.10445 2.1454 10.09 2.13095 2 P 0 
P 10.63661004 2.31615 6 P 0 0;5=4,7=1
P 10.09 2.40335 6 P 0 0;5=4,7=1
P 12.81495 3.85433002 11 P 0 0;3,5=2,7=0
L 10.09 2.40335 10.10445 2.4178 2 P 0 
L 10.10445 2.4178 10.1359 2.4178 2 P 0 
L 10.1359 2.4178 10.141 2.4127 2 P 0 
L 10.141 2.4127 10.159 2.4127 2 P 0 
L 10.159 2.4127 10.1641 2.4178 2 P 0 
L 10.1641 2.4178 10.1821 2.4178 2 P 0 
L 10.1821 2.4178 10.1872 2.4127 2 P 0 
L 10.1872 2.4127 10.2052 2.4127 2 P 0 
L 10.2052 2.4127 10.2103 2.4178 2 P 0 
L 10.2103 2.4178 10.2398 2.4178 2 P 0 
L 10.2398 2.4178 10.2469 2.4249 2 P 0 
L 10.2469 2.4249 10.33603996 2.4249 2 P 0 
L 10.33603996 2.4249 10.34223996 2.4187 2 P 0 
L 10.34223996 2.4187 10.36023996 2.4187 2 P 0 
L 10.36023996 2.4187 10.36643996 2.4249 2 P 0 
L 10.36643996 2.4249 10.38443996 2.4249 2 P 0 
L 10.38443996 2.4249 10.39063996 2.4187 2 P 0 
L 10.39063996 2.4187 10.40863996 2.4187 2 P 0 
L 10.40863996 2.4187 10.41483996 2.4249 2 P 0 
L 10.41483996 2.4249 10.4414 2.4249 2 P 0 
L 10.4414 2.4249 10.48001998 2.38628002 2 P 0 
L 10.48001998 2.38628002 10.48001998 2.37668002 2 P 0 
L 10.48001998 2.37668002 10.49275 2.36395 2 P 0 
L 10.49275 2.36395 10.49755 2.36395 2 P 0 
L 10.49755 2.36395 10.50233996 2.36396004 2 P 0 
L 10.50233996 2.36396004 10.53071004 2.3356 2 P 0 
L 10.53071004 2.3356 10.65006004 2.3356 2 P 0 
L 10.65006004 2.3356 10.65606004 2.3296 2 P 0 
L 10.65606004 2.3296 10.65606004 2.2971 2 P 0 
L 10.65606004 2.2971 10.65006004 2.2911 2 P 0 
L 10.65006004 2.2911 10.64261004 2.2911 2 P 0 
L 10.64261004 2.2911 10.63661004 2.2971 2 P 0 
L 10.63661004 2.2971 10.63661004 2.31615 2 P 0 
P 11.73316004 2.012 6 P 0 0;5=4,7=1
P 11.65593002 2.015 25 P 0 0;2,5=0,7=0
P 12.63778996 3.1063 11 P 0 0;3,5=2,7=0
L 11.65593002 2.015 11.67243002 1.9985 2 P 0 
L 11.67243002 1.9985 11.71966004 1.9985 2 P 0 
L 11.71966004 1.9985 11.73316004 2.012 2 P 0 
P 11.73316004 1.972 6 P 0 0;5=4,7=1
P 11.65593002 1.97 25 P 0 0;2,5=0,7=0
P 12.55905 3.14566998 11 P 0 0;3,5=2,7=0
L 11.65593002 1.97 11.67333002 1.9874 2 P 0 
L 11.67333002 1.9874 11.71776004 1.9874 2 P 0 
L 11.71776004 1.9874 11.73316004 1.972 2 P 0 
P 11.45593002 1.73 25 P 0 0;2,5=0,7=0
L 11.53316004 1.732 11.51776004 1.7474 2 P 0 
L 11.51776004 1.7474 11.47333002 1.7474 2 P 0 
L 11.47333002 1.7474 11.45593002 1.73 2 P 0 
P 11.53316004 1.732 6 P 0 0;5=4,7=1
P 12.55905 2.98818996 11 P 0 0;3,5=2,7=0
P 12.81495 3.69685 11 P 0 0;3,5=2,7=0
P 10.58661004 2.26615 6 P 0 0;5=4,7=1
L 10.58661004 2.26615 10.58661004 2.2527 2 P 0 
L 10.58661004 2.2527 10.58061004 2.2467 2 P 0 
L 10.58061004 2.2467 10.49193996 2.2467 2 P 0 
L 10.49193996 2.2467 10.22483996 2.2938 2 P 0 
L 10.22483996 2.2938 10.10445 2.2938 2 P 0 
L 10.10445 2.2938 10.09 2.30825 2 P 0 
P 10.09 2.30825 6 P 0 0;5=4,7=1
L 11.53316004 1.772 11.51966004 1.7585 2 P 0 
L 11.51966004 1.7585 11.47243002 1.7585 2 P 0 
L 11.47243002 1.7585 11.45593002 1.775 2 P 0 
P 11.53316004 1.772 6 P 0 0;5=4,7=1
P 11.45593002 1.775 25 P 0 0;2,5=0,7=0
P 12.63778996 2.94881998 11 P 0 0;3,5=2,7=0
P 12.81495 4.32676998 11 P 0 0;3,5=2,7=0
P 10.63661004 2.46615 6 P 0 0;5=4,7=1
P 9.975 2.62445 6 P 0 0;5=4,7=1
L 10.63661004 2.46615 10.63661004 2.4471 2 P 0 
L 10.63661004 2.4471 10.64261004 2.4411 2 P 0 
L 10.64261004 2.4411 10.64906004 2.4411 2 P 0 
L 10.64906004 2.4411 10.65606004 2.4481 2 P 0 
L 10.65606004 2.4481 10.65606004 2.5296 2 P 0 
L 10.65606004 2.5296 10.65006004 2.5356 2 P 0 
L 10.65006004 2.5356 10.55643002 2.5356 2 P 0 
L 10.55643002 2.5356 10.54495 2.54708002 2 P 0 
L 10.54495 2.54708002 10.54048002 2.54706998 2 P 0 
L 10.54048002 2.54706998 10.54046004 2.54705 2 P 0 
L 10.54046004 2.54705 10.53598002 2.54705 2 P 0 
L 10.53598002 2.54705 10.52323996 2.55978002 2 P 0 
L 10.52323996 2.55978002 10.52323002 2.56426004 2 P 0 
L 10.52323002 2.56426004 10.52325 2.56428002 2 P 0 
L 10.52325 2.56428002 10.52325 2.56875 2 P 0 
L 10.52325 2.56875 10.49908002 2.5929 2 P 0 
L 10.49908002 2.5929 10.3894 2.5929 2 P 0 
L 10.3894 2.5929 10.3434 2.6389 2 P 0 
L 10.3434 2.6389 10.32341998 2.6389 2 P 0 
L 10.32341998 2.6389 10.31651998 2.632 2 P 0 
L 10.31651998 2.632 10.29851998 2.632 2 P 0 
L 10.29851998 2.632 10.29161998 2.6389 2 P 0 
L 10.29161998 2.6389 10.27361998 2.6389 2 P 0 
L 10.27361998 2.6389 10.26671998 2.632 2 P 0 
L 10.26671998 2.632 10.24871998 2.632 2 P 0 
L 10.24871998 2.632 10.24181998 2.6389 2 P 0 
L 10.24181998 2.6389 10.1083 2.6389 2 P 0 
L 10.1083 2.6389 10.1032 2.6338 2 P 0 
L 10.1032 2.6338 10.0852 2.6338 2 P 0 
L 10.0852 2.6338 10.0801 2.6389 2 P 0 
L 10.0801 2.6389 10.0621 2.6389 2 P 0 
L 10.0621 2.6389 10.057 2.6338 2 P 0 
L 10.057 2.6338 10.039 2.6338 2 P 0 
L 10.039 2.6338 10.0339 2.6389 2 P 0 
L 10.0339 2.6389 9.98945 2.6389 2 P 0 
L 9.98945 2.6389 9.975 2.62445 2 P 0 
P 12.63778996 2.79133996 11 P 0 0;3,5=2,7=0
P 11.73316004 1.852 6 P 0 0;5=4,7=1
P 11.65593002 1.855 25 P 0 0;2,5=0,7=0
L 11.65593002 1.855 11.67243002 1.8385 2 P 0 
L 11.67243002 1.8385 11.71966004 1.8385 2 P 0 
L 11.71966004 1.8385 11.73316004 1.852 2 P 0 
P 12.55905 2.83071004 11 P 0 0;3,5=2,7=0
P 11.73316004 1.812 6 P 0 0;5=4,7=1
P 11.65593002 1.81 25 P 0 0;2,5=0,7=0
L 11.65593002 1.81 11.67333002 1.8274 2 P 0 
L 11.67333002 1.8274 11.71776004 1.8274 2 P 0 
L 11.71776004 1.8274 11.73316004 1.812 2 P 0 
P 10.73661004 2.46615 6 P 0 0;5=4,7=1
L 10.73661004 2.46615 10.73661004 2.4527 2 P 0 
L 10.73661004 2.4527 10.73061004 2.4467 2 P 0 
L 10.73061004 2.4467 10.72316004 2.4467 2 P 0 
L 10.72316004 2.4467 10.71716004 2.4527 2 P 0 
L 10.71716004 2.4527 10.71716004 2.5842 2 P 0 
L 10.71716004 2.5842 10.70466004 2.5967 2 P 0 
L 10.70466004 2.5967 10.57628996 2.5967 2 P 0 
L 10.57628996 2.5967 10.51088996 2.6621 2 P 0 
L 10.51088996 2.6621 10.4616 2.6621 2 P 0 
L 10.4616 2.6621 10.4016 2.7221 2 P 0 
L 10.4016 2.7221 10.10445 2.7221 2 P 0 
L 10.10445 2.7221 10.09 2.73655 2 P 0 
P 10.09 2.73655 6 P 0 0;5=4,7=1
P 12.81495 4.48425 11 P 0 0;3,5=2,7=0
P 10.63661004 2.26615 6 P 0 0;5=4,7=1
P 10.09 2.44335 6 P 0 0;5=4,7=1
P 12.73621004 3.8937 11 P 0 0;3,5=2,7=0
L 10.09 2.44335 10.10445 2.4289 2 P 0 
L 10.10445 2.4289 10.2352 2.4289 2 P 0 
L 10.2352 2.4289 10.2423 2.436 2 P 0 
L 10.2423 2.436 10.446 2.436 2 P 0 
L 10.446 2.436 10.50223996 2.37976004 2 P 0 
L 10.50223996 2.37976004 10.50226004 2.37976004 2 P 0 
L 10.50226004 2.37976004 10.53531998 2.3467 2 P 0 
L 10.53531998 2.3467 10.65466004 2.3467 2 P 0 
L 10.65466004 2.3467 10.66716004 2.3342 2 P 0 
L 10.66716004 2.3342 10.66716004 2.2925 2 P 0 
L 10.66716004 2.2925 10.65466004 2.28 2 P 0 
L 10.65466004 2.28 10.64261004 2.28 2 P 0 
L 10.64261004 2.28 10.63661004 2.274 2 P 0 
L 10.63661004 2.274 10.63661004 2.26615 2 P 0 
P 10.58661004 2.41615 6 P 0 0;5=4,7=1
L 10.58661004 2.41615 10.58661004 2.4027 2 P 0 
L 10.58661004 2.4027 10.58061004 2.3967 2 P 0 
L 10.58061004 2.3967 10.558 2.3967 2 P 0 
L 10.558 2.3967 10.45825 2.49645 2 P 0 
L 10.45825 2.49645 9.98945 2.49645 2 P 0 
L 9.98945 2.49645 9.975 2.5109 2 P 0 
P 9.975 2.5109 6 P 0 0;5=4,7=1
P 12.81495 4.16928996 11 P 0 0;3,5=2,7=0
P 1.025 -0.35 26 P 0 0;3,5=9,7=0
P 1.325 -0.35 26 P 0 0;5=9,7=0
P 1.175 -0.35 26 P 0 0;5=9,7=0
P 0.725 -0.35 26 P 0 0;5=9,7=0
P 0.875 -0.35 26 P 0 0;5=9,7=0
P 12.73621004 4.05118002 11 P 0 0;3,5=2,7=0
P 10.68661004 2.36615 6 P 0 0;5=4,7=1
L 10.68661004 2.36615 10.68661004 2.3796 2 P 0 
L 10.68661004 2.3796 10.68061004 2.3856 2 P 0 
L 10.68061004 2.3856 10.61856004 2.3856 2 P 0 
L 10.61856004 2.3856 10.60606004 2.3981 2 P 0 
L 10.60606004 2.3981 10.60606004 2.4796 2 P 0 
L 10.60606004 2.4796 10.60006004 2.4856 2 P 0 
L 10.60006004 2.4856 10.5264 2.4856 2 P 0 
L 10.5264 2.4856 10.473 2.539 2 P 0 
L 10.473 2.539 10.346 2.539 2 P 0 
L 10.346 2.539 10.3321 2.5529 2 P 0 
L 10.3321 2.5529 10.10445 2.5529 2 P 0 
L 10.10445 2.5529 10.09 2.53845 2 P 0 
P 10.09 2.53845 6 P 0 0;5=4,7=1
P 12.81495 2.35826998 11 P 0 0;3,5=2,7=0
P 10.63661004 1.86615 6 P 0 0;5=4,7=1
P 10.35543002 1.52156998 6 P 0 0;5=4,7=1
L 10.63661004 1.86615 10.63661004 1.8869 2 P 0 
L 10.63661004 1.8869 10.64261004 1.8929 2 P 0 
L 10.64261004 1.8929 10.64806004 1.8929 2 P 0 
L 10.64806004 1.8929 10.65606004 1.8849 2 P 0 
L 10.65606004 1.8849 10.65606004 1.80206004 2 P 0 
L 10.65606004 1.80206004 10.48731998 1.63331998 2 P 0 
L 10.48731998 1.63331998 10.48011004 1.63331998 2 P 0 
L 10.48011004 1.63331998 10.46736998 1.62058996 2 P 0 
L 10.46736998 1.62058996 10.46736998 1.61336998 2 P 0 
L 10.46736998 1.61336998 10.45465 1.60065 2 P 0 
L 10.45465 1.60065 10.44743996 1.60065 2 P 0 
L 10.44743996 1.60065 10.4347 1.58791998 2 P 0 
L 10.4347 1.58791998 10.4347 1.5807 2 P 0 
L 10.4347 1.5807 10.42198002 1.56798002 2 P 0 
L 10.42198002 1.56798002 10.41476004 1.56798002 2 P 0 
L 10.41476004 1.56798002 10.40201998 1.55523996 2 P 0 
L 10.40201998 1.55523996 10.40201998 1.54801998 2 P 0 
L 10.40201998 1.54801998 10.37556998 1.52156998 2 P 0 
L 10.37556998 1.52156998 10.35543002 1.52156998 2 P 0 
P 5.03268002 2.01615 6 P 0 0;5=4,7=1
L 5.03268002 2.01615 5.03268002 2.0296 2 P 0 
L 5.03268002 2.0296 5.03868002 2.0356 2 P 0 
L 5.03868002 2.0356 5.1554 2.0356 2 P 0 
L 5.1554 2.0356 5.22965 1.96135 2 P 0 
L 5.22965 1.96135 5.44663002 1.96135 2 P 0 
L 5.44663002 1.96135 5.46358002 1.9444 2 P 0 
P 5.46358002 1.9444 25 P 0 0;2,5=0,7=0
P 5.08268002 2.21615 6 P 0 0;5=4,7=1
L 5.08268002 2.21615 5.08268002 2.2296 2 P 0 
L 5.08268002 2.2296 5.08868002 2.2356 2 P 0 
L 5.08868002 2.2356 5.2856 2.2356 2 P 0 
L 5.2856 2.2356 5.28765 2.23765 2 P 0 
L 5.28765 2.23765 5.44663002 2.23765 2 P 0 
L 5.44663002 2.23765 5.46358002 2.2207 2 P 0 
P 5.46358002 2.2207 25 P 0 0;2,5=0,7=0
P 12.73621004 2.16141998 11 P 0 0;3,5=2,7=0
P 10.68661004 1.96615 6 P 0 0;5=4,7=1
P 10.46445 1.395 6 P 0 0;5=4,7=1
L 10.68661004 1.96615 10.68661004 1.957 2 P 0 
L 10.68661004 1.957 10.69261004 1.951 2 P 0 
L 10.69261004 1.951 10.7045 1.951 2 P 0 
L 10.7045 1.951 10.71716004 1.93833996 2 P 0 
L 10.71716004 1.93833996 10.71716004 1.84616004 2 P 0 
L 10.71716004 1.84616004 10.713 1.842 2 P 0 
L 10.713 1.842 10.713 1.766 2 P 0 
L 10.713 1.766 10.5 1.553 2 P 0 
L 10.5 1.553 10.5 1.49 2 P 0 
L 10.5 1.49 10.45 1.44 2 P 0 
L 10.45 1.44 10.45 1.40945 2 P 0 
L 10.45 1.40945 10.46445 1.395 2 P 0 
P 5.72185 2.97441004 30 P 0 0;2,5=8
P 9.95743996 2.82441004 30 P 0 0;2,5=8
P 3.91351004 2.59441004 30 P 0 0;2,5=8
P 0.2 -0.293 18 P 0 0;5=18
P 12.27 0.29 18 P 0 0;5=18
P 0.66 0.29 18 P 0 0;5=18
P 0.2 5.82361998 18 P 0 0;5=18
P 11.99518996 0.29 10 P 0 0;2,5=19
P 0.9211 0.2854 10 P 0 0;2,5=19
P 0.5836 5.36731998 10 P 0 0;2,5=19
P 0.5 -0.293 10 P 0 0;2,5=19
P 12.4252 6.31661998 10 P 0 0;2,5=19
P 0.5 6.31661998 10 P 0 0;2,5=19
P 12.4252 -0.293 10 P 0 0;2,5=19
P 12.81495 1.57086998 11 P 0 0;5=2
P 12.73621004 1.5315 11 P 0 0;5=2
P 12.63778996 2.7126 11 P 0 0;5=2
P 12.55905 2.67323002 11 P 0 0;5=2
P 12.55905 1.64961004 11 P 0 0;5=2
P 12.63778996 1.61023996 11 P 0 0;5=2
P 12.55905 1.57086998 11 P 0 0;5=2
P 12.63778996 1.5315 11 P 0 0;5=2
P 12.73621004 1.68898002 11 P 0 0;5=2
P 12.81495 1.64961004 11 P 0 0;5=2
P 12.63778996 1.68898002 11 P 0 0;5=2
P 12.55905 1.72835 11 P 0 0;5=2
P 12.81495 1.72835 11 P 0 0;5=2
P 12.73621004 1.45276004 11 P 0 0;5=2
P 12.81495 1.41338996 11 P 0 0;5=2
P 12.73621004 1.37401998 26 P 0 0;5=10
P 12.63778996 1.45276004 11 P 0 0;5=2
P 12.55905 1.41338996 11 P 0 0;5=2
P 0.35038996 1.5315 11 P 0 0;5=2
P 0.27165 1.49213002 11 P 0 0;5=2
P 0.17323002 2.67323002 11 P 0 0;5=2
P 0.09448996 2.63386004 11 P 0 0;5=2
P 0.09448996 1.61023996 11 P 0 0;5=2
P 0.17323002 1.57086998 11 P 0 0;5=2
P 0.09448996 1.5315 11 P 0 0;5=2
P 0.17323002 1.49213002 11 P 0 0;5=2
P 0.27165 1.64961004 11 P 0 0;5=2
P 0.35038996 1.61023996 11 P 0 0;5=2
P 0.17323002 1.64961004 11 P 0 0;5=2
P 0.09448996 1.68898002 11 P 0 0;5=2
P 0.35038996 1.68898002 11 P 0 0;5=2
P 0.27165 1.41338996 11 P 0 0;5=2
P 0.35038996 1.37401998 11 P 0 0;5=2
P 0.27165 1.33465 26 P 0 0;5=10
P 0.17323002 1.41338996 11 P 0 0;5=2
P 0.09448996 1.37401998 11 P 0 0;5=2
P 10.20866004 5.4441 23 P 0 0;5=20
P 5.78346004 5.4441 23 P 0 0;5=20
P 12.7252 6.31661998 18 P 0 0;5=18
P 0.2 6.31661998 18 P 0 0;5=18
P 12.7252 -0.293 18 P 0 0;5=18
P 0.22245 4.87401004 16 P 0 0;5=7
P 12.68701004 0.46063002 19 P 0 0;5=21
P 12.68701998 5.4252 19 P 0 0;5=21
P 0.22245 0.42126004 19 P 0 0;5=21
P 0.22255 5.38583002 19 P 0 0;5=21
L 1.88908002 -1.91246004 1.89293002 -1.91246004 0 P 0 ;0
L 1.89126998 -1.91146004 1.89656998 -1.91146004 0 P 0 ;0
L 1.89393996 -1.91046004 1.9155 -1.91046004 0 P 0 ;0
L 1.91593996 -1.91246004 1.92048996 -1.91246004 0 P 0 ;0
L 1.9126 -1.91146004 1.9184 -1.91146004 0 P 0 ;0
L 1.89763002 -1.90946004 1.91016998 -1.90946004 0 P 0 ;0
L 1.89053002 -1.96001004 1.8974 -1.96001004 0 P 0 ;0
L 1.89053002 -1.95901004 1.8974 -1.95901004 0 P 0 ;0
L 1.89053002 -1.95801004 1.8974 -1.95801004 0 P 0 ;0
L 1.89053002 -1.95701004 1.8974 -1.95701004 0 P 0 ;0
L 1.89053002 -1.95601004 1.8974 -1.95601004 0 P 0 ;0
L 1.89053002 -1.95501004 1.8974 -1.95501004 0 P 0 ;0
L 1.89053002 -1.95401004 1.8974 -1.95401004 0 P 0 ;0
L 1.89053002 -1.95301004 1.89741004 -1.95301004 0 P 0 ;0
L 1.89053002 -1.95201004 1.89741998 -1.95201004 0 P 0 ;0
L 1.89053002 -1.95101004 1.89743996 -1.95101004 0 P 0 ;0
L 1.89053002 -1.95001004 1.89745 -1.95001004 0 P 0 ;0
L 1.89053002 -1.94901004 1.89746004 -1.94901004 0 P 0 ;0
L 1.89053002 -1.94801004 1.89753002 -1.94801004 0 P 0 ;0
L 1.89053002 -1.94701004 1.8977 -1.94701004 0 P 0 ;0
L 1.89053002 -1.94601004 1.89798002 -1.94601004 0 P 0 ;0
L 1.89053002 -1.94501004 1.89861004 -1.94501004 0 P 0 ;0
L 1.89053002 -1.94401004 1.90005 -1.94401004 0 P 0 ;0
L 1.89053002 -1.94301004 1.9113 -1.94301004 0 P 0 ;0
L 1.89053002 -1.94201004 1.91168002 -1.94201004 0 P 0 ;0
L 1.89053002 -1.94101004 1.91246998 -1.94101004 0 P 0 ;0
L 1.89053002 -1.94001004 1.90093996 -1.94001004 0 P 0 ;0
L 1.89053002 -1.93901004 1.89856004 -1.93901004 0 P 0 ;0
L 1.89053002 -1.93801004 1.89786998 -1.93801004 0 P 0 ;0
L 1.89053002 -1.93701004 1.89753996 -1.93701004 0 P 0 ;0
L 1.89053002 -1.93601004 1.89746998 -1.93601004 0 P 0 ;0
L 1.89053002 -1.93501004 1.89743996 -1.93501004 0 P 0 ;0
L 1.89053002 -1.93401004 1.89741998 -1.93401004 0 P 0 ;0
L 1.89053002 -1.93301004 1.8974 -1.93301004 0 P 0 ;0
L 1.89053002 -1.93201004 1.8974 -1.93201004 0 P 0 ;0
L 1.89053002 -1.93101004 1.8974 -1.93101004 0 P 0 ;0
L 1.89053002 -1.93001004 1.8974 -1.93001004 0 P 0 ;0
L 1.89053002 -1.92901004 1.8974 -1.92901004 0 P 0 ;0
L 1.89053002 -1.92801004 1.89753002 -1.92801004 0 P 0 ;0
L 1.89053002 -1.92701004 1.89793996 -1.92701004 0 P 0 ;0
L 1.89053002 -1.92601004 1.91713002 -1.92601004 0 P 0 ;0
L 1.89053002 -1.92501004 1.91628996 -1.92501004 0 P 0 ;0
L 1.89053002 -1.92401004 1.91513996 -1.92401004 0 P 0 ;0
L 1.89053002 -1.92301004 1.91321998 -1.92301004 0 P 0 ;0
L 1.89053002 -1.92201004 1.90551004 -1.92201004 0 P 0 ;0
L 1.89438996 -1.97246004 1.91331004 -1.97246004 0 P 0 ;0
L 1.89106998 -1.97146004 1.89973002 -1.97146004 0 P 0 ;0
L 1.88878002 -1.97046004 1.8949 -1.97046004 0 P 0 ;0
L 1.88698002 -1.96946004 1.89206998 -1.96946004 0 P 0 ;0
L 1.88546004 -1.96846004 1.88986998 -1.96846004 0 P 0 ;0
L 1.88416998 -1.96746004 1.88808996 -1.96746004 0 P 0 ;0
L 1.88288002 -1.96646004 1.88655 -1.96646004 0 P 0 ;0
L 1.88176998 -1.96546004 1.88518002 -1.96546004 0 P 0 ;0
L 1.88068996 -1.96446004 1.88393996 -1.96446004 0 P 0 ;0
L 1.87968996 -1.96346004 1.88286004 -1.96346004 0 P 0 ;0
L 1.87878002 -1.96246004 1.88186004 -1.96246004 0 P 0 ;0
L 1.8786 -1.92046004 1.88126998 -1.92046004 0 P 0 ;0
L 1.87946998 -1.91946004 1.88223002 -1.91946004 0 P 0 ;0
L 1.88048002 -1.91846004 1.88321004 -1.91846004 0 P 0 ;0
L 1.88153996 -1.91746004 1.88436998 -1.91746004 0 P 0 ;0
L 1.88273002 -1.91646004 1.88558996 -1.91646004 0 P 0 ;0
L 1.88406004 -1.91546004 1.88696998 -1.91546004 0 P 0 ;0
L 1.88548996 -1.91446004 1.88853002 -1.91446004 0 P 0 ;0
L 1.88718002 -1.91346004 1.89041998 -1.91346004 0 P 0 ;0
L 1.90896004 -1.92963996 1.90921998 -1.92991998 0 P 0 ;0
L 1.90921998 -1.92991998 1.90945 -1.93021998 0 P 0 ;0
L 1.90945 -1.93021998 1.90966004 -1.93053002 0 P 0 ;0
L 1.90966004 -1.93053002 1.90983002 -1.93086004 0 P 0 ;0
L 1.90983002 -1.93086004 1.90998002 -1.93121004 0 P 0 ;0
L 1.90998002 -1.93121004 1.9101 -1.93156998 0 P 0 ;0
L 1.9101 -1.93156998 1.91018996 -1.93193996 0 P 0 ;0
L 1.91018996 -1.93193996 1.91023996 -1.93231004 0 P 0 ;0
L 1.91023996 -1.93231004 1.91026998 -1.93265 0 P 0 ;0
L 1.91026998 -1.93265 1.91026004 -1.93298002 0 P 0 ;0
L 1.91026004 -1.93298002 1.91023002 -1.93331004 0 P 0 ;0
L 1.91023002 -1.93331004 1.91016998 -1.93363996 0 P 0 ;0
L 1.91016998 -1.93363996 1.91008996 -1.93396004 0 P 0 ;0
L 1.91008996 -1.93396004 1.90998002 -1.93428002 0 P 0 ;0
L 1.90998002 -1.93428002 1.90983996 -1.93458002 0 P 0 ;0
L 1.90983996 -1.93458002 1.90968996 -1.93486998 0 P 0 ;0
L 1.90968996 -1.93486998 1.90951004 -1.93516004 0 P 0 ;0
L 1.90951004 -1.93516004 1.90921004 -1.93556004 0 P 0 ;0
L 1.90921004 -1.93556004 1.90888002 -1.93593002 0 P 0 ;0
L 1.90888002 -1.93593002 1.90853002 -1.93626998 0 P 0 ;0
L 1.90853002 -1.93626998 1.90815 -1.93658996 0 P 0 ;0
L 1.90815 -1.93658996 1.90773996 -1.93686998 0 P 0 ;0
L 1.90773996 -1.93686998 1.90731998 -1.93711998 0 P 0 ;0
L 1.90731998 -1.93711998 1.90686998 -1.93733996 0 P 0 ;0
L 1.90686998 -1.93733996 1.90615 -1.93761004 0 P 0 ;0
L 1.90615 -1.93761004 1.90541998 -1.93783002 0 P 0 ;0
L 1.90541998 -1.93783002 1.90466004 -1.93798002 0 P 0 ;0
L 1.90466004 -1.93798002 1.9039 -1.93808002 0 P 0 ;0
L 1.9039 -1.93808002 1.90311998 -1.9381 0 P 0 ;0
L 1.90311998 -1.9381 1.90196004 -1.93808002 0 P 0 ;0
L 1.90196004 -1.93808002 1.90078996 -1.93798996 0 P 0 ;0
L 1.90078996 -1.93798996 1.90068002 -1.93798002 0 P 0 ;0
L 1.90068002 -1.93798002 1.90058002 -1.93795 0 P 0 ;0
L 1.90058002 -1.93795 1.90046998 -1.93791998 0 P 0 ;0
L 1.90046998 -1.93791998 1.90038002 -1.93788002 0 P 0 ;0
L 1.90038002 -1.93788002 1.90028002 -1.93783002 0 P 0 ;0
L 1.90028002 -1.93783002 1.90018996 -1.93778002 0 P 0 ;0
L 1.90018996 -1.93778002 1.9001 -1.93771004 0 P 0 ;0
L 1.9001 -1.93771004 1.90001998 -1.93763996 0 P 0 ;0
L 1.90001998 -1.93763996 1.89988002 -1.93748002 0 P 0 ;0
L 1.89988002 -1.93748002 1.89978002 -1.93733996 0 P 0 ;0
L 1.89978002 -1.93733996 1.89961998 -1.93703996 0 P 0 ;0
L 1.89961998 -1.93703996 1.89956998 -1.93688002 0 P 0 ;0
L 1.89956998 -1.93688002 1.89951998 -1.93671004 0 P 0 ;0
L 1.89951998 -1.93671004 1.89948996 -1.93655 0 P 0 ;0
L 1.89948996 -1.93655 1.89946998 -1.93636998 0 P 0 ;0
L 1.89946998 -1.93636998 1.8994 -1.93323002 0 P 0 ;0
L 1.8994 -1.93323002 1.8994 -1.92833002 0 P 0 ;0
L 1.8994 -1.92833002 1.90353996 -1.92833002 0 P 0 ;0
L 1.90353996 -1.92833002 1.90436998 -1.92835 0 P 0 ;0
L 1.90436998 -1.92835 1.9052 -1.92843002 0 P 0 ;0
L 1.9052 -1.92843002 1.90603002 -1.92853996 0 P 0 ;0
L 1.90603002 -1.92853996 1.90683996 -1.92871004 0 P 0 ;0
L 1.90683996 -1.92871004 1.90751004 -1.9289 0 P 0 ;0
L 1.90751004 -1.9289 1.90818002 -1.92913002 0 P 0 ;0
L 1.90818002 -1.92913002 1.90851998 -1.92928996 0 P 0 ;0
L 1.90851998 -1.92928996 1.90868002 -1.92938996 0 P 0 ;0
L 1.90868002 -1.92938996 1.90883002 -1.92951004 0 P 0 ;0
L 1.90883002 -1.92951004 1.90896004 -1.92963996 0 P 0 ;0
L 1.91188996 -1.96001004 1.91638996 -1.96001004 0 P 0 ;0
L 1.91156998 -1.95901004 1.91926998 -1.95901004 0 P 0 ;0
L 1.91125 -1.95801004 1.91891998 -1.95801004 0 P 0 ;0
L 1.91091998 -1.95701004 1.91853002 -1.95701004 0 P 0 ;0
L 1.9106 -1.95601004 1.91811004 -1.95601004 0 P 0 ;0
L 1.91025 -1.95501004 1.91765 -1.95501004 0 P 0 ;0
L 1.90988996 -1.95401004 1.91718996 -1.95401004 0 P 0 ;0
L 1.90953002 -1.95301004 1.91673002 -1.95301004 0 P 0 ;0
L 1.90918002 -1.95201004 1.91626998 -1.95201004 0 P 0 ;0
L 1.90881998 -1.95101004 1.91576004 -1.95101004 0 P 0 ;0
L 1.90841004 -1.95001004 1.91523996 -1.95001004 0 P 0 ;0
L 1.90793996 -1.94901004 1.91471004 -1.94901004 0 P 0 ;0
L 1.90738996 -1.94801004 1.91418002 -1.94801004 0 P 0 ;0
L 1.90676998 -1.94701004 1.9136 -1.94701004 0 P 0 ;0
L 1.90598996 -1.94601004 1.91261004 -1.94601004 0 P 0 ;0
L 1.90495 -1.94501004 1.91175 -1.94501004 0 P 0 ;0
L 1.90325 -1.94401004 1.91133002 -1.94401004 0 P 0 ;0
L 1.90456004 -1.94001004 1.91383002 -1.94001004 0 P 0 ;0
L 1.90801004 -1.93901004 1.91523002 -1.93901004 0 P 0 ;0
L 1.90956998 -1.93801004 1.91635 -1.93801004 0 P 0 ;0
L 1.9106 -1.93701004 1.91718002 -1.93701004 0 P 0 ;0
L 1.91133996 -1.93601004 1.91781004 -1.93601004 0 P 0 ;0
L 1.91183996 -1.93501004 1.91826004 -1.93501004 0 P 0 ;0
L 1.91213002 -1.93401004 1.9186 -1.93401004 0 P 0 ;0
L 1.91226004 -1.93301004 1.9188 -1.93301004 0 P 0 ;0
L 1.91221998 -1.93201004 1.9189 -1.93201004 0 P 0 ;0
L 1.91201998 -1.93101004 1.9189 -1.93101004 0 P 0 ;0
L 1.91163996 -1.93001004 1.91878996 -1.93001004 0 P 0 ;0
L 1.91105 -1.92901004 1.91856998 -1.92901004 0 P 0 ;0
L 1.91013996 -1.92801004 1.91823002 -1.92801004 0 P 0 ;0
L 1.90816998 -1.92701004 1.91776004 -1.92701004 0 P 0 ;0
L 1.90313996 -1.94011004 1.90316998 -1.9401 0 P 0 ;0
L 1.90316998 -1.9401 1.9032 -1.9401 0 P 0 ;0
L 1.9032 -1.9401 1.90398002 -1.94006998 0 P 0 ;0
L 1.90398002 -1.94006998 1.90406004 -1.94006998 0 P 0 ;0
L 1.90406004 -1.94006998 1.90413996 -1.94006004 0 P 0 ;0
L 1.90413996 -1.94006004 1.9049 -1.93996998 0 P 0 ;0
L 1.9049 -1.93996998 1.90493996 -1.93996004 0 P 0 ;0
L 1.90493996 -1.93996004 1.90498996 -1.93996004 0 P 0 ;0
L 1.90498996 -1.93996004 1.90506998 -1.93993996 0 P 0 ;0
L 1.90506998 -1.93993996 1.90581998 -1.93978002 0 P 0 ;0
L 1.90581998 -1.93978002 1.90586004 -1.93978002 0 P 0 ;0
L 1.90586004 -1.93978002 1.90593996 -1.93976004 0 P 0 ;0
L 1.90593996 -1.93976004 1.90596998 -1.93973996 0 P 0 ;0
L 1.90596998 -1.93973996 1.90671004 -1.93953002 0 P 0 ;0
L 1.90671004 -1.93953002 1.90678996 -1.93951004 0 P 0 ;0
L 1.90678996 -1.93951004 1.90758996 -1.93921004 0 P 0 ;0
L 1.90758996 -1.93921004 1.90766004 -1.93916998 0 P 0 ;0
L 1.90766004 -1.93916998 1.9077 -1.93915 0 P 0 ;0
L 1.9077 -1.93915 1.90773996 -1.93913996 0 P 0 ;0
L 1.90773996 -1.93913996 1.90818996 -1.93891998 0 P 0 ;0
L 1.90818996 -1.93891998 1.90821998 -1.9389 0 P 0 ;0
L 1.90821998 -1.9389 1.90826004 -1.93888996 0 P 0 ;0
L 1.90826004 -1.93888996 1.90828996 -1.93886998 0 P 0 ;0
L 1.90828996 -1.93886998 1.90833002 -1.93885 0 P 0 ;0
L 1.90833002 -1.93885 1.90875 -1.9386 0 P 0 ;0
L 1.90875 -1.9386 1.90883002 -1.93856004 0 P 0 ;0
L 1.90883002 -1.93856004 1.90888996 -1.93851004 0 P 0 ;0
L 1.90888996 -1.93851004 1.90928996 -1.93823002 0 P 0 ;0
L 1.90928996 -1.93823002 1.90933002 -1.9382 0 P 0 ;0
L 1.90933002 -1.9382 1.90936004 -1.93818002 0 P 0 ;0
L 1.90936004 -1.93818002 1.90938996 -1.93815 0 P 0 ;0
L 1.90938996 -1.93815 1.90941998 -1.93813002 0 P 0 ;0
L 1.90941998 -1.93813002 1.9098 -1.93781998 0 P 0 ;0
L 1.9098 -1.93781998 1.90986004 -1.93776004 0 P 0 ;0
L 1.90986004 -1.93776004 1.90988996 -1.93773996 0 P 0 ;0
L 1.90988996 -1.93773996 1.90991998 -1.93771004 0 P 0 ;0
L 1.90991998 -1.93771004 1.91028002 -1.93736004 0 P 0 ;0
L 1.91028002 -1.93736004 1.91038996 -1.93725 0 P 0 ;0
L 1.91038996 -1.93725 1.91071004 -1.93688002 0 P 0 ;0
L 1.91071004 -1.93688002 1.91073996 -1.93685 0 P 0 ;0
L 1.91073996 -1.93685 1.91116004 -1.9363 0 P 0 ;0
L 1.91116004 -1.9363 1.9112 -1.93623002 0 P 0 ;0
L 1.9112 -1.93623002 1.91138002 -1.93595 0 P 0 ;0
L 1.91138002 -1.93595 1.9114 -1.93591004 0 P 0 ;0
L 1.9114 -1.93591004 1.91143996 -1.93585 0 P 0 ;0
L 1.91143996 -1.93585 1.91146004 -1.93581004 0 P 0 ;0
L 1.91146004 -1.93581004 1.91161004 -1.93551998 0 P 0 ;0
L 1.91161004 -1.93551998 1.91163002 -1.93548996 0 P 0 ;0
L 1.91163002 -1.93548996 1.91165 -1.93545 0 P 0 ;0
L 1.91165 -1.93545 1.91166004 -1.93541004 0 P 0 ;0
L 1.91166004 -1.93541004 1.91168002 -1.93538002 0 P 0 ;0
L 1.91168002 -1.93538002 1.91181004 -1.93506998 0 P 0 ;0
L 1.91181004 -1.93506998 1.91183996 -1.935 0 P 0 ;0
L 1.91183996 -1.935 1.91186004 -1.93496004 0 P 0 ;0
L 1.91186004 -1.93496004 1.91186998 -1.93493002 0 P 0 ;0
L 1.91186998 -1.93493002 1.91198002 -1.93461004 0 P 0 ;0
L 1.91198002 -1.93461004 1.91198996 -1.93456998 0 P 0 ;0
L 1.91198996 -1.93456998 1.912 -1.93453996 0 P 0 ;0
L 1.912 -1.93453996 1.9121 -1.93413996 0 P 0 ;0
L 1.9121 -1.93413996 1.91211998 -1.9341 0 P 0 ;0
L 1.91211998 -1.9341 1.91211998 -1.93406004 0 P 0 ;0
L 1.91211998 -1.93406004 1.91213002 -1.93401998 0 P 0 ;0
L 1.91213002 -1.93401998 1.91213996 -1.93398996 0 P 0 ;0
L 1.91213996 -1.93398996 1.9122 -1.93366004 0 P 0 ;0
L 1.9122 -1.93366004 1.91221004 -1.93358002 0 P 0 ;0
L 1.91221004 -1.93358002 1.91221004 -1.93353996 0 P 0 ;0
L 1.91221004 -1.93353996 1.91221998 -1.9335 0 P 0 ;0
L 1.91221998 -1.9335 1.91225 -1.93316998 0 P 0 ;0
L 1.91225 -1.93316998 1.91226004 -1.93308996 0 P 0 ;0
L 1.91226004 -1.93308996 1.91226004 -1.93268002 0 P 0 ;0
L 1.91226004 -1.93268002 1.91226998 -1.93263996 0 P 0 ;0
L 1.91226998 -1.93263996 1.91226998 -1.9326 0 P 0 ;0
L 1.91226998 -1.9326 1.91226004 -1.93251998 0 P 0 ;0
L 1.91226004 -1.93251998 1.91223996 -1.93218996 0 P 0 ;0
L 1.91223996 -1.93218996 1.91223996 -1.93215 0 P 0 ;0
L 1.91223996 -1.93215 1.91223002 -1.9321 0 P 0 ;0
L 1.91223002 -1.9321 1.91223002 -1.93206004 0 P 0 ;0
L 1.91223002 -1.93206004 1.91221998 -1.93201998 0 P 0 ;0
L 1.91221998 -1.93201998 1.91216998 -1.93163996 0 P 0 ;0
L 1.91216998 -1.93163996 1.91216004 -1.9316 0 P 0 ;0
L 1.91216004 -1.9316 1.91213996 -1.93151004 0 P 0 ;0
L 1.91213996 -1.93151004 1.91213002 -1.93146998 0 P 0 ;0
L 1.91213002 -1.93146998 1.91205 -1.93111004 0 P 0 ;0
L 1.91205 -1.93111004 1.91203996 -1.93106004 0 P 0 ;0
L 1.91203996 -1.93106004 1.91203002 -1.93101998 0 P 0 ;0
L 1.91203002 -1.93101998 1.91201004 -1.93098002 0 P 0 ;0
L 1.91201004 -1.93098002 1.912 -1.93093996 0 P 0 ;0
L 1.912 -1.93093996 1.91188002 -1.93058002 0 P 0 ;0
L 1.91188002 -1.93058002 1.91186998 -1.93053996 0 P 0 ;0
L 1.91186998 -1.93053996 1.91185 -1.9305 0 P 0 ;0
L 1.91185 -1.9305 1.91183996 -1.93046004 0 P 0 ;0
L 1.91183996 -1.93046004 1.91181998 -1.93043002 0 P 0 ;0
L 1.91181998 -1.93043002 1.91166998 -1.93008002 0 P 0 ;0
L 1.91166998 -1.93008002 1.91166004 -1.93003996 0 P 0 ;0
L 1.91166004 -1.93003996 1.9116 -1.92991998 0 P 0 ;0
L 1.9116 -1.92991998 1.91141998 -1.92958996 0 P 0 ;0
L 1.91141998 -1.92958996 1.9114 -1.92955 0 P 0 ;0
L 1.9114 -1.92955 1.91138002 -1.92951998 0 P 0 ;0
L 1.91138002 -1.92951998 1.91133002 -1.92945 0 P 0 ;0
L 1.91133002 -1.92945 1.91113002 -1.92913002 0 P 0 ;0
L 1.91113002 -1.92913002 1.91111004 -1.92908996 0 P 0 ;0
L 1.91111004 -1.92908996 1.91108996 -1.92906004 0 P 0 ;0
L 1.91108996 -1.92906004 1.91106004 -1.92901998 0 P 0 ;0
L 1.91106004 -1.92901998 1.91103002 -1.92898996 0 P 0 ;0
L 1.91103002 -1.92898996 1.9108 -1.92868996 0 P 0 ;0
L 1.9108 -1.92868996 1.91076998 -1.92866004 0 P 0 ;0
L 1.91076998 -1.92866004 1.91075 -1.92861998 0 P 0 ;0
L 1.91075 -1.92861998 1.91068996 -1.92856004 0 P 0 ;0
L 1.91068996 -1.92856004 1.91043002 -1.92828002 0 P 0 ;0
L 1.91043002 -1.92828002 1.91035 -1.9282 0 P 0 ;0
L 1.91035 -1.9282 1.91033002 -1.92816998 0 P 0 ;0
L 1.91033002 -1.92816998 1.91018996 -1.92803996 0 P 0 ;0
L 1.91018996 -1.92803996 1.91018002 -1.92803996 0 P 0 ;0
L 1.91018002 -1.92803996 1.91016004 -1.92801998 0 P 0 ;0
L 1.91016004 -1.92801998 1.91011998 -1.92798996 0 P 0 ;0
L 1.91011998 -1.92798996 1.91006004 -1.92793002 0 P 0 ;0
L 1.91006004 -1.92793002 1.90991004 -1.92781998 0 P 0 ;0
L 1.90991004 -1.92781998 1.90988002 -1.9278 0 P 0 ;0
L 1.90988002 -1.9278 1.90983996 -1.92776998 0 P 0 ;0
L 1.90983996 -1.92776998 1.90976998 -1.92771998 0 P 0 ;0
L 1.90976998 -1.92771998 1.90961004 -1.92761998 0 P 0 ;0
L 1.90961004 -1.92761998 1.90953996 -1.92756998 0 P 0 ;0
L 1.90953996 -1.92756998 1.9095 -1.92755 0 P 0 ;0
L 1.9095 -1.92755 1.90946998 -1.92753002 0 P 0 ;0
L 1.90946998 -1.92753002 1.9093 -1.92743996 0 P 0 ;0
L 1.9093 -1.92743996 1.90926004 -1.92741998 0 P 0 ;0
L 1.90926004 -1.92741998 1.90923002 -1.9274 0 P 0 ;0
L 1.90923002 -1.9274 1.90915 -1.92736998 0 P 0 ;0
L 1.90915 -1.92736998 1.90896998 -1.92728996 0 P 0 ;0
L 1.90896998 -1.92728996 1.90893996 -1.92728002 0 P 0 ;0
L 1.90893996 -1.92728002 1.9089 -1.92726004 0 P 0 ;0
L 1.9089 -1.92726004 1.90886998 -1.92725 0 P 0 ;0
L 1.90886998 -1.92725 1.90883002 -1.92723996 0 P 0 ;0
L 1.90883002 -1.92723996 1.90816004 -1.92701004 0 P 0 ;0
L 1.90816004 -1.92701004 1.90813996 -1.927 0 P 0 ;0
L 1.90813996 -1.927 1.9081 -1.92698996 0 P 0 ;0
L 1.9081 -1.92698996 1.90803996 -1.92696998 0 P 0 ;0
L 1.90803996 -1.92696998 1.90736998 -1.92678002 0 P 0 ;0
L 1.90736998 -1.92678002 1.90723996 -1.92675 0 P 0 ;0
L 1.90723996 -1.92675 1.90643002 -1.92658996 0 P 0 ;0
L 1.90643002 -1.92658996 1.90636998 -1.92656998 0 P 0 ;0
L 1.90636998 -1.92656998 1.90633996 -1.92656998 0 P 0 ;0
L 1.90633996 -1.92656998 1.90631004 -1.92656004 0 P 0 ;0
L 1.90631004 -1.92656004 1.90548996 -1.92645 0 P 0 ;0
L 1.90548996 -1.92645 1.90543996 -1.92643996 0 P 0 ;0
L 1.90543996 -1.92643996 1.9054 -1.92643002 0 P 0 ;0
L 1.9054 -1.92643002 1.90538002 -1.92643002 0 P 0 ;0
L 1.90538002 -1.92643002 1.90455 -1.92636004 0 P 0 ;0
L 1.90455 -1.92636004 1.90443002 -1.92636004 0 P 0 ;0
L 1.90443002 -1.92636004 1.9036 -1.92633002 0 P 0 ;0
L 1.9036 -1.92633002 1.8994 -1.92633002 0 P 0 ;0
L 1.8994 -1.92633002 1.89798002 -1.92691004 0 P 0 ;0
L 1.89798002 -1.92691004 1.8974 -1.92833002 0 P 0 ;0
L 1.8974 -1.92833002 1.8974 -1.93328002 0 P 0 ;0
L 1.8974 -1.93328002 1.89748002 -1.93643002 0 P 0 ;0
L 1.89748002 -1.93643002 1.89748002 -1.93656004 0 P 0 ;0
L 1.89748002 -1.93656004 1.8975 -1.93673002 0 P 0 ;0
L 1.8975 -1.93673002 1.89751004 -1.93681004 0 P 0 ;0
L 1.89751004 -1.93681004 1.89751998 -1.9369 0 P 0 ;0
L 1.89751998 -1.9369 1.89755 -1.93706004 0 P 0 ;0
L 1.89755 -1.93706004 1.89758002 -1.93718996 0 P 0 ;0
L 1.89758002 -1.93718996 1.89758996 -1.93723002 0 P 0 ;0
L 1.89758996 -1.93723002 1.89763002 -1.9374 0 P 0 ;0
L 1.89763002 -1.9374 1.89763996 -1.93743996 0 P 0 ;0
L 1.89763996 -1.93743996 1.89766004 -1.93748002 0 P 0 ;0
L 1.89766004 -1.93748002 1.89768002 -1.93756004 0 P 0 ;0
L 1.89768002 -1.93756004 1.89773996 -1.93771998 0 P 0 ;0
L 1.89773996 -1.93771998 1.89776004 -1.93776004 0 P 0 ;0
L 1.89776004 -1.93776004 1.89776998 -1.9378 0 P 0 ;0
L 1.89776998 -1.9378 1.89781004 -1.93788002 0 P 0 ;0
L 1.89781004 -1.93788002 1.89788002 -1.93803996 0 P 0 ;0
L 1.89788002 -1.93803996 1.8979 -1.93808002 0 P 0 ;0
L 1.8979 -1.93808002 1.89791998 -1.93811004 0 P 0 ;0
L 1.89791998 -1.93811004 1.89796004 -1.93818996 0 P 0 ;0
L 1.89796004 -1.93818996 1.89803996 -1.93833996 0 P 0 ;0
L 1.89803996 -1.93833996 1.89813996 -1.93848002 0 P 0 ;0
L 1.89813996 -1.93848002 1.89823002 -1.93861998 0 P 0 ;0
L 1.89823002 -1.93861998 1.89828002 -1.93868996 0 P 0 ;0
L 1.89828002 -1.93868996 1.89831004 -1.93873002 0 P 0 ;0
L 1.89831004 -1.93873002 1.89833996 -1.93876004 0 P 0 ;0
L 1.89833996 -1.93876004 1.8984 -1.93883996 0 P 0 ;0
L 1.8984 -1.93883996 1.89848996 -1.93893002 0 P 0 ;0
L 1.89848996 -1.93893002 1.89851004 -1.93896004 0 P 0 ;0
L 1.89851004 -1.93896004 1.89868002 -1.93913002 0 P 0 ;0
L 1.89868002 -1.93913002 1.89871004 -1.93915 0 P 0 ;0
L 1.89871004 -1.93915 1.89878996 -1.93921998 0 P 0 ;0
L 1.89878996 -1.93921998 1.89885 -1.93928002 0 P 0 ;0
L 1.89885 -1.93928002 1.89888002 -1.9393 0 P 0 ;0
L 1.89888002 -1.9393 1.89891998 -1.93931998 0 P 0 ;0
L 1.89891998 -1.93931998 1.89901004 -1.93938996 0 P 0 ;0
L 1.89901004 -1.93938996 1.89903996 -1.93941004 0 P 0 ;0
L 1.89903996 -1.93941004 1.89906998 -1.93943996 0 P 0 ;0
L 1.89906998 -1.93943996 1.8991 -1.93946004 0 P 0 ;0
L 1.8991 -1.93946004 1.89913996 -1.93948002 0 P 0 ;0
L 1.89913996 -1.93948002 1.89923002 -1.93953996 0 P 0 ;0
L 1.89923002 -1.93953996 1.89926998 -1.93956004 0 P 0 ;0
L 1.89926998 -1.93956004 1.8993 -1.93958002 0 P 0 ;0
L 1.8993 -1.93958002 1.89933996 -1.9396 0 P 0 ;0
L 1.89933996 -1.9396 1.89936998 -1.93961004 0 P 0 ;0
L 1.89936998 -1.93961004 1.89938002 -1.93961004 0 P 0 ;0
L 1.89938002 -1.93961004 1.89946998 -1.93966004 0 P 0 ;0
L 1.89946998 -1.93966004 1.89953996 -1.9397 0 P 0 ;0
L 1.89953996 -1.9397 1.89971998 -1.93976998 0 P 0 ;0
L 1.89971998 -1.93976998 1.89975 -1.93978996 0 P 0 ;0
L 1.89975 -1.93978996 1.89978996 -1.9398 0 P 0 ;0
L 1.89978996 -1.9398 1.89986998 -1.93983002 0 P 0 ;0
L 1.89986998 -1.93983002 1.89996998 -1.93986004 0 P 0 ;0
L 1.89996998 -1.93986004 1.90001004 -1.93986998 0 P 0 ;0
L 1.90001004 -1.93986998 1.90005 -1.93988996 0 P 0 ;0
L 1.90005 -1.93988996 1.90013002 -1.9399 0 P 0 ;0
L 1.90013002 -1.9399 1.90023002 -1.93993002 0 P 0 ;0
L 1.90023002 -1.93993002 1.90023996 -1.93993002 0 P 0 ;0
L 1.90023996 -1.93993002 1.90028002 -1.93993996 0 P 0 ;0
L 1.90028002 -1.93993996 1.90031004 -1.93995 0 P 0 ;0
L 1.90031004 -1.93995 1.90036004 -1.93995 0 P 0 ;0
L 1.90036004 -1.93995 1.9004 -1.93996004 0 P 0 ;0
L 1.9004 -1.93996004 1.9005 -1.93996998 0 P 0 ;0
L 1.9005 -1.93996998 1.90061004 -1.93998996 0 P 0 ;0
L 1.90061004 -1.93998996 1.90063996 -1.93998996 0 P 0 ;0
L 1.90063996 -1.93998996 1.90181004 -1.94006998 0 P 0 ;0
L 1.90181004 -1.94006998 1.90183996 -1.94008002 0 P 0 ;0
L 1.90183996 -1.94008002 1.90191004 -1.94008002 0 P 0 ;0
L 1.90191004 -1.94008002 1.90308002 -1.9401 0 P 0 ;0
L 1.90308002 -1.9401 1.90311004 -1.9401 0 P 0 ;0
L 1.90311004 -1.9401 1.90313996 -1.94011004 0 P 0 ;0
L 1.90841004 -1.97146004 1.91683996 -1.97146004 0 P 0 ;0
L 1.9135 -1.97046004 1.91931004 -1.97046004 0 P 0 ;0
L 1.91655 -1.96946004 1.92131004 -1.96946004 0 P 0 ;0
L 1.91891998 -1.96846004 1.92301004 -1.96846004 0 P 0 ;0
L 1.92088996 -1.96746004 1.9245 -1.96746004 0 P 0 ;0
L 1.92251004 -1.96646004 1.9258 -1.96646004 0 P 0 ;0
L 1.92391004 -1.96546004 1.92696004 -1.96546004 0 P 0 ;0
L 1.92513002 -1.96446004 1.92803002 -1.96446004 0 P 0 ;0
L 1.9262 -1.96346004 1.92898996 -1.96346004 0 P 0 ;0
L 1.92713996 -1.96246004 1.92986004 -1.96246004 0 P 0 ;0
L 1.928 -1.96146004 1.93068996 -1.96146004 0 P 0 ;0
L 1.92878002 -1.96046004 1.93143002 -1.96046004 0 P 0 ;0
L 1.92951004 -1.95946004 1.93216004 -1.95946004 0 P 0 ;0
L 1.93016998 -1.95846004 1.93278996 -1.95846004 0 P 0 ;0
L 1.93078002 -1.95746004 1.93341004 -1.95746004 0 P 0 ;0
L 1.93133002 -1.95646004 1.93396004 -1.95646004 0 P 0 ;0
L 1.93185 -1.95546004 1.93448996 -1.95546004 0 P 0 ;0
L 1.93231004 -1.95446004 1.93495 -1.95446004 0 P 0 ;0
L 1.93275 -1.95346004 1.93541004 -1.95346004 0 P 0 ;0
L 1.93311998 -1.95246004 1.93586004 -1.95246004 0 P 0 ;0
L 1.93348002 -1.95146004 1.93628996 -1.95146004 0 P 0 ;0
L 1.93376998 -1.95046004 1.93666004 -1.95046004 0 P 0 ;0
L 1.93405 -1.94946004 1.93693002 -1.94946004 0 P 0 ;0
L 1.93428002 -1.94846004 1.93715 -1.94846004 0 P 0 ;0
L 1.93446998 -1.94746004 1.93733002 -1.94746004 0 P 0 ;0
L 1.93466004 -1.94646004 1.93743002 -1.94646004 0 P 0 ;0
L 1.93478996 -1.94546004 1.93748996 -1.94546004 0 P 0 ;0
L 1.9349 -1.94446998 1.93751998 -1.94446998 0 P 0 ;0
L 1.93496998 -1.94346004 1.93755 -1.94346004 0 P 0 ;0
L 1.93501998 -1.94246004 1.93758002 -1.94246004 0 P 0 ;0
L 1.93505 -1.94146998 1.93758996 -1.94146998 0 P 0 ;0
L 1.93503002 -1.94046004 1.93755 -1.94046004 0 P 0 ;0
L 1.935 -1.93946004 1.93751998 -1.93946004 0 P 0 ;0
L 1.93491998 -1.93846004 1.93748002 -1.93846004 0 P 0 ;0
L 1.93481004 -1.93746004 1.93738996 -1.93746004 0 P 0 ;0
L 1.93468996 -1.93646004 1.93726998 -1.93646004 0 P 0 ;0
L 1.93451004 -1.93546004 1.93716004 -1.93546004 0 P 0 ;0
L 1.93433002 -1.93446004 1.93703996 -1.93446004 0 P 0 ;0
L 1.93408996 -1.93346004 1.93685 -1.93346004 0 P 0 ;0
L 1.93383002 -1.93246004 1.93666004 -1.93246004 0 P 0 ;0
L 1.93353002 -1.93146004 1.93638996 -1.93146004 0 P 0 ;0
L 1.9332 -1.93046004 1.93611998 -1.93046004 0 P 0 ;0
L 1.93283996 -1.92946004 1.93576998 -1.92946004 0 P 0 ;0
L 1.93241004 -1.92846004 1.93541004 -1.92846004 0 P 0 ;0
L 1.93198996 -1.92746004 1.93498002 -1.92746004 0 P 0 ;0
L 1.93146998 -1.92646004 1.93451004 -1.92646004 0 P 0 ;0
L 1.93096004 -1.92546004 1.93398002 -1.92546004 0 P 0 ;0
L 1.93035 -1.92446998 1.93338002 -1.92446998 0 P 0 ;0
L 1.92973002 -1.92346004 1.93275 -1.92346004 0 P 0 ;0
L 1.92903002 -1.92246004 1.93201004 -1.92246004 0 P 0 ;0
L 1.92831004 -1.92146004 1.93125 -1.92146004 0 P 0 ;0
L 1.92746998 -1.92046004 1.93041004 -1.92046004 0 P 0 ;0
L 1.92661004 -1.91946004 1.92948996 -1.91946004 0 P 0 ;0
L 1.92558996 -1.91846004 1.92851004 -1.91846004 0 P 0 ;0
L 1.9245 -1.91746004 1.92741998 -1.91746004 0 P 0 ;0
L 1.92328996 -1.91646004 1.92621998 -1.91646004 0 P 0 ;0
L 1.92188002 -1.91546004 1.92491998 -1.91546004 0 P 0 ;0
L 1.92026004 -1.91446004 1.92358996 -1.91446004 0 P 0 ;0
L 1.91835 -1.91346004 1.92208002 -1.91346004 0 P 0 ;0
L 1.82446998 -2.08323996 1.87608002 -2.08323996 0 P 0 ;0
L 1.82403002 -2.08223996 1.87601004 -2.08223996 0 P 0 ;0
L 1.8234 -2.08123996 1.87591004 -2.08123996 0 P 0 ;0
L 1.82256004 -2.08023996 1.87578002 -2.08023996 0 P 0 ;0
L 1.82166004 -2.07923996 1.87558996 -2.07923996 0 P 0 ;0
L 1.82061998 -2.07823996 1.87533002 -2.07823996 0 P 0 ;0
L 1.81946004 -2.07723996 1.87498996 -2.07723996 0 P 0 ;0
L 1.81818002 -2.07623996 1.8746 -2.07623996 0 P 0 ;0
L 1.8168 -2.07523996 1.87416998 -2.07523996 0 P 0 ;0
L 1.81541998 -2.07423996 1.87371004 -2.07423996 0 P 0 ;0
L 1.81403002 -2.07323996 1.87316998 -2.07323996 0 P 0 ;0
L 1.81265 -2.07223996 1.87261004 -2.07223996 0 P 0 ;0
L 1.81126998 -2.07123996 1.87196004 -2.07123996 0 P 0 ;0
L 1.80986004 -2.07023996 1.87128002 -2.07023996 0 P 0 ;0
L 1.80843996 -2.06923996 1.87051998 -2.06923996 0 P 0 ;0
L 1.80703002 -2.06823996 1.8697 -2.06823996 0 P 0 ;0
L 1.80561004 -2.06723996 1.86883002 -2.06723996 0 P 0 ;0
L 1.8042 -2.06623996 1.86796004 -2.06623996 0 P 0 ;0
L 1.80278002 -2.06523996 1.86705 -2.06523996 0 P 0 ;0
L 1.80136004 -2.06423996 1.86608002 -2.06423996 0 P 0 ;0
L 1.79995 -2.06323996 1.8651 -2.06323996 0 P 0 ;0
L 1.79865 -2.06223996 1.86411004 -2.06223996 0 P 0 ;0
L 1.79735 -2.06123996 1.86301998 -2.06123996 0 P 0 ;0
L 1.79605 -2.06023996 1.86193002 -2.06023996 0 P 0 ;0
L 1.79475 -2.05923996 1.86083996 -2.05923996 0 P 0 ;0
L 1.79345 -2.05823996 1.85966998 -2.05823996 0 P 0 ;0
L 1.79215 -2.05723996 1.85846004 -2.05723996 0 P 0 ;0
L 1.79088002 -2.05623996 1.85726004 -2.05623996 0 P 0 ;0
L 1.78971998 -2.05523996 1.85598996 -2.05523996 0 P 0 ;0
L 1.78856004 -2.05423996 1.85461998 -2.05423996 0 P 0 ;0
L 1.7874 -2.05323996 1.85326004 -2.05323996 0 P 0 ;0
L 1.78623002 -2.05223996 1.8519 -2.05223996 0 P 0 ;0
L 1.78506998 -2.05123996 1.85053996 -2.05123996 0 P 0 ;0
L 1.78398002 -2.05023996 1.84918002 -2.05023996 0 P 0 ;0
L 1.783 -2.04923996 1.84781004 -2.04923996 0 P 0 ;0
L 1.87086004 -2.03023996 1.87535 -2.03023996 0 P 0 ;0
L 1.91633002 -1.91473002 1.9183 -1.91565 0 P 0 ;0
L 1.9183 -1.91565 1.92018996 -1.91673002 0 P 0 ;0
L 1.92018996 -1.91673002 1.92196998 -1.91796998 0 P 0 ;0
L 1.92196998 -1.91796998 1.92365 -1.91936004 0 P 0 ;0
L 1.92365 -1.91936004 1.9252 -1.92088002 0 P 0 ;0
L 1.9252 -1.92088002 1.92661004 -1.92253996 0 P 0 ;0
L 1.92661004 -1.92253996 1.92795 -1.92436998 0 P 0 ;0
L 1.92795 -1.92436998 1.92913996 -1.9263 0 P 0 ;0
L 1.92913996 -1.9263 1.93018002 -1.92831998 0 P 0 ;0
L 1.93018002 -1.92831998 1.93106998 -1.93041004 0 P 0 ;0
L 1.93106998 -1.93041004 1.93178996 -1.93256004 0 P 0 ;0
L 1.93178996 -1.93256004 1.93236004 -1.93476004 0 P 0 ;0
L 1.93236004 -1.93476004 1.93276004 -1.93703996 0 P 0 ;0
L 1.93276004 -1.93703996 1.93298996 -1.93933996 0 P 0 ;0
L 1.93298996 -1.93933996 1.93306004 -1.94165 0 P 0 ;0
L 1.93306004 -1.94165 1.93295 -1.94396998 0 P 0 ;0
L 1.93295 -1.94396998 1.93268002 -1.94626004 0 P 0 ;0
L 1.93268002 -1.94626004 1.93223002 -1.94853996 0 P 0 ;0
L 1.93223002 -1.94853996 1.93161998 -1.95071998 0 P 0 ;0
L 1.93161998 -1.95071998 1.93085 -1.95285 0 P 0 ;0
L 1.93085 -1.95285 1.92991004 -1.95491004 0 P 0 ;0
L 1.92991004 -1.95491004 1.92881004 -1.95688996 0 P 0 ;0
L 1.92881004 -1.95688996 1.92756004 -1.95878002 0 P 0 ;0
L 1.92756004 -1.95878002 1.92616004 -1.96056998 0 P 0 ;0
L 1.92616004 -1.96056998 1.92493996 -1.9619 0 P 0 ;0
L 1.92493996 -1.9619 1.92361998 -1.96313996 0 P 0 ;0
L 1.92361998 -1.96313996 1.9222 -1.96426004 0 P 0 ;0
L 1.9222 -1.96426004 1.9207 -1.96526998 0 P 0 ;0
L 1.9207 -1.96526998 1.91911004 -1.96616998 0 P 0 ;0
L 1.91911004 -1.96616998 1.91686998 -1.96721004 0 P 0 ;0
L 1.91686998 -1.96721004 1.91456004 -1.96806998 0 P 0 ;0
L 1.91456004 -1.96806998 1.91218996 -1.96876004 0 P 0 ;0
L 1.91218996 -1.96876004 1.90975 -1.96926998 0 P 0 ;0
L 1.90975 -1.96926998 1.90725 -1.9696 0 P 0 ;0
L 1.90725 -1.9696 1.90473002 -1.96973996 0 P 0 ;0
L 1.90473002 -1.96973996 1.9022 -1.96968996 0 P 0 ;0
L 1.9022 -1.96968996 1.89966998 -1.96945 0 P 0 ;0
L 1.89966998 -1.96945 1.89778002 -1.96913002 0 P 0 ;0
L 1.89778002 -1.96913002 1.89591998 -1.96868996 0 P 0 ;0
L 1.89591998 -1.96868996 1.8941 -1.96811004 0 P 0 ;0
L 1.8941 -1.96811004 1.89231004 -1.96741004 0 P 0 ;0
L 1.89231004 -1.96741004 1.89058002 -1.96658002 0 P 0 ;0
L 1.89058002 -1.96658002 1.88875 -1.96553996 0 P 0 ;0
L 1.88875 -1.96553996 1.88698996 -1.96435 0 P 0 ;0
L 1.88698996 -1.96435 1.88533996 -1.96303002 0 P 0 ;0
L 1.88533996 -1.96303002 1.88378996 -1.9616 0 P 0 ;0
L 1.88378996 -1.9616 1.88235 -1.96003996 0 P 0 ;0
L 1.88235 -1.96003996 1.88103002 -1.95838996 0 P 0 ;0
L 1.88103002 -1.95838996 1.87983996 -1.95663002 0 P 0 ;0
L 1.87983996 -1.95663002 1.87861998 -1.95446998 0 P 0 ;0
L 1.87861998 -1.95446998 1.87758002 -1.9522 0 P 0 ;0
L 1.87758002 -1.9522 1.87673996 -1.94986004 0 P 0 ;0
L 1.87673996 -1.94986004 1.8761 -1.94745 0 P 0 ;0
L 1.8761 -1.94745 1.87568002 -1.945 0 P 0 ;0
L 1.87568002 -1.945 1.87546004 -1.94248996 0 P 0 ;0
L 1.87546004 -1.94248996 1.87546004 -1.93998996 0 P 0 ;0
L 1.87546004 -1.93998996 1.87566998 -1.93748996 0 P 0 ;0
L 1.87566998 -1.93748996 1.87608996 -1.93501998 0 P 0 ;0
L 1.87608996 -1.93501998 1.87671998 -1.9326 0 P 0 ;0
L 1.87671998 -1.9326 1.87755 -1.93023002 0 P 0 ;0
L 1.87755 -1.93023002 1.8786 -1.92793002 0 P 0 ;0
L 1.8786 -1.92793002 1.87981998 -1.92575 0 P 0 ;0
L 1.87981998 -1.92575 1.88123002 -1.92368002 0 P 0 ;0
L 1.88123002 -1.92368002 1.88281004 -1.92175 0 P 0 ;0
L 1.88281004 -1.92175 1.88455 -1.91996004 0 P 0 ;0
L 1.88455 -1.91996004 1.88643002 -1.91831998 0 P 0 ;0
L 1.88643002 -1.91831998 1.88845 -1.91686004 0 P 0 ;0
L 1.88845 -1.91686004 1.88986998 -1.91598996 0 P 0 ;0
L 1.88986998 -1.91598996 1.89135 -1.91523002 0 P 0 ;0
L 1.89135 -1.91523002 1.89288002 -1.91458996 0 P 0 ;0
L 1.89288002 -1.91458996 1.89446998 -1.91406004 0 P 0 ;0
L 1.89446998 -1.91406004 1.89688996 -1.91343996 0 P 0 ;0
L 1.89688996 -1.91343996 1.89935 -1.91298996 0 P 0 ;0
L 1.89935 -1.91298996 1.90183996 -1.91271004 0 P 0 ;0
L 1.90183996 -1.91271004 1.9044 -1.91261004 0 P 0 ;0
L 1.9044 -1.91261004 1.90695 -1.91268002 0 P 0 ;0
L 1.90695 -1.91268002 1.90948996 -1.91291998 0 P 0 ;0
L 1.90948996 -1.91291998 1.91181998 -1.91331998 0 P 0 ;0
L 1.91181998 -1.91331998 1.91408996 -1.91393002 0 P 0 ;0
L 1.91408996 -1.91393002 1.91633002 -1.91473002 0 P 0 ;0
L 1.89498002 -1.90801998 1.8922 -1.90893002 0 P 0 ;0
L 1.8922 -1.90893002 1.88948002 -1.91003002 0 P 0 ;0
L 1.88948002 -1.91003002 1.88686004 -1.91133002 0 P 0 ;0
L 1.88686004 -1.91133002 1.88431004 -1.91283996 0 P 0 ;0
L 1.88431004 -1.91283996 1.88201004 -1.91446004 0 P 0 ;0
L 1.88201004 -1.91446004 1.87985 -1.91626998 0 P 0 ;0
L 1.87985 -1.91626998 1.87785 -1.91826004 0 P 0 ;0
L 1.87785 -1.91826004 1.87601998 -1.92041004 0 P 0 ;0
L 1.87601998 -1.92041004 1.87441004 -1.92266998 0 P 0 ;0
L 1.87441004 -1.92266998 1.87298996 -1.92505 0 P 0 ;0
L 1.87298996 -1.92505 1.87178002 -1.92756004 0 P 0 ;0
L 1.87178002 -1.92756004 1.87078996 -1.93015 0 P 0 ;0
L 1.87078996 -1.93015 1.87 -1.93286998 0 P 0 ;0
L 1.87 -1.93286998 1.86943996 -1.93563996 0 P 0 ;0
L 1.86943996 -1.93563996 1.86908996 -1.93845 0 P 0 ;0
L 1.86908996 -1.93845 1.86898002 -1.94128996 0 P 0 ;0
L 1.86898002 -1.94128996 1.86911998 -1.94485 0 P 0 ;0
L 1.86911998 -1.94485 1.86953996 -1.94841004 0 P 0 ;0
L 1.86953996 -1.94841004 1.86996004 -1.95048996 0 P 0 ;0
L 1.86996004 -1.95048996 1.87053002 -1.95251998 0 P 0 ;0
L 1.87053002 -1.95251998 1.87125 -1.95451998 0 P 0 ;0
L 1.87125 -1.95451998 1.87211004 -1.95643002 0 P 0 ;0
L 1.87211004 -1.95643002 1.8731 -1.95826004 0 P 0 ;0
L 1.8731 -1.95826004 1.87423996 -1.96001998 0 P 0 ;0
L 1.87423996 -1.96001998 1.87636998 -1.96278996 0 P 0 ;0
L 1.87636998 -1.96278996 1.87871998 -1.96536998 0 P 0 ;0
L 1.87871998 -1.96536998 1.88145 -1.96788002 0 P 0 ;0
L 1.88145 -1.96788002 1.88436998 -1.97015 0 P 0 ;0
L 1.88436998 -1.97015 1.88621004 -1.97135 0 P 0 ;0
L 1.88621004 -1.97135 1.88813002 -1.97238002 0 P 0 ;0
L 1.88813002 -1.97238002 1.89013002 -1.97326004 0 P 0 ;0
L 1.89013002 -1.97326004 1.89228002 -1.97398996 0 P 0 ;0
L 1.89228002 -1.97398996 1.89446998 -1.97455 0 P 0 ;0
L 1.89446998 -1.97455 1.89671004 -1.97493996 0 P 0 ;0
L 1.89671004 -1.97493996 1.90076998 -1.97533996 0 P 0 ;0
L 1.90076998 -1.97533996 1.90485 -1.97546998 0 P 0 ;0
L 1.90485 -1.97546998 1.90821004 -1.97531998 0 P 0 ;0
L 1.90821004 -1.97531998 1.91153996 -1.97488996 0 P 0 ;0
L 1.91153996 -1.97488996 1.91481998 -1.97418996 0 P 0 ;0
L 1.91481998 -1.97418996 1.9171 -1.9735 0 P 0 ;0
L 1.9171 -1.9735 1.91933002 -1.97266004 0 P 0 ;0
L 1.91933002 -1.97266004 1.92148002 -1.97166004 0 P 0 ;0
L 1.92148002 -1.97166004 1.92356998 -1.97048996 0 P 0 ;0
L 1.92356998 -1.97048996 1.92553996 -1.96918996 0 P 0 ;0
L 1.92553996 -1.96918996 1.92741004 -1.96773996 0 P 0 ;0
L 1.92741004 -1.96773996 1.92916004 -1.96616998 0 P 0 ;0
L 1.92916004 -1.96616998 1.93081004 -1.96446004 0 P 0 ;0
L 1.93081004 -1.96446004 1.93236998 -1.96256998 0 P 0 ;0
L 1.93236998 -1.96256998 1.93381004 -1.96058996 0 P 0 ;0
L 1.93381004 -1.96058996 1.93511998 -1.95851004 0 P 0 ;0
L 1.93511998 -1.95851004 1.93628996 -1.95633996 0 P 0 ;0
L 1.93628996 -1.95633996 1.93803996 -1.95251998 0 P 0 ;0
L 1.93803996 -1.95251998 1.93858002 -1.95101998 0 P 0 ;0
L 1.93858002 -1.95101998 1.93898996 -1.94948002 0 P 0 ;0
L 1.93898996 -1.94948002 1.93928996 -1.94786998 0 P 0 ;0
L 1.93928996 -1.94786998 1.93946004 -1.94625 0 P 0 ;0
L 1.93946004 -1.94625 1.9396 -1.94178002 0 P 0 ;0
L 1.9396 -1.94178002 1.93946004 -1.93803996 0 P 0 ;0
L 1.93946004 -1.93803996 1.93905 -1.9343 0 P 0 ;0
L 1.93905 -1.9343 1.93863996 -1.93213996 0 P 0 ;0
L 1.93863996 -1.93213996 1.93808002 -1.93001998 0 P 0 ;0
L 1.93808002 -1.93001998 1.93736004 -1.92795 0 P 0 ;0
L 1.93736004 -1.92795 1.93653002 -1.92601004 0 P 0 ;0
L 1.93653002 -1.92601004 1.93555 -1.92415 0 P 0 ;0
L 1.93555 -1.92415 1.93441998 -1.92236004 0 P 0 ;0
L 1.93441998 -1.92236004 1.9331 -1.92056004 0 P 0 ;0
L 1.9331 -1.92056004 1.93166998 -1.91885 0 P 0 ;0
L 1.93166998 -1.91885 1.93011998 -1.91723002 0 P 0 ;0
L 1.93011998 -1.91723002 1.92896004 -1.91615 0 P 0 ;0
L 1.92896004 -1.91615 1.92775 -1.91511004 0 P 0 ;0
L 1.92775 -1.91511004 1.92493002 -1.91295 0 P 0 ;0
L 1.92493002 -1.91295 1.9221 -1.91108002 0 P 0 ;0
L 1.9221 -1.91108002 1.92095 -1.91043002 0 P 0 ;0
L 1.92095 -1.91043002 1.91975 -1.90985 0 P 0 ;0
L 1.91975 -1.90985 1.91796004 -1.90913996 0 P 0 ;0
L 1.91796004 -1.90913996 1.91613002 -1.90856004 0 P 0 ;0
L 1.91613002 -1.90856004 1.91423996 -1.9081 0 P 0 ;0
L 1.91423996 -1.9081 1.91086004 -1.90751998 0 P 0 ;0
L 1.91086004 -1.90751998 1.90743002 -1.90716004 0 P 0 ;0
L 1.90743002 -1.90716004 1.90401004 -1.90701004 0 P 0 ;0
L 1.90401004 -1.90701004 1.90058002 -1.90708002 0 P 0 ;0
L 1.90058002 -1.90708002 1.8987 -1.90726004 0 P 0 ;0
L 1.8987 -1.90726004 1.89683002 -1.90756998 0 P 0 ;0
L 1.89683002 -1.90756998 1.89498002 -1.90801998 0 P 0 ;0
L 1.86643002 -2.02923996 1.87525 -2.02923996 0 P 0 ;0
L 1.86176998 -2.02823996 1.87515 -2.02823996 0 P 0 ;0
L 1.85588996 -2.02723996 1.87505 -2.02723996 0 P 0 ;0
L 1.78365 -2.00523996 1.87281004 -2.00523996 0 P 0 ;0
L 1.78451004 -2.00423996 1.87271004 -2.00423996 0 P 0 ;0
L 1.78546998 -2.00323996 1.87261004 -2.00323996 0 P 0 ;0
L 1.78655 -2.00223996 1.8725 -2.00223996 0 P 0 ;0
L 1.78776004 -2.00123996 1.8724 -2.00123996 0 P 0 ;0
L 1.78915 -2.00023996 1.8723 -2.00023996 0 P 0 ;0
L 1.79078996 -1.99923996 1.8722 -1.99923996 0 P 0 ;0
L 1.79263996 -1.99823996 1.87208996 -1.99823996 0 P 0 ;0
L 1.79458996 -1.99723996 1.87198996 -1.99723996 0 P 0 ;0
L 1.79686998 -1.99623996 1.87188002 -1.99623996 0 P 0 ;0
L 1.79946004 -1.99523996 1.87178002 -1.99523996 0 P 0 ;0
L 1.80231004 -1.99423996 1.86961998 -1.99423996 0 P 0 ;0
L 1.80596004 -1.99323996 1.86218002 -1.99323996 0 P 0 ;0
L 1.81051004 -1.99223996 1.85398002 -1.99223996 0 P 0 ;0
L 1.81676004 -1.99123996 1.84395 -1.99123996 0 P 0 ;0
L 1.87786998 -1.96146004 1.88093996 -1.96146004 0 P 0 ;0
L 1.8771 -1.96046004 1.88013002 -1.96046004 0 P 0 ;0
L 1.87633996 -1.95946004 1.87933996 -1.95946004 0 P 0 ;0
L 1.87561998 -1.95846004 1.87866998 -1.95846004 0 P 0 ;0
L 1.87496998 -1.95746004 1.87801998 -1.95746004 0 P 0 ;0
L 1.8744 -1.95646004 1.87745 -1.95646004 0 P 0 ;0
L 1.87386998 -1.95546004 1.87688002 -1.95546004 0 P 0 ;0
L 1.87341998 -1.95446004 1.87641998 -1.95446004 0 P 0 ;0
L 1.87298996 -1.95346004 1.87596004 -1.95346004 0 P 0 ;0
L 1.87263002 -1.95246004 1.87555 -1.95246004 0 P 0 ;0
L 1.87231004 -1.95146004 1.87518996 -1.95146004 0 P 0 ;0
L 1.87203002 -1.95046004 1.87483002 -1.95046004 0 P 0 ;0
L 1.87178996 -1.94946004 1.87456998 -1.94946004 0 P 0 ;0
L 1.87158996 -1.94846004 1.87431004 -1.94846004 0 P 0 ;0
L 1.87143996 -1.94746004 1.87408002 -1.94746004 0 P 0 ;0
L 1.87133002 -1.94646004 1.8739 -1.94646004 0 P 0 ;0
L 1.87121004 -1.94546004 1.87373002 -1.94546004 0 P 0 ;0
L 1.8711 -1.94446998 1.87361998 -1.94446998 0 P 0 ;0
L 1.87106998 -1.94346004 1.87353996 -1.94346004 0 P 0 ;0
L 1.87103002 -1.94246004 1.87346004 -1.94246004 0 P 0 ;0
L 1.87098996 -1.94146998 1.87346004 -1.94146998 0 P 0 ;0
L 1.87101004 -1.94046004 1.87346004 -1.94046004 0 P 0 ;0
L 1.87106004 -1.93946004 1.87348996 -1.93946004 0 P 0 ;0
L 1.87111004 -1.93846004 1.87358002 -1.93846004 0 P 0 ;0
L 1.87123002 -1.93746004 1.87366004 -1.93746004 0 P 0 ;0
L 1.87135 -1.93646004 1.87381998 -1.93646004 0 P 0 ;0
L 1.87151004 -1.93546004 1.87398996 -1.93546004 0 P 0 ;0
L 1.87171998 -1.93446004 1.87416998 -1.93446004 0 P 0 ;0
L 1.87191998 -1.93346004 1.87443002 -1.93346004 0 P 0 ;0
L 1.8722 -1.93246004 1.87468996 -1.93246004 0 P 0 ;0
L 1.87248996 -1.93146004 1.875 -1.93146004 0 P 0 ;0
L 1.87281004 -1.93046004 1.87535 -1.93046004 0 P 0 ;0
L 1.87318996 -1.92946004 1.87571004 -1.92946004 0 P 0 ;0
L 1.87356998 -1.92846004 1.87616004 -1.92846004 0 P 0 ;0
L 1.87405 -1.92746004 1.87661004 -1.92746004 0 P 0 ;0
L 1.87453002 -1.92646004 1.87711998 -1.92646004 0 P 0 ;0
L 1.87506998 -1.92546004 1.87768996 -1.92546004 0 P 0 ;0
L 1.87566004 -1.92446998 1.87826998 -1.92446998 0 P 0 ;0
L 1.87628996 -1.92346004 1.87896004 -1.92346004 0 P 0 ;0
L 1.87701004 -1.92246004 1.87963996 -1.92246004 0 P 0 ;0
L 1.87775 -1.92146004 1.88046004 -1.92146004 0 P 0 ;0
L 1.90483996 -1.97346004 1.9009 -1.97333996 0 P 0 ;0
L 1.9009 -1.97333996 1.89698002 -1.97295 0 P 0 ;0
L 1.89698002 -1.97295 1.89488996 -1.97258996 0 P 0 ;0
L 1.89488996 -1.97258996 1.89285 -1.97206998 0 P 0 ;0
L 1.89285 -1.97206998 1.89086004 -1.97138996 0 P 0 ;0
L 1.89086004 -1.97138996 1.889 -1.97058002 0 P 0 ;0
L 1.889 -1.97058002 1.88723002 -1.96961998 0 P 0 ;0
L 1.88723002 -1.96961998 1.88553002 -1.96851998 0 P 0 ;0
L 1.88553002 -1.96851998 1.88273996 -1.96636004 0 P 0 ;0
L 1.88273996 -1.96636004 1.88013996 -1.96396004 0 P 0 ;0
L 1.88013996 -1.96396004 1.8779 -1.9615 0 P 0 ;0
L 1.8779 -1.9615 1.87588002 -1.95886998 0 P 0 ;0
L 1.87588002 -1.95886998 1.87483002 -1.95723996 0 P 0 ;0
L 1.87483002 -1.95723996 1.8739 -1.95553996 0 P 0 ;0
L 1.8739 -1.95553996 1.87311004 -1.95376998 0 P 0 ;0
L 1.87311004 -1.95376998 1.87243002 -1.95191004 0 P 0 ;0
L 1.87243002 -1.95191004 1.8719 -1.95001998 0 P 0 ;0
L 1.8719 -1.95001998 1.87151998 -1.9481 0 P 0 ;0
L 1.87151998 -1.9481 1.87111004 -1.94468996 0 P 0 ;0
L 1.87111004 -1.94468996 1.87098002 -1.94128996 0 P 0 ;0
L 1.87098002 -1.94128996 1.87108996 -1.93861004 0 P 0 ;0
L 1.87108996 -1.93861004 1.87141004 -1.93596998 0 P 0 ;0
L 1.87141004 -1.93596998 1.87195 -1.93335 0 P 0 ;0
L 1.87195 -1.93335 1.87268996 -1.93078996 0 P 0 ;0
L 1.87268996 -1.93078996 1.87361998 -1.92835 0 P 0 ;0
L 1.87361998 -1.92835 1.87475 -1.926 0 P 0 ;0
L 1.87475 -1.926 1.87608996 -1.92376004 0 P 0 ;0
L 1.87608996 -1.92376004 1.8776 -1.92163996 0 P 0 ;0
L 1.8776 -1.92163996 1.87931998 -1.91961998 0 P 0 ;0
L 1.87931998 -1.91961998 1.8812 -1.91775 0 P 0 ;0
L 1.8812 -1.91775 1.88323002 -1.91605 0 P 0 ;0
L 1.88323002 -1.91605 1.8854 -1.91451998 0 P 0 ;0
L 1.8854 -1.91451998 1.88781004 -1.91308996 0 P 0 ;0
L 1.88781004 -1.91308996 1.89031004 -1.91186004 0 P 0 ;0
L 1.89031004 -1.91186004 1.89288002 -1.9108 0 P 0 ;0
L 1.89288002 -1.9108 1.89553002 -1.90995 0 P 0 ;0
L 1.89553002 -1.90995 1.89723002 -1.90953002 0 P 0 ;0
L 1.89723002 -1.90953002 1.89896004 -1.90923996 0 P 0 ;0
L 1.89896004 -1.90923996 1.90068996 -1.90908002 0 P 0 ;0
L 1.90068996 -1.90908002 1.90398996 -1.90901004 0 P 0 ;0
L 1.90398996 -1.90901004 1.90728002 -1.90915 0 P 0 ;0
L 1.90728002 -1.90915 1.91058996 -1.90951004 0 P 0 ;0
L 1.91058996 -1.90951004 1.91383996 -1.91006004 0 P 0 ;0
L 1.91383996 -1.91006004 1.91558996 -1.91048996 0 P 0 ;0
L 1.91558996 -1.91048996 1.91728996 -1.91101998 0 P 0 ;0
L 1.91728996 -1.91101998 1.91895 -1.91168002 0 P 0 ;0
L 1.91895 -1.91168002 1.92001998 -1.9122 0 P 0 ;0
L 1.92001998 -1.9122 1.92105 -1.91278996 0 P 0 ;0
L 1.92105 -1.91278996 1.92376998 -1.91458002 0 P 0 ;0
L 1.92376998 -1.91458002 1.92648996 -1.91666998 0 P 0 ;0
L 1.92648996 -1.91666998 1.92763002 -1.91763996 0 P 0 ;0
L 1.92763002 -1.91763996 1.92871004 -1.91865 0 P 0 ;0
L 1.92871004 -1.91865 1.93018002 -1.92018996 0 P 0 ;0
L 1.93018002 -1.92018996 1.93153002 -1.9218 0 P 0 ;0
L 1.93153002 -1.9218 1.93276998 -1.92348996 0 P 0 ;0
L 1.93276998 -1.92348996 1.93381004 -1.92515 0 P 0 ;0
L 1.93381004 -1.92515 1.93471998 -1.92686998 0 P 0 ;0
L 1.93471998 -1.92686998 1.9355 -1.92866998 0 P 0 ;0
L 1.9355 -1.92866998 1.93616998 -1.93061004 0 P 0 ;0
L 1.93616998 -1.93061004 1.93668996 -1.93258002 0 P 0 ;0
L 1.93668996 -1.93258002 1.93706998 -1.93458996 0 P 0 ;0
L 1.93706998 -1.93458996 1.93746998 -1.93818996 0 P 0 ;0
L 1.93746998 -1.93818996 1.9376 -1.94178996 0 P 0 ;0
L 1.9376 -1.94178996 1.93746004 -1.94611004 0 P 0 ;0
L 1.93746004 -1.94611004 1.93731004 -1.94758996 0 P 0 ;0
L 1.93731004 -1.94758996 1.93705 -1.94903996 0 P 0 ;0
L 1.93705 -1.94903996 1.93666998 -1.95041998 0 P 0 ;0
L 1.93666998 -1.95041998 1.93618002 -1.95176004 0 P 0 ;0
L 1.93618002 -1.95176004 1.9345 -1.95545 0 P 0 ;0
L 1.9345 -1.95545 1.93338996 -1.9575 0 P 0 ;0
L 1.93338996 -1.9575 1.93216004 -1.95946998 0 P 0 ;0
L 1.93216004 -1.95946998 1.93078996 -1.96133996 0 P 0 ;0
L 1.93078996 -1.96133996 1.92931004 -1.96311998 0 P 0 ;0
L 1.92931004 -1.96311998 1.92776998 -1.96473002 0 P 0 ;0
L 1.92776998 -1.96473002 1.92613002 -1.96621004 0 P 0 ;0
L 1.92613002 -1.96621004 1.92438002 -1.96756004 0 P 0 ;0
L 1.92438002 -1.96756004 1.92253002 -1.96878002 0 P 0 ;0
L 1.92253002 -1.96878002 1.92056998 -1.96986998 0 P 0 ;0
L 1.92056998 -1.96986998 1.91855 -1.97081998 0 P 0 ;0
L 1.91855 -1.97081998 1.91646004 -1.97161004 0 P 0 ;0
L 1.91646004 -1.97161004 1.91433002 -1.97223996 0 P 0 ;0
L 1.91433002 -1.97223996 1.9112 -1.97291004 0 P 0 ;0
L 1.9112 -1.97291004 1.90803996 -1.97331998 0 P 0 ;0
L 1.90803996 -1.97331998 1.90483996 -1.97346004 0 P 0 ;0
L 1.90476004 -1.97173996 1.9048 -1.97173996 0 P 0 ;0
L 1.9048 -1.97173996 1.90483996 -1.97173002 0 P 0 ;0
L 1.90483996 -1.97173002 1.90736004 -1.9716 0 P 0 ;0
L 1.90736004 -1.9716 1.9074 -1.97158996 0 P 0 ;0
L 1.9074 -1.97158996 1.90746998 -1.97158996 0 P 0 ;0
L 1.90746998 -1.97158996 1.90751004 -1.97158002 0 P 0 ;0
L 1.90751004 -1.97158002 1.91001004 -1.97126004 0 P 0 ;0
L 1.91001004 -1.97126004 1.91005 -1.97125 0 P 0 ;0
L 1.91005 -1.97125 1.91008002 -1.97123996 0 P 0 ;0
L 1.91008002 -1.97123996 1.91011998 -1.97123996 0 P 0 ;0
L 1.91011998 -1.97123996 1.91016004 -1.97123002 0 P 0 ;0
L 1.91016004 -1.97123002 1.9126 -1.97071998 0 P 0 ;0
L 1.9126 -1.97071998 1.9126 -1.97071004 0 P 0 ;0
L 1.9126 -1.97071004 1.91266998 -1.97071004 0 P 0 ;0
L 1.91266998 -1.97071004 1.91271004 -1.97068996 0 P 0 ;0
L 1.91271004 -1.97068996 1.91275 -1.97068002 0 P 0 ;0
L 1.91275 -1.97068002 1.91511998 -1.96998996 0 P 0 ;0
L 1.91511998 -1.96998996 1.91515 -1.96998996 0 P 0 ;0
L 1.91515 -1.96998996 1.91518996 -1.96996998 0 P 0 ;0
L 1.91518996 -1.96996998 1.91523002 -1.96996004 0 P 0 ;0
L 1.91523002 -1.96996004 1.91526004 -1.96995 0 P 0 ;0
L 1.91526004 -1.96995 1.91756998 -1.96908002 0 P 0 ;0
L 1.91756998 -1.96908002 1.91761004 -1.96906998 0 P 0 ;0
L 1.91761004 -1.96906998 1.91768002 -1.96903996 0 P 0 ;0
L 1.91768002 -1.96903996 1.91771004 -1.96901998 0 P 0 ;0
L 1.91771004 -1.96901998 1.91995 -1.96798002 0 P 0 ;0
L 1.91995 -1.96798002 1.92001998 -1.96795 0 P 0 ;0
L 1.92001998 -1.96795 1.92005 -1.96793002 0 P 0 ;0
L 1.92005 -1.96793002 1.92008996 -1.96791004 0 P 0 ;0
L 1.92008996 -1.96791004 1.92168002 -1.96701998 0 P 0 ;0
L 1.92168002 -1.96701998 1.92171998 -1.967 0 P 0 ;0
L 1.92171998 -1.967 1.92175 -1.96698002 0 P 0 ;0
L 1.92175 -1.96698002 1.92178996 -1.96695 0 P 0 ;0
L 1.92178996 -1.96695 1.92181998 -1.96693002 0 P 0 ;0
L 1.92181998 -1.96693002 1.92331998 -1.96591998 0 P 0 ;0
L 1.92331998 -1.96591998 1.92336004 -1.9659 0 P 0 ;0
L 1.92336004 -1.9659 1.92341998 -1.96586004 0 P 0 ;0
L 1.92341998 -1.96586004 1.92345 -1.96583002 0 P 0 ;0
L 1.92345 -1.96583002 1.92486004 -1.9647 0 P 0 ;0
L 1.92486004 -1.9647 1.92493002 -1.96465 0 P 0 ;0
L 1.92493002 -1.96465 1.92496004 -1.96463002 0 P 0 ;0
L 1.92496004 -1.96463002 1.92498996 -1.9646 0 P 0 ;0
L 1.92498996 -1.9646 1.92631004 -1.96336998 0 P 0 ;0
L 1.92631004 -1.96336998 1.9264 -1.96328002 0 P 0 ;0
L 1.9264 -1.96328002 1.92641998 -1.96325 0 P 0 ;0
L 1.92641998 -1.96325 1.92763996 -1.96191998 0 P 0 ;0
L 1.92763996 -1.96191998 1.92766998 -1.96188996 0 P 0 ;0
L 1.92766998 -1.96188996 1.92768996 -1.96186004 0 P 0 ;0
L 1.92768996 -1.96186004 1.92771998 -1.96183002 0 P 0 ;0
L 1.92771998 -1.96183002 1.92773996 -1.9618 0 P 0 ;0
L 1.92773996 -1.9618 1.92913996 -1.96001004 0 P 0 ;0
L 1.92913996 -1.96001004 1.92918996 -1.95995 0 P 0 ;0
L 1.92918996 -1.95995 1.92921004 -1.95991004 0 P 0 ;0
L 1.92921004 -1.95991004 1.92923002 -1.95988002 0 P 0 ;0
L 1.92923002 -1.95988002 1.93048002 -1.95798996 0 P 0 ;0
L 1.93048002 -1.95798996 1.93051998 -1.95793002 0 P 0 ;0
L 1.93051998 -1.95793002 1.93053996 -1.95788996 0 P 0 ;0
L 1.93053996 -1.95788996 1.93056004 -1.95786004 0 P 0 ;0
L 1.93056004 -1.95786004 1.93166004 -1.95588002 0 P 0 ;0
L 1.93166004 -1.95588002 1.93171004 -1.95576998 0 P 0 ;0
L 1.93171004 -1.95576998 1.93173002 -1.95573996 0 P 0 ;0
L 1.93173002 -1.95573996 1.93266998 -1.95366998 0 P 0 ;0
L 1.93266998 -1.95366998 1.93271004 -1.95356998 0 P 0 ;0
L 1.93271004 -1.95356998 1.93273002 -1.95353002 0 P 0 ;0
L 1.93273002 -1.95353002 1.9335 -1.9514 0 P 0 ;0
L 1.9335 -1.9514 1.93351004 -1.95136998 0 P 0 ;0
L 1.93351004 -1.95136998 1.93353002 -1.95133002 0 P 0 ;0
L 1.93353002 -1.95133002 1.93355 -1.95125 0 P 0 ;0
L 1.93355 -1.95125 1.93416004 -1.94906998 0 P 0 ;0
L 1.93416004 -1.94906998 1.93416998 -1.94903002 0 P 0 ;0
L 1.93416998 -1.94903002 1.93418002 -1.949 0 P 0 ;0
L 1.93418002 -1.949 1.93418002 -1.94896004 0 P 0 ;0
L 1.93418002 -1.94896004 1.93418996 -1.94891998 0 P 0 ;0
L 1.93418996 -1.94891998 1.93463996 -1.94665 0 P 0 ;0
L 1.93463996 -1.94665 1.93463996 -1.94661004 0 P 0 ;0
L 1.93463996 -1.94661004 1.93465 -1.94656998 0 P 0 ;0
L 1.93465 -1.94656998 1.93466004 -1.9465 0 P 0 ;0
L 1.93466004 -1.9465 1.93493996 -1.9442 0 P 0 ;0
L 1.93493996 -1.9442 1.93493996 -1.94413002 0 P 0 ;0
L 1.93493996 -1.94413002 1.93495 -1.94408996 0 P 0 ;0
L 1.93495 -1.94408996 1.93495 -1.94406004 0 P 0 ;0
L 1.93495 -1.94406004 1.93505 -1.94173996 0 P 0 ;0
L 1.93505 -1.94173996 1.93506004 -1.94171004 0 P 0 ;0
L 1.93506004 -1.94171004 1.93506004 -1.9416 0 P 0 ;0
L 1.93506004 -1.9416 1.93498996 -1.93928996 0 P 0 ;0
L 1.93498996 -1.93928996 1.93498996 -1.93921004 0 P 0 ;0
L 1.93498996 -1.93921004 1.93498002 -1.93913996 0 P 0 ;0
L 1.93498002 -1.93913996 1.93475 -1.93683996 0 P 0 ;0
L 1.93475 -1.93683996 1.93473996 -1.93676998 0 P 0 ;0
L 1.93473996 -1.93676998 1.93473002 -1.93673002 0 P 0 ;0
L 1.93473002 -1.93673002 1.93473002 -1.93668996 0 P 0 ;0
L 1.93473002 -1.93668996 1.93433002 -1.93441004 0 P 0 ;0
L 1.93433002 -1.93441004 1.93431998 -1.93436998 0 P 0 ;0
L 1.93431998 -1.93436998 1.93431004 -1.93433996 0 P 0 ;0
L 1.93431004 -1.93433996 1.93428996 -1.93426004 0 P 0 ;0
L 1.93428996 -1.93426004 1.93373002 -1.93206004 0 P 0 ;0
L 1.93373002 -1.93206004 1.93368996 -1.93191998 0 P 0 ;0
L 1.93368996 -1.93191998 1.93296004 -1.92976998 0 P 0 ;0
L 1.93296004 -1.92976998 1.93293996 -1.9297 0 P 0 ;0
L 1.93293996 -1.9297 1.93291004 -1.92963002 0 P 0 ;0
L 1.93291004 -1.92963002 1.93201998 -1.92753996 0 P 0 ;0
L 1.93201998 -1.92753996 1.93196998 -1.92743002 0 P 0 ;0
L 1.93196998 -1.92743002 1.93196004 -1.9274 0 P 0 ;0
L 1.93196004 -1.9274 1.93091998 -1.92538996 0 P 0 ;0
L 1.93091998 -1.92538996 1.9309 -1.92536004 0 P 0 ;0
L 1.9309 -1.92536004 1.93088002 -1.92531998 0 P 0 ;0
L 1.93088002 -1.92531998 1.93086004 -1.92528996 0 P 0 ;0
L 1.93086004 -1.92528996 1.93083996 -1.92525 0 P 0 ;0
L 1.93083996 -1.92525 1.92965 -1.92331998 0 P 0 ;0
L 1.92965 -1.92331998 1.92956998 -1.9232 0 P 0 ;0
L 1.92956998 -1.9232 1.92823002 -1.92136004 0 P 0 ;0
L 1.92823002 -1.92136004 1.92818002 -1.9213 0 P 0 ;0
L 1.92818002 -1.9213 1.92816004 -1.92126998 0 P 0 ;0
L 1.92816004 -1.92126998 1.92813002 -1.92123996 0 P 0 ;0
L 1.92813002 -1.92123996 1.92671998 -1.91958002 0 P 0 ;0
L 1.92671998 -1.91958002 1.9266 -1.91946004 0 P 0 ;0
L 1.9266 -1.91946004 1.92505 -1.91793002 0 P 0 ;0
L 1.92505 -1.91793002 1.92498996 -1.91786998 0 P 0 ;0
L 1.92498996 -1.91786998 1.92493002 -1.91781998 0 P 0 ;0
L 1.92493002 -1.91781998 1.92325 -1.91643002 0 P 0 ;0
L 1.92325 -1.91643002 1.92318996 -1.91636998 0 P 0 ;0
L 1.92318996 -1.91636998 1.92311998 -1.91631998 0 P 0 ;0
L 1.92311998 -1.91631998 1.92133002 -1.91508002 0 P 0 ;0
L 1.92133002 -1.91508002 1.92126004 -1.91503996 0 P 0 ;0
L 1.92126004 -1.91503996 1.92121998 -1.91501004 0 P 0 ;0
L 1.92121998 -1.91501004 1.92118002 -1.91498996 0 P 0 ;0
L 1.92118002 -1.91498996 1.91928996 -1.91391004 0 P 0 ;0
L 1.91928996 -1.91391004 1.91926004 -1.91388996 0 P 0 ;0
L 1.91926004 -1.91388996 1.91913996 -1.91383002 0 P 0 ;0
L 1.91913996 -1.91383002 1.91716998 -1.91291004 0 P 0 ;0
L 1.91716998 -1.91291004 1.91711998 -1.91288996 0 P 0 ;0
L 1.91711998 -1.91288996 1.91705 -1.91286004 0 P 0 ;0
L 1.91705 -1.91286004 1.917 -1.91285 0 P 0 ;0
L 1.917 -1.91285 1.91476998 -1.91203996 0 P 0 ;0
L 1.91476998 -1.91203996 1.91468996 -1.91201998 0 P 0 ;0
L 1.91468996 -1.91201998 1.91465 -1.912 0 P 0 ;0
L 1.91465 -1.912 1.9146 -1.91198996 0 P 0 ;0
L 1.9146 -1.91198996 1.91233002 -1.91138996 0 P 0 ;0
L 1.91233002 -1.91138996 1.91228002 -1.91138002 0 P 0 ;0
L 1.91228002 -1.91138002 1.91223996 -1.91136998 0 P 0 ;0
L 1.91223996 -1.91136998 1.91216004 -1.91136004 0 P 0 ;0
L 1.91216004 -1.91136004 1.90983002 -1.91095 0 P 0 ;0
L 1.90983002 -1.91095 1.9098 -1.91093996 0 P 0 ;0
L 1.9098 -1.91093996 1.90976004 -1.91093996 0 P 0 ;0
L 1.90976004 -1.91093996 1.90971998 -1.91093002 0 P 0 ;0
L 1.90971998 -1.91093002 1.90968002 -1.91093002 0 P 0 ;0
L 1.90968002 -1.91093002 1.90713996 -1.91068996 0 P 0 ;0
L 1.90713996 -1.91068996 1.9071 -1.91068002 0 P 0 ;0
L 1.9071 -1.91068002 1.907 -1.91068002 0 P 0 ;0
L 1.907 -1.91068002 1.90445 -1.91061004 0 P 0 ;0
L 1.90445 -1.91061004 1.90431004 -1.91061004 0 P 0 ;0
L 1.90431004 -1.91061004 1.90176004 -1.91071004 0 P 0 ;0
L 1.90176004 -1.91071004 1.90173002 -1.91071998 0 P 0 ;0
L 1.90173002 -1.91071998 1.90166004 -1.91071998 0 P 0 ;0
L 1.90166004 -1.91071998 1.90161998 -1.91073002 0 P 0 ;0
L 1.90161998 -1.91073002 1.89913002 -1.911 0 P 0 ;0
L 1.89913002 -1.911 1.89906004 -1.91101004 0 P 0 ;0
L 1.89906004 -1.91101004 1.89901998 -1.91101998 0 P 0 ;0
L 1.89901998 -1.91101998 1.89898996 -1.91101998 0 P 0 ;0
L 1.89898996 -1.91101998 1.89653002 -1.91146998 0 P 0 ;0
L 1.89653002 -1.91146998 1.8965 -1.91148002 0 P 0 ;0
L 1.8965 -1.91148002 1.89646004 -1.91148002 0 P 0 ;0
L 1.89646004 -1.91148002 1.8964 -1.9115 0 P 0 ;0
L 1.8964 -1.9115 1.89396998 -1.91211998 0 P 0 ;0
L 1.89396998 -1.91211998 1.89393996 -1.91213002 0 P 0 ;0
L 1.89393996 -1.91213002 1.89383002 -1.91216004 0 P 0 ;0
L 1.89383002 -1.91216004 1.89225 -1.91268996 0 P 0 ;0
L 1.89225 -1.91268996 1.89218002 -1.91271998 0 P 0 ;0
L 1.89218002 -1.91271998 1.89211004 -1.91273996 0 P 0 ;0
L 1.89211004 -1.91273996 1.8921 -1.91273996 0 P 0 ;0
L 1.8921 -1.91273996 1.89058002 -1.91338996 0 P 0 ;0
L 1.89058002 -1.91338996 1.89043996 -1.91345 0 P 0 ;0
L 1.89043996 -1.91345 1.88896004 -1.91421004 0 P 0 ;0
L 1.88896004 -1.91421004 1.88893002 -1.91423002 0 P 0 ;0
L 1.88893002 -1.91423002 1.8889 -1.91423996 0 P 0 ;0
L 1.8889 -1.91423996 1.88886004 -1.91426004 0 P 0 ;0
L 1.88886004 -1.91426004 1.88883002 -1.91428002 0 P 0 ;0
L 1.88883002 -1.91428002 1.88741004 -1.91515 0 P 0 ;0
L 1.88741004 -1.91515 1.88733996 -1.91518996 0 P 0 ;0
L 1.88733996 -1.91518996 1.88728002 -1.91523996 0 P 0 ;0
L 1.88728002 -1.91523996 1.88526004 -1.9167 0 P 0 ;0
L 1.88526004 -1.9167 1.88521998 -1.91673002 0 P 0 ;0
L 1.88521998 -1.91673002 1.88518996 -1.91675 0 P 0 ;0
L 1.88518996 -1.91675 1.88516004 -1.91678002 0 P 0 ;0
L 1.88516004 -1.91678002 1.88511998 -1.91681004 0 P 0 ;0
L 1.88511998 -1.91681004 1.88323002 -1.91845 0 P 0 ;0
L 1.88323002 -1.91845 1.8832 -1.91846998 0 P 0 ;0
L 1.8832 -1.91846998 1.88311004 -1.91856004 0 P 0 ;0
L 1.88311004 -1.91856004 1.88136998 -1.92036004 0 P 0 ;0
L 1.88136998 -1.92036004 1.88128002 -1.92045 0 P 0 ;0
L 1.88128002 -1.92045 1.88125 -1.92048996 0 P 0 ;0
L 1.88125 -1.92048996 1.87968002 -1.92241998 0 P 0 ;0
L 1.87968002 -1.92241998 1.87965 -1.92245 0 P 0 ;0
L 1.87965 -1.92245 1.87961998 -1.92248996 0 P 0 ;0
L 1.87961998 -1.92248996 1.87956998 -1.92256004 0 P 0 ;0
L 1.87956998 -1.92256004 1.87816998 -1.92461998 0 P 0 ;0
L 1.87816998 -1.92461998 1.8781 -1.92473002 0 P 0 ;0
L 1.8781 -1.92473002 1.87808002 -1.92476998 0 P 0 ;0
L 1.87808002 -1.92476998 1.87685 -1.92695 0 P 0 ;0
L 1.87685 -1.92695 1.87683002 -1.92698996 0 P 0 ;0
L 1.87683002 -1.92698996 1.87681004 -1.92701998 0 P 0 ;0
L 1.87681004 -1.92701998 1.87678996 -1.92706998 0 P 0 ;0
L 1.87678996 -1.92706998 1.87676998 -1.92711004 0 P 0 ;0
L 1.87676998 -1.92711004 1.87573002 -1.92941004 0 P 0 ;0
L 1.87573002 -1.92941004 1.87571004 -1.92945 0 P 0 ;0
L 1.87571004 -1.92945 1.8757 -1.92948996 0 P 0 ;0
L 1.8757 -1.92948996 1.87568002 -1.92951998 0 P 0 ;0
L 1.87568002 -1.92951998 1.87566998 -1.92956998 0 P 0 ;0
L 1.87566998 -1.92956998 1.87483996 -1.93193002 0 P 0 ;0
L 1.87483996 -1.93193002 1.87481004 -1.93201004 0 P 0 ;0
L 1.87481004 -1.93201004 1.87478996 -1.93208996 0 P 0 ;0
L 1.87478996 -1.93208996 1.87416004 -1.93451998 0 P 0 ;0
L 1.87416004 -1.93451998 1.87413996 -1.93456004 0 P 0 ;0
L 1.87413996 -1.93456004 1.87413002 -1.9346 0 P 0 ;0
L 1.87413002 -1.9346 1.87413002 -1.93463996 0 P 0 ;0
L 1.87413002 -1.93463996 1.87411998 -1.93468002 0 P 0 ;0
L 1.87411998 -1.93468002 1.8737 -1.93715 0 P 0 ;0
L 1.8737 -1.93715 1.87368996 -1.93718996 0 P 0 ;0
L 1.87368996 -1.93718996 1.87368002 -1.93723996 0 P 0 ;0
L 1.87368002 -1.93723996 1.87368002 -1.93731998 0 P 0 ;0
L 1.87368002 -1.93731998 1.87346998 -1.93981998 0 P 0 ;0
L 1.87346998 -1.93981998 1.87346004 -1.93986004 0 P 0 ;0
L 1.87346004 -1.93986004 1.87346004 -1.94258002 0 P 0 ;0
L 1.87346004 -1.94258002 1.87346998 -1.94266004 0 P 0 ;0
L 1.87346998 -1.94266004 1.87368002 -1.94516998 0 P 0 ;0
L 1.87368002 -1.94516998 1.87368996 -1.94521004 0 P 0 ;0
L 1.87368996 -1.94521004 1.87368996 -1.94525 0 P 0 ;0
L 1.87368996 -1.94525 1.87371004 -1.94533996 0 P 0 ;0
L 1.87371004 -1.94533996 1.87413996 -1.94778996 0 P 0 ;0
L 1.87413996 -1.94778996 1.87413996 -1.94783996 0 P 0 ;0
L 1.87413996 -1.94783996 1.87416998 -1.94796004 0 P 0 ;0
L 1.87416998 -1.94796004 1.87481004 -1.95036998 0 P 0 ;0
L 1.87481004 -1.95036998 1.87483996 -1.95048996 0 P 0 ;0
L 1.87483996 -1.95048996 1.87486004 -1.95053002 0 P 0 ;0
L 1.87486004 -1.95053002 1.8757 -1.95288002 0 P 0 ;0
L 1.8757 -1.95288002 1.87571004 -1.95291998 0 P 0 ;0
L 1.87571004 -1.95291998 1.87575 -1.953 0 P 0 ;0
L 1.87575 -1.953 1.87576004 -1.95303996 0 P 0 ;0
L 1.87576004 -1.95303996 1.8768 -1.9553 0 P 0 ;0
L 1.8768 -1.9553 1.87686004 -1.95541998 0 P 0 ;0
L 1.87686004 -1.95541998 1.87688002 -1.95545 0 P 0 ;0
L 1.87688002 -1.95545 1.8781 -1.95761004 0 P 0 ;0
L 1.8781 -1.95761004 1.87811998 -1.95761004 0 P 0 ;0
L 1.87811998 -1.95761004 1.8781 -1.95761998 0 P 0 ;0
L 1.8781 -1.95761998 1.87813996 -1.95768996 0 P 0 ;0
L 1.87813996 -1.95768996 1.87816998 -1.95771998 0 P 0 ;0
L 1.87816998 -1.95771998 1.87818996 -1.95775 0 P 0 ;0
L 1.87818996 -1.95775 1.87938002 -1.95951004 0 P 0 ;0
L 1.87938002 -1.95951004 1.87943996 -1.9596 0 P 0 ;0
L 1.87943996 -1.9596 1.87946998 -1.95963002 0 P 0 ;0
L 1.87946998 -1.95963002 1.88078002 -1.96128996 0 P 0 ;0
L 1.88078002 -1.96128996 1.88081004 -1.96131998 0 P 0 ;0
L 1.88081004 -1.96131998 1.88083002 -1.96135 0 P 0 ;0
L 1.88083002 -1.96135 1.88086004 -1.96136998 0 P 0 ;0
L 1.88086004 -1.96136998 1.88088002 -1.9614 0 P 0 ;0
L 1.88088002 -1.9614 1.88231998 -1.96295 0 P 0 ;0
L 1.88231998 -1.96295 1.88233996 -1.96298002 0 P 0 ;0
L 1.88233996 -1.96298002 1.8824 -1.96303996 0 P 0 ;0
L 1.8824 -1.96303996 1.88243002 -1.96306004 0 P 0 ;0
L 1.88243002 -1.96306004 1.88398002 -1.9645 0 P 0 ;0
L 1.88398002 -1.9645 1.88401004 -1.96451998 0 P 0 ;0
L 1.88401004 -1.96451998 1.88403002 -1.96455 0 P 0 ;0
L 1.88403002 -1.96455 1.88406998 -1.96458002 0 P 0 ;0
L 1.88406998 -1.96458002 1.88408996 -1.9646 0 P 0 ;0
L 1.88408996 -1.9646 1.88575 -1.96591004 0 P 0 ;0
L 1.88575 -1.96591004 1.88578002 -1.96593996 0 P 0 ;0
L 1.88578002 -1.96593996 1.88586998 -1.966 0 P 0 ;0
L 1.88586998 -1.966 1.88761998 -1.96718996 0 P 0 ;0
L 1.88761998 -1.96718996 1.88766004 -1.96721004 0 P 0 ;0
L 1.88766004 -1.96721004 1.88775 -1.96726998 0 P 0 ;0
L 1.88775 -1.96726998 1.88958996 -1.96831998 0 P 0 ;0
L 1.88958996 -1.96831998 1.88965 -1.96836004 0 P 0 ;0
L 1.88965 -1.96836004 1.88968002 -1.96836998 0 P 0 ;0
L 1.88968002 -1.96836998 1.88971998 -1.96838996 0 P 0 ;0
L 1.88971998 -1.96838996 1.89145 -1.96921998 0 P 0 ;0
L 1.89145 -1.96921998 1.89151004 -1.96925 0 P 0 ;0
L 1.89151004 -1.96925 1.89155 -1.96926004 0 P 0 ;0
L 1.89155 -1.96926004 1.89158002 -1.96926998 0 P 0 ;0
L 1.89158002 -1.96926998 1.89336004 -1.96996998 0 P 0 ;0
L 1.89336004 -1.96996998 1.89336004 -1.96998002 0 P 0 ;0
L 1.89336004 -1.96998002 1.89346004 -1.97001004 0 P 0 ;0
L 1.89346004 -1.97001004 1.89348996 -1.97001998 0 P 0 ;0
L 1.89348996 -1.97001998 1.89531998 -1.9706 0 P 0 ;0
L 1.89531998 -1.9706 1.89536004 -1.97061004 0 P 0 ;0
L 1.89536004 -1.97061004 1.89541998 -1.97063002 0 P 0 ;0
L 1.89541998 -1.97063002 1.89546004 -1.97063002 0 P 0 ;0
L 1.89546004 -1.97063002 1.89731998 -1.97108002 0 P 0 ;0
L 1.89731998 -1.97108002 1.89741998 -1.9711 0 P 0 ;0
L 1.89741998 -1.9711 1.89746004 -1.9711 0 P 0 ;0
L 1.89746004 -1.9711 1.89746004 -1.97111004 0 P 0 ;0
L 1.89746004 -1.97111004 1.89933996 -1.97141998 0 P 0 ;0
L 1.89933996 -1.97141998 1.89936998 -1.97143002 0 P 0 ;0
L 1.89936998 -1.97143002 1.89941004 -1.97143002 0 P 0 ;0
L 1.89941004 -1.97143002 1.89945 -1.97143996 0 P 0 ;0
L 1.89945 -1.97143996 1.89948002 -1.97143996 0 P 0 ;0
L 1.89948002 -1.97143996 1.90201004 -1.97168002 0 P 0 ;0
L 1.90201004 -1.97168002 1.90205 -1.97168002 0 P 0 ;0
L 1.90205 -1.97168002 1.90208996 -1.97168996 0 P 0 ;0
L 1.90208996 -1.97168996 1.90216004 -1.97168996 0 P 0 ;0
L 1.90216004 -1.97168996 1.90468996 -1.97173996 0 P 0 ;0
L 1.90468996 -1.97173996 1.90476004 -1.97173996 0 P 0 ;0
L 1.80616004 -2.12823996 1.83348996 -2.12823996 0 P 0 ;0
L 1.79591998 -2.12723996 1.8396 -2.12723996 0 P 0 ;0
L 1.78818002 -2.12623996 1.84465 -2.12623996 0 P 0 ;0
L 1.82003996 -2.09123996 1.87618996 -2.09123996 0 P 0 ;0
L 1.82198996 -2.09023996 1.8762 -2.09023996 0 P 0 ;0
L 1.82325 -2.08923996 1.8762 -2.08923996 0 P 0 ;0
L 1.82411998 -2.08823996 1.87618996 -2.08823996 0 P 0 ;0
L 1.82463002 -2.08723996 1.87616998 -2.08723996 0 P 0 ;0
L 1.82488002 -2.08623996 1.87615 -2.08623996 0 P 0 ;0
L 1.82493002 -2.08523996 1.87613002 -2.08523996 0 P 0 ;0
L 1.82476998 -2.08423996 1.87611004 -2.08423996 0 P 0 ;0
L 1.64846004 -2.08295 1.73316998 -2.08295 0 P 0 ;0
L 1.64811998 -2.08195 1.73356998 -2.08195 0 P 0 ;0
L 1.64776998 -2.08095 1.73398002 -2.08095 0 P 0 ;0
L 1.64743002 -2.07995 1.73438002 -2.07995 0 P 0 ;0
L 1.64708996 -2.07895 1.73478996 -2.07895 0 P 0 ;0
L 1.64673996 -2.07795 1.7352 -2.07795 0 P 0 ;0
L 1.6464 -2.07695 1.7356 -2.07695 0 P 0 ;0
L 1.64605 -2.07595 1.73601004 -2.07595 0 P 0 ;0
L 1.64571004 -2.07495 1.73641004 -2.07495 0 P 0 ;0
L 1.64536004 -2.07395 1.73681004 -2.07395 0 P 0 ;0
L 1.64501998 -2.07295 1.73721998 -2.07295 0 P 0 ;0
L 1.64466998 -2.07195 1.73761998 -2.07195 0 P 0 ;0
L 1.64433002 -2.07095 1.73803002 -2.07095 0 P 0 ;0
L 1.64398002 -2.06995 1.69251004 -2.06995 0 P 0 ;0
L 1.69583002 -2.06995 1.73843996 -2.06995 0 P 0 ;0
L 1.64363002 -2.06895 1.69168002 -2.06895 0 P 0 ;0
L 1.69671998 -2.06895 1.73883996 -2.06895 0 P 0 ;0
L 1.64328996 -2.06795 1.69136004 -2.06795 0 P 0 ;0
L 1.69708996 -2.06795 1.73925 -2.06795 0 P 0 ;0
L 1.64293996 -2.06695 1.69108002 -2.06695 0 P 0 ;0
L 1.69738002 -2.06695 1.73965 -2.06695 0 P 0 ;0
L 1.64258996 -2.06595 1.6908 -2.06595 0 P 0 ;0
L 1.69768002 -2.06595 1.74006004 -2.06595 0 P 0 ;0
L 1.64223996 -2.06495 1.69051998 -2.06495 0 P 0 ;0
L 1.69796998 -2.06495 1.74046004 -2.06495 0 P 0 ;0
L 1.6419 -2.06395 1.69023002 -2.06395 0 P 0 ;0
L 1.69826998 -2.06395 1.74086004 -2.06395 0 P 0 ;0
L 1.64155 -2.06295 1.68996004 -2.06295 0 P 0 ;0
L 1.69856004 -2.06295 1.74126998 -2.06295 0 P 0 ;0
L 1.6412 -2.06195 1.68966998 -2.06195 0 P 0 ;0
L 1.69886004 -2.06195 1.74168002 -2.06195 0 P 0 ;0
L 1.64085 -2.06095 1.68938996 -2.06095 0 P 0 ;0
L 1.69915 -2.06095 1.74208002 -2.06095 0 P 0 ;0
L 1.6405 -2.05995 1.68911004 -2.05995 0 P 0 ;0
L 1.69945 -2.05995 1.74248002 -2.05995 0 P 0 ;0
L 1.64016004 -2.05895 1.68883002 -2.05895 0 P 0 ;0
L 1.69973996 -2.05895 1.74288996 -2.05895 0 P 0 ;0
L 1.63981004 -2.05795 1.68855 -2.05795 0 P 0 ;0
L 1.70003996 -2.05795 1.74328996 -2.05795 0 P 0 ;0
L 1.63946004 -2.05695 1.68826998 -2.05695 0 P 0 ;0
L 1.70033002 -2.05695 1.7437 -2.05695 0 P 0 ;0
L 1.63911004 -2.05595 1.68798996 -2.05595 0 P 0 ;0
L 1.70063002 -2.05595 1.7441 -2.05595 0 P 0 ;0
L 1.63876998 -2.05495 1.68771004 -2.05495 0 P 0 ;0
L 1.70091998 -2.05495 1.74451004 -2.05495 0 P 0 ;0
L 1.63841998 -2.05395 1.68741998 -2.05395 0 P 0 ;0
L 1.70121998 -2.05395 1.74491004 -2.05395 0 P 0 ;0
L 1.63806998 -2.05295 1.68713996 -2.05295 0 P 0 ;0
L 1.70151004 -2.05295 1.74531004 -2.05295 0 P 0 ;0
L 1.63771998 -2.05195 1.68686004 -2.05195 0 P 0 ;0
L 1.70181004 -2.05195 1.74571998 -2.05195 0 P 0 ;0
L 1.63738002 -2.05095 1.68658002 -2.05095 0 P 0 ;0
L 1.7021 -2.05095 1.74611998 -2.05095 0 P 0 ;0
L 1.63703002 -2.04995 1.6863 -2.04995 0 P 0 ;0
L 1.7024 -2.04995 1.74653002 -2.04995 0 P 0 ;0
L 1.63668002 -2.04895 1.68601998 -2.04895 0 P 0 ;0
L 1.70268996 -2.04895 1.74693002 -2.04895 0 P 0 ;0
L 1.63633002 -2.04795 1.68573996 -2.04795 0 P 0 ;0
L 1.70298996 -2.04795 1.74733002 -2.04795 0 P 0 ;0
L 1.63598002 -2.04695 1.68546004 -2.04695 0 P 0 ;0
L 1.70328002 -2.04695 1.74773996 -2.04695 0 P 0 ;0
L 1.63563996 -2.04595 1.68518002 -2.04595 0 P 0 ;0
L 1.70358002 -2.04595 1.74813996 -2.04595 0 P 0 ;0
L 1.63528996 -2.04495 1.6849 -2.04495 0 P 0 ;0
L 1.70386998 -2.04495 1.74855 -2.04495 0 P 0 ;0
L 1.63493996 -2.04395 1.68461004 -2.04395 0 P 0 ;0
L 1.70416998 -2.04395 1.74895 -2.04395 0 P 0 ;0
L 1.63458996 -2.04295 1.68433002 -2.04295 0 P 0 ;0
L 1.70446004 -2.04295 1.74936004 -2.04295 0 P 0 ;0
L 1.63425 -2.04195 1.68405 -2.04195 0 P 0 ;0
L 1.70475 -2.04195 1.74976004 -2.04195 0 P 0 ;0
L 1.6339 -2.04095 1.68376998 -2.04095 0 P 0 ;0
L 1.70503002 -2.04095 1.75016004 -2.04095 0 P 0 ;0
L 1.63355 -2.03995 1.68348996 -2.03995 0 P 0 ;0
L 1.70531998 -2.03995 1.75056998 -2.03995 0 P 0 ;0
L 1.6332 -2.03895 1.68321004 -2.03895 0 P 0 ;0
L 1.7056 -2.03895 1.75096998 -2.03895 0 P 0 ;0
L 1.63286004 -2.03795 1.68293002 -2.03795 0 P 0 ;0
L 1.70588996 -2.03795 1.75138002 -2.03795 0 P 0 ;0
L 1.63251004 -2.03695 1.68266004 -2.03695 0 P 0 ;0
L 1.70618002 -2.03695 1.75178002 -2.03695 0 P 0 ;0
L 1.63216004 -2.03595 1.68238002 -2.03595 0 P 0 ;0
L 1.70646998 -2.03595 1.75218996 -2.03595 0 P 0 ;0
L 1.63181004 -2.03495 1.6821 -2.03495 0 P 0 ;0
L 1.70675 -2.03495 1.75258996 -2.03495 0 P 0 ;0
L 1.63146998 -2.03395 1.68183002 -2.03395 0 P 0 ;0
L 1.70703996 -2.03395 1.75298996 -2.03395 0 P 0 ;0
L 1.63111998 -2.03295 1.68155 -2.03295 0 P 0 ;0
L 1.70733002 -2.03295 1.7534 -2.03295 0 P 0 ;0
L 1.63076998 -2.03195 1.68126998 -2.03195 0 P 0 ;0
L 1.70761004 -2.03195 1.75381004 -2.03195 0 P 0 ;0
L 1.63041998 -2.03095 1.68098996 -2.03095 0 P 0 ;0
L 1.7079 -2.03095 1.75421004 -2.03095 0 P 0 ;0
L 1.63006998 -2.02995 1.68071004 -2.02995 0 P 0 ;0
L 1.70818996 -2.02995 1.75461004 -2.02995 0 P 0 ;0
L 1.62973002 -2.02895 1.68043996 -2.02895 0 P 0 ;0
L 1.70846998 -2.02895 1.75501998 -2.02895 0 P 0 ;0
L 1.62938002 -2.02795 1.68016004 -2.02795 0 P 0 ;0
L 1.70876004 -2.02795 1.75541998 -2.02795 0 P 0 ;0
L 1.62903002 -2.02695 1.67988002 -2.02695 0 P 0 ;0
L 1.70905 -2.02695 1.75583002 -2.02695 0 P 0 ;0
L 1.62868002 -2.02595 1.6796 -2.02595 0 P 0 ;0
L 1.70933996 -2.02595 1.75623002 -2.02595 0 P 0 ;0
L 1.62831004 -2.02495 1.67933002 -2.02495 0 P 0 ;0
L 1.70961998 -2.02495 1.75663996 -2.02495 0 P 0 ;0
L 1.62793996 -2.02395 1.67905 -2.02395 0 P 0 ;0
L 1.70991004 -2.02395 1.75703996 -2.02395 0 P 0 ;0
L 1.62756998 -2.02295 1.67876998 -2.02295 0 P 0 ;0
L 1.7102 -2.02295 1.75743996 -2.02295 0 P 0 ;0
L 1.6272 -2.02195 1.6785 -2.02195 0 P 0 ;0
L 1.71048002 -2.02195 1.75785 -2.02195 0 P 0 ;0
L 1.62683002 -2.02095 1.67821998 -2.02095 0 P 0 ;0
L 1.71076004 -2.02095 1.75825 -2.02095 0 P 0 ;0
L 1.62646998 -2.01995 1.67793996 -2.01995 0 P 0 ;0
L 1.71101004 -2.01995 1.75866004 -2.01995 0 P 0 ;0
L 1.6261 -2.01895 1.67766004 -2.01895 0 P 0 ;0
L 1.71126998 -2.01895 1.75906004 -2.01895 0 P 0 ;0
L 1.62573002 -2.01795 1.67738996 -2.01795 0 P 0 ;0
L 1.71151998 -2.01795 1.75946998 -2.01795 0 P 0 ;0
L 1.62536004 -2.01695 1.67711004 -2.01695 0 P 0 ;0
L 1.71176998 -2.01695 1.75986998 -2.01695 0 P 0 ;0
L 1.62498996 -2.01595 1.67683002 -2.01595 0 P 0 ;0
L 1.71203002 -2.01595 1.76026998 -2.01595 0 P 0 ;0
L 1.62461998 -2.01495 1.67656004 -2.01495 0 P 0 ;0
L 1.71228002 -2.01495 1.76068002 -2.01495 0 P 0 ;0
L 1.62425 -2.01395 1.67628002 -2.01395 0 P 0 ;0
L 1.71253996 -2.01395 1.76108002 -2.01395 0 P 0 ;0
L 1.62388002 -2.01295 1.67601998 -2.01295 0 P 0 ;0
L 1.71278996 -2.01295 1.76148996 -2.01295 0 P 0 ;0
L 1.62351004 -2.01195 1.67576998 -2.01195 0 P 0 ;0
L 1.71305 -2.01195 1.76188996 -2.01195 0 P 0 ;0
L 1.62313996 -2.01095 1.67551998 -2.01095 0 P 0 ;0
L 1.7133 -2.01095 1.76228996 -2.01095 0 P 0 ;0
L 1.62276998 -2.00995 1.67528002 -2.00995 0 P 0 ;0
L 1.71355 -2.00995 1.7627 -2.00995 0 P 0 ;0
L 1.6224 -2.00895 1.67503002 -2.00895 0 P 0 ;0
L 1.71381004 -2.00895 1.7631 -2.00895 0 P 0 ;0
L 1.62203002 -2.00795 1.67478996 -2.00795 0 P 0 ;0
L 1.71406004 -2.00795 1.76351004 -2.00795 0 P 0 ;0
L 1.62166004 -2.00695 1.67453996 -2.00695 0 P 0 ;0
L 1.71431004 -2.00695 1.76391004 -2.00695 0 P 0 ;0
L 1.62128996 -2.00595 1.67428996 -2.00595 0 P 0 ;0
L 1.71453996 -2.00595 1.76431998 -2.00595 0 P 0 ;0
L 1.62091004 -2.00495 1.67405 -2.00495 0 P 0 ;0
L 1.71476998 -2.00495 1.76471998 -2.00495 0 P 0 ;0
L 1.62051998 -2.00395 1.6738 -2.00395 0 P 0 ;0
L 1.715 -2.00395 1.76511998 -2.00395 0 P 0 ;0
L 1.62013002 -2.00295 1.67355 -2.00295 0 P 0 ;0
L 1.71523002 -2.00295 1.76553002 -2.00295 0 P 0 ;0
L 1.61973996 -2.00195 1.67331004 -2.00195 0 P 0 ;0
L 1.71546004 -2.00195 1.76593996 -2.00195 0 P 0 ;0
L 1.61935 -2.00095 1.67306004 -2.00095 0 P 0 ;0
L 1.71568996 -2.00095 1.76633996 -2.00095 0 P 0 ;0
L 1.61896004 -1.99995 1.67283996 -1.99995 0 P 0 ;0
L 1.71591998 -1.99995 1.76673996 -1.99995 0 P 0 ;0
L 1.61856998 -1.99895 1.67261998 -1.99895 0 P 0 ;0
L 1.71613996 -1.99895 1.76715 -1.99895 0 P 0 ;0
L 1.71638002 -1.99795 1.76755 -1.99795 0 P 0 ;0
L 1.7166 -1.99695 1.76796004 -1.99695 0 P 0 ;0
L 1.71683002 -1.99595 1.76836004 -1.99595 0 P 0 ;0
L 1.71866998 -1.99495 1.76876998 -1.99495 0 P 0 ;0
L 1.78213996 -2.04823996 1.84641998 -2.04823996 0 P 0 ;0
L 1.78138002 -2.04723996 1.84498996 -2.04723996 0 P 0 ;0
L 1.78071004 -2.04623996 1.84356004 -2.04623996 0 P 0 ;0
L 1.7801 -2.04523996 1.84213996 -2.04523996 0 P 0 ;0
L 1.77956004 -2.04423996 1.84071004 -2.04423996 0 P 0 ;0
L 1.77908996 -2.04323996 1.83928002 -2.04323996 0 P 0 ;0
L 1.77866004 -2.04223996 1.83786004 -2.04223996 0 P 0 ;0
L 1.77831004 -2.04123996 1.83658996 -2.04123996 0 P 0 ;0
L 1.77796004 -2.04023996 1.83536004 -2.04023996 0 P 0 ;0
L 1.77761004 -2.03923996 1.83428002 -2.03923996 0 P 0 ;0
L 1.77733996 -2.03823996 1.83321998 -2.03823996 0 P 0 ;0
L 1.77706998 -2.03723996 1.83236998 -2.03723996 0 P 0 ;0
L 1.7768 -2.03623996 1.83171004 -2.03623996 0 P 0 ;0
L 1.7766 -2.03523996 1.83121004 -2.03523996 0 P 0 ;0
L 1.77641004 -2.03423996 1.83085 -2.03423996 0 P 0 ;0
L 1.77621004 -2.03323996 1.83071004 -2.03323996 0 P 0 ;0
L 1.77608002 -2.03223996 1.83076998 -2.03223996 0 P 0 ;0
L 1.77596004 -2.03123996 1.83106004 -2.03123996 0 P 0 ;0
L 1.77583996 -2.03023996 1.83158996 -2.03023996 0 P 0 ;0
L 1.77576004 -2.02923996 1.83238002 -2.02923996 0 P 0 ;0
L 1.7757 -2.02823996 1.83356998 -2.02823996 0 P 0 ;0
L 1.7757 -2.02723996 1.83591998 -2.02723996 0 P 0 ;0
L 1.77571998 -2.02623996 1.87495 -2.02623996 0 P 0 ;0
L 1.7758 -2.02523996 1.87485 -2.02523996 0 P 0 ;0
L 1.77588996 -2.02423996 1.87475 -2.02423996 0 P 0 ;0
L 1.77605 -2.02323996 1.87465 -2.02323996 0 P 0 ;0
L 1.77621004 -2.02223996 1.87455 -2.02223996 0 P 0 ;0
L 1.7764 -2.02123996 1.87445 -2.02123996 0 P 0 ;0
L 1.77665 -2.02023996 1.87433996 -2.02023996 0 P 0 ;0
L 1.7769 -2.01923996 1.87425 -2.01923996 0 P 0 ;0
L 1.7772 -2.01823996 1.87413996 -2.01823996 0 P 0 ;0
L 1.77753002 -2.01723996 1.87405 -2.01723996 0 P 0 ;0
L 1.77786004 -2.01623996 1.87393996 -2.01623996 0 P 0 ;0
L 1.77823002 -2.01523996 1.87383996 -2.01523996 0 P 0 ;0
L 1.77863996 -2.01423996 1.87373996 -2.01423996 0 P 0 ;0
L 1.77903996 -2.01323996 1.87363996 -2.01323996 0 P 0 ;0
L 1.7795 -2.01223996 1.87353996 -2.01223996 0 P 0 ;0
L 1.77998996 -2.01123996 1.87343996 -2.01123996 0 P 0 ;0
L 1.78046998 -2.01023996 1.87333002 -2.01023996 0 P 0 ;0
L 1.78103996 -2.00923996 1.87323002 -2.00923996 0 P 0 ;0
L 1.78161004 -2.00823996 1.87311998 -2.00823996 0 P 0 ;0
L 1.78221004 -2.00723996 1.87301998 -2.00723996 0 P 0 ;0
L 1.78288002 -2.00623996 1.87291998 -2.00623996 0 P 0 ;0
L 1.64213996 -2.14795 1.70566004 -2.14795 0 P 0 ;0
L 1.64518996 -2.14695 1.7062 -2.14695 0 P 0 ;0
L 1.64728996 -2.14595 1.70673996 -2.14595 0 P 0 ;0
L 1.64906998 -2.14495 1.70728002 -2.14495 0 P 0 ;0
L 1.65058002 -2.14395 1.70783002 -2.14395 0 P 0 ;0
L 1.6519 -2.14295 1.70836998 -2.14295 0 P 0 ;0
L 1.65311998 -2.14195 1.70881998 -2.14195 0 P 0 ;0
L 1.65416998 -2.14095 1.70926998 -2.14095 0 P 0 ;0
L 1.65508996 -2.13995 1.70973002 -2.13995 0 P 0 ;0
L 1.65588002 -2.13895 1.71018002 -2.13895 0 P 0 ;0
L 1.65658002 -2.13795 1.71063002 -2.13795 0 P 0 ;0
L 1.65726998 -2.13695 1.71108996 -2.13695 0 P 0 ;0
L 1.65791998 -2.13595 1.71153996 -2.13595 0 P 0 ;0
L 1.65853002 -2.13495 1.71198996 -2.13495 0 P 0 ;0
L 1.65913002 -2.13395 1.71245 -2.13395 0 P 0 ;0
L 1.65968002 -2.13295 1.7129 -2.13295 0 P 0 ;0
L 1.66021998 -2.13195 1.71331004 -2.13195 0 P 0 ;0
L 1.66071998 -2.13095 1.71371998 -2.13095 0 P 0 ;0
L 1.66121004 -2.12995 1.71411998 -2.12995 0 P 0 ;0
L 1.66166998 -2.12895 1.71453002 -2.12895 0 P 0 ;0
L 1.66201004 -2.12795 1.71493996 -2.12795 0 P 0 ;0
L 1.66223996 -2.12695 1.71533996 -2.12695 0 P 0 ;0
L 1.66235 -2.12595 1.71575 -2.12595 0 P 0 ;0
L 1.66236004 -2.12495 1.71615 -2.12495 0 P 0 ;0
L 1.66228002 -2.12395 1.71656004 -2.12395 0 P 0 ;0
L 1.66211998 -2.12295 1.71696004 -2.12295 0 P 0 ;0
L 1.66188002 -2.12195 1.71736004 -2.12195 0 P 0 ;0
L 1.66156004 -2.12095 1.71776998 -2.12095 0 P 0 ;0
L 1.66121004 -2.11995 1.71818002 -2.11995 0 P 0 ;0
L 1.66086998 -2.11895 1.71858002 -2.11895 0 P 0 ;0
L 1.66053002 -2.11795 1.71898996 -2.11795 0 P 0 ;0
L 1.66018002 -2.11695 1.71938996 -2.11695 0 P 0 ;0
L 1.65983996 -2.11595 1.7198 -2.11595 0 P 0 ;0
L 1.65948996 -2.11495 1.7202 -2.11495 0 P 0 ;0
L 1.65913996 -2.11395 1.72061004 -2.11395 0 P 0 ;0
L 1.6588 -2.11295 1.72101004 -2.11295 0 P 0 ;0
L 1.65846004 -2.11195 1.72141998 -2.11195 0 P 0 ;0
L 1.65811004 -2.11095 1.72181998 -2.11095 0 P 0 ;0
L 1.65776998 -2.10995 1.72223002 -2.10995 0 P 0 ;0
L 1.65741998 -2.10895 1.72263002 -2.10895 0 P 0 ;0
L 1.65708002 -2.10795 1.72303996 -2.10795 0 P 0 ;0
L 1.65673002 -2.10695 1.72343996 -2.10695 0 P 0 ;0
L 1.65638996 -2.10595 1.72385 -2.10595 0 P 0 ;0
L 1.65605 -2.10495 1.72425 -2.10495 0 P 0 ;0
L 1.6557 -2.10395 1.72466004 -2.10395 0 P 0 ;0
L 1.65536004 -2.10295 1.72506998 -2.10295 0 P 0 ;0
L 1.65501004 -2.10195 1.72546998 -2.10195 0 P 0 ;0
L 1.65466998 -2.10095 1.72588002 -2.10095 0 P 0 ;0
L 1.65431998 -2.09995 1.72628002 -2.09995 0 P 0 ;0
L 1.65398002 -2.09895 1.72668996 -2.09895 0 P 0 ;0
L 1.65363002 -2.09795 1.72708996 -2.09795 0 P 0 ;0
L 1.65328996 -2.09695 1.72748996 -2.09695 0 P 0 ;0
L 1.65293996 -2.09595 1.7279 -2.09595 0 P 0 ;0
L 1.6526 -2.09495 1.72831004 -2.09495 0 P 0 ;0
L 1.65225 -2.09395 1.72871004 -2.09395 0 P 0 ;0
L 1.65191004 -2.09295 1.72911998 -2.09295 0 P 0 ;0
L 1.65156998 -2.09195 1.72951998 -2.09195 0 P 0 ;0
L 1.65121998 -2.09095 1.72993002 -2.09095 0 P 0 ;0
L 1.65088002 -2.08995 1.73033002 -2.08995 0 P 0 ;0
L 1.65053002 -2.08895 1.73073996 -2.08895 0 P 0 ;0
L 1.65018996 -2.08795 1.73113996 -2.08795 0 P 0 ;0
L 1.64983996 -2.08695 1.73155 -2.08695 0 P 0 ;0
L 1.6495 -2.08595 1.73195 -2.08595 0 P 0 ;0
L 1.64915 -2.08495 1.73236004 -2.08495 0 P 0 ;0
L 1.64881004 -2.08395 1.73276004 -2.08395 0 P 0 ;0
L 1.81726998 -1.98915 1.81196004 -1.9899 0 P 0 ;0
L 1.81196004 -1.9899 1.80668996 -1.99096998 0 P 0 ;0
L 1.80668996 -1.99096998 1.8019 -1.99226004 0 P 0 ;0
L 1.8019 -1.99226004 1.79718996 -1.99391004 0 P 0 ;0
L 1.79718996 -1.99391004 1.79316004 -1.99568002 0 P 0 ;0
L 1.79316004 -1.99568002 1.78926998 -1.99778002 0 P 0 ;0
L 1.78926998 -1.99778002 1.78771004 -1.99878002 0 P 0 ;0
L 1.78771004 -1.99878002 1.78623002 -1.99988002 0 P 0 ;0
L 1.78623002 -1.99988002 1.78481004 -2.00108002 0 P 0 ;0
L 1.78481004 -2.00108002 1.78346998 -2.00238996 0 P 0 ;0
L 1.78346998 -2.00238996 1.78228996 -2.00371998 0 P 0 ;0
L 1.78228996 -2.00371998 1.78121004 -2.00513002 0 P 0 ;0
L 1.78121004 -2.00513002 1.78023002 -2.00661004 0 P 0 ;0
L 1.78023002 -2.00661004 1.77868002 -2.00933996 0 P 0 ;0
L 1.77868002 -2.00933996 1.77731998 -2.01216998 0 P 0 ;0
L 1.77731998 -2.01216998 1.77611004 -2.01516004 0 P 0 ;0
L 1.77611004 -2.01516004 1.77508996 -2.01823002 0 P 0 ;0
L 1.77508996 -2.01823002 1.77436998 -2.02111004 0 P 0 ;0
L 1.77436998 -2.02111004 1.77388996 -2.02406004 0 P 0 ;0
L 1.77388996 -2.02406004 1.77371998 -2.02603996 0 P 0 ;0
L 1.77371998 -2.02603996 1.77368996 -2.02801998 0 P 0 ;0
L 1.77368996 -2.02801998 1.7738 -2.03001998 0 P 0 ;0
L 1.7738 -2.03001998 1.7742 -2.03338996 0 P 0 ;0
L 1.7742 -2.03338996 1.77485 -2.03671004 0 P 0 ;0
L 1.77485 -2.03671004 1.77573002 -2.03993996 0 P 0 ;0
L 1.77573002 -2.03993996 1.77683996 -2.04308002 0 P 0 ;0
L 1.77683996 -2.04308002 1.7776 -2.04481998 0 P 0 ;0
L 1.7776 -2.04481998 1.7785 -2.04648996 0 P 0 ;0
L 1.7785 -2.04648996 1.77953002 -2.04808996 0 P 0 ;0
L 1.77953002 -2.04808996 1.78061004 -2.04953996 0 P 0 ;0
L 1.78061004 -2.04953996 1.78181004 -2.05091004 0 P 0 ;0
L 1.78181004 -2.05091004 1.78311004 -2.05218996 0 P 0 ;0
L 1.78311004 -2.05218996 1.78988996 -2.05801998 0 P 0 ;0
L 1.78988996 -2.05801998 1.79883996 -2.06491004 0 P 0 ;0
L 1.79883996 -2.06491004 1.80976998 -2.07261004 0 P 0 ;0
L 1.80976998 -2.07261004 1.81753002 -2.07823002 0 P 0 ;0
L 1.81753002 -2.07823002 1.81896998 -2.07943002 0 P 0 ;0
L 1.81896998 -2.07943002 1.82033002 -2.08073002 0 P 0 ;0
L 1.82033002 -2.08073002 1.82156998 -2.08213996 0 P 0 ;0
L 1.82156998 -2.08213996 1.82186004 -2.08251004 0 P 0 ;0
L 1.82186004 -2.08251004 1.82211004 -2.0829 0 P 0 ;0
L 1.82211004 -2.0829 1.82233002 -2.08331004 0 P 0 ;0
L 1.82233002 -2.08331004 1.82253002 -2.08373996 0 P 0 ;0
L 1.82253002 -2.08373996 1.82268002 -2.08418002 0 P 0 ;0
L 1.82268002 -2.08418002 1.82281004 -2.08463002 0 P 0 ;0
L 1.82281004 -2.08463002 1.8229 -2.0851 0 P 0 ;0
L 1.8229 -2.0851 1.82293002 -2.08533996 0 P 0 ;0
L 1.82293002 -2.08533996 1.82293996 -2.08558996 0 P 0 ;0
L 1.82293996 -2.08558996 1.82291998 -2.08583996 0 P 0 ;0
L 1.82291998 -2.08583996 1.82288002 -2.08608002 0 P 0 ;0
L 1.82288002 -2.08608002 1.82283002 -2.08631998 0 P 0 ;0
L 1.82283002 -2.08631998 1.82275 -2.08656004 0 P 0 ;0
L 1.82275 -2.08656004 1.82265 -2.08678996 0 P 0 ;0
L 1.82265 -2.08678996 1.82253996 -2.087 0 P 0 ;0
L 1.82253996 -2.087 1.8224 -2.08721004 0 P 0 ;0
L 1.8224 -2.08721004 1.82225 -2.08741004 0 P 0 ;0
L 1.82225 -2.08741004 1.82208996 -2.08758996 0 P 0 ;0
L 1.82208996 -2.08758996 1.8216 -2.08803996 0 P 0 ;0
L 1.8216 -2.08803996 1.82106998 -2.08845 0 P 0 ;0
L 1.82106998 -2.08845 1.82051004 -2.08881004 0 P 0 ;0
L 1.82051004 -2.08881004 1.81991998 -2.08911998 0 P 0 ;0
L 1.81991998 -2.08911998 1.81931004 -2.08936998 0 P 0 ;0
L 1.81931004 -2.08936998 1.81868002 -2.08958002 0 P 0 ;0
L 1.81868002 -2.08958002 1.81803002 -2.08973002 0 P 0 ;0
L 1.81803002 -2.08973002 1.81736004 -2.08981998 0 P 0 ;0
L 1.81736004 -2.08981998 1.81293002 -2.09001998 0 P 0 ;0
L 1.81293002 -2.09001998 1.80846998 -2.08986004 0 P 0 ;0
L 1.80846998 -2.08986004 1.80256998 -2.08923002 0 P 0 ;0
L 1.80256998 -2.08923002 1.79668002 -2.08818996 0 P 0 ;0
L 1.79668002 -2.08818996 1.78223002 -2.08458002 0 P 0 ;0
L 1.78223002 -2.08458002 1.77788996 -2.08338002 0 P 0 ;0
L 1.77788996 -2.08338002 1.77415 -2.08246004 0 P 0 ;0
L 1.77415 -2.08246004 1.77095 -2.08175 0 P 0 ;0
L 1.77095 -2.08175 1.7709 -2.08173996 0 P 0 ;0
L 1.7709 -2.08173996 1.77076998 -2.08173996 0 P 0 ;0
L 1.77076998 -2.08173996 1.77068996 -2.08176004 0 P 0 ;0
L 1.77068996 -2.08176004 1.77053002 -2.08183996 0 P 0 ;0
L 1.77053002 -2.08183996 1.77043002 -2.08193996 0 P 0 ;0
L 1.77043002 -2.08193996 1.77036998 -2.08201998 0 P 0 ;0
L 1.77036998 -2.08201998 1.77031998 -2.08211998 0 P 0 ;0
L 1.77031998 -2.08211998 1.7703 -2.08216998 0 P 0 ;0
L 1.7703 -2.08216998 1.77028996 -2.08223002 0 P 0 ;0
L 1.77028996 -2.08223002 1.77028002 -2.08228002 0 P 0 ;0
L 1.77028002 -2.08228002 1.77028002 -2.08238996 0 P 0 ;0
L 1.77028002 -2.08238996 1.77056998 -2.08838996 0 P 0 ;0
L 1.77056998 -2.08838996 1.77096004 -2.09526004 0 P 0 ;0
L 1.77096004 -2.09526004 1.77153996 -2.1033 0 P 0 ;0
L 1.77153996 -2.1033 1.77236004 -2.11291004 0 P 0 ;0
L 1.77236004 -2.11291004 1.77311004 -2.1194 0 P 0 ;0
L 1.77311004 -2.1194 1.77383002 -2.12398002 0 P 0 ;0
L 1.77383002 -2.12398002 1.77386004 -2.12411004 0 P 0 ;0
L 1.77386004 -2.12411004 1.7739 -2.12423002 0 P 0 ;0
L 1.7739 -2.12423002 1.77395 -2.12436004 0 P 0 ;0
L 1.77395 -2.12436004 1.77401004 -2.12448002 0 P 0 ;0
L 1.77401004 -2.12448002 1.77408002 -2.12458996 0 P 0 ;0
L 1.77408002 -2.12458996 1.77416004 -2.1247 0 P 0 ;0
L 1.77416004 -2.1247 1.77425 -2.1248 0 P 0 ;0
L 1.77425 -2.1248 1.77435 -2.12488996 0 P 0 ;0
L 1.77435 -2.12488996 1.77445 -2.12496998 0 P 0 ;0
L 1.77445 -2.12496998 1.77456998 -2.12505 0 P 0 ;0
L 1.77456998 -2.12505 1.77571004 -2.12568996 0 P 0 ;0
L 1.77571004 -2.12568996 1.7769 -2.12623996 0 P 0 ;0
L 1.7769 -2.12623996 1.77813002 -2.12668996 0 P 0 ;0
L 1.77813002 -2.12668996 1.7794 -2.12703996 0 P 0 ;0
L 1.7794 -2.12703996 1.78068996 -2.12728996 0 P 0 ;0
L 1.78068996 -2.12728996 1.79791998 -2.12951004 0 P 0 ;0
L 1.79791998 -2.12951004 1.81536004 -2.13106004 0 P 0 ;0
L 1.81536004 -2.13106004 1.82125 -2.13123996 0 P 0 ;0
L 1.82125 -2.13123996 1.82716004 -2.13098996 0 P 0 ;0
L 1.82716004 -2.13098996 1.83583996 -2.12998002 0 P 0 ;0
L 1.83583996 -2.12998002 1.84445 -2.12836004 0 P 0 ;0
L 1.84445 -2.12836004 1.84911998 -2.12711004 0 P 0 ;0
L 1.84911998 -2.12711004 1.85366004 -2.12548002 0 P 0 ;0
L 1.85366004 -2.12548002 1.85806998 -2.12348002 0 P 0 ;0
L 1.85806998 -2.12348002 1.86078996 -2.12196998 0 P 0 ;0
L 1.86078996 -2.12196998 1.8634 -2.12026998 0 P 0 ;0
L 1.8634 -2.12026998 1.86586998 -2.11836998 0 P 0 ;0
L 1.86586998 -2.11836998 1.86821004 -2.11628002 0 P 0 ;0
L 1.86821004 -2.11628002 1.87026004 -2.11413002 0 P 0 ;0
L 1.87026004 -2.11413002 1.8721 -2.11181998 0 P 0 ;0
L 1.8721 -2.11181998 1.87375 -2.10936004 0 P 0 ;0
L 1.87375 -2.10936004 1.87516998 -2.10673996 0 P 0 ;0
L 1.87516998 -2.10673996 1.87605 -2.10483996 0 P 0 ;0
L 1.87605 -2.10483996 1.87683996 -2.10291004 0 P 0 ;0
L 1.87683996 -2.10291004 1.8772 -2.10188002 0 P 0 ;0
L 1.8772 -2.10188002 1.87748996 -2.10083002 0 P 0 ;0
L 1.87748996 -2.10083002 1.87771004 -2.09976998 0 P 0 ;0
L 1.87771004 -2.09976998 1.87798002 -2.09788996 0 P 0 ;0
L 1.87798002 -2.09788996 1.87811998 -2.09601004 0 P 0 ;0
L 1.87811998 -2.09601004 1.87821004 -2.08966998 0 P 0 ;0
L 1.87821004 -2.08966998 1.8781 -2.08353996 0 P 0 ;0
L 1.8781 -2.08353996 1.87798002 -2.08166004 0 P 0 ;0
L 1.87798002 -2.08166004 1.87773002 -2.07976998 0 P 0 ;0
L 1.87773002 -2.07976998 1.87753002 -2.07873996 0 P 0 ;0
L 1.87753002 -2.07873996 1.87726998 -2.07773996 0 P 0 ;0
L 1.87726998 -2.07773996 1.87695 -2.07673996 0 P 0 ;0
L 1.87695 -2.07673996 1.87628996 -2.07505 0 P 0 ;0
L 1.87628996 -2.07505 1.87553002 -2.07338002 0 P 0 ;0
L 1.87553002 -2.07338002 1.87441004 -2.07133996 0 P 0 ;0
L 1.87441004 -2.07133996 1.87313996 -2.06938002 0 P 0 ;0
L 1.87313996 -2.06938002 1.87171004 -2.06751004 0 P 0 ;0
L 1.87171004 -2.06751004 1.8688 -2.06416004 0 P 0 ;0
L 1.8688 -2.06416004 1.86566998 -2.06095 0 P 0 ;0
L 1.86566998 -2.06095 1.86181998 -2.05741998 0 P 0 ;0
L 1.86181998 -2.05741998 1.85778002 -2.05406998 0 P 0 ;0
L 1.85778002 -2.05406998 1.84833996 -2.04715 0 P 0 ;0
L 1.84833996 -2.04715 1.83913996 -2.0407 0 P 0 ;0
L 1.83913996 -2.0407 1.83686004 -2.0389 0 P 0 ;0
L 1.83686004 -2.0389 1.83471998 -2.03691998 0 P 0 ;0
L 1.83471998 -2.03691998 1.83428002 -2.03643002 0 P 0 ;0
L 1.83428002 -2.03643002 1.83386998 -2.0359 0 P 0 ;0
L 1.83386998 -2.0359 1.83351004 -2.03535 0 P 0 ;0
L 1.83351004 -2.03535 1.83318996 -2.03476004 0 P 0 ;0
L 1.83318996 -2.03476004 1.83291998 -2.03415 0 P 0 ;0
L 1.83291998 -2.03415 1.83283996 -2.03393996 0 P 0 ;0
L 1.83283996 -2.03393996 1.83278002 -2.03371004 0 P 0 ;0
L 1.83278002 -2.03371004 1.83273002 -2.03348996 0 P 0 ;0
L 1.83273002 -2.03348996 1.83271004 -2.03326004 0 P 0 ;0
L 1.83271004 -2.03326004 1.8327 -2.03303002 0 P 0 ;0
L 1.8327 -2.03303002 1.83271004 -2.0328 0 P 0 ;0
L 1.83271004 -2.0328 1.83275 -2.03258002 0 P 0 ;0
L 1.83275 -2.03258002 1.83278996 -2.03235 0 P 0 ;0
L 1.83278996 -2.03235 1.83286004 -2.03213002 0 P 0 ;0
L 1.83286004 -2.03213002 1.83293996 -2.03191998 0 P 0 ;0
L 1.83293996 -2.03191998 1.83305 -2.03171004 0 P 0 ;0
L 1.83305 -2.03171004 1.83325 -2.03135 0 P 0 ;0
L 1.83325 -2.03135 1.83348996 -2.03101998 0 P 0 ;0
L 1.83348996 -2.03101998 1.83375 -2.03071004 0 P 0 ;0
L 1.83375 -2.03071004 1.83403002 -2.03041004 0 P 0 ;0
L 1.83403002 -2.03041004 1.83433996 -2.03015 0 P 0 ;0
L 1.83433996 -2.03015 1.83466998 -2.02991004 0 P 0 ;0
L 1.83466998 -2.02991004 1.83501998 -2.02968996 0 P 0 ;0
L 1.83501998 -2.02968996 1.83538002 -2.02951004 0 P 0 ;0
L 1.83538002 -2.02951004 1.83576004 -2.02936004 0 P 0 ;0
L 1.83576004 -2.02936004 1.83615 -2.02923996 0 P 0 ;0
L 1.83615 -2.02923996 1.83655 -2.02915 0 P 0 ;0
L 1.83655 -2.02915 1.8392 -2.02873996 0 P 0 ;0
L 1.8392 -2.02873996 1.84188002 -2.0285 0 P 0 ;0
L 1.84188002 -2.0285 1.84458002 -2.02841004 0 P 0 ;0
L 1.84458002 -2.02841004 1.84993996 -2.02858002 0 P 0 ;0
L 1.84993996 -2.02858002 1.85526998 -2.02916004 0 P 0 ;0
L 1.85526998 -2.02916004 1.86155 -2.03023002 0 P 0 ;0
L 1.86155 -2.03023002 1.86778002 -2.03158002 0 P 0 ;0
L 1.86778002 -2.03158002 1.8713 -2.03238996 0 P 0 ;0
L 1.8713 -2.03238996 1.87428996 -2.03303002 0 P 0 ;0
L 1.87428996 -2.03303002 1.8769 -2.03356004 0 P 0 ;0
L 1.8769 -2.03356004 1.87691998 -2.03356998 0 P 0 ;0
L 1.87691998 -2.03356998 1.87696004 -2.03356998 0 P 0 ;0
L 1.87696004 -2.03356998 1.87696998 -2.03356004 0 P 0 ;0
L 1.87696998 -2.03356004 1.87701004 -2.03356004 0 P 0 ;0
L 1.87701004 -2.03356004 1.87703996 -2.03353996 0 P 0 ;0
L 1.87703996 -2.03353996 1.87706004 -2.03353002 0 P 0 ;0
L 1.87706004 -2.03353002 1.87706998 -2.03351998 0 P 0 ;0
L 1.87706998 -2.03351998 1.87708996 -2.03351004 0 P 0 ;0
L 1.87708996 -2.03351004 1.8771 -2.03348996 0 P 0 ;0
L 1.8771 -2.03348996 1.87711004 -2.03348002 0 P 0 ;0
L 1.87711004 -2.03348002 1.87721998 -2.0333 0 P 0 ;0
L 1.87721998 -2.0333 1.87731998 -2.0331 0 P 0 ;0
L 1.87731998 -2.0331 1.8774 -2.0329 0 P 0 ;0
L 1.8774 -2.0329 1.87746004 -2.03268996 0 P 0 ;0
L 1.87746004 -2.03268996 1.87751004 -2.03248002 0 P 0 ;0
L 1.87751004 -2.03248002 1.87753002 -2.03226998 0 P 0 ;0
L 1.87753002 -2.03226998 1.87753996 -2.03205 0 P 0 ;0
L 1.87753996 -2.03205 1.87753002 -2.03183002 0 P 0 ;0
L 1.87753002 -2.03183002 1.87565 -2.01323996 0 P 0 ;0
L 1.87565 -2.01323996 1.87371004 -1.99451998 0 P 0 ;0
L 1.87371004 -1.99451998 1.8737 -1.99438996 0 P 0 ;0
L 1.8737 -1.99438996 1.87366998 -1.99426998 0 P 0 ;0
L 1.87366998 -1.99426998 1.87363002 -1.99415 0 P 0 ;0
L 1.87363002 -1.99415 1.87358002 -1.99403002 0 P 0 ;0
L 1.87358002 -1.99403002 1.87351998 -1.99391004 0 P 0 ;0
L 1.87351998 -1.99391004 1.87346004 -1.9938 0 P 0 ;0
L 1.87346004 -1.9938 1.87338002 -1.9937 0 P 0 ;0
L 1.87338002 -1.9937 1.87328996 -1.9936 0 P 0 ;0
L 1.87328996 -1.9936 1.8732 -1.99351004 0 P 0 ;0
L 1.8732 -1.99351004 1.8731 -1.99343002 0 P 0 ;0
L 1.8731 -1.99343002 1.87298996 -1.99335 0 P 0 ;0
L 1.87298996 -1.99335 1.87248002 -1.99305 0 P 0 ;0
L 1.87248002 -1.99305 1.87193996 -1.99278002 0 P 0 ;0
L 1.87193996 -1.99278002 1.87136998 -1.99256998 0 P 0 ;0
L 1.87136998 -1.99256998 1.87078996 -1.99241004 0 P 0 ;0
L 1.87078996 -1.99241004 1.8702 -1.9923 0 P 0 ;0
L 1.8702 -1.9923 1.85876004 -1.99076004 0 P 0 ;0
L 1.85876004 -1.99076004 1.84691998 -1.98943002 0 P 0 ;0
L 1.84691998 -1.98943002 1.83693002 -1.98876004 0 P 0 ;0
L 1.83693002 -1.98876004 1.8318 -1.98863002 0 P 0 ;0
L 1.8318 -1.98863002 1.82623002 -1.98866998 0 P 0 ;0
L 1.82623002 -1.98866998 1.82106004 -1.98883996 0 P 0 ;0
L 1.82106004 -1.98883996 1.81726998 -1.98915 0 P 0 ;0
L 1.78061004 -2.12523996 1.84838002 -2.12523996 0 P 0 ;0
L 1.77733002 -2.12423996 1.85121004 -2.12423996 0 P 0 ;0
L 1.77573996 -2.12323996 1.85376998 -2.12323996 0 P 0 ;0
L 1.77558002 -2.12223996 1.85596998 -2.12223996 0 P 0 ;0
L 1.77541998 -2.12123996 1.85798996 -2.12123996 0 P 0 ;0
L 1.77526998 -2.12023996 1.85978996 -2.12023996 0 P 0 ;0
L 1.77511004 -2.11923996 1.86131998 -2.11923996 0 P 0 ;0
L 1.77498996 -2.11823996 1.86276004 -2.11823996 0 P 0 ;0
L 1.77486998 -2.11723996 1.86406998 -2.11723996 0 P 0 ;0
L 1.77475 -2.11623996 1.86526004 -2.11623996 0 P 0 ;0
L 1.77463996 -2.11523996 1.86638002 -2.11523996 0 P 0 ;0
L 1.77451998 -2.11423996 1.8674 -2.11423996 0 P 0 ;0
L 1.77441004 -2.11323996 1.86835 -2.11323996 0 P 0 ;0
L 1.77431004 -2.11223996 1.86921004 -2.11223996 0 P 0 ;0
L 1.77421998 -2.11123996 1.87001004 -2.11123996 0 P 0 ;0
L 1.77413996 -2.11023996 1.87075 -2.11023996 0 P 0 ;0
L 1.77405 -2.10923996 1.87141998 -2.10923996 0 P 0 ;0
L 1.77396998 -2.10823996 1.87208002 -2.10823996 0 P 0 ;0
L 1.77388002 -2.10723996 1.87261998 -2.10723996 0 P 0 ;0
L 1.7738 -2.10623996 1.87316998 -2.10623996 0 P 0 ;0
L 1.77371004 -2.10523996 1.87366004 -2.10523996 0 P 0 ;0
L 1.77363002 -2.10423996 1.87411998 -2.10423996 0 P 0 ;0
L 1.77353996 -2.10323996 1.87453996 -2.10323996 0 P 0 ;0
L 1.77346998 -2.10223996 1.87495 -2.10223996 0 P 0 ;0
L 1.7734 -2.10123996 1.8753 -2.10123996 0 P 0 ;0
L 1.77333002 -2.10023996 1.87556998 -2.10023996 0 P 0 ;0
L 1.77325 -2.09923996 1.87576998 -2.09923996 0 P 0 ;0
L 1.77318002 -2.09823996 1.87591998 -2.09823996 0 P 0 ;0
L 1.77311004 -2.09723996 1.87603002 -2.09723996 0 P 0 ;0
L 1.77303996 -2.09623996 1.8761 -2.09623996 0 P 0 ;0
L 1.77296998 -2.09523996 1.87613002 -2.09523996 0 P 0 ;0
L 1.77291004 -2.09423996 1.87613996 -2.09423996 0 P 0 ;0
L 1.77285 -2.09323996 1.87616004 -2.09323996 0 P 0 ;0
L 1.77278996 -2.09223996 1.87616998 -2.09223996 0 P 0 ;0
L 1.77273002 -2.09123996 1.80256998 -2.09123996 0 P 0 ;0
L 1.77268002 -2.09023996 1.7968 -2.09023996 0 P 0 ;0
L 1.77261998 -2.08923996 1.79263002 -2.08923996 0 P 0 ;0
L 1.77256004 -2.08823996 1.78861998 -2.08823996 0 P 0 ;0
L 1.77251004 -2.08723996 1.7846 -2.08723996 0 P 0 ;0
L 1.77246004 -2.08623996 1.7807 -2.08623996 0 P 0 ;0
L 1.77241998 -2.08523996 1.77705 -2.08523996 0 P 0 ;0
L 1.77236998 -2.08423996 1.77293996 -2.08423996 0 P 0 ;0
L 1.62463996 -2.18195 1.65948996 -2.18195 0 P 0 ;0
L 1.61963996 -2.18095 1.66483002 -2.18095 0 P 0 ;0
L 1.61818002 -1.99795 1.6724 -1.99795 0 P 0 ;0
L 1.61778996 -1.99695 1.67218002 -1.99695 0 P 0 ;0
L 1.6174 -1.99595 1.67196004 -1.99595 0 P 0 ;0
L 1.61701004 -1.99495 1.67173996 -1.99495 0 P 0 ;0
L 1.61391998 -2.15695 1.70026004 -2.15695 0 P 0 ;0
L 1.61386004 -2.15595 1.70088002 -2.15595 0 P 0 ;0
L 1.61381004 -2.15495 1.70151004 -2.15495 0 P 0 ;0
L 1.61375 -2.15395 1.70213996 -2.15395 0 P 0 ;0
L 1.6137 -2.15295 1.70276004 -2.15295 0 P 0 ;0
L 1.61365 -2.15195 1.70338996 -2.15195 0 P 0 ;0
L 1.6136 -2.15095 1.70401004 -2.15095 0 P 0 ;0
L 1.61355 -2.14995 1.70456998 -2.14995 0 P 0 ;0
L 1.61348996 -2.14895 1.70511998 -2.14895 0 P 0 ;0
L 1.61343996 -2.14795 1.61738002 -2.14795 0 P 0 ;0
L 1.55341004 -2.08286998 1.60538002 -2.08286998 0 P 0 ;0
L 1.55286004 -2.08186998 1.60526998 -2.08186998 0 P 0 ;0
L 1.5521 -2.08086998 1.6051 -2.08086998 0 P 0 ;0
L 1.55126998 -2.07986998 1.6049 -2.07986998 0 P 0 ;0
L 1.55033996 -2.07886998 1.60463996 -2.07886998 0 P 0 ;0
L 1.54928996 -2.07786998 1.60433002 -2.07786998 0 P 0 ;0
L 1.54806998 -2.07686998 1.60398996 -2.07686998 0 P 0 ;0
L 1.5467 -2.07586998 1.60356998 -2.07586998 0 P 0 ;0
L 1.54531004 -2.07486998 1.6031 -2.07486998 0 P 0 ;0
L 1.54391004 -2.07386998 1.60258996 -2.07386998 0 P 0 ;0
L 1.54251004 -2.07286998 1.60201004 -2.07286998 0 P 0 ;0
L 1.54111998 -2.07186998 1.60138002 -2.07186998 0 P 0 ;0
L 1.53971998 -2.07086998 1.60068002 -2.07086998 0 P 0 ;0
L 1.53833002 -2.06986998 1.59993002 -2.06986998 0 P 0 ;0
L 1.53693002 -2.06886998 1.59908002 -2.06886998 0 P 0 ;0
L 1.53556004 -2.06786998 1.59821004 -2.06786998 0 P 0 ;0
L 1.53418996 -2.06686998 1.59733996 -2.06686998 0 P 0 ;0
L 1.53281998 -2.06586998 1.59646998 -2.06586998 0 P 0 ;0
L 1.53145 -2.06486998 1.5955 -2.06486998 0 P 0 ;0
L 1.53008002 -2.06386998 1.59453002 -2.06386998 0 P 0 ;0
L 1.52871004 -2.06286998 1.59356004 -2.06286998 0 P 0 ;0
L 1.52733996 -2.06186998 1.59253002 -2.06186998 0 P 0 ;0
L 1.52596998 -2.06086998 1.59145 -2.06086998 0 P 0 ;0
L 1.5246 -2.05986998 1.59038002 -2.05986998 0 P 0 ;0
L 1.52323002 -2.05886998 1.5893 -2.05886998 0 P 0 ;0
L 1.52186004 -2.05786998 1.58813996 -2.05786998 0 P 0 ;0
L 1.52053996 -2.05686998 1.58696004 -2.05686998 0 P 0 ;0
L 1.51935 -2.05586998 1.58576998 -2.05586998 0 P 0 ;0
L 1.51816004 -2.05486998 1.58456998 -2.05486998 0 P 0 ;0
L 1.51706998 -2.05386998 1.58321004 -2.05386998 0 P 0 ;0
L 1.51603996 -2.05286998 1.58185 -2.05286998 0 P 0 ;0
L 1.51501998 -2.05186998 1.58048996 -2.05186998 0 P 0 ;0
L 1.51408996 -2.05086998 1.57913002 -2.05086998 0 P 0 ;0
L 1.5132 -2.04986998 1.57776998 -2.04986998 0 P 0 ;0
L 1.51231998 -2.04886998 1.57641998 -2.04886998 0 P 0 ;0
L 1.51151004 -2.04786998 1.57505 -2.04786998 0 P 0 ;0
L 1.51075 -2.04686998 1.57365 -2.04686998 0 P 0 ;0
L 1.51008002 -2.04586998 1.57223002 -2.04586998 0 P 0 ;0
L 1.50945 -2.04486998 1.57081004 -2.04486998 0 P 0 ;0
L 1.50888002 -2.04386998 1.56938996 -2.04386998 0 P 0 ;0
L 1.50836004 -2.04286998 1.56796998 -2.04286998 0 P 0 ;0
L 1.5079 -2.04186998 1.56655 -2.04186998 0 P 0 ;0
L 1.50748002 -2.04086998 1.56518996 -2.04086998 0 P 0 ;0
L 1.50708996 -2.03986998 1.564 -2.03986998 0 P 0 ;0
L 1.50676004 -2.03886998 1.56296998 -2.03886998 0 P 0 ;0
L 1.50641998 -2.03786998 1.56206004 -2.03786998 0 P 0 ;0
L 1.50616998 -2.03686998 1.56125 -2.03686998 0 P 0 ;0
L 1.50591004 -2.03586998 1.56066998 -2.03586998 0 P 0 ;0
L 1.5057 -2.03486998 1.56031998 -2.03486998 0 P 0 ;0
L 1.50551998 -2.03386998 1.56016004 -2.03386998 0 P 0 ;0
L 1.50533996 -2.03286998 1.56016998 -2.03286998 0 P 0 ;0
L 1.50523996 -2.03186998 1.56036004 -2.03186998 0 P 0 ;0
L 1.50513002 -2.03086998 1.56071998 -2.03086998 0 P 0 ;0
L 1.50506998 -2.02986998 1.56131004 -2.02986998 0 P 0 ;0
L 1.50503996 -2.02886998 1.5622 -2.02886998 0 P 0 ;0
L 1.50501004 -2.02786998 1.56355 -2.02786998 0 P 0 ;0
L 1.50501998 -2.02686998 1.5657 -2.02686998 0 P 0 ;0
L 1.50506998 -2.02586998 1.60378996 -2.02586998 0 P 0 ;0
L 1.50511998 -2.02486998 1.60371004 -2.02486998 0 P 0 ;0
L 1.50521004 -2.02386998 1.60363996 -2.02386998 0 P 0 ;0
L 1.50533996 -2.02286998 1.60356998 -2.02286998 0 P 0 ;0
L 1.50546998 -2.02186998 1.6035 -2.02186998 0 P 0 ;0
L 1.50563996 -2.02086998 1.60343002 -2.02086998 0 P 0 ;0
L 1.50585 -2.01986998 1.60336004 -2.01986998 0 P 0 ;0
L 1.50606004 -2.01886998 1.60328996 -2.01886998 0 P 0 ;0
L 1.50633002 -2.01786998 1.60321998 -2.01786998 0 P 0 ;0
L 1.50661998 -2.01686998 1.60315 -2.01686998 0 P 0 ;0
L 1.50691004 -2.01586998 1.60308002 -2.01586998 0 P 0 ;0
L 1.50726998 -2.01486998 1.603 -2.01486998 0 P 0 ;0
L 1.50766004 -2.01386998 1.60293002 -2.01386998 0 P 0 ;0
L 1.50808996 -2.01286998 1.60285 -2.01286998 0 P 0 ;0
L 1.50856998 -2.01186998 1.60278002 -2.01186998 0 P 0 ;0
L 1.50908996 -2.01086998 1.6027 -2.01086998 0 P 0 ;0
L 1.50966004 -2.00986998 1.60261998 -2.00986998 0 P 0 ;0
L 1.51028996 -2.00886998 1.60255 -2.00886998 0 P 0 ;0
L 1.51096998 -2.00786998 1.60246998 -2.00786998 0 P 0 ;0
L 1.51171998 -2.00686998 1.6024 -2.00686998 0 P 0 ;0
L 1.51253996 -2.00586998 1.60233002 -2.00586998 0 P 0 ;0
L 1.51343996 -2.00486998 1.60225 -2.00486998 0 P 0 ;0
L 1.5144 -2.00386998 1.60218002 -2.00386998 0 P 0 ;0
L 1.51551998 -2.00286998 1.6021 -2.00286998 0 P 0 ;0
L 1.51663996 -2.00186998 1.60203002 -2.00186998 0 P 0 ;0
L 1.51795 -2.00086998 1.60195 -2.00086998 0 P 0 ;0
L 1.51928996 -1.99986998 1.60183996 -1.99986998 0 P 0 ;0
L 1.52086998 -1.99886998 1.60173002 -1.99886998 0 P 0 ;0
L 1.52258996 -1.99786998 1.60156998 -1.99786998 0 P 0 ;0
L 1.52451004 -1.99686998 1.60138996 -1.99686998 0 P 0 ;0
L 1.52686998 -1.99586998 1.60106998 -1.99586998 0 P 0 ;0
L 1.52976004 -1.99486998 1.59943996 -1.99486998 0 P 0 ;0
L 1.53283002 -1.99386998 1.59543002 -1.99386998 0 P 0 ;0
L 1.53678996 -1.99286998 1.59003996 -1.99286998 0 P 0 ;0
L 1.54173996 -1.99186998 1.58073996 -1.99186998 0 P 0 ;0
L 1.55036998 -1.99086998 1.56493002 -1.99086998 0 P 0 ;0
L 1.6036 -2.03086998 1.60413996 -2.03086998 0 P 0 ;0
L 1.59891004 -2.02986998 1.60406998 -2.02986998 0 P 0 ;0
L 1.59435 -2.02886998 1.604 -2.02886998 0 P 0 ;0
L 1.58838996 -2.02786998 1.60393002 -2.02786998 0 P 0 ;0
L 1.57981004 -2.02686998 1.60386004 -2.02686998 0 P 0 ;0
L 1.54575 -1.98923996 1.53931998 -1.99021998 0 P 0 ;0
L 1.53931998 -1.99021998 1.53298996 -1.99171998 0 P 0 ;0
L 1.53298996 -1.99171998 1.52678996 -1.99373996 0 P 0 ;0
L 1.52678996 -1.99373996 1.52376998 -1.995 0 P 0 ;0
L 1.52376998 -1.995 1.52086998 -1.99651004 0 P 0 ;0
L 1.52086998 -1.99651004 1.5181 -1.99826004 0 P 0 ;0
L 1.5181 -1.99826004 1.51548002 -2.00023002 0 P 0 ;0
L 1.51548002 -2.00023002 1.51301004 -2.00243002 0 P 0 ;0
L 1.51301004 -2.00243002 1.51128996 -2.00423002 0 P 0 ;0
L 1.51128996 -2.00423002 1.50971998 -2.00616004 0 P 0 ;0
L 1.50971998 -2.00616004 1.50831004 -2.00821004 0 P 0 ;0
L 1.50831004 -2.00821004 1.50706998 -2.01036998 0 P 0 ;0
L 1.50706998 -2.01036998 1.50598996 -2.01261998 0 P 0 ;0
L 1.50598996 -2.01261998 1.50508996 -2.01496998 0 P 0 ;0
L 1.50508996 -2.01496998 1.5042 -2.01801004 0 P 0 ;0
L 1.5042 -2.01801004 1.50355 -2.02111004 0 P 0 ;0
L 1.50355 -2.02111004 1.50313996 -2.02426004 0 P 0 ;0
L 1.50313996 -2.02426004 1.50298996 -2.02743002 0 P 0 ;0
L 1.50298996 -2.02743002 1.50308996 -2.03063002 0 P 0 ;0
L 1.50308996 -2.03063002 1.50338002 -2.03326998 0 P 0 ;0
L 1.50338002 -2.03326998 1.50385 -2.03588002 0 P 0 ;0
L 1.50385 -2.03588002 1.50451004 -2.03845 0 P 0 ;0
L 1.50451004 -2.03845 1.50535 -2.04096998 0 P 0 ;0
L 1.50535 -2.04096998 1.50633002 -2.0433 0 P 0 ;0
L 1.50633002 -2.0433 1.5075 -2.04553002 0 P 0 ;0
L 1.5075 -2.04553002 1.50883996 -2.04766998 0 P 0 ;0
L 1.50883996 -2.04766998 1.51036998 -2.04968996 0 P 0 ;0
L 1.51036998 -2.04968996 1.51323002 -2.05291998 0 P 0 ;0
L 1.51323002 -2.05291998 1.51631998 -2.05593996 0 P 0 ;0
L 1.51631998 -2.05593996 1.51961998 -2.05871004 0 P 0 ;0
L 1.51961998 -2.05871004 1.53591004 -2.0706 0 P 0 ;0
L 1.53591004 -2.0706 1.54668002 -2.07831004 0 P 0 ;0
L 1.54668002 -2.07831004 1.54793996 -2.07933996 0 P 0 ;0
L 1.54793996 -2.07933996 1.54911998 -2.08046998 0 P 0 ;0
L 1.54911998 -2.08046998 1.55021004 -2.08168002 0 P 0 ;0
L 1.55021004 -2.08168002 1.5512 -2.08298996 0 P 0 ;0
L 1.5512 -2.08298996 1.55136004 -2.08323002 0 P 0 ;0
L 1.55136004 -2.08323002 1.5515 -2.08348002 0 P 0 ;0
L 1.5515 -2.08348002 1.55161004 -2.08373996 0 P 0 ;0
L 1.55161004 -2.08373996 1.5517 -2.08401998 0 P 0 ;0
L 1.5517 -2.08401998 1.55176998 -2.0843 0 P 0 ;0
L 1.55176998 -2.0843 1.55181004 -2.08458002 0 P 0 ;0
L 1.55181004 -2.08458002 1.55183002 -2.08486998 0 P 0 ;0
L 1.55183002 -2.08486998 1.55181998 -2.08516004 0 P 0 ;0
L 1.55181998 -2.08516004 1.55178996 -2.08545 0 P 0 ;0
L 1.55178996 -2.08545 1.55173996 -2.08573002 0 P 0 ;0
L 1.55173996 -2.08573002 1.55166004 -2.086 0 P 0 ;0
L 1.55166004 -2.086 1.55156004 -2.08628002 0 P 0 ;0
L 1.55156004 -2.08628002 1.55136998 -2.08666998 0 P 0 ;0
L 1.55136998 -2.08666998 1.55115 -2.08703996 0 P 0 ;0
L 1.55115 -2.08703996 1.5509 -2.08738996 0 P 0 ;0
L 1.5509 -2.08738996 1.55063002 -2.08771998 0 P 0 ;0
L 1.55063002 -2.08771998 1.55033002 -2.08803002 0 P 0 ;0
L 1.55033002 -2.08803002 1.55 -2.08831004 0 P 0 ;0
L 1.55 -2.08831004 1.54966004 -2.08856004 0 P 0 ;0
L 1.54966004 -2.08856004 1.54928996 -2.08878996 0 P 0 ;0
L 1.54928996 -2.08878996 1.5489 -2.08898996 0 P 0 ;0
L 1.5489 -2.08898996 1.54786004 -2.08941004 0 P 0 ;0
L 1.54786004 -2.08941004 1.54678996 -2.08973996 0 P 0 ;0
L 1.54678996 -2.08973996 1.54568002 -2.08998002 0 P 0 ;0
L 1.54568002 -2.08998002 1.54456998 -2.09011998 0 P 0 ;0
L 1.54456998 -2.09011998 1.54343996 -2.09016998 0 P 0 ;0
L 1.54343996 -2.09016998 1.53906998 -2.09003002 0 P 0 ;0
L 1.53906998 -2.09003002 1.53468002 -2.08961998 0 P 0 ;0
L 1.53468002 -2.08961998 1.52908996 -2.08878996 0 P 0 ;0
L 1.52908996 -2.08878996 1.52351004 -2.08766004 0 P 0 ;0
L 1.52351004 -2.08766004 1.51005 -2.08418996 0 P 0 ;0
L 1.51005 -2.08418996 1.50631004 -2.08318002 0 P 0 ;0
L 1.50631004 -2.08318002 1.50308002 -2.08238996 0 P 0 ;0
L 1.50308002 -2.08238996 1.50033996 -2.08183002 0 P 0 ;0
L 1.50033996 -2.08183002 1.5003 -2.08181998 0 P 0 ;0
L 1.5003 -2.08181998 1.50016004 -2.08181998 0 P 0 ;0
L 1.50016004 -2.08181998 1.50011998 -2.08183002 0 P 0 ;0
L 1.50011998 -2.08183002 1.50006998 -2.08183996 0 P 0 ;0
L 1.50006998 -2.08183996 1.50003002 -2.08186004 0 P 0 ;0
L 1.50003002 -2.08186004 1.49998996 -2.08186998 0 P 0 ;0
L 1.49998996 -2.08186998 1.49995 -2.08188996 0 P 0 ;0
L 1.49995 -2.08188996 1.49991004 -2.08191998 0 P 0 ;0
L 1.49991004 -2.08191998 1.49988002 -2.08195 0 P 0 ;0
L 1.49988002 -2.08195 1.49983996 -2.08198002 0 P 0 ;0
L 1.49983996 -2.08198002 1.4997 -2.08213996 0 P 0 ;0
L 1.4997 -2.08213996 1.49956004 -2.08231998 0 P 0 ;0
L 1.49956004 -2.08231998 1.49943996 -2.0825 0 P 0 ;0
L 1.49943996 -2.0825 1.49933996 -2.0827 0 P 0 ;0
L 1.49933996 -2.0827 1.49925 -2.0829 0 P 0 ;0
L 1.49925 -2.0829 1.49918996 -2.08311004 0 P 0 ;0
L 1.49918996 -2.08311004 1.49913996 -2.08333002 0 P 0 ;0
L 1.49913996 -2.08333002 1.49911004 -2.08355 0 P 0 ;0
L 1.49911004 -2.08355 1.4991 -2.08376998 0 P 0 ;0
L 1.4991 -2.08376998 1.49911004 -2.08398996 0 P 0 ;0
L 1.49911004 -2.08398996 1.50071004 -2.10395 0 P 0 ;0
L 1.50071004 -2.10395 1.5024 -2.12403996 0 P 0 ;0
L 1.5024 -2.12403996 1.50241998 -2.12418002 0 P 0 ;0
L 1.50241998 -2.12418002 1.50246004 -2.12431004 0 P 0 ;0
L 1.50246004 -2.12431004 1.50248996 -2.12445 0 P 0 ;0
L 1.50248996 -2.12445 1.50255 -2.12456998 0 P 0 ;0
L 1.50255 -2.12456998 1.50261004 -2.1247 0 P 0 ;0
L 1.50261004 -2.1247 1.50276998 -2.12491998 0 P 0 ;0
L 1.50276998 -2.12491998 1.50286004 -2.12501998 0 P 0 ;0
L 1.50286004 -2.12501998 1.50296998 -2.12511998 0 P 0 ;0
L 1.50296998 -2.12511998 1.50308002 -2.12521004 0 P 0 ;0
L 1.50308002 -2.12521004 1.50318996 -2.12528002 0 P 0 ;0
L 1.50318996 -2.12528002 1.50331998 -2.12535 0 P 0 ;0
L 1.50331998 -2.12535 1.50343996 -2.1254 0 P 0 ;0
L 1.50343996 -2.1254 1.50391998 -2.12556004 0 P 0 ;0
L 1.50391998 -2.12556004 1.5044 -2.12568996 0 P 0 ;0
L 1.5044 -2.12568996 1.50848002 -2.12648996 0 P 0 ;0
L 1.50848002 -2.12648996 1.51328996 -2.12738002 0 P 0 ;0
L 1.51328996 -2.12738002 1.51873996 -2.12833996 0 P 0 ;0
L 1.51873996 -2.12833996 1.52606004 -2.12945 0 P 0 ;0
L 1.52606004 -2.12945 1.53343996 -2.13023002 0 P 0 ;0
L 1.53343996 -2.13023002 1.54886998 -2.13086998 0 P 0 ;0
L 1.54886998 -2.13086998 1.56305 -2.1303 0 P 0 ;0
L 1.56305 -2.1303 1.56666004 -2.12988996 0 P 0 ;0
L 1.56666004 -2.12988996 1.57023002 -2.12926998 0 P 0 ;0
L 1.57023002 -2.12926998 1.5738 -2.12843002 0 P 0 ;0
L 1.5738 -2.12843002 1.57945 -2.12668996 0 P 0 ;0
L 1.57945 -2.12668996 1.58498002 -2.12456998 0 P 0 ;0
L 1.58498002 -2.12456998 1.58793996 -2.12318002 0 P 0 ;0
L 1.58793996 -2.12318002 1.59078996 -2.12156004 0 P 0 ;0
L 1.59078996 -2.12156004 1.59348996 -2.11971998 0 P 0 ;0
L 1.59348996 -2.11971998 1.59525 -2.11833002 0 P 0 ;0
L 1.59525 -2.11833002 1.5969 -2.11681998 0 P 0 ;0
L 1.5969 -2.11681998 1.59846004 -2.11521004 0 P 0 ;0
L 1.59846004 -2.11521004 1.59991004 -2.11348002 0 P 0 ;0
L 1.59991004 -2.11348002 1.60175 -2.11093996 0 P 0 ;0
L 1.60175 -2.11093996 1.60338002 -2.10826998 0 P 0 ;0
L 1.60338002 -2.10826998 1.60481004 -2.10548002 0 P 0 ;0
L 1.60481004 -2.10548002 1.60573002 -2.10321004 0 P 0 ;0
L 1.60573002 -2.10321004 1.60646004 -2.10088002 0 P 0 ;0
L 1.60646004 -2.10088002 1.60698002 -2.09848996 0 P 0 ;0
L 1.60698002 -2.09848996 1.60756004 -2.09421998 0 P 0 ;0
L 1.60756004 -2.09421998 1.6078 -2.08991004 0 P 0 ;0
L 1.6078 -2.08991004 1.60768996 -2.08565 0 P 0 ;0
L 1.60768996 -2.08565 1.60723002 -2.08141998 0 P 0 ;0
L 1.60723002 -2.08141998 1.60691998 -2.07968002 0 P 0 ;0
L 1.60691998 -2.07968002 1.60646998 -2.07796998 0 P 0 ;0
L 1.60646998 -2.07796998 1.60591998 -2.0763 0 P 0 ;0
L 1.60591998 -2.0763 1.60523002 -2.07466998 0 P 0 ;0
L 1.60523002 -2.07466998 1.60411998 -2.07246998 0 P 0 ;0
L 1.60411998 -2.07246998 1.60281004 -2.07038002 0 P 0 ;0
L 1.60281004 -2.07038002 1.60131998 -2.06838996 0 P 0 ;0
L 1.60131998 -2.06838996 1.59803996 -2.06461998 0 P 0 ;0
L 1.59803996 -2.06461998 1.59455 -2.06101998 0 P 0 ;0
L 1.59455 -2.06101998 1.59031998 -2.05708996 0 P 0 ;0
L 1.59031998 -2.05708996 1.58586004 -2.05333996 0 P 0 ;0
L 1.58586004 -2.05333996 1.57588002 -2.04598996 0 P 0 ;0
L 1.57588002 -2.04598996 1.56685 -2.03963996 0 P 0 ;0
L 1.56685 -2.03963996 1.56578002 -2.03878996 0 P 0 ;0
L 1.56578002 -2.03878996 1.56476998 -2.03786004 0 P 0 ;0
L 1.56476998 -2.03786004 1.56383002 -2.03686998 0 P 0 ;0
L 1.56383002 -2.03686998 1.56295 -2.0358 0 P 0 ;0
L 1.56295 -2.0358 1.56276998 -2.03555 0 P 0 ;0
L 1.56276998 -2.03555 1.56261004 -2.03528002 0 P 0 ;0
L 1.56261004 -2.03528002 1.56246998 -2.035 0 P 0 ;0
L 1.56246998 -2.035 1.56236004 -2.03471998 0 P 0 ;0
L 1.56236004 -2.03471998 1.56226998 -2.03441998 0 P 0 ;0
L 1.56226998 -2.03441998 1.5622 -2.03411998 0 P 0 ;0
L 1.5622 -2.03411998 1.56216004 -2.03381998 0 P 0 ;0
L 1.56216004 -2.03381998 1.56213996 -2.03351004 0 P 0 ;0
L 1.56213996 -2.03351004 1.56215 -2.0332 0 P 0 ;0
L 1.56215 -2.0332 1.56218002 -2.03288996 0 P 0 ;0
L 1.56218002 -2.03288996 1.56225 -2.03253996 0 P 0 ;0
L 1.56225 -2.03253996 1.56233996 -2.03221004 0 P 0 ;0
L 1.56233996 -2.03221004 1.56246004 -2.03186998 0 P 0 ;0
L 1.56246004 -2.03186998 1.56261004 -2.03156004 0 P 0 ;0
L 1.56261004 -2.03156004 1.56278996 -2.03125 0 P 0 ;0
L 1.56278996 -2.03125 1.56298002 -2.03096004 0 P 0 ;0
L 1.56298002 -2.03096004 1.56321004 -2.03068996 0 P 0 ;0
L 1.56321004 -2.03068996 1.56345 -2.03043996 0 P 0 ;0
L 1.56345 -2.03043996 1.56371004 -2.0302 0 P 0 ;0
L 1.56371004 -2.0302 1.56416004 -2.02986004 0 P 0 ;0
L 1.56416004 -2.02986004 1.56463002 -2.02955 0 P 0 ;0
L 1.56463002 -2.02955 1.56511998 -2.02928002 0 P 0 ;0
L 1.56511998 -2.02928002 1.56561998 -2.02903002 0 P 0 ;0
L 1.56561998 -2.02903002 1.56611998 -2.02883996 0 P 0 ;0
L 1.56611998 -2.02883996 1.56663996 -2.02866998 0 P 0 ;0
L 1.56663996 -2.02866998 1.56716004 -2.02855 0 P 0 ;0
L 1.56716004 -2.02855 1.5677 -2.02846998 0 P 0 ;0
L 1.5677 -2.02846998 1.56926998 -2.02835 0 P 0 ;0
L 1.56926998 -2.02835 1.57085 -2.02833996 0 P 0 ;0
L 1.57085 -2.02833996 1.57725 -2.02866998 0 P 0 ;0
L 1.57725 -2.02866998 1.58205 -2.02906004 0 P 0 ;0
L 1.58205 -2.02906004 1.58746998 -2.02975 0 P 0 ;0
L 1.58746998 -2.02975 1.59271004 -2.03056998 0 P 0 ;0
L 1.59271004 -2.03056998 1.59681004 -2.03143002 0 P 0 ;0
L 1.59681004 -2.03143002 1.60016004 -2.03221998 0 P 0 ;0
L 1.60016004 -2.03221998 1.60308002 -2.03281004 0 P 0 ;0
L 1.60308002 -2.03281004 1.60553996 -2.03323996 0 P 0 ;0
L 1.60553996 -2.03323996 1.60568996 -2.03323996 0 P 0 ;0
L 1.60568996 -2.03323996 1.60576998 -2.03321998 0 P 0 ;0
L 1.60576998 -2.03321998 1.60586004 -2.03316004 0 P 0 ;0
L 1.60586004 -2.03316004 1.6059 -2.03313996 0 P 0 ;0
L 1.6059 -2.03313996 1.60591998 -2.03311004 0 P 0 ;0
L 1.60591998 -2.03311004 1.60598996 -2.03303996 0 P 0 ;0
L 1.60598996 -2.03303996 1.60605 -2.03296998 0 P 0 ;0
L 1.60605 -2.03296998 1.6061 -2.03288996 0 P 0 ;0
L 1.6061 -2.03288996 1.60618002 -2.03273002 0 P 0 ;0
L 1.60618002 -2.03273002 1.60621004 -2.03263002 0 P 0 ;0
L 1.60621004 -2.03263002 1.60623002 -2.03253996 0 P 0 ;0
L 1.60623002 -2.03253996 1.60625 -2.03236004 0 P 0 ;0
L 1.60625 -2.03236004 1.60623996 -2.03226004 0 P 0 ;0
L 1.60623996 -2.03226004 1.60508002 -2.01578002 0 P 0 ;0
L 1.60508002 -2.01578002 1.60393996 -2.00068002 0 P 0 ;0
L 1.60393996 -2.00068002 1.60368002 -1.99833996 0 P 0 ;0
L 1.60368002 -1.99833996 1.60326998 -1.99601004 0 P 0 ;0
L 1.60326998 -1.99601004 1.60321004 -1.99576998 0 P 0 ;0
L 1.60321004 -1.99576998 1.60313996 -1.99553002 0 P 0 ;0
L 1.60313996 -1.99553002 1.60303996 -1.9953 0 P 0 ;0
L 1.60303996 -1.9953 1.60293002 -1.99508002 0 P 0 ;0
L 1.60293002 -1.99508002 1.60281004 -1.99486004 0 P 0 ;0
L 1.60281004 -1.99486004 1.60261998 -1.9946 0 P 0 ;0
L 1.60261998 -1.9946 1.60241004 -1.99435 0 P 0 ;0
L 1.60241004 -1.99435 1.60218002 -1.99411998 0 P 0 ;0
L 1.60218002 -1.99411998 1.60191998 -1.99391004 0 P 0 ;0
L 1.60191998 -1.99391004 1.60161004 -1.99368996 0 P 0 ;0
L 1.60161004 -1.99368996 1.60128996 -1.99348996 0 P 0 ;0
L 1.60128996 -1.99348996 1.60095 -1.99331998 0 P 0 ;0
L 1.60095 -1.99331998 1.6006 -1.99316004 0 P 0 ;0
L 1.6006 -1.99316004 1.59966004 -1.99283002 0 P 0 ;0
L 1.59966004 -1.99283002 1.59871004 -1.99255 0 P 0 ;0
L 1.59871004 -1.99255 1.5933 -1.99135 0 P 0 ;0
L 1.5933 -1.99135 1.5878 -1.9905 0 P 0 ;0
L 1.5878 -1.9905 1.57285 -1.98915 0 P 0 ;0
L 1.57285 -1.98915 1.55763996 -1.98861004 0 P 0 ;0
L 1.55763996 -1.98861004 1.55171004 -1.98876004 0 P 0 ;0
L 1.55171004 -1.98876004 1.54575 -1.98923996 0 P 0 ;0
L 1.53011998 -2.12786998 1.5666 -2.12786998 0 P 0 ;0
L 1.52236004 -2.12686998 1.57168002 -2.12686998 0 P 0 ;0
L 1.51621998 -2.12586998 1.5753 -2.12586998 0 P 0 ;0
L 1.51071004 -2.12486998 1.57856004 -2.12486998 0 P 0 ;0
L 1.50553002 -2.12386998 1.58121004 -2.12386998 0 P 0 ;0
L 1.50431004 -2.12286998 1.58381998 -2.12286998 0 P 0 ;0
L 1.50423002 -2.12186998 1.58601998 -2.12186998 0 P 0 ;0
L 1.50413996 -2.12086998 1.58796004 -2.12086998 0 P 0 ;0
L 1.50406004 -2.11986998 1.58971004 -2.11986998 0 P 0 ;0
L 1.50396998 -2.11886998 1.59118002 -2.11886998 0 P 0 ;0
L 1.50388996 -2.11786998 1.5926 -2.11786998 0 P 0 ;0
L 1.50381004 -2.11686998 1.59386004 -2.11686998 0 P 0 ;0
L 1.50371998 -2.11586998 1.59496998 -2.11586998 0 P 0 ;0
L 1.50363996 -2.11486998 1.59601004 -2.11486998 0 P 0 ;0
L 1.50355 -2.11386998 1.59696998 -2.11386998 0 P 0 ;0
L 1.50346998 -2.11286998 1.59781004 -2.11286998 0 P 0 ;0
L 1.50338002 -2.11186998 1.5986 -2.11186998 0 P 0 ;0
L 1.5033 -2.11086998 1.59933002 -2.11086998 0 P 0 ;0
L 1.50321004 -2.10986998 1.60005 -2.10986998 0 P 0 ;0
L 1.50313002 -2.10886998 1.60066998 -2.10886998 0 P 0 ;0
L 1.50305 -2.10786998 1.60128002 -2.10786998 0 P 0 ;0
L 1.50296004 -2.10686998 1.60185 -2.10686998 0 P 0 ;0
L 1.50288002 -2.10586998 1.60236004 -2.10586998 0 P 0 ;0
L 1.50278996 -2.10486998 1.60286998 -2.10486998 0 P 0 ;0
L 1.50271004 -2.10386998 1.6033 -2.10386998 0 P 0 ;0
L 1.50263002 -2.10286998 1.60371004 -2.10286998 0 P 0 ;0
L 1.50255 -2.10186998 1.60405 -2.10186998 0 P 0 ;0
L 1.50246998 -2.10086998 1.60436004 -2.10086998 0 P 0 ;0
L 1.50238996 -2.09986998 1.60463002 -2.09986998 0 P 0 ;0
L 1.50231004 -2.09886998 1.60485 -2.09886998 0 P 0 ;0
L 1.50223002 -2.09786998 1.60505 -2.09786998 0 P 0 ;0
L 1.50215 -2.09686998 1.60518002 -2.09686998 0 P 0 ;0
L 1.50206998 -2.09586998 1.60531998 -2.09586998 0 P 0 ;0
L 1.50198996 -2.09486998 1.60545 -2.09486998 0 P 0 ;0
L 1.50191004 -2.09386998 1.60558002 -2.09386998 0 P 0 ;0
L 1.50183002 -2.09286998 1.60563002 -2.09286998 0 P 0 ;0
L 1.50175 -2.09186998 1.53725 -2.09186998 0 P 0 ;0
L 1.54638996 -2.09186998 1.60568996 -2.09186998 0 P 0 ;0
L 1.50166998 -2.09086998 1.5295 -2.09086998 0 P 0 ;0
L 1.54956998 -2.09086998 1.60573996 -2.09086998 0 P 0 ;0
L 1.50158996 -2.08986998 1.52436004 -2.08986998 0 P 0 ;0
L 1.55125 -2.08986998 1.60578996 -2.08986998 0 P 0 ;0
L 1.50151004 -2.08886998 1.52021004 -2.08886998 0 P 0 ;0
L 1.55226998 -2.08886998 1.60576998 -2.08886998 0 P 0 ;0
L 1.50143002 -2.08786998 1.51633002 -2.08786998 0 P 0 ;0
L 1.55298002 -2.08786998 1.60573996 -2.08786998 0 P 0 ;0
L 1.50133996 -2.08686998 1.51246004 -2.08686998 0 P 0 ;0
L 1.55346998 -2.08686998 1.60571998 -2.08686998 0 P 0 ;0
L 1.50126998 -2.08586998 1.50861998 -2.08586998 0 P 0 ;0
L 1.55375 -2.08586998 1.60568996 -2.08586998 0 P 0 ;0
L 1.50118002 -2.08486998 1.50481004 -2.08486998 0 P 0 ;0
L 1.55383002 -2.08486998 1.60558996 -2.08486998 0 P 0 ;0
L 1.55371998 -2.08386998 1.60548996 -2.08386998 0 P 0 ;0
L 1.54886998 -2.12886998 1.53358996 -2.12823996 0 P 0 ;0
L 1.53358996 -2.12823996 1.52631998 -2.12746998 0 P 0 ;0
L 1.52631998 -2.12746998 1.51906004 -2.12636998 0 P 0 ;0
L 1.51906004 -2.12636998 1.51363002 -2.12541004 0 P 0 ;0
L 1.51363002 -2.12541004 1.50886998 -2.12451998 0 P 0 ;0
L 1.50886998 -2.12451998 1.50483996 -2.12373996 0 P 0 ;0
L 1.50483996 -2.12373996 1.50448996 -2.12365 0 P 0 ;0
L 1.50448996 -2.12365 1.50438002 -2.12361004 0 P 0 ;0
L 1.50438002 -2.12361004 1.5027 -2.10378002 0 P 0 ;0
L 1.5027 -2.10378002 1.50111998 -2.08403002 0 P 0 ;0
L 1.50111998 -2.08403002 1.50263996 -2.08433996 0 P 0 ;0
L 1.50263996 -2.08433996 1.50581004 -2.08511004 0 P 0 ;0
L 1.50581004 -2.08511004 1.50955 -2.08611998 0 P 0 ;0
L 1.50955 -2.08611998 1.52306004 -2.08961004 0 P 0 ;0
L 1.52306004 -2.08961004 1.52311004 -2.08961998 0 P 0 ;0
L 1.52311004 -2.08961998 1.52875 -2.09076004 0 P 0 ;0
L 1.52875 -2.09076004 1.5288 -2.09076004 0 P 0 ;0
L 1.5288 -2.09076004 1.53443996 -2.09161004 0 P 0 ;0
L 1.53443996 -2.09161004 1.53893996 -2.09203002 0 P 0 ;0
L 1.53893996 -2.09203002 1.54346004 -2.09216998 0 P 0 ;0
L 1.54346004 -2.09216998 1.54473996 -2.09211004 0 P 0 ;0
L 1.54473996 -2.09211004 1.54603002 -2.09195 0 P 0 ;0
L 1.54603002 -2.09195 1.54728996 -2.09166998 0 P 0 ;0
L 1.54728996 -2.09166998 1.54853002 -2.09128996 0 P 0 ;0
L 1.54853002 -2.09128996 1.54973002 -2.09081004 0 P 0 ;0
L 1.54973002 -2.09081004 1.55026998 -2.09053996 0 P 0 ;0
L 1.55026998 -2.09053996 1.55076998 -2.09023002 0 P 0 ;0
L 1.55076998 -2.09023002 1.55118002 -2.08991998 0 P 0 ;0
L 1.55118002 -2.08991998 1.55118002 -2.08991004 0 P 0 ;0
L 1.55118002 -2.08991004 1.5512 -2.08991004 0 P 0 ;0
L 1.5512 -2.08991004 1.55125 -2.08986998 0 P 0 ;0
L 1.55125 -2.08986998 1.55131004 -2.08981998 0 P 0 ;0
L 1.55131004 -2.08981998 1.55126998 -2.08978002 0 P 0 ;0
L 1.55126998 -2.08978002 1.55136004 -2.08978002 0 P 0 ;0
L 1.55136004 -2.08978002 1.5517 -2.08948996 0 P 0 ;0
L 1.5517 -2.08948996 1.55206004 -2.08911998 0 P 0 ;0
L 1.55206004 -2.08911998 1.55205 -2.08911004 0 P 0 ;0
L 1.55205 -2.08911004 1.55206004 -2.08911004 0 P 0 ;0
L 1.55206004 -2.08911004 1.55211998 -2.08906004 0 P 0 ;0
L 1.55211998 -2.08906004 1.55248996 -2.08861004 0 P 0 ;0
L 1.55248996 -2.08861004 1.55283996 -2.08811998 0 P 0 ;0
L 1.55283996 -2.08811998 1.55313996 -2.08761004 0 P 0 ;0
L 1.55313996 -2.08761004 1.5534 -2.08706998 0 P 0 ;0
L 1.5534 -2.08706998 1.55356004 -2.08663002 0 P 0 ;0
L 1.55356004 -2.08663002 1.55368996 -2.08618996 0 P 0 ;0
L 1.55368996 -2.08618996 1.55376998 -2.08573996 0 P 0 ;0
L 1.55376998 -2.08573996 1.55378002 -2.08565 0 P 0 ;0
L 1.55378002 -2.08565 1.55381998 -2.08528002 0 P 0 ;0
L 1.55381998 -2.08528002 1.55383002 -2.08481998 0 P 0 ;0
L 1.55383002 -2.08481998 1.5538 -2.08436998 0 P 0 ;0
L 1.5538 -2.08436998 1.55373002 -2.08391998 0 P 0 ;0
L 1.55373002 -2.08391998 1.55361998 -2.08346998 0 P 0 ;0
L 1.55361998 -2.08346998 1.55348002 -2.08303996 0 P 0 ;0
L 1.55348002 -2.08303996 1.5533 -2.08261004 0 P 0 ;0
L 1.5533 -2.08261004 1.55308996 -2.08221004 0 P 0 ;0
L 1.55308996 -2.08221004 1.55283996 -2.08183002 0 P 0 ;0
L 1.55283996 -2.08183002 1.55175 -2.0804 0 P 0 ;0
L 1.55175 -2.0804 1.55055 -2.07908002 0 P 0 ;0
L 1.55055 -2.07908002 1.54926004 -2.07783996 0 P 0 ;0
L 1.54926004 -2.07783996 1.54788996 -2.07671998 0 P 0 ;0
L 1.54788996 -2.07671998 1.53706998 -2.06898002 0 P 0 ;0
L 1.53706998 -2.06898002 1.52085 -2.05713996 0 P 0 ;0
L 1.52085 -2.05713996 1.51766004 -2.05445 0 P 0 ;0
L 1.51766004 -2.05445 1.51468002 -2.05153996 0 P 0 ;0
L 1.51468002 -2.05153996 1.51191998 -2.04841998 0 P 0 ;0
L 1.51191998 -2.04841998 1.51048996 -2.04651998 0 P 0 ;0
L 1.51048996 -2.04651998 1.50923002 -2.04453002 0 P 0 ;0
L 1.50923002 -2.04453002 1.50813996 -2.04245 0 P 0 ;0
L 1.50813996 -2.04245 1.50721998 -2.04026004 0 P 0 ;0
L 1.50721998 -2.04026004 1.50643002 -2.03788002 0 P 0 ;0
L 1.50643002 -2.03788002 1.50581004 -2.03545 0 P 0 ;0
L 1.50581004 -2.03545 1.50536004 -2.03298996 0 P 0 ;0
L 1.50536004 -2.03298996 1.50508996 -2.0305 0 P 0 ;0
L 1.50508996 -2.0305 1.50498996 -2.02745 0 P 0 ;0
L 1.50498996 -2.02745 1.50513996 -2.02443996 0 P 0 ;0
L 1.50513996 -2.02443996 1.50551998 -2.02145 0 P 0 ;0
L 1.50551998 -2.02145 1.50613996 -2.0185 0 P 0 ;0
L 1.50613996 -2.0185 1.50698996 -2.01561004 0 P 0 ;0
L 1.50698996 -2.01561004 1.50783002 -2.01341004 0 P 0 ;0
L 1.50783002 -2.01341004 1.50883002 -2.0113 0 P 0 ;0
L 1.50883002 -2.0113 1.51 -2.00928002 0 P 0 ;0
L 1.51 -2.00928002 1.51133002 -2.00736004 0 P 0 ;0
L 1.51133002 -2.00736004 1.5128 -2.00555 0 P 0 ;0
L 1.5128 -2.00555 1.5144 -2.00386004 0 P 0 ;0
L 1.5144 -2.00386004 1.51675 -2.00176998 0 P 0 ;0
L 1.51675 -2.00176998 1.51923002 -1.9999 0 P 0 ;0
L 1.51923002 -1.9999 1.52186004 -1.99823996 0 P 0 ;0
L 1.52186004 -1.99823996 1.52461998 -1.99681004 0 P 0 ;0
L 1.52461998 -1.99681004 1.52748996 -1.99561004 0 P 0 ;0
L 1.52748996 -1.99561004 1.53353002 -1.99363996 0 P 0 ;0
L 1.53353002 -1.99363996 1.5397 -1.99218002 0 P 0 ;0
L 1.5397 -1.99218002 1.54598002 -1.99123002 0 P 0 ;0
L 1.54598002 -1.99123002 1.55181004 -1.99075 0 P 0 ;0
L 1.55181004 -1.99075 1.55763002 -1.99061998 0 P 0 ;0
L 1.55763002 -1.99061998 1.57273002 -1.99113996 0 P 0 ;0
L 1.57273002 -1.99113996 1.58755 -1.99248996 0 P 0 ;0
L 1.58755 -1.99248996 1.59293002 -1.99331998 0 P 0 ;0
L 1.59293002 -1.99331998 1.59821004 -1.99448996 0 P 0 ;0
L 1.59821004 -1.99448996 1.59905 -1.99473002 0 P 0 ;0
L 1.59905 -1.99473002 1.59986004 -1.99501998 0 P 0 ;0
L 1.59986004 -1.99501998 1.60008002 -1.99511998 0 P 0 ;0
L 1.60008002 -1.99511998 1.6003 -1.99523002 0 P 0 ;0
L 1.6003 -1.99523002 1.60051004 -1.99536004 0 P 0 ;0
L 1.60051004 -1.99536004 1.60071004 -1.9955 0 P 0 ;0
L 1.60071004 -1.9955 1.60083002 -1.99561004 0 P 0 ;0
L 1.60083002 -1.99561004 1.60093996 -1.99571004 0 P 0 ;0
L 1.60093996 -1.99571004 1.60103996 -1.99583002 0 P 0 ;0
L 1.60103996 -1.99583002 1.60111998 -1.99595 0 P 0 ;0
L 1.60111998 -1.99595 1.60116998 -1.99601998 0 P 0 ;0
L 1.60116998 -1.99601998 1.60121004 -1.99611004 0 P 0 ;0
L 1.60121004 -1.99611004 1.60125 -1.99621004 0 P 0 ;0
L 1.60125 -1.99621004 1.60128002 -1.9963 0 P 0 ;0
L 1.60128002 -1.9963 1.60131004 -1.99641004 0 P 0 ;0
L 1.60131004 -1.99641004 1.6017 -1.99861998 0 P 0 ;0
L 1.6017 -1.99861998 1.60195 -2.00086998 0 P 0 ;0
L 1.60195 -2.00086998 1.60308002 -2.01593002 0 P 0 ;0
L 1.60308002 -2.01593002 1.60415 -2.03096998 0 P 0 ;0
L 1.60415 -2.03096998 1.60345 -2.03083996 0 P 0 ;0
L 1.60345 -2.03083996 1.60058996 -2.03026004 0 P 0 ;0
L 1.60058996 -2.03026004 1.59723002 -2.02948002 0 P 0 ;0
L 1.59723002 -2.02948002 1.59721998 -2.02948002 0 P 0 ;0
L 1.59721998 -2.02948002 1.59306998 -2.0286 0 P 0 ;0
L 1.59306998 -2.0286 1.58776004 -2.02776998 0 P 0 ;0
L 1.58776004 -2.02776998 1.58226004 -2.02708002 0 P 0 ;0
L 1.58226004 -2.02708002 1.57738002 -2.02666998 0 P 0 ;0
L 1.57738002 -2.02666998 1.5709 -2.02633996 0 P 0 ;0
L 1.5709 -2.02633996 1.56918996 -2.02635 0 P 0 ;0
L 1.56918996 -2.02635 1.56746998 -2.02648996 0 P 0 ;0
L 1.56746998 -2.02648996 1.56678996 -2.02658996 0 P 0 ;0
L 1.56678996 -2.02658996 1.56611998 -2.02673996 0 P 0 ;0
L 1.56611998 -2.02673996 1.56546004 -2.02695 0 P 0 ;0
L 1.56546004 -2.02695 1.56481998 -2.0272 0 P 0 ;0
L 1.56481998 -2.0272 1.56418996 -2.0275 0 P 0 ;0
L 1.56418996 -2.0275 1.56358002 -2.02785 0 P 0 ;0
L 1.56358002 -2.02785 1.563 -2.02823002 0 P 0 ;0
L 1.563 -2.02823002 1.56245 -2.02865 0 P 0 ;0
L 1.56245 -2.02865 1.56206998 -2.02898996 0 P 0 ;0
L 1.56206998 -2.02898996 1.56171004 -2.02936004 0 P 0 ;0
L 1.56171004 -2.02936004 1.56138002 -2.02976004 0 P 0 ;0
L 1.56138002 -2.02976004 1.56108996 -2.03018996 0 P 0 ;0
L 1.56108996 -2.03018996 1.56083002 -2.03063996 0 P 0 ;0
L 1.56083002 -2.03063996 1.56061998 -2.0311 0 P 0 ;0
L 1.56061998 -2.0311 1.56043996 -2.03158996 0 P 0 ;0
L 1.56043996 -2.03158996 1.5603 -2.03208002 0 P 0 ;0
L 1.5603 -2.03208002 1.5602 -2.0326 0 P 0 ;0
L 1.5602 -2.0326 1.56015 -2.03308002 0 P 0 ;0
L 1.56015 -2.03308002 1.56013996 -2.03353996 0 P 0 ;0
L 1.56013996 -2.03353996 1.56016004 -2.03391004 0 P 0 ;0
L 1.56016004 -2.03391004 1.56048002 -2.03391004 0 P 0 ;0
L 1.56048002 -2.03391004 1.56016004 -2.03393002 0 P 0 ;0
L 1.56016004 -2.03393002 1.56016998 -2.03401004 0 P 0 ;0
L 1.56016998 -2.03401004 1.56023002 -2.03448002 0 P 0 ;0
L 1.56023002 -2.03448002 1.56025 -2.03456004 0 P 0 ;0
L 1.56025 -2.03456004 1.56033002 -2.03493002 0 P 0 ;0
L 1.56033002 -2.03493002 1.56046998 -2.03538002 0 P 0 ;0
L 1.56046998 -2.03538002 1.56063996 -2.03581998 0 P 0 ;0
L 1.56063996 -2.03581998 1.56085 -2.03623996 0 P 0 ;0
L 1.56085 -2.03623996 1.56108996 -2.03663996 0 P 0 ;0
L 1.56108996 -2.03663996 1.56136004 -2.03701998 0 P 0 ;0
L 1.56136004 -2.03701998 1.56233002 -2.03818996 0 P 0 ;0
L 1.56233002 -2.03818996 1.56336998 -2.03928996 0 P 0 ;0
L 1.56336998 -2.03928996 1.56448002 -2.04031004 0 P 0 ;0
L 1.56448002 -2.04031004 1.56566004 -2.04123996 0 P 0 ;0
L 1.56566004 -2.04123996 1.57471004 -2.04761998 0 P 0 ;0
L 1.57471004 -2.04761998 1.58461998 -2.05491004 0 P 0 ;0
L 1.58461998 -2.05491004 1.58898996 -2.05858996 0 P 0 ;0
L 1.58898996 -2.05858996 1.59315 -2.06245 0 P 0 ;0
L 1.59315 -2.06245 1.59656998 -2.06596998 0 P 0 ;0
L 1.59656998 -2.06596998 1.59976004 -2.06965 0 P 0 ;0
L 1.59976004 -2.06965 1.60116004 -2.07151004 0 P 0 ;0
L 1.60116004 -2.07151004 1.60238002 -2.07346004 0 P 0 ;0
L 1.60238002 -2.07346004 1.60341998 -2.0755 0 P 0 ;0
L 1.60341998 -2.0755 1.60403996 -2.077 0 P 0 ;0
L 1.60403996 -2.077 1.60456004 -2.07853996 0 P 0 ;0
L 1.60456004 -2.07853996 1.60496004 -2.08011004 0 P 0 ;0
L 1.60496004 -2.08011004 1.60525 -2.0817 0 P 0 ;0
L 1.60525 -2.0817 1.60568996 -2.08578002 0 P 0 ;0
L 1.60568996 -2.08578002 1.60578996 -2.08988002 0 P 0 ;0
L 1.60578996 -2.08988002 1.60556998 -2.09403002 0 P 0 ;0
L 1.60556998 -2.09403002 1.60501004 -2.09813996 0 P 0 ;0
L 1.60501004 -2.09813996 1.60451998 -2.10036998 0 P 0 ;0
L 1.60451998 -2.10036998 1.60383996 -2.10253996 0 P 0 ;0
L 1.60383996 -2.10253996 1.60298996 -2.10465 0 P 0 ;0
L 1.60298996 -2.10465 1.60163996 -2.1073 0 P 0 ;0
L 1.60163996 -2.1073 1.60008002 -2.10983002 0 P 0 ;0
L 1.60008002 -2.10983002 1.59833002 -2.11225 0 P 0 ;0
L 1.59833002 -2.11225 1.59696998 -2.11386998 0 P 0 ;0
L 1.59696998 -2.11386998 1.59551004 -2.11538996 0 P 0 ;0
L 1.59551004 -2.11538996 1.59395 -2.1168 0 P 0 ;0
L 1.59395 -2.1168 1.59231004 -2.11811004 0 P 0 ;0
L 1.59231004 -2.11811004 1.58973002 -2.11986004 0 P 0 ;0
L 1.58973002 -2.11986004 1.58701998 -2.1214 0 P 0 ;0
L 1.58701998 -2.1214 1.5842 -2.12273002 0 P 0 ;0
L 1.5842 -2.12273002 1.5788 -2.1248 0 P 0 ;0
L 1.5788 -2.1248 1.57326998 -2.12648996 0 P 0 ;0
L 1.57326998 -2.12648996 1.56983002 -2.12731004 0 P 0 ;0
L 1.56983002 -2.12731004 1.56638002 -2.12791004 0 P 0 ;0
L 1.56638002 -2.12791004 1.56288996 -2.1283 0 P 0 ;0
L 1.56288996 -2.1283 1.54886998 -2.12886998 0 P 0 ;0
L 1.35851998 -2.06545 1.47866004 -2.06545 0 P 0 ;0
L 1.35936004 -2.06445 1.47871004 -2.06445 0 P 0 ;0
L 1.36041004 -2.06345 1.47875 -2.06345 0 P 0 ;0
L 1.36163996 -2.06245 1.4788 -2.06245 0 P 0 ;0
L 1.36293996 -2.06145 1.47883996 -2.06145 0 P 0 ;0
L 1.36436004 -2.06045 1.47888996 -2.06045 0 P 0 ;0
L 1.36598002 -2.05945 1.47893996 -2.05945 0 P 0 ;0
L 1.36776004 -2.05845 1.47898996 -2.05845 0 P 0 ;0
L 1.36971004 -2.05745 1.47903002 -2.05745 0 P 0 ;0
L 1.37166004 -2.05645 1.47908002 -2.05645 0 P 0 ;0
L 1.37391004 -2.05545 1.47911998 -2.05545 0 P 0 ;0
L 1.37616998 -2.05445 1.47916998 -2.05445 0 P 0 ;0
L 1.37873002 -2.05345 1.47921004 -2.05345 0 P 0 ;0
L 1.38136004 -2.05245 1.47926004 -2.05245 0 P 0 ;0
L 1.36875 -2.03345 1.37108996 -2.03345 0 P 0 ;0
L 1.36886004 -2.03245 1.37385 -2.03245 0 P 0 ;0
L 1.36896998 -2.03145 1.37678002 -2.03145 0 P 0 ;0
L 1.36908996 -2.03045 1.3797 -2.03045 0 P 0 ;0
L 1.36921004 -2.02945 1.38261998 -2.02945 0 P 0 ;0
L 1.36933002 -2.02845 1.38638996 -2.02845 0 P 0 ;0
L 1.36946004 -2.02745 1.39023996 -2.02745 0 P 0 ;0
L 1.36958002 -2.02645 1.39503002 -2.02645 0 P 0 ;0
L 1.3697 -2.02545 1.40068002 -2.02545 0 P 0 ;0
L 1.36981998 -2.02445 1.41053996 -2.02445 0 P 0 ;0
L 1.36993996 -2.02345 1.47993996 -2.02345 0 P 0 ;0
L 1.37008002 -2.02245 1.47988002 -2.02245 0 P 0 ;0
L 1.37021004 -2.02145 1.47978002 -2.02145 0 P 0 ;0
L 1.37033996 -2.02045 1.47968002 -2.02045 0 P 0 ;0
L 1.37046998 -2.01945 1.47953002 -2.01945 0 P 0 ;0
L 1.3706 -2.01845 1.47936004 -2.01845 0 P 0 ;0
L 1.37073002 -2.01745 1.47918002 -2.01745 0 P 0 ;0
L 1.37086004 -2.01645 1.47893002 -2.01645 0 P 0 ;0
L 1.37098996 -2.01545 1.47868002 -2.01545 0 P 0 ;0
L 1.37113002 -2.01445 1.4784 -2.01445 0 P 0 ;0
L 1.37126998 -2.01345 1.47806004 -2.01345 0 P 0 ;0
L 1.3714 -2.01245 1.47773002 -2.01245 0 P 0 ;0
L 1.37153996 -2.01145 1.47733002 -2.01145 0 P 0 ;0
L 1.37168002 -2.01045 1.47691004 -2.01045 0 P 0 ;0
L 1.37181004 -2.00945 1.47641004 -2.00945 0 P 0 ;0
L 1.37195 -2.00845 1.47588996 -2.00845 0 P 0 ;0
L 1.37208002 -2.00745 1.47528002 -2.00745 0 P 0 ;0
L 1.37221004 -2.00645 1.47463996 -2.00645 0 P 0 ;0
L 1.37235 -2.00545 1.47391998 -2.00545 0 P 0 ;0
L 1.37248996 -2.00445 1.47311004 -2.00445 0 P 0 ;0
L 1.37261998 -2.00345 1.47225 -2.00345 0 P 0 ;0
L 1.37276004 -2.00245 1.47126998 -2.00245 0 P 0 ;0
L 1.3729 -2.00145 1.4702 -2.00145 0 P 0 ;0
L 1.37303002 -2.00045 1.46903996 -2.00045 0 P 0 ;0
L 1.37316998 -1.99945 1.46775 -1.99945 0 P 0 ;0
L 1.3733 -1.99845 1.46625 -1.99845 0 P 0 ;0
L 1.37343996 -1.99745 1.46455 -1.99745 0 P 0 ;0
L 1.37356998 -1.99645 1.46253996 -1.99645 0 P 0 ;0
L 1.37753002 -1.99545 1.46041004 -1.99545 0 P 0 ;0
L 1.38218996 -1.99445 1.45781004 -1.99445 0 P 0 ;0
L 1.42925 -2.08345 1.47785 -2.08345 0 P 0 ;0
L 1.42931998 -2.08245 1.47788996 -2.08245 0 P 0 ;0
L 1.42938002 -2.08145 1.47793002 -2.08145 0 P 0 ;0
L 1.42945 -2.08045 1.47796998 -2.08045 0 P 0 ;0
L 1.42951004 -2.07945 1.47801004 -2.07945 0 P 0 ;0
L 1.42958002 -2.07845 1.47806004 -2.07845 0 P 0 ;0
L 1.42963996 -2.07745 1.4781 -2.07745 0 P 0 ;0
L 1.4297 -2.07645 1.47815 -2.07645 0 P 0 ;0
L 1.42976998 -2.07545 1.4782 -2.07545 0 P 0 ;0
L 1.42983002 -2.07445 1.47825 -2.07445 0 P 0 ;0
L 1.4299 -2.07345 1.47828996 -2.07345 0 P 0 ;0
L 1.42963996 -2.07245 1.47833996 -2.07245 0 P 0 ;0
L 1.42918996 -2.07145 1.47838002 -2.07145 0 P 0 ;0
L 1.38425 -2.05145 1.47931004 -2.05145 0 P 0 ;0
L 1.38731998 -2.05045 1.47933996 -2.05045 0 P 0 ;0
L 1.39088002 -2.04945 1.47938002 -2.04945 0 P 0 ;0
L 1.3947 -2.04845 1.47941004 -2.04845 0 P 0 ;0
L 1.39851004 -2.04745 1.47945 -2.04745 0 P 0 ;0
L 1.40233002 -2.04645 1.47948002 -2.04645 0 P 0 ;0
L 1.40608002 -2.04545 1.47951004 -2.04545 0 P 0 ;0
L 1.40983002 -2.04445 1.47955 -2.04445 0 P 0 ;0
L 1.41306998 -2.04345 1.47958996 -2.04345 0 P 0 ;0
L 1.41591998 -2.04245 1.47961998 -2.04245 0 P 0 ;0
L 1.41876998 -2.04145 1.47965 -2.04145 0 P 0 ;0
L 1.42133996 -2.04045 1.47968996 -2.04045 0 P 0 ;0
L 1.42361998 -2.03945 1.47971998 -2.03945 0 P 0 ;0
L 1.42591004 -2.03845 1.47975 -2.03845 0 P 0 ;0
L 1.42805 -2.03745 1.47978002 -2.03745 0 P 0 ;0
L 1.42936004 -2.03645 1.47981004 -2.03645 0 P 0 ;0
L 1.43003002 -2.03545 1.47983002 -2.03545 0 P 0 ;0
L 1.43081998 -2.03445 1.47986004 -2.03445 0 P 0 ;0
L 1.43121004 -2.03345 1.47988002 -2.03345 0 P 0 ;0
L 1.43141998 -2.03245 1.4799 -2.03245 0 P 0 ;0
L 1.43146998 -2.03145 1.47993002 -2.03145 0 P 0 ;0
L 1.43136004 -2.03045 1.47996004 -2.03045 0 P 0 ;0
L 1.43108002 -2.02945 1.47998002 -2.02945 0 P 0 ;0
L 1.4306 -2.02845 1.48001004 -2.02845 0 P 0 ;0
L 1.42986998 -2.02745 1.48001004 -2.02745 0 P 0 ;0
L 1.42875 -2.02645 1.47998996 -2.02645 0 P 0 ;0
L 1.42658996 -2.02545 1.47996998 -2.02545 0 P 0 ;0
L 1.42203996 -2.02445 1.47996004 -2.02445 0 P 0 ;0
L 1.38748002 -1.99345 1.45483002 -1.99345 0 P 0 ;0
L 1.39331998 -1.99245 1.45108996 -1.99245 0 P 0 ;0
L 1.40051004 -1.99145 1.44503002 -1.99145 0 P 0 ;0
L 1.38096998 -2.12745 1.4051 -2.12745 0 P 0 ;0
L 1.37671004 -2.12645 1.41113996 -2.12645 0 P 0 ;0
L 1.3736 -2.12545 1.41238996 -2.12545 0 P 0 ;0
L 1.37096998 -2.12445 1.41268002 -2.12445 0 P 0 ;0
L 1.36876998 -2.12345 1.41296998 -2.12345 0 P 0 ;0
L 1.36685 -2.12245 1.41326998 -2.12245 0 P 0 ;0
L 1.36516004 -2.12145 1.41356004 -2.12145 0 P 0 ;0
L 1.36366004 -2.12045 1.41385 -2.12045 0 P 0 ;0
L 1.36225 -2.11945 1.41413996 -2.11945 0 P 0 ;0
L 1.361 -2.11845 1.41443002 -2.11845 0 P 0 ;0
L 1.35983002 -2.11745 1.41471998 -2.11745 0 P 0 ;0
L 1.35876004 -2.11645 1.41501004 -2.11645 0 P 0 ;0
L 1.42661998 -2.12445 1.47693002 -2.12445 0 P 0 ;0
L 1.42665 -2.12345 1.47693002 -2.12345 0 P 0 ;0
L 1.4267 -2.12245 1.47693002 -2.12245 0 P 0 ;0
L 1.42675 -2.12145 1.47693002 -2.12145 0 P 0 ;0
L 1.42681004 -2.12045 1.47693002 -2.12045 0 P 0 ;0
L 1.42686998 -2.11945 1.47693002 -2.11945 0 P 0 ;0
L 1.42691998 -2.11845 1.47693002 -2.11845 0 P 0 ;0
L 1.42698996 -2.11745 1.47693002 -2.11745 0 P 0 ;0
L 1.42705 -2.11645 1.47693002 -2.11645 0 P 0 ;0
L 1.42711004 -2.11545 1.47693002 -2.11545 0 P 0 ;0
L 1.42716998 -2.11445 1.47693002 -2.11445 0 P 0 ;0
L 1.42723002 -2.11345 1.47693996 -2.11345 0 P 0 ;0
L 1.4273 -2.11245 1.47695 -2.11245 0 P 0 ;0
L 1.42736998 -2.11145 1.47696004 -2.11145 0 P 0 ;0
L 1.42743996 -2.11045 1.47698002 -2.11045 0 P 0 ;0
L 1.42751004 -2.10945 1.47698996 -2.10945 0 P 0 ;0
L 1.42758002 -2.10845 1.47701004 -2.10845 0 P 0 ;0
L 1.42765 -2.10745 1.47703002 -2.10745 0 P 0 ;0
L 1.42771004 -2.10645 1.47703996 -2.10645 0 P 0 ;0
L 1.42778002 -2.10545 1.47706998 -2.10545 0 P 0 ;0
L 1.42783996 -2.10445 1.4771 -2.10445 0 P 0 ;0
L 1.42791004 -2.10345 1.47713002 -2.10345 0 P 0 ;0
L 1.42798002 -2.10245 1.47716004 -2.10245 0 P 0 ;0
L 1.42805 -2.10145 1.4772 -2.10145 0 P 0 ;0
L 1.42811004 -2.10045 1.47723002 -2.10045 0 P 0 ;0
L 1.40953002 -2.09945 1.41973002 -2.09945 0 P 0 ;0
L 1.42818002 -2.09945 1.47726004 -2.09945 0 P 0 ;0
L 1.41618002 -2.09845 1.41996998 -2.09845 0 P 0 ;0
L 1.42825 -2.09845 1.47728996 -2.09845 0 P 0 ;0
L 1.42831998 -2.09745 1.47733002 -2.09745 0 P 0 ;0
L 1.42838996 -2.09645 1.47736004 -2.09645 0 P 0 ;0
L 1.42846004 -2.09545 1.47738996 -2.09545 0 P 0 ;0
L 1.42851998 -2.09445 1.47741998 -2.09445 0 P 0 ;0
L 1.42858996 -2.09345 1.47746004 -2.09345 0 P 0 ;0
L 1.42866004 -2.09245 1.4775 -2.09245 0 P 0 ;0
L 1.42873002 -2.09145 1.47753996 -2.09145 0 P 0 ;0
L 1.42878996 -2.09045 1.47758002 -2.09045 0 P 0 ;0
L 1.42886004 -2.08945 1.47761998 -2.08945 0 P 0 ;0
L 1.42893002 -2.08845 1.47766004 -2.08845 0 P 0 ;0
L 1.42898996 -2.08745 1.4777 -2.08745 0 P 0 ;0
L 1.42906004 -2.08645 1.47773002 -2.08645 0 P 0 ;0
L 1.42911998 -2.08545 1.47776998 -2.08545 0 P 0 ;0
L 1.42918996 -2.08445 1.47781004 -2.08445 0 P 0 ;0
L 1.61686004 -2.17995 1.66846004 -2.17995 0 P 0 ;0
L 1.61591004 -2.17895 1.67158996 -2.17895 0 P 0 ;0
L 1.61553996 -2.17795 1.67431998 -2.17795 0 P 0 ;0
L 1.61526998 -2.17695 1.67675 -2.17695 0 P 0 ;0
L 1.61508002 -2.17595 1.67903996 -2.17595 0 P 0 ;0
L 1.61496998 -2.17495 1.68108002 -2.17495 0 P 0 ;0
L 1.61491004 -2.17395 1.68295 -2.17395 0 P 0 ;0
L 1.61485 -2.17295 1.68458996 -2.17295 0 P 0 ;0
L 1.61478996 -2.17195 1.6861 -2.17195 0 P 0 ;0
L 1.61473002 -2.17095 1.6875 -2.17095 0 P 0 ;0
L 1.61466998 -2.16995 1.68876998 -2.16995 0 P 0 ;0
L 1.61461004 -2.16895 1.68998002 -2.16895 0 P 0 ;0
L 1.61455 -2.16795 1.69108002 -2.16795 0 P 0 ;0
L 1.61448996 -2.16695 1.69211998 -2.16695 0 P 0 ;0
L 1.61443002 -2.16595 1.69316004 -2.16595 0 P 0 ;0
L 1.61436998 -2.16495 1.69411998 -2.16495 0 P 0 ;0
L 1.61431004 -2.16395 1.69498996 -2.16395 0 P 0 ;0
L 1.61425 -2.16295 1.69586004 -2.16295 0 P 0 ;0
L 1.61418996 -2.16195 1.69673002 -2.16195 0 P 0 ;0
L 1.61413002 -2.16095 1.69746998 -2.16095 0 P 0 ;0
L 1.61406998 -2.15995 1.6982 -2.15995 0 P 0 ;0
L 1.61401998 -2.15895 1.69893996 -2.15895 0 P 0 ;0
L 1.61396998 -2.15795 1.69963002 -2.15795 0 P 0 ;0
L 1.64433002 -2.18295 1.63151004 -2.18271004 0 P 0 ;0
L 1.63151004 -2.18271004 1.62658002 -2.18226998 0 P 0 ;0
L 1.62658002 -2.18226998 1.62168996 -2.18146998 0 P 0 ;0
L 1.62168996 -2.18146998 1.6201 -2.1811 0 P 0 ;0
L 1.6201 -2.1811 1.61853996 -2.18061004 0 P 0 ;0
L 1.61853996 -2.18061004 1.61701004 -2.18001998 0 P 0 ;0
L 1.61701004 -2.18001998 1.61686004 -2.17995 0 P 0 ;0
L 1.61686004 -2.17995 1.61671004 -2.17986998 0 P 0 ;0
L 1.61671004 -2.17986998 1.61656998 -2.17976998 0 P 0 ;0
L 1.61656998 -2.17976998 1.61643996 -2.17966998 0 P 0 ;0
L 1.61643996 -2.17966998 1.61631998 -2.17955 0 P 0 ;0
L 1.61631998 -2.17955 1.61621004 -2.17943002 0 P 0 ;0
L 1.61621004 -2.17943002 1.6161 -2.1793 0 P 0 ;0
L 1.6161 -2.1793 1.61601004 -2.17915 0 P 0 ;0
L 1.61601004 -2.17915 1.61593002 -2.179 0 P 0 ;0
L 1.61593002 -2.179 1.61586004 -2.17885 0 P 0 ;0
L 1.61586004 -2.17885 1.61553002 -2.17791004 0 P 0 ;0
L 1.61553002 -2.17791004 1.61526998 -2.17696004 0 P 0 ;0
L 1.61526998 -2.17696004 1.61508996 -2.17598996 0 P 0 ;0
L 1.61508996 -2.17598996 1.61496998 -2.17496998 0 P 0 ;0
L 1.61496998 -2.17496998 1.61408002 -2.16011004 0 P 0 ;0
L 1.61408002 -2.16011004 1.61341998 -2.14758996 0 P 0 ;0
L 1.61341998 -2.14758996 1.6202 -2.14821004 0 P 0 ;0
L 1.6202 -2.14821004 1.62023002 -2.14821004 0 P 0 ;0
L 1.62023002 -2.14821004 1.63216998 -2.14893996 0 P 0 ;0
L 1.63216998 -2.14893996 1.6349 -2.14893002 0 P 0 ;0
L 1.6349 -2.14893002 1.63761998 -2.14873002 0 P 0 ;0
L 1.63761998 -2.14873002 1.64031998 -2.14835 0 P 0 ;0
L 1.64031998 -2.14835 1.64198996 -2.14798996 0 P 0 ;0
L 1.64198996 -2.14798996 1.64363002 -2.14751998 0 P 0 ;0
L 1.64363002 -2.14751998 1.64523002 -2.14693002 0 P 0 ;0
L 1.64523002 -2.14693002 1.64678996 -2.14623002 0 P 0 ;0
L 1.64678996 -2.14623002 1.64888002 -2.14506998 0 P 0 ;0
L 1.64888002 -2.14506998 1.65086998 -2.14376004 0 P 0 ;0
L 1.65086998 -2.14376004 1.65093996 -2.14371004 0 P 0 ;0
L 1.65093996 -2.14371004 1.65275 -2.14228996 0 P 0 ;0
L 1.65275 -2.14228996 1.6539 -2.14123996 0 P 0 ;0
L 1.6539 -2.14123996 1.65496004 -2.14011004 0 P 0 ;0
L 1.65496004 -2.14011004 1.65591998 -2.13891004 0 P 0 ;0
L 1.65591998 -2.13891004 1.65755 -2.13653996 0 P 0 ;0
L 1.65755 -2.13653996 1.65901998 -2.13415 0 P 0 ;0
L 1.65901998 -2.13415 1.65903002 -2.13413002 0 P 0 ;0
L 1.65903002 -2.13413002 1.66035 -2.13171998 0 P 0 ;0
L 1.66035 -2.13171998 1.66155 -2.12925 0 P 0 ;0
L 1.66155 -2.12925 1.66183996 -2.12851998 0 P 0 ;0
L 1.66183996 -2.12851998 1.66206998 -2.12776004 0 P 0 ;0
L 1.66206998 -2.12776004 1.66223996 -2.12696998 0 P 0 ;0
L 1.66223996 -2.12696998 1.66233996 -2.12618002 0 P 0 ;0
L 1.66233996 -2.12618002 1.66236998 -2.12538996 0 P 0 ;0
L 1.66236998 -2.12538996 1.66233002 -2.12436004 0 P 0 ;0
L 1.66233002 -2.12436004 1.66221004 -2.12335 0 P 0 ;0
L 1.66221004 -2.12335 1.662 -2.12235 0 P 0 ;0
L 1.662 -2.12235 1.66171004 -2.12141004 0 P 0 ;0
L 1.66171004 -2.12141004 1.64438996 -2.07113002 0 P 0 ;0
L 1.64438996 -2.07113002 1.62871998 -2.02606004 0 P 0 ;0
L 1.62871998 -2.02606004 1.62116004 -2.00558996 0 P 0 ;0
L 1.62116004 -2.00558996 1.62116004 -2.00556998 0 P 0 ;0
L 1.62116004 -2.00556998 1.61681004 -1.99443996 0 P 0 ;0
L 1.61681004 -1.99443996 1.67163002 -1.99443996 0 P 0 ;0
L 1.67163002 -1.99443996 1.67301004 -2.00076004 0 P 0 ;0
L 1.67301004 -2.00076004 1.67613002 -2.01341998 0 P 0 ;0
L 1.67613002 -2.01341998 1.68331004 -2.03931998 0 P 0 ;0
L 1.68331004 -2.03931998 1.69153002 -2.06856998 0 P 0 ;0
L 1.69153002 -2.06856998 1.6916 -2.06876004 0 P 0 ;0
L 1.6916 -2.06876004 1.69168996 -2.06896998 0 P 0 ;0
L 1.69168996 -2.06896998 1.69181004 -2.06918002 0 P 0 ;0
L 1.69181004 -2.06918002 1.69193002 -2.06936998 0 P 0 ;0
L 1.69193002 -2.06936998 1.69208002 -2.06956004 0 P 0 ;0
L 1.69208002 -2.06956004 1.69223996 -2.06973002 0 P 0 ;0
L 1.69223996 -2.06973002 1.69241998 -2.06988002 0 P 0 ;0
L 1.69241998 -2.06988002 1.6926 -2.07001998 0 P 0 ;0
L 1.6926 -2.07001998 1.6928 -2.07015 0 P 0 ;0
L 1.6928 -2.07015 1.69301004 -2.07025 0 P 0 ;0
L 1.69301004 -2.07025 1.69323002 -2.07033996 0 P 0 ;0
L 1.69323002 -2.07033996 1.69346004 -2.07041004 0 P 0 ;0
L 1.69346004 -2.07041004 1.69368002 -2.07045 0 P 0 ;0
L 1.69368002 -2.07045 1.69391998 -2.07048002 0 P 0 ;0
L 1.69391998 -2.07048002 1.69413996 -2.07048996 0 P 0 ;0
L 1.69413996 -2.07048996 1.6944 -2.07048002 0 P 0 ;0
L 1.6944 -2.07048002 1.69465 -2.07045 0 P 0 ;0
L 1.69465 -2.07045 1.69488996 -2.07038996 0 P 0 ;0
L 1.69488996 -2.07038996 1.69513996 -2.07031998 0 P 0 ;0
L 1.69513996 -2.07031998 1.69536998 -2.07021998 0 P 0 ;0
L 1.69536998 -2.07021998 1.69558996 -2.0701 0 P 0 ;0
L 1.69558996 -2.0701 1.69581004 -2.06996998 0 P 0 ;0
L 1.69581004 -2.06996998 1.69601004 -2.06981998 0 P 0 ;0
L 1.69601004 -2.06981998 1.6962 -2.06965 0 P 0 ;0
L 1.6962 -2.06965 1.69636998 -2.06946004 0 P 0 ;0
L 1.69636998 -2.06946004 1.69653002 -2.06926004 0 P 0 ;0
L 1.69653002 -2.06926004 1.69666004 -2.06905 0 P 0 ;0
L 1.69666004 -2.06905 1.69678996 -2.06883002 0 P 0 ;0
L 1.69678996 -2.06883002 1.69688002 -2.0686 0 P 0 ;0
L 1.69688002 -2.0686 1.69695 -2.0684 0 P 0 ;0
L 1.69695 -2.0684 1.70426004 -2.04365 0 P 0 ;0
L 1.70426004 -2.04365 1.70426004 -2.04363002 0 P 0 ;0
L 1.70426004 -2.04363002 1.71066998 -2.0213 0 P 0 ;0
L 1.71066998 -2.0213 1.71068002 -2.02126004 0 P 0 ;0
L 1.71068002 -2.02126004 1.71431998 -2.00693996 0 P 0 ;0
L 1.71431998 -2.00693996 1.71706004 -1.99496998 0 P 0 ;0
L 1.71706004 -1.99496998 1.74335 -1.9947 0 P 0 ;0
L 1.74335 -1.9947 1.75403002 -1.99461004 0 P 0 ;0
L 1.75403002 -1.99461004 1.76301004 -1.99465 0 P 0 ;0
L 1.76301004 -1.99465 1.76886004 -1.99471004 0 P 0 ;0
L 1.76886004 -1.99471004 1.76883996 -1.99476004 0 P 0 ;0
L 1.76883996 -1.99476004 1.74021004 -2.06556004 0 P 0 ;0
L 1.74021004 -2.06556004 1.71298002 -2.13276998 0 P 0 ;0
L 1.71298002 -2.13276998 1.70836998 -2.14293996 0 P 0 ;0
L 1.70836998 -2.14293996 1.70413996 -2.15076004 0 P 0 ;0
L 1.70413996 -2.15076004 1.69941998 -2.15828996 0 P 0 ;0
L 1.69941998 -2.15828996 1.6967 -2.16198996 0 P 0 ;0
L 1.6967 -2.16198996 1.6937 -2.16541998 0 P 0 ;0
L 1.6937 -2.16541998 1.69041998 -2.1686 0 P 0 ;0
L 1.69041998 -2.1686 1.68793996 -2.17063002 0 P 0 ;0
L 1.68793996 -2.17063002 1.68535 -2.17248002 0 P 0 ;0
L 1.68535 -2.17248002 1.68263996 -2.17413996 0 P 0 ;0
L 1.68263996 -2.17413996 1.67981004 -2.17561004 0 P 0 ;0
L 1.67981004 -2.17561004 1.67525 -2.17761004 0 P 0 ;0
L 1.67525 -2.17761004 1.6706 -2.17931998 0 P 0 ;0
L 1.6706 -2.17931998 1.66586004 -2.18073002 0 P 0 ;0
L 1.66586004 -2.18073002 1.66141998 -2.1817 0 P 0 ;0
L 1.66141998 -2.1817 1.65691998 -2.18228996 0 P 0 ;0
L 1.65691998 -2.18228996 1.64433002 -2.18295 0 P 0 ;0
L 1.61928996 -2.00628002 1.62683996 -2.02673002 0 P 0 ;0
L 1.62683996 -2.02673002 1.6425 -2.07178002 0 P 0 ;0
L 1.6425 -2.07178002 1.65981004 -2.12201998 0 P 0 ;0
L 1.65981004 -2.12201998 1.66006004 -2.12283996 0 P 0 ;0
L 1.66006004 -2.12283996 1.66023002 -2.12368002 0 P 0 ;0
L 1.66023002 -2.12368002 1.66033996 -2.12451998 0 P 0 ;0
L 1.66033996 -2.12451998 1.66036998 -2.12538002 0 P 0 ;0
L 1.66036998 -2.12538002 1.66033996 -2.12601004 0 P 0 ;0
L 1.66033996 -2.12601004 1.66026998 -2.12663996 0 P 0 ;0
L 1.66026998 -2.12663996 1.66013996 -2.12725 0 P 0 ;0
L 1.66013996 -2.12725 1.65995 -2.12786004 0 P 0 ;0
L 1.65995 -2.12786004 1.65971004 -2.12843996 0 P 0 ;0
L 1.65971004 -2.12843996 1.65856998 -2.1308 0 P 0 ;0
L 1.65856998 -2.1308 1.6573 -2.13313002 0 P 0 ;0
L 1.6573 -2.13313002 1.65586998 -2.13545 0 P 0 ;0
L 1.65586998 -2.13545 1.65431004 -2.13771998 0 P 0 ;0
L 1.65431004 -2.13771998 1.65343996 -2.1388 0 P 0 ;0
L 1.65343996 -2.1388 1.65248996 -2.13981998 0 P 0 ;0
L 1.65248996 -2.13981998 1.65146004 -2.14076004 0 P 0 ;0
L 1.65146004 -2.14076004 1.64971004 -2.14213002 0 P 0 ;0
L 1.64971004 -2.14213002 1.64785 -2.14336004 0 P 0 ;0
L 1.64785 -2.14336004 1.64588996 -2.14443996 0 P 0 ;0
L 1.64588996 -2.14443996 1.64446998 -2.14508002 0 P 0 ;0
L 1.64446998 -2.14508002 1.64301004 -2.14561998 0 P 0 ;0
L 1.64301004 -2.14561998 1.64151004 -2.14605 0 P 0 ;0
L 1.64151004 -2.14605 1.63996998 -2.14636998 0 P 0 ;0
L 1.63996998 -2.14636998 1.63741004 -2.14673996 0 P 0 ;0
L 1.63741004 -2.14673996 1.63483002 -2.14693002 0 P 0 ;0
L 1.63483002 -2.14693002 1.63223002 -2.14693996 0 P 0 ;0
L 1.63223002 -2.14693996 1.62036004 -2.14621998 0 P 0 ;0
L 1.62036004 -2.14621998 1.6113 -2.14538002 0 P 0 ;0
L 1.6113 -2.14538002 1.61208996 -2.16023002 0 P 0 ;0
L 1.61208996 -2.16023002 1.61298002 -2.17515 0 P 0 ;0
L 1.61298002 -2.17515 1.6131 -2.17628002 0 P 0 ;0
L 1.6131 -2.17628002 1.61331998 -2.17741004 0 P 0 ;0
L 1.61331998 -2.17741004 1.61361998 -2.17851004 0 P 0 ;0
L 1.61361998 -2.17851004 1.614 -2.17958996 0 P 0 ;0
L 1.614 -2.17958996 1.61413996 -2.17988996 0 P 0 ;0
L 1.61413996 -2.17988996 1.61428996 -2.18018002 0 P 0 ;0
L 1.61428996 -2.18018002 1.61446998 -2.18045 0 P 0 ;0
L 1.61446998 -2.18045 1.61466998 -2.18071004 0 P 0 ;0
L 1.61466998 -2.18071004 1.61488996 -2.18095 0 P 0 ;0
L 1.61488996 -2.18095 1.61511998 -2.18116998 0 P 0 ;0
L 1.61511998 -2.18116998 1.61538002 -2.18138002 0 P 0 ;0
L 1.61538002 -2.18138002 1.61565 -2.18156004 0 P 0 ;0
L 1.61565 -2.18156004 1.61593002 -2.18173002 0 P 0 ;0
L 1.61593002 -2.18173002 1.61623002 -2.18186004 0 P 0 ;0
L 1.61623002 -2.18186004 1.61788002 -2.1825 0 P 0 ;0
L 1.61788002 -2.1825 1.61956998 -2.18301998 0 P 0 ;0
L 1.61956998 -2.18301998 1.6213 -2.18343002 0 P 0 ;0
L 1.6213 -2.18343002 1.62633002 -2.18426004 0 P 0 ;0
L 1.62633002 -2.18426004 1.6314 -2.18471004 0 P 0 ;0
L 1.6314 -2.18471004 1.64436004 -2.18495 0 P 0 ;0
L 1.64436004 -2.18495 1.65711004 -2.18428002 0 P 0 ;0
L 1.65711004 -2.18428002 1.66176998 -2.18366998 0 P 0 ;0
L 1.66176998 -2.18366998 1.66636004 -2.18266998 0 P 0 ;0
L 1.66636004 -2.18266998 1.67123002 -2.18121004 0 P 0 ;0
L 1.67123002 -2.18121004 1.676 -2.17946998 0 P 0 ;0
L 1.676 -2.17946998 1.68068002 -2.17741998 0 P 0 ;0
L 1.68068002 -2.17741998 1.68361998 -2.17588002 0 P 0 ;0
L 1.68361998 -2.17588002 1.68646004 -2.17415 0 P 0 ;0
L 1.68646004 -2.17415 1.68916004 -2.17221998 0 P 0 ;0
L 1.68916004 -2.17221998 1.69175 -2.17008996 0 P 0 ;0
L 1.69175 -2.17008996 1.69515 -2.1668 0 P 0 ;0
L 1.69515 -2.1668 1.69826004 -2.16323996 0 P 0 ;0
L 1.69826004 -2.16323996 1.70108002 -2.15941998 0 P 0 ;0
L 1.70108002 -2.15941998 1.70586004 -2.15176998 0 P 0 ;0
L 1.70586004 -2.15176998 1.71016004 -2.14383002 0 P 0 ;0
L 1.71016004 -2.14383002 1.71481998 -2.13356004 0 P 0 ;0
L 1.71481998 -2.13356004 1.74206998 -2.06631004 0 P 0 ;0
L 1.74206998 -2.06631004 1.77071004 -1.99548002 0 P 0 ;0
L 1.77071004 -1.99548002 1.77088002 -1.99498996 0 P 0 ;0
L 1.77088002 -1.99498996 1.77101998 -1.99448996 0 P 0 ;0
L 1.77101998 -1.99448996 1.77111998 -1.99398996 0 P 0 ;0
L 1.77111998 -1.99398996 1.77118002 -1.99346998 0 P 0 ;0
L 1.77118002 -1.99346998 1.7712 -1.99295 0 P 0 ;0
L 1.7712 -1.99295 1.7712 -1.99293002 0 P 0 ;0
L 1.7712 -1.99293002 1.77118996 -1.99286998 0 P 0 ;0
L 1.77118996 -1.99286998 1.77118002 -1.99286004 0 P 0 ;0
L 1.77118002 -1.99286004 1.77118002 -1.99283996 0 P 0 ;0
L 1.77118002 -1.99283996 1.77111004 -1.99276998 0 P 0 ;0
L 1.77111004 -1.99276998 1.77106998 -1.99275 0 P 0 ;0
L 1.77106998 -1.99275 1.77106004 -1.99273996 0 P 0 ;0
L 1.77106004 -1.99273996 1.771 -1.99273002 0 P 0 ;0
L 1.771 -1.99273002 1.77098002 -1.99273002 0 P 0 ;0
L 1.77098002 -1.99273002 1.76301004 -1.99265 0 P 0 ;0
L 1.76301004 -1.99265 1.75401998 -1.99261004 0 P 0 ;0
L 1.75401998 -1.99261004 1.74333002 -1.9927 0 P 0 ;0
L 1.74333002 -1.9927 1.71546004 -1.99298996 0 P 0 ;0
L 1.71546004 -1.99298996 1.71236998 -2.00646998 0 P 0 ;0
L 1.71236998 -2.00646998 1.70873996 -2.02078002 0 P 0 ;0
L 1.70873996 -2.02078002 1.70233996 -2.04308002 0 P 0 ;0
L 1.70233996 -2.04308002 1.69505 -2.0678 0 P 0 ;0
L 1.69505 -2.0678 1.69501998 -2.06788002 0 P 0 ;0
L 1.69501998 -2.06788002 1.69498996 -2.06795 0 P 0 ;0
L 1.69498996 -2.06795 1.69495 -2.06801998 0 P 0 ;0
L 1.69495 -2.06801998 1.69485 -2.06816004 0 P 0 ;0
L 1.69485 -2.06816004 1.69478996 -2.06821998 0 P 0 ;0
L 1.69478996 -2.06821998 1.69466998 -2.06831998 0 P 0 ;0
L 1.69466998 -2.06831998 1.69453002 -2.0684 0 P 0 ;0
L 1.69453002 -2.0684 1.69445 -2.06843002 0 P 0 ;0
L 1.69445 -2.06843002 1.69438002 -2.06846004 0 P 0 ;0
L 1.69438002 -2.06846004 1.69428996 -2.06846998 0 P 0 ;0
L 1.69428996 -2.06846998 1.69421004 -2.06848996 0 P 0 ;0
L 1.69421004 -2.06848996 1.69406998 -2.06848996 0 P 0 ;0
L 1.69406998 -2.06848996 1.69395 -2.06846998 0 P 0 ;0
L 1.69395 -2.06846998 1.69383002 -2.06843002 0 P 0 ;0
L 1.69383002 -2.06843002 1.69373002 -2.06836998 0 P 0 ;0
L 1.69373002 -2.06836998 1.69363002 -2.06828996 0 P 0 ;0
L 1.69363002 -2.06828996 1.69358996 -2.06823996 0 P 0 ;0
L 1.69358996 -2.06823996 1.69355 -2.0682 0 P 0 ;0
L 1.69355 -2.0682 1.69351998 -2.06815 0 P 0 ;0
L 1.69351998 -2.06815 1.69346004 -2.06803996 0 P 0 ;0
L 1.69346004 -2.06803996 1.69343996 -2.06798002 0 P 0 ;0
L 1.69343996 -2.06798002 1.68523002 -2.03878002 0 P 0 ;0
L 1.68523002 -2.03878002 1.67806998 -2.01291998 0 P 0 ;0
L 1.67806998 -2.01291998 1.67496004 -2.00031004 0 P 0 ;0
L 1.67496004 -2.00031004 1.67323002 -1.99243996 0 P 0 ;0
L 1.67323002 -1.99243996 1.61388002 -1.99243996 0 P 0 ;0
L 1.61388002 -1.99243996 1.61928996 -2.00628002 0 P 0 ;0
L 1.35018002 -2.08345 1.39488996 -2.08345 0 P 0 ;0
L 1.35026004 -2.08245 1.39586004 -2.08245 0 P 0 ;0
L 1.35041004 -2.08145 1.39708996 -2.08145 0 P 0 ;0
L 1.35058996 -2.08045 1.39853002 -2.08045 0 P 0 ;0
L 1.35083996 -2.07945 1.40031998 -2.07945 0 P 0 ;0
L 1.35116998 -2.07845 1.40271004 -2.07845 0 P 0 ;0
L 1.35158002 -2.07745 1.40561998 -2.07745 0 P 0 ;0
L 1.35203002 -2.07645 1.4092 -2.07645 0 P 0 ;0
L 1.35248002 -2.07545 1.41288996 -2.07545 0 P 0 ;0
L 1.35293002 -2.07445 1.4164 -2.07445 0 P 0 ;0
L 1.35338996 -2.07345 1.41975 -2.07345 0 P 0 ;0
L 1.35393996 -2.07245 1.42293996 -2.07245 0 P 0 ;0
L 1.35448996 -2.07145 1.42606998 -2.07145 0 P 0 ;0
L 1.35505 -2.07045 1.47843002 -2.07045 0 P 0 ;0
L 1.3557 -2.06945 1.47846998 -2.06945 0 P 0 ;0
L 1.35635 -2.06845 1.47851998 -2.06845 0 P 0 ;0
L 1.35701998 -2.06745 1.47856998 -2.06745 0 P 0 ;0
L 1.35776998 -2.06645 1.47861004 -2.06645 0 P 0 ;0
L 1.29346998 -2.00516004 1.33388996 -2.00516004 0 P 0 ;0
L 1.29448996 -2.00416004 1.33385 -2.00416004 0 P 0 ;0
L 1.29551004 -2.00316004 1.33381004 -2.00316004 0 P 0 ;0
L 1.29653996 -2.00216004 1.33376004 -2.00216004 0 P 0 ;0
L 1.29756004 -2.00116004 1.33371004 -2.00116004 0 P 0 ;0
L 1.29861998 -2.00016004 1.33366004 -2.00016004 0 P 0 ;0
L 1.29973002 -1.99916004 1.3336 -1.99916004 0 P 0 ;0
L 1.30101004 -1.99816004 1.33355 -1.99816004 0 P 0 ;0
L 1.30238996 -1.99716004 1.3335 -1.99716004 0 P 0 ;0
L 1.30393996 -1.99616004 1.33345 -1.99616004 0 P 0 ;0
L 1.30571004 -1.99516004 1.33338996 -1.99516004 0 P 0 ;0
L 1.3077 -1.99416004 1.33333002 -1.99416004 0 P 0 ;0
L 1.31001004 -1.99316004 1.33328002 -1.99316004 0 P 0 ;0
L 1.31288002 -1.99216004 1.33321998 -1.99216004 0 P 0 ;0
L 1.31688996 -1.99116004 1.33316004 -1.99116004 0 P 0 ;0
L 1.39798996 -1.98971998 1.39326998 -1.99043002 0 P 0 ;0
L 1.39326998 -1.99043002 1.38806998 -1.9913 0 P 0 ;0
L 1.38806998 -1.9913 1.38316004 -1.9922 0 P 0 ;0
L 1.38316004 -1.9922 1.37946004 -1.99296998 0 P 0 ;0
L 1.37946004 -1.99296998 1.3718 -1.99466998 0 P 0 ;0
L 1.3718 -1.99466998 1.36896004 -2.01553996 0 P 0 ;0
L 1.36896004 -2.01553996 1.36791004 -2.02358996 0 P 0 ;0
L 1.36791004 -2.02358996 1.36708002 -2.03043002 0 P 0 ;0
L 1.36708002 -2.03043002 1.36638996 -2.03646004 0 P 0 ;0
L 1.36638996 -2.03646004 1.36638002 -2.03648996 0 P 0 ;0
L 1.36638002 -2.03648996 1.36638996 -2.03653002 0 P 0 ;0
L 1.36638996 -2.03653002 1.36638996 -2.03656998 0 P 0 ;0
L 1.36638996 -2.03656998 1.3664 -2.03663996 0 P 0 ;0
L 1.3664 -2.03663996 1.36641998 -2.03666998 0 P 0 ;0
L 1.36641998 -2.03666998 1.36643002 -2.03671004 0 P 0 ;0
L 1.36643002 -2.03671004 1.36648996 -2.0368 0 P 0 ;0
L 1.36648996 -2.0368 1.36656004 -2.03686004 0 P 0 ;0
L 1.36656004 -2.03686004 1.3666 -2.03688996 0 P 0 ;0
L 1.3666 -2.03688996 1.36663002 -2.03691004 0 P 0 ;0
L 1.36663002 -2.03691004 1.36666004 -2.03691004 0 P 0 ;0
L 1.36666004 -2.03691004 1.36671004 -2.03693002 0 P 0 ;0
L 1.36671004 -2.03693002 1.36676998 -2.03693002 0 P 0 ;0
L 1.36676998 -2.03693002 1.36685 -2.03691998 0 P 0 ;0
L 1.36685 -2.03691998 1.36895 -2.03628002 0 P 0 ;0
L 1.36895 -2.03628002 1.37143002 -2.03545 0 P 0 ;0
L 1.37143002 -2.03545 1.37428996 -2.03441004 0 P 0 ;0
L 1.37428996 -2.03441004 1.38346004 -2.03126998 0 P 0 ;0
L 1.38346004 -2.03126998 1.39251998 -2.02891998 0 P 0 ;0
L 1.39251998 -2.02891998 1.40156004 -2.02731998 0 P 0 ;0
L 1.40156004 -2.02731998 1.41068002 -2.02643996 0 P 0 ;0
L 1.41068002 -2.02643996 1.41566998 -2.02628002 0 P 0 ;0
L 1.41566998 -2.02628002 1.42066004 -2.02633996 0 P 0 ;0
L 1.42066004 -2.02633996 1.42221004 -2.02646998 0 P 0 ;0
L 1.42221004 -2.02646998 1.42375 -2.02671998 0 P 0 ;0
L 1.42375 -2.02671998 1.42525 -2.0271 0 P 0 ;0
L 1.42525 -2.0271 1.42671998 -2.02761004 0 P 0 ;0
L 1.42671998 -2.02761004 1.42706004 -2.02776004 0 P 0 ;0
L 1.42706004 -2.02776004 1.42738002 -2.02793002 0 P 0 ;0
L 1.42738002 -2.02793002 1.42768002 -2.02813996 0 P 0 ;0
L 1.42768002 -2.02813996 1.42796998 -2.02836004 0 P 0 ;0
L 1.42796998 -2.02836004 1.42823002 -2.02861004 0 P 0 ;0
L 1.42823002 -2.02861004 1.42848002 -2.02888996 0 P 0 ;0
L 1.42848002 -2.02888996 1.4287 -2.02918002 0 P 0 ;0
L 1.4287 -2.02918002 1.42888996 -2.02948996 0 P 0 ;0
L 1.42888996 -2.02948996 1.42906004 -2.02981004 0 P 0 ;0
L 1.42906004 -2.02981004 1.4292 -2.03015 0 P 0 ;0
L 1.4292 -2.03015 1.42931998 -2.0305 0 P 0 ;0
L 1.42931998 -2.0305 1.4294 -2.03086004 0 P 0 ;0
L 1.4294 -2.03086004 1.42945 -2.03121998 0 P 0 ;0
L 1.42945 -2.03121998 1.42946998 -2.03158002 0 P 0 ;0
L 1.42946998 -2.03158002 1.42946004 -2.03195 0 P 0 ;0
L 1.42946004 -2.03195 1.42941998 -2.03231004 0 P 0 ;0
L 1.42941998 -2.03231004 1.42935 -2.03266998 0 P 0 ;0
L 1.42935 -2.03266998 1.42925 -2.03301998 0 P 0 ;0
L 1.42925 -2.03301998 1.42911998 -2.03336004 0 P 0 ;0
L 1.42911998 -2.03336004 1.42896004 -2.03368996 0 P 0 ;0
L 1.42896004 -2.03368996 1.42875 -2.03405 0 P 0 ;0
L 1.42875 -2.03405 1.42851004 -2.03438996 0 P 0 ;0
L 1.42851004 -2.03438996 1.42825 -2.03471004 0 P 0 ;0
L 1.42825 -2.03471004 1.42796004 -2.03501004 0 P 0 ;0
L 1.42796004 -2.03501004 1.42765 -2.03528996 0 P 0 ;0
L 1.42765 -2.03528996 1.42731998 -2.03553996 0 P 0 ;0
L 1.42731998 -2.03553996 1.42696998 -2.03576004 0 P 0 ;0
L 1.42696998 -2.03576004 1.4266 -2.03596004 0 P 0 ;0
L 1.4266 -2.03596004 1.41951004 -2.03906004 0 P 0 ;0
L 1.41951004 -2.03906004 1.4109 -2.04208996 0 P 0 ;0
L 1.4109 -2.04208996 1.40178002 -2.04451998 0 P 0 ;0
L 1.40178002 -2.04451998 1.3878 -2.04818996 0 P 0 ;0
L 1.3878 -2.04818996 1.38176998 -2.05015 0 P 0 ;0
L 1.38176998 -2.05015 1.3758 -2.05243002 0 P 0 ;0
L 1.3758 -2.05243002 1.37086998 -2.0546 0 P 0 ;0
L 1.37086998 -2.0546 1.36603996 -2.05708002 0 P 0 ;0
L 1.36603996 -2.05708002 1.36356004 -2.05856004 0 P 0 ;0
L 1.36356004 -2.05856004 1.36118996 -2.06023002 0 P 0 ;0
L 1.36118996 -2.06023002 1.35895 -2.06206004 0 P 0 ;0
L 1.35895 -2.06206004 1.35805 -2.06291004 0 P 0 ;0
L 1.35805 -2.06291004 1.35721998 -2.06385 0 P 0 ;0
L 1.35721998 -2.06385 1.35518996 -2.06655 0 P 0 ;0
L 1.35518996 -2.06655 1.3532 -2.06961998 0 P 0 ;0
L 1.3532 -2.06961998 1.35156004 -2.07263002 0 P 0 ;0
L 1.35156004 -2.07263002 1.34951004 -2.07718002 0 P 0 ;0
L 1.34951004 -2.07718002 1.34911004 -2.07825 0 P 0 ;0
L 1.34911004 -2.07825 1.34878996 -2.07935 0 P 0 ;0
L 1.34878996 -2.07935 1.34853002 -2.08046998 0 P 0 ;0
L 1.34853002 -2.08046998 1.34825 -2.08238002 0 P 0 ;0
L 1.34825 -2.08238002 1.34811998 -2.08431004 0 P 0 ;0
L 1.34811998 -2.08431004 1.348 -2.09128996 0 P 0 ;0
L 1.348 -2.09128996 1.3481 -2.09761004 0 P 0 ;0
L 1.3481 -2.09761004 1.34823002 -2.09961004 0 P 0 ;0
L 1.34823002 -2.09961004 1.34846998 -2.10161004 0 P 0 ;0
L 1.34846998 -2.10161004 1.34876998 -2.10321998 0 P 0 ;0
L 1.34876998 -2.10321998 1.3492 -2.10478996 0 P 0 ;0
L 1.3492 -2.10478996 1.3498 -2.10648996 0 P 0 ;0
L 1.3498 -2.10648996 1.3505 -2.10815 0 P 0 ;0
L 1.3505 -2.10815 1.35178996 -2.11066004 0 P 0 ;0
L 1.35178996 -2.11066004 1.35328002 -2.11305 0 P 0 ;0
L 1.35328002 -2.11305 1.35496998 -2.1153 0 P 0 ;0
L 1.35496998 -2.1153 1.35685 -2.1174 0 P 0 ;0
L 1.35685 -2.1174 1.35891998 -2.11933996 0 P 0 ;0
L 1.35891998 -2.11933996 1.36126998 -2.12121998 0 P 0 ;0
L 1.36126998 -2.12121998 1.36373996 -2.12293002 0 P 0 ;0
L 1.36373996 -2.12293002 1.36633002 -2.12446004 0 P 0 ;0
L 1.36633002 -2.12446004 1.36901004 -2.1258 0 P 0 ;0
L 1.36901004 -2.1258 1.3718 -2.12695 0 P 0 ;0
L 1.3718 -2.12695 1.37578996 -2.12828002 0 P 0 ;0
L 1.37578996 -2.12828002 1.37986998 -2.12928996 0 P 0 ;0
L 1.37986998 -2.12928996 1.38401998 -2.12998996 0 P 0 ;0
L 1.38401998 -2.12998996 1.3882 -2.13036004 0 P 0 ;0
L 1.3882 -2.13036004 1.39443002 -2.13045 0 P 0 ;0
L 1.39443002 -2.13045 1.40066004 -2.13006998 0 P 0 ;0
L 1.40066004 -2.13006998 1.40685 -2.12923002 0 P 0 ;0
L 1.40685 -2.12923002 1.41371004 -2.12801998 0 P 0 ;0
L 1.41371004 -2.12801998 1.41583002 -2.12081004 0 P 0 ;0
L 1.41583002 -2.12081004 1.41953996 -2.10798996 0 P 0 ;0
L 1.41953996 -2.10798996 1.42135 -2.10126998 0 P 0 ;0
L 1.42135 -2.10126998 1.42236998 -2.097 0 P 0 ;0
L 1.42236998 -2.097 1.42238996 -2.09691004 0 P 0 ;0
L 1.42238996 -2.09691004 1.4224 -2.09681998 0 P 0 ;0
L 1.4224 -2.09681998 1.4224 -2.09673996 0 P 0 ;0
L 1.4224 -2.09673996 1.42238002 -2.09656004 0 P 0 ;0
L 1.42238002 -2.09656004 1.42235 -2.09648002 0 P 0 ;0
L 1.42235 -2.09648002 1.42233002 -2.09638996 0 P 0 ;0
L 1.42233002 -2.09638996 1.42225 -2.09623002 0 P 0 ;0
L 1.42225 -2.09623002 1.4222 -2.09616004 0 P 0 ;0
L 1.4222 -2.09616004 1.42213996 -2.09608996 0 P 0 ;0
L 1.42213996 -2.09608996 1.42208996 -2.09601998 0 P 0 ;0
L 1.42208996 -2.09601998 1.42203996 -2.09598996 0 P 0 ;0
L 1.42203996 -2.09598996 1.42198996 -2.09595 0 P 0 ;0
L 1.42198996 -2.09595 1.42188996 -2.09588996 0 P 0 ;0
L 1.42188996 -2.09588996 1.42183002 -2.09586004 0 P 0 ;0
L 1.42183002 -2.09586004 1.42178002 -2.09585 0 P 0 ;0
L 1.42178002 -2.09585 1.42171998 -2.09583002 0 P 0 ;0
L 1.42171998 -2.09583002 1.42166004 -2.09581998 0 P 0 ;0
L 1.42166004 -2.09581998 1.42153996 -2.09581998 0 P 0 ;0
L 1.42153996 -2.09581998 1.41978002 -2.09591004 0 P 0 ;0
L 1.41978002 -2.09591004 1.41763996 -2.09615 0 P 0 ;0
L 1.41763996 -2.09615 1.41521998 -2.09658002 0 P 0 ;0
L 1.41521998 -2.09658002 1.4107 -2.09733002 0 P 0 ;0
L 1.4107 -2.09733002 1.40613002 -2.09775 0 P 0 ;0
L 1.40613002 -2.09775 1.40481004 -2.09778002 0 P 0 ;0
L 1.40481004 -2.09778002 1.40348996 -2.09771998 0 P 0 ;0
L 1.40348996 -2.09771998 1.40216998 -2.09756004 0 P 0 ;0
L 1.40216998 -2.09756004 1.40086998 -2.0973 0 P 0 ;0
L 1.40086998 -2.0973 1.39958996 -2.09695 0 P 0 ;0
L 1.39958996 -2.09695 1.39895 -2.09671998 0 P 0 ;0
L 1.39895 -2.09671998 1.39831998 -2.09643002 0 P 0 ;0
L 1.39831998 -2.09643002 1.39773002 -2.0961 0 P 0 ;0
L 1.39773002 -2.0961 1.39716004 -2.09571004 0 P 0 ;0
L 1.39716004 -2.09571004 1.39663002 -2.09528002 0 P 0 ;0
L 1.39663002 -2.09528002 1.39613996 -2.0948 0 P 0 ;0
L 1.39613996 -2.0948 1.39568002 -2.09428002 0 P 0 ;0
L 1.39568002 -2.09428002 1.39533996 -2.09381998 0 P 0 ;0
L 1.39533996 -2.09381998 1.39505 -2.09333996 0 P 0 ;0
L 1.39505 -2.09333996 1.39478996 -2.09281998 0 P 0 ;0
L 1.39478996 -2.09281998 1.39456998 -2.09228996 0 P 0 ;0
L 1.39456998 -2.09228996 1.3944 -2.09173996 0 P 0 ;0
L 1.3944 -2.09173996 1.39428002 -2.09118996 0 P 0 ;0
L 1.39428002 -2.09118996 1.39421004 -2.09061998 0 P 0 ;0
L 1.39421004 -2.09061998 1.39418002 -2.09003996 0 P 0 ;0
L 1.39418002 -2.09003996 1.39421004 -2.08943002 0 P 0 ;0
L 1.39421004 -2.08943002 1.39428002 -2.08883002 0 P 0 ;0
L 1.39428002 -2.08883002 1.39441004 -2.08823002 0 P 0 ;0
L 1.39441004 -2.08823002 1.3946 -2.08765 0 P 0 ;0
L 1.3946 -2.08765 1.39483002 -2.08708002 0 P 0 ;0
L 1.39483002 -2.08708002 1.39511004 -2.08653996 0 P 0 ;0
L 1.39511004 -2.08653996 1.39555 -2.08583996 0 P 0 ;0
L 1.39555 -2.08583996 1.39603996 -2.08518002 0 P 0 ;0
L 1.39603996 -2.08518002 1.39658002 -2.08456004 0 P 0 ;0
L 1.39658002 -2.08456004 1.39716004 -2.08396998 0 P 0 ;0
L 1.39716004 -2.08396998 1.39778002 -2.08343002 0 P 0 ;0
L 1.39778002 -2.08343002 1.39878996 -2.08266998 0 P 0 ;0
L 1.39878996 -2.08266998 1.39985 -2.08196998 0 P 0 ;0
L 1.39985 -2.08196998 1.40096004 -2.08135 0 P 0 ;0
L 1.40096004 -2.08135 1.40211998 -2.08081004 0 P 0 ;0
L 1.40211998 -2.08081004 1.40503002 -2.07971004 0 P 0 ;0
L 1.40503002 -2.07971004 1.40801998 -2.07881998 0 P 0 ;0
L 1.40801998 -2.07881998 1.41128996 -2.07796004 0 P 0 ;0
L 1.41128996 -2.07796004 1.41506004 -2.07691998 0 P 0 ;0
L 1.41506004 -2.07691998 1.41871998 -2.07585 0 P 0 ;0
L 1.41871998 -2.07585 1.42165 -2.07495 0 P 0 ;0
L 1.42165 -2.07495 1.42791998 -2.07295 0 P 0 ;0
L 1.42791998 -2.07295 1.42731998 -2.08241004 0 P 0 ;0
L 1.42731998 -2.08241004 1.42701004 -2.08708002 0 P 0 ;0
L 1.42701004 -2.08708002 1.42658002 -2.09353996 0 P 0 ;0
L 1.42658002 -2.09353996 1.4261 -2.10055 0 P 0 ;0
L 1.4261 -2.10055 1.42566998 -2.10706004 0 P 0 ;0
L 1.42566998 -2.10706004 1.42525 -2.11306004 0 P 0 ;0
L 1.42525 -2.11306004 1.42491998 -2.11851998 0 P 0 ;0
L 1.42491998 -2.11851998 1.42466004 -2.1231 0 P 0 ;0
L 1.42466004 -2.1231 1.42461004 -2.12471004 0 P 0 ;0
L 1.42461004 -2.12471004 1.4246 -2.12716004 0 P 0 ;0
L 1.4246 -2.12716004 1.47893002 -2.12716004 0 P 0 ;0
L 1.47893002 -2.12716004 1.47893002 -2.11358002 0 P 0 ;0
L 1.47893002 -2.11358002 1.47905 -2.10616998 0 P 0 ;0
L 1.47905 -2.10616998 1.47943996 -2.09385 0 P 0 ;0
L 1.47943996 -2.09385 1.48 -2.07968996 0 P 0 ;0
L 1.48 -2.07968996 1.48066004 -2.0655 0 P 0 ;0
L 1.48066004 -2.0655 1.4813 -2.05168996 0 P 0 ;0
L 1.4813 -2.05168996 1.48175 -2.03873996 0 P 0 ;0
L 1.48175 -2.03873996 1.48201998 -2.02785 0 P 0 ;0
L 1.48201998 -2.02785 1.48191998 -2.02286004 0 P 0 ;0
L 1.48191998 -2.02286004 1.48165 -2.01995 0 P 0 ;0
L 1.48165 -2.01995 1.48115 -2.01708002 0 P 0 ;0
L 1.48115 -2.01708002 1.48043996 -2.01425 0 P 0 ;0
L 1.48043996 -2.01425 1.47951004 -2.01146998 0 P 0 ;0
L 1.47951004 -2.01146998 1.47866998 -2.00946998 0 P 0 ;0
L 1.47866998 -2.00946998 1.47768002 -2.00753996 0 P 0 ;0
L 1.47768002 -2.00753996 1.47655 -2.00568002 0 P 0 ;0
L 1.47655 -2.00568002 1.47528002 -2.00391998 0 P 0 ;0
L 1.47528002 -2.00391998 1.47388002 -2.00225 0 P 0 ;0
L 1.47388002 -2.00225 1.47228996 -2.00063002 0 P 0 ;0
L 1.47228996 -2.00063002 1.4706 -1.99911998 0 P 0 ;0
L 1.4706 -1.99911998 1.4688 -1.99773002 0 P 0 ;0
L 1.4688 -1.99773002 1.46691004 -1.99648002 0 P 0 ;0
L 1.46691004 -1.99648002 1.46491998 -1.99535 0 P 0 ;0
L 1.46491998 -1.99535 1.46098996 -1.99351004 0 P 0 ;0
L 1.46098996 -1.99351004 1.45693002 -1.99196998 0 P 0 ;0
L 1.45693002 -1.99196998 1.45276004 -1.99076004 0 P 0 ;0
L 1.45276004 -1.99076004 1.44953996 -1.99006004 0 P 0 ;0
L 1.44953996 -1.99006004 1.44628996 -1.98956004 0 P 0 ;0
L 1.44628996 -1.98956004 1.44298002 -1.98923996 0 P 0 ;0
L 1.44298002 -1.98923996 1.42695 -1.98856998 0 P 0 ;0
L 1.42695 -1.98856998 1.41038996 -1.98865 0 P 0 ;0
L 1.41038996 -1.98865 1.4042 -1.98901004 0 P 0 ;0
L 1.4042 -1.98901004 1.39798996 -1.98971998 0 P 0 ;0
L 1.35778996 -2.11545 1.4153 -2.11545 0 P 0 ;0
L 1.35688996 -2.11445 1.41558996 -2.11445 0 P 0 ;0
L 1.35608002 -2.11345 1.41588002 -2.11345 0 P 0 ;0
L 1.35533002 -2.11245 1.41616998 -2.11245 0 P 0 ;0
L 1.35463996 -2.11145 1.41646004 -2.11145 0 P 0 ;0
L 1.35401004 -2.11045 1.41675 -2.11045 0 P 0 ;0
L 1.35341004 -2.10945 1.41703996 -2.10945 0 P 0 ;0
L 1.3529 -2.10845 1.41733002 -2.10845 0 P 0 ;0
L 1.35238002 -2.10745 1.41761998 -2.10745 0 P 0 ;0
L 1.35195 -2.10645 1.41788002 -2.10645 0 P 0 ;0
L 1.35155 -2.10545 1.41816004 -2.10545 0 P 0 ;0
L 1.3512 -2.10445 1.41841998 -2.10445 0 P 0 ;0
L 1.35091004 -2.10345 1.41868996 -2.10345 0 P 0 ;0
L 1.35066004 -2.10245 1.41896004 -2.10245 0 P 0 ;0
L 1.35046998 -2.10145 1.41923002 -2.10145 0 P 0 ;0
L 1.35033996 -2.10045 1.41948996 -2.10045 0 P 0 ;0
L 1.35021998 -2.09945 1.40141004 -2.09945 0 P 0 ;0
L 1.35016004 -2.09845 1.39791004 -2.09845 0 P 0 ;0
L 1.3501 -2.09745 1.39616004 -2.09745 0 P 0 ;0
L 1.35008002 -2.09645 1.39496004 -2.09645 0 P 0 ;0
L 1.35006998 -2.09545 1.39406004 -2.09545 0 P 0 ;0
L 1.35005 -2.09445 1.39338002 -2.09445 0 P 0 ;0
L 1.35003996 -2.09345 1.39288002 -2.09345 0 P 0 ;0
L 1.35001998 -2.09245 1.39253002 -2.09245 0 P 0 ;0
L 1.35001004 -2.09145 1.3923 -2.09145 0 P 0 ;0
L 1.35001998 -2.09045 1.3922 -2.09045 0 P 0 ;0
L 1.35003002 -2.08945 1.3922 -2.08945 0 P 0 ;0
L 1.35005 -2.08845 1.39231998 -2.08845 0 P 0 ;0
L 1.35006998 -2.08745 1.39256004 -2.08745 0 P 0 ;0
L 1.35008002 -2.08645 1.39293002 -2.08645 0 P 0 ;0
L 1.3501 -2.08545 1.39343002 -2.08545 0 P 0 ;0
L 1.35011004 -2.08445 1.39408996 -2.08445 0 P 0 ;0
L 1.39438002 -2.12845 1.3883 -2.12836004 0 P 0 ;0
L 1.3883 -2.12836004 1.38426998 -2.128 0 P 0 ;0
L 1.38426998 -2.128 1.38028002 -2.12733002 0 P 0 ;0
L 1.38028002 -2.12733002 1.37635 -2.12636004 0 P 0 ;0
L 1.37635 -2.12636004 1.37248996 -2.12508002 0 P 0 ;0
L 1.37248996 -2.12508002 1.36983996 -2.12398002 0 P 0 ;0
L 1.36983996 -2.12398002 1.36728996 -2.1227 0 P 0 ;0
L 1.36728996 -2.1227 1.36481998 -2.12123996 0 P 0 ;0
L 1.36481998 -2.12123996 1.36246004 -2.11961004 0 P 0 ;0
L 1.36246004 -2.11961004 1.36023002 -2.11781998 0 P 0 ;0
L 1.36023002 -2.11781998 1.35828996 -2.116 0 P 0 ;0
L 1.35828996 -2.116 1.35651998 -2.11403002 0 P 0 ;0
L 1.35651998 -2.11403002 1.35493002 -2.11191004 0 P 0 ;0
L 1.35493002 -2.11191004 1.35353002 -2.10966998 0 P 0 ;0
L 1.35353002 -2.10966998 1.35231004 -2.10731004 0 P 0 ;0
L 1.35231004 -2.10731004 1.35166998 -2.10576998 0 P 0 ;0
L 1.35166998 -2.10576998 1.35111004 -2.1042 0 P 0 ;0
L 1.35111004 -2.1042 1.35071998 -2.10276004 0 P 0 ;0
L 1.35071998 -2.10276004 1.35045 -2.1013 0 P 0 ;0
L 1.35045 -2.1013 1.35021998 -2.09943002 0 P 0 ;0
L 1.35021998 -2.09943002 1.3501 -2.09753002 0 P 0 ;0
L 1.3501 -2.09753002 1.35001004 -2.09128002 0 P 0 ;0
L 1.35001004 -2.09128002 1.35011998 -2.0844 0 P 0 ;0
L 1.35011998 -2.0844 1.35023996 -2.08258996 0 P 0 ;0
L 1.35023996 -2.08258996 1.3505 -2.08083996 0 P 0 ;0
L 1.3505 -2.08083996 1.35071998 -2.07985 0 P 0 ;0
L 1.35071998 -2.07985 1.35101004 -2.07888002 0 P 0 ;0
L 1.35101004 -2.07888002 1.35136004 -2.07793002 0 P 0 ;0
L 1.35136004 -2.07793002 1.35335 -2.07351998 0 P 0 ;0
L 1.35335 -2.07351998 1.35491998 -2.07065 0 P 0 ;0
L 1.35491998 -2.07065 1.35683002 -2.0677 0 P 0 ;0
L 1.35683002 -2.0677 1.35876998 -2.06511004 0 P 0 ;0
L 1.35876998 -2.06511004 1.35948996 -2.0643 0 P 0 ;0
L 1.35948996 -2.0643 1.36026998 -2.06356004 0 P 0 ;0
L 1.36026998 -2.06356004 1.3624 -2.06181998 0 P 0 ;0
L 1.3624 -2.06181998 1.36465 -2.06023996 0 P 0 ;0
L 1.36465 -2.06023996 1.36701004 -2.05883002 0 P 0 ;0
L 1.36701004 -2.05883002 1.37173002 -2.05641004 0 P 0 ;0
L 1.37173002 -2.05641004 1.37656004 -2.05426998 0 P 0 ;0
L 1.37656004 -2.05426998 1.38243002 -2.05203996 0 P 0 ;0
L 1.38243002 -2.05203996 1.38836004 -2.0501 0 P 0 ;0
L 1.38836004 -2.0501 1.4023 -2.04645 0 P 0 ;0
L 1.4023 -2.04645 1.41148996 -2.044 0 P 0 ;0
L 1.41148996 -2.044 1.42016998 -2.04095 0 P 0 ;0
L 1.42016998 -2.04095 1.42016998 -2.04093996 0 P 0 ;0
L 1.42016998 -2.04093996 1.42021004 -2.04093996 0 P 0 ;0
L 1.42021004 -2.04093996 1.42023996 -2.04093002 0 P 0 ;0
L 1.42023996 -2.04093002 1.42746998 -2.03776004 0 P 0 ;0
L 1.42746998 -2.03776004 1.42753002 -2.03773002 0 P 0 ;0
L 1.42753002 -2.03773002 1.42796998 -2.03748996 0 P 0 ;0
L 1.42796998 -2.03748996 1.42846004 -2.03718996 0 P 0 ;0
L 1.42846004 -2.03718996 1.42891998 -2.03683996 0 P 0 ;0
L 1.42891998 -2.03683996 1.42935 -2.03646004 0 P 0 ;0
L 1.42935 -2.03646004 1.42975 -2.03603996 0 P 0 ;0
L 1.42975 -2.03603996 1.43011004 -2.0356 0 P 0 ;0
L 1.43011004 -2.0356 1.43016004 -2.03553002 0 P 0 ;0
L 1.43016004 -2.03553002 1.4299 -2.03535 0 P 0 ;0
L 1.4299 -2.03535 1.43028002 -2.03535 0 P 0 ;0
L 1.43028002 -2.03535 1.43043996 -2.03513002 0 P 0 ;0
L 1.43043996 -2.03513002 1.43048002 -2.03506004 0 P 0 ;0
L 1.43048002 -2.03506004 1.43041998 -2.03501998 0 P 0 ;0
L 1.43041998 -2.03501998 1.4305 -2.03501998 0 P 0 ;0
L 1.4305 -2.03501998 1.43073002 -2.03463002 0 P 0 ;0
L 1.43073002 -2.03463002 1.43096004 -2.03415 0 P 0 ;0
L 1.43096004 -2.03415 1.43115 -2.03365 0 P 0 ;0
L 1.43115 -2.03365 1.4313 -2.03313002 0 P 0 ;0
L 1.4313 -2.03313002 1.4314 -2.03261004 0 P 0 ;0
L 1.4314 -2.03261004 1.43146004 -2.03208002 0 P 0 ;0
L 1.43146004 -2.03208002 1.43146998 -2.03155 0 P 0 ;0
L 1.43146998 -2.03155 1.43143996 -2.03101004 0 P 0 ;0
L 1.43143996 -2.03101004 1.43143002 -2.03093002 0 P 0 ;0
L 1.43143002 -2.03093002 1.43136004 -2.03048996 0 P 0 ;0
L 1.43136004 -2.03048996 1.43125 -2.02996998 0 P 0 ;0
L 1.43125 -2.02996998 1.43108002 -2.02946004 0 P 0 ;0
L 1.43108002 -2.02946004 1.43086998 -2.02896004 0 P 0 ;0
L 1.43086998 -2.02896004 1.43063002 -2.02848996 0 P 0 ;0
L 1.43063002 -2.02848996 1.43033996 -2.02803996 0 P 0 ;0
L 1.43033996 -2.02803996 1.43001998 -2.02761004 0 P 0 ;0
L 1.43001998 -2.02761004 1.42966004 -2.02721004 0 P 0 ;0
L 1.42966004 -2.02721004 1.42928002 -2.02685 0 P 0 ;0
L 1.42928002 -2.02685 1.42886004 -2.02651998 0 P 0 ;0
L 1.42886004 -2.02651998 1.42841998 -2.02623002 0 P 0 ;0
L 1.42841998 -2.02623002 1.42795 -2.02596998 0 P 0 ;0
L 1.42795 -2.02596998 1.42746004 -2.02575 0 P 0 ;0
L 1.42746004 -2.02575 1.42583002 -2.02518002 0 P 0 ;0
L 1.42583002 -2.02518002 1.42416004 -2.02476004 0 P 0 ;0
L 1.42416004 -2.02476004 1.42245 -2.02448002 0 P 0 ;0
L 1.42245 -2.02448002 1.42075 -2.02435 0 P 0 ;0
L 1.42075 -2.02435 1.41565 -2.02428002 0 P 0 ;0
L 1.41565 -2.02428002 1.4156 -2.02428002 0 P 0 ;0
L 1.4156 -2.02428002 1.41055 -2.02445 0 P 0 ;0
L 1.41055 -2.02445 1.41048002 -2.02445 0 P 0 ;0
L 1.41048002 -2.02445 1.40128996 -2.02533996 0 P 0 ;0
L 1.40128996 -2.02533996 1.39208996 -2.02696998 0 P 0 ;0
L 1.39208996 -2.02696998 1.38288002 -2.02936004 0 P 0 ;0
L 1.38288002 -2.02936004 1.37363002 -2.03251998 0 P 0 ;0
L 1.37363002 -2.03251998 1.37076998 -2.03356004 0 P 0 ;0
L 1.37076998 -2.03356004 1.36865 -2.03426998 0 P 0 ;0
L 1.36865 -2.03426998 1.36906004 -2.03066998 0 P 0 ;0
L 1.36906004 -2.03066998 1.36988996 -2.02383996 0 P 0 ;0
L 1.36988996 -2.02383996 1.37095 -2.01581004 0 P 0 ;0
L 1.37095 -2.01581004 1.37358996 -1.99631998 0 P 0 ;0
L 1.37358996 -1.99631998 1.37988002 -1.99491998 0 P 0 ;0
L 1.37988002 -1.99491998 1.38353996 -1.99416998 0 P 0 ;0
L 1.38353996 -1.99416998 1.38841998 -1.99326998 0 P 0 ;0
L 1.38841998 -1.99326998 1.39358002 -1.9924 0 P 0 ;0
L 1.39358002 -1.9924 1.39825 -1.9917 0 P 0 ;0
L 1.39825 -1.9917 1.40436998 -1.991 0 P 0 ;0
L 1.40436998 -1.991 1.41045 -1.99065 0 P 0 ;0
L 1.41045 -1.99065 1.42691004 -1.99056998 0 P 0 ;0
L 1.42691004 -1.99056998 1.44283996 -1.99123996 0 P 0 ;0
L 1.44283996 -1.99123996 1.44603996 -1.99153996 0 P 0 ;0
L 1.44603996 -1.99153996 1.44918002 -1.99203002 0 P 0 ;0
L 1.44918002 -1.99203002 1.45226004 -1.9927 0 P 0 ;0
L 1.45226004 -1.9927 1.4563 -1.99386998 0 P 0 ;0
L 1.4563 -1.99386998 1.46021004 -1.99535 0 P 0 ;0
L 1.46021004 -1.99535 1.464 -1.99713002 0 P 0 ;0
L 1.464 -1.99713002 1.46586004 -1.99818996 0 P 0 ;0
L 1.46586004 -1.99818996 1.46763996 -1.99936004 0 P 0 ;0
L 1.46763996 -1.99936004 1.46931998 -2.00066004 0 P 0 ;0
L 1.46931998 -2.00066004 1.47091004 -2.00206998 0 P 0 ;0
L 1.47091004 -2.00206998 1.47238996 -2.00358996 0 P 0 ;0
L 1.47238996 -2.00358996 1.4737 -2.00515 0 P 0 ;0
L 1.4737 -2.00515 1.47488002 -2.00678996 0 P 0 ;0
L 1.47488002 -2.00678996 1.47593996 -2.00851004 0 P 0 ;0
L 1.47593996 -2.00851004 1.47686004 -2.01031004 0 P 0 ;0
L 1.47686004 -2.01031004 1.47763996 -2.01216998 0 P 0 ;0
L 1.47763996 -2.01216998 1.47851998 -2.01481004 0 P 0 ;0
L 1.47851998 -2.01481004 1.47918996 -2.01748996 0 P 0 ;0
L 1.47918996 -2.01748996 1.47966004 -2.02021998 0 P 0 ;0
L 1.47966004 -2.02021998 1.47993002 -2.02296998 0 P 0 ;0
L 1.47993002 -2.02296998 1.48001998 -2.02783996 0 P 0 ;0
L 1.48001998 -2.02783996 1.47975 -2.03868996 0 P 0 ;0
L 1.47975 -2.03868996 1.4793 -2.05161004 0 P 0 ;0
L 1.4793 -2.05161004 1.47866004 -2.06543002 0 P 0 ;0
L 1.47866004 -2.06543002 1.47801004 -2.07961004 0 P 0 ;0
L 1.47801004 -2.07961004 1.47743996 -2.09378996 0 P 0 ;0
L 1.47743996 -2.09378996 1.47705 -2.10613002 0 P 0 ;0
L 1.47705 -2.10613002 1.47693002 -2.11356004 0 P 0 ;0
L 1.47693002 -2.11356004 1.47693002 -2.12516004 0 P 0 ;0
L 1.47693002 -2.12516004 1.42661004 -2.12516004 0 P 0 ;0
L 1.42661004 -2.12516004 1.42661004 -2.12473996 0 P 0 ;0
L 1.42661004 -2.12473996 1.42666004 -2.12318002 0 P 0 ;0
L 1.42666004 -2.12318002 1.42691004 -2.11863996 0 P 0 ;0
L 1.42691004 -2.11863996 1.42725 -2.1132 0 P 0 ;0
L 1.42725 -2.1132 1.42766004 -2.1072 0 P 0 ;0
L 1.42766004 -2.1072 1.42766004 -2.10718996 0 P 0 ;0
L 1.42766004 -2.10718996 1.4281 -2.10068996 0 P 0 ;0
L 1.4281 -2.10068996 1.42858002 -2.09368002 0 P 0 ;0
L 1.42858002 -2.09368002 1.42901004 -2.08721004 0 P 0 ;0
L 1.42901004 -2.08721004 1.42901004 -2.0872 0 P 0 ;0
L 1.42901004 -2.0872 1.42931004 -2.08256004 0 P 0 ;0
L 1.42931004 -2.08256004 1.42991998 -2.07308002 0 P 0 ;0
L 1.42991998 -2.07308002 1.42916004 -2.07136998 0 P 0 ;0
L 1.42916004 -2.07136998 1.42731998 -2.07105 0 P 0 ;0
L 1.42731998 -2.07105 1.42105 -2.07303996 0 P 0 ;0
L 1.42105 -2.07303996 1.41815 -2.07393002 0 P 0 ;0
L 1.41815 -2.07393002 1.41451004 -2.075 0 P 0 ;0
L 1.41451004 -2.075 1.41076004 -2.07603002 0 P 0 ;0
L 1.41076004 -2.07603002 1.40748002 -2.0769 0 P 0 ;0
L 1.40748002 -2.0769 1.40438996 -2.07781004 0 P 0 ;0
L 1.40438996 -2.07781004 1.40431998 -2.07783996 0 P 0 ;0
L 1.40431998 -2.07783996 1.40133996 -2.07896998 0 P 0 ;0
L 1.40133996 -2.07896998 1.40005 -2.07956998 0 P 0 ;0
L 1.40005 -2.07956998 1.39881998 -2.08026004 0 P 0 ;0
L 1.39881998 -2.08026004 1.39763996 -2.08103002 0 P 0 ;0
L 1.39763996 -2.08103002 1.39651998 -2.08188002 0 P 0 ;0
L 1.39651998 -2.08188002 1.39578996 -2.08251004 0 P 0 ;0
L 1.39578996 -2.08251004 1.39573996 -2.08256004 0 P 0 ;0
L 1.39573996 -2.08256004 1.3951 -2.08318996 0 P 0 ;0
L 1.3951 -2.08318996 1.39446998 -2.08393002 0 P 0 ;0
L 1.39446998 -2.08393002 1.3939 -2.08471004 0 P 0 ;0
L 1.3939 -2.08471004 1.39336998 -2.08553996 0 P 0 ;0
L 1.39336998 -2.08553996 1.39301004 -2.08623996 0 P 0 ;0
L 1.39301004 -2.08623996 1.39271004 -2.08696998 0 P 0 ;0
L 1.39271004 -2.08696998 1.39248002 -2.08771998 0 P 0 ;0
L 1.39248002 -2.08771998 1.39231004 -2.08848996 0 P 0 ;0
L 1.39231004 -2.08848996 1.39221004 -2.08926004 0 P 0 ;0
L 1.39221004 -2.08926004 1.39218002 -2.09003996 0 P 0 ;0
L 1.39218002 -2.09003996 1.39221004 -2.0908 0 P 0 ;0
L 1.39221004 -2.0908 1.39231004 -2.09153002 0 P 0 ;0
L 1.39231004 -2.09153002 1.39246998 -2.09226004 0 P 0 ;0
L 1.39246998 -2.09226004 1.39268996 -2.09296998 0 P 0 ;0
L 1.39268996 -2.09296998 1.39296004 -2.09365 0 P 0 ;0
L 1.39296004 -2.09365 1.3933 -2.09431004 0 P 0 ;0
L 1.3933 -2.09431004 1.39368996 -2.09493996 0 P 0 ;0
L 1.39368996 -2.09493996 1.39411998 -2.09553996 0 P 0 ;0
L 1.39411998 -2.09553996 1.39468996 -2.09618002 0 P 0 ;0
L 1.39468996 -2.09618002 1.3953 -2.09678002 0 P 0 ;0
L 1.3953 -2.09678002 1.39596004 -2.09731998 0 P 0 ;0
L 1.39596004 -2.09731998 1.39666998 -2.0978 0 P 0 ;0
L 1.39666998 -2.0978 1.39673996 -2.09783996 0 P 0 ;0
L 1.39673996 -2.09783996 1.39741004 -2.09821998 0 P 0 ;0
L 1.39741004 -2.09821998 1.39748996 -2.09825 0 P 0 ;0
L 1.39748996 -2.09825 1.39818996 -2.09856998 0 P 0 ;0
L 1.39818996 -2.09856998 1.39898996 -2.09886004 0 P 0 ;0
L 1.39898996 -2.09886004 1.39906998 -2.09888002 0 P 0 ;0
L 1.39906998 -2.09888002 1.40043996 -2.09888002 0 P 0 ;0
L 1.40043996 -2.09888002 1.40033996 -2.09923002 0 P 0 ;0
L 1.40033996 -2.09923002 1.40041998 -2.09925 0 P 0 ;0
L 1.40041998 -2.09925 1.40186004 -2.09953002 0 P 0 ;0
L 1.40186004 -2.09953002 1.40331004 -2.09971004 0 P 0 ;0
L 1.40331004 -2.09971004 1.40478002 -2.09978002 0 P 0 ;0
L 1.40478002 -2.09978002 1.40625 -2.09975 0 P 0 ;0
L 1.40625 -2.09975 1.41096004 -2.09931004 0 P 0 ;0
L 1.41096004 -2.09931004 1.41556998 -2.09855 0 P 0 ;0
L 1.41556998 -2.09855 1.41791998 -2.09813002 0 P 0 ;0
L 1.41791998 -2.09813002 1.41995 -2.09791004 0 P 0 ;0
L 1.41995 -2.09791004 1.4201 -2.0979 0 P 0 ;0
L 1.4201 -2.0979 1.41941004 -2.10078002 0 P 0 ;0
L 1.41941004 -2.10078002 1.41761004 -2.10745 0 P 0 ;0
L 1.41761004 -2.10745 1.41391004 -2.12025 0 P 0 ;0
L 1.41391004 -2.12025 1.41215 -2.12626998 0 P 0 ;0
L 1.41215 -2.12626998 1.40655 -2.12725 0 P 0 ;0
L 1.40655 -2.12725 1.40046004 -2.12808002 0 P 0 ;0
L 1.40046004 -2.12808002 1.39438002 -2.12845 0 P 0 ;0
L 1.15303002 -2.08283002 1.20788996 -2.08283002 0 P 0 ;0
L 1.15398996 -2.08183002 1.20795 -2.08183002 0 P 0 ;0
L 1.15483002 -2.08083002 1.208 -2.08083002 0 P 0 ;0
L 1.15555 -2.07983002 1.20805 -2.07983002 0 P 0 ;0
L 1.15621998 -2.07883002 1.2081 -2.07883002 0 P 0 ;0
L 1.15681998 -2.07783002 1.20816004 -2.07783002 0 P 0 ;0
L 1.15733002 -2.07683002 1.20821004 -2.07683002 0 P 0 ;0
L 1.15778996 -2.07583002 1.20826004 -2.07583002 0 P 0 ;0
L 1.15818002 -2.07483002 1.20831004 -2.07483002 0 P 0 ;0
L 1.15853996 -2.07383002 1.20836998 -2.07383002 0 P 0 ;0
L 1.15881998 -2.07283002 1.20841998 -2.07283002 0 P 0 ;0
L 1.1591 -2.07183002 1.20846998 -2.07183002 0 P 0 ;0
L 1.15938002 -2.07083002 1.20853002 -2.07083002 0 P 0 ;0
L 1.1596 -2.06983002 1.20858002 -2.06983002 0 P 0 ;0
L 1.15981004 -2.06883002 1.20863996 -2.06883002 0 P 0 ;0
L 1.16001004 -2.06783002 1.20868996 -2.06783002 0 P 0 ;0
L 1.1602 -2.06683002 1.20875 -2.06683002 0 P 0 ;0
L 1.16033996 -2.06583002 1.2088 -2.06583002 0 P 0 ;0
L 1.16048996 -2.06483002 1.20886004 -2.06483002 0 P 0 ;0
L 1.16063996 -2.06383002 1.20891998 -2.06383002 0 P 0 ;0
L 1.16078002 -2.06283002 1.20896998 -2.06283002 0 P 0 ;0
L 1.16088996 -2.06183002 1.20903002 -2.06183002 0 P 0 ;0
L 1.16098996 -2.06083002 1.20908002 -2.06083002 0 P 0 ;0
L 1.16108996 -2.05983002 1.20913996 -2.05983002 0 P 0 ;0
L 1.16118002 -2.05883002 1.20918996 -2.05883002 0 P 0 ;0
L 1.16128002 -2.05783002 1.20925 -2.05783002 0 P 0 ;0
L 1.16133996 -2.05683002 1.2093 -2.05683002 0 P 0 ;0
L 1.1614 -2.05583002 1.20936004 -2.05583002 0 P 0 ;0
L 1.16146004 -2.05483002 1.20941004 -2.05483002 0 P 0 ;0
L 1.16151998 -2.05383002 1.20946998 -2.05383002 0 P 0 ;0
L 1.16158002 -2.05283002 1.20951998 -2.05283002 0 P 0 ;0
L 1.16163996 -2.05183002 1.20958002 -2.05183002 0 P 0 ;0
L 1.1617 -2.05083002 1.20963996 -2.05083002 0 P 0 ;0
L 1.16175 -2.04983002 1.2097 -2.04983002 0 P 0 ;0
L 1.16181004 -2.04883002 1.20975 -2.04883002 0 P 0 ;0
L 1.16186998 -2.04783002 1.20981004 -2.04783002 0 P 0 ;0
L 1.16193002 -2.04683002 1.20986998 -2.04683002 0 P 0 ;0
L 1.16198996 -2.04583002 1.20993002 -2.04583002 0 P 0 ;0
L 1.16205 -2.04483002 1.20998996 -2.04483002 0 P 0 ;0
L 1.16211004 -2.04383002 1.21005 -2.04383002 0 P 0 ;0
L 1.16215 -2.04283002 1.2101 -2.04283002 0 P 0 ;0
L 1.1622 -2.04183002 1.21016004 -2.04183002 0 P 0 ;0
L 1.16225 -2.04083002 1.21021998 -2.04083002 0 P 0 ;0
L 1.16228996 -2.03983002 1.21028002 -2.03983002 0 P 0 ;0
L 1.16233996 -2.03883002 1.21033996 -2.03883002 0 P 0 ;0
L 1.16238002 -2.03783002 1.2104 -2.03783002 0 P 0 ;0
L 1.16243002 -2.03683002 1.21046004 -2.03683002 0 P 0 ;0
L 1.16246998 -2.03583002 1.21051004 -2.03583002 0 P 0 ;0
L 1.16251998 -2.03483002 1.21056998 -2.03483002 0 P 0 ;0
L 1.16256998 -2.03383002 1.21063996 -2.03383002 0 P 0 ;0
L 1.16261004 -2.03283002 1.2107 -2.03283002 0 P 0 ;0
L 1.16266004 -2.03183002 1.21076004 -2.03183002 0 P 0 ;0
L 1.1627 -2.03083002 1.21083002 -2.03083002 0 P 0 ;0
L 1.16015 -1.97631004 1.17066004 -1.97631004 0 P 0 ;0
L 1.15961998 -1.97531004 1.17026004 -1.97531004 0 P 0 ;0
L 1.1591 -1.97431004 1.16986998 -1.97431004 0 P 0 ;0
L 1.15856998 -1.97331004 1.16946998 -1.97331004 0 P 0 ;0
L 1.15803996 -1.97231004 1.16903002 -1.97231004 0 P 0 ;0
L 1.15746998 -1.97131004 1.16858996 -1.97131004 0 P 0 ;0
L 1.1569 -1.97031004 1.16815 -1.97031004 0 P 0 ;0
L 1.15631998 -1.96931004 1.16771004 -1.96931004 0 P 0 ;0
L 1.15573996 -1.96831004 1.16726998 -1.96831004 0 P 0 ;0
L 1.15516004 -1.96731004 1.16681998 -1.96731004 0 P 0 ;0
L 1.15458996 -1.96631004 1.16638002 -1.96631004 0 P 0 ;0
L 1.15398002 -1.96531004 1.16593996 -1.96531004 0 P 0 ;0
L 1.1533 -1.96431004 1.16548996 -1.96431004 0 P 0 ;0
L 1.15261998 -1.96331004 1.16503002 -1.96331004 0 P 0 ;0
L 1.15193996 -1.96231004 1.16448002 -1.96231004 0 P 0 ;0
L 1.15126004 -1.96131004 1.16393002 -1.96131004 0 P 0 ;0
L 1.15058002 -1.96031004 1.16338002 -1.96031004 0 P 0 ;0
L 1.1499 -1.95931004 1.16283002 -1.95931004 0 P 0 ;0
L 1.1491 -1.95831004 1.16228996 -1.95831004 0 P 0 ;0
L 1.14831004 -1.95731004 1.16173996 -1.95731004 0 P 0 ;0
L 1.14751004 -1.95631004 1.16118996 -1.95631004 0 P 0 ;0
L 1.14671004 -1.95531004 1.16063996 -1.95531004 0 P 0 ;0
L 1.14591998 -1.95431004 1.16008996 -1.95431004 0 P 0 ;0
L 1.14511998 -1.95331004 1.15943996 -1.95331004 0 P 0 ;0
L 1.1442 -1.95231004 1.15878002 -1.95231004 0 P 0 ;0
L 1.14326998 -1.95131004 1.15811004 -1.95131004 0 P 0 ;0
L 1.14233996 -1.95031004 1.15745 -1.95031004 0 P 0 ;0
L 1.14141004 -1.94931004 1.15678002 -1.94931004 0 P 0 ;0
L 1.14048996 -1.94831004 1.15611998 -1.94831004 0 P 0 ;0
L 1.1395 -1.94731004 1.15545 -1.94731004 0 P 0 ;0
L 1.13843002 -1.94631004 1.15478996 -1.94631004 0 P 0 ;0
L 1.13736004 -1.94531004 1.15411998 -1.94531004 0 P 0 ;0
L 1.13628996 -1.94431004 1.15333002 -1.94431004 0 P 0 ;0
L 1.13521004 -1.94331004 1.15253002 -1.94331004 0 P 0 ;0
L 1.13413996 -1.94231004 1.15173996 -1.94231004 0 P 0 ;0
L 1.13306998 -1.94131004 1.15093996 -1.94131004 0 P 0 ;0
L 1.132 -1.94031004 1.15013996 -1.94031004 0 P 0 ;0
L 1.13081004 -1.93931004 1.14935 -1.93931004 0 P 0 ;0
L 1.12958002 -1.93831004 1.14855 -1.93831004 0 P 0 ;0
L 1.12833996 -1.93731004 1.14775 -1.93731004 0 P 0 ;0
L 1.1271 -1.93631004 1.14688996 -1.93631004 0 P 0 ;0
L 1.12586004 -1.93531004 1.14593996 -1.93531004 0 P 0 ;0
L 1.12461998 -1.93431004 1.14498996 -1.93431004 0 P 0 ;0
L 1.12338002 -1.93331004 1.14405 -1.93331004 0 P 0 ;0
L 1.12203002 -1.93231004 1.1431 -1.93231004 0 P 0 ;0
L 1.1206 -1.93131004 1.14216004 -1.93131004 0 P 0 ;0
L 1.11916004 -1.93031004 1.14121004 -1.93031004 0 P 0 ;0
L 1.11771998 -1.92931004 1.14026998 -1.92931004 0 P 0 ;0
L 1.11628996 -1.92831004 1.13931998 -1.92831004 0 P 0 ;0
L 1.11483996 -1.92731004 1.13838002 -1.92731004 0 P 0 ;0
L 1.11338996 -1.92631004 1.13743002 -1.92631004 0 P 0 ;0
L 1.11171998 -1.92531004 1.13648996 -1.92531004 0 P 0 ;0
L 1.11005 -1.92431004 1.13538002 -1.92431004 0 P 0 ;0
L 1.10838002 -1.92331004 1.13426998 -1.92331004 0 P 0 ;0
L 1.1067 -1.92231004 1.13315 -1.92231004 0 P 0 ;0
L 1.10503002 -1.92131004 1.13203002 -1.92131004 0 P 0 ;0
L 1.10336004 -1.92031004 1.13091998 -1.92031004 0 P 0 ;0
L 1.1015 -1.91931004 1.1298 -1.91931004 0 P 0 ;0
L 1.09955 -1.91831004 1.12868002 -1.91831004 0 P 0 ;0
L 1.16275 -2.02983002 1.21088996 -2.02983002 0 P 0 ;0
L 1.16278996 -2.02883002 1.21095 -2.02883002 0 P 0 ;0
L 1.16283996 -2.02783002 1.21101004 -2.02783002 0 P 0 ;0
L 1.16226998 -2.02683002 1.21108002 -2.02683002 0 P 0 ;0
L 1.16153996 -2.02583002 1.21113996 -2.02583002 0 P 0 ;0
L 1.15846004 -2.02483002 1.2112 -2.02483002 0 P 0 ;0
L 1.10036004 -2.00383002 1.21255 -2.00383002 0 P 0 ;0
L 1.10226004 -2.00283002 1.2126 -2.00283002 0 P 0 ;0
L 1.10433996 -2.00183002 1.21266998 -2.00183002 0 P 0 ;0
L 1.1065 -2.00083002 1.21273002 -2.00083002 0 P 0 ;0
L 1.10886998 -1.99983002 1.21278996 -1.99983002 0 P 0 ;0
L 1.11138002 -1.99883002 1.21285 -1.99883002 0 P 0 ;0
L 1.11436998 -1.99783002 1.21288002 -1.99783002 0 P 0 ;0
L 1.11748996 -1.99683002 1.21255 -1.99683002 0 P 0 ;0
L 1.12061998 -1.99583002 1.2089 -1.99583002 0 P 0 ;0
L 1.12433996 -1.99483002 1.2036 -1.99483002 0 P 0 ;0
L 1.12863996 -1.99383002 1.19728002 -1.99383002 0 P 0 ;0
L 1.13295 -1.99283002 1.19096998 -1.99283002 0 P 0 ;0
L 1.13985 -1.99183002 1.18111998 -1.99183002 0 P 0 ;0
L 1.14948002 -1.99083002 1.1651 -1.99083002 0 P 0 ;0
L 1.24218002 -2.08316004 1.29143996 -2.08316004 0 P 0 ;0
L 1.24223002 -2.08216004 1.29151004 -2.08216004 0 P 0 ;0
L 1.24228002 -2.08116004 1.29158996 -2.08116004 0 P 0 ;0
L 1.24233996 -2.08016004 1.29166004 -2.08016004 0 P 0 ;0
L 1.24238996 -2.07916004 1.29173002 -2.07916004 0 P 0 ;0
L 1.24245 -2.07816004 1.29181004 -2.07816004 0 P 0 ;0
L 1.2425 -2.07716004 1.29188002 -2.07716004 0 P 0 ;0
L 1.24256004 -2.07616004 1.29195 -2.07616004 0 P 0 ;0
L 1.24261004 -2.07516004 1.29203002 -2.07516004 0 P 0 ;0
L 1.24266998 -2.07416004 1.2921 -2.07416004 0 P 0 ;0
L 1.24271998 -2.07316004 1.29216998 -2.07316004 0 P 0 ;0
L 1.24278002 -2.07216004 1.29223996 -2.07216004 0 P 0 ;0
L 1.24283002 -2.07116004 1.29231998 -2.07116004 0 P 0 ;0
L 1.24288002 -2.07016004 1.29238996 -2.07016004 0 P 0 ;0
L 1.24293002 -2.06916004 1.29246004 -2.06916004 0 P 0 ;0
L 1.24296998 -2.06816004 1.29253002 -2.06816004 0 P 0 ;0
L 1.24301998 -2.06716004 1.29261004 -2.06716004 0 P 0 ;0
L 1.24306004 -2.06616004 1.2927 -2.06616004 0 P 0 ;0
L 1.24311004 -2.06516004 1.29281004 -2.06516004 0 P 0 ;0
L 1.24315 -2.06416004 1.29291998 -2.06416004 0 P 0 ;0
L 1.2432 -2.06316004 1.29303002 -2.06316004 0 P 0 ;0
L 1.24323996 -2.06216004 1.29315 -2.06216004 0 P 0 ;0
L 1.24328996 -2.06116004 1.29331998 -2.06116004 0 P 0 ;0
L 1.24333002 -2.06016004 1.2935 -2.06016004 0 P 0 ;0
L 1.24338002 -2.05916004 1.29366998 -2.05916004 0 P 0 ;0
L 1.24341998 -2.05816004 1.29385 -2.05816004 0 P 0 ;0
L 1.24346998 -2.05716004 1.29408996 -2.05716004 0 P 0 ;0
L 1.24351004 -2.05616004 1.29433996 -2.05616004 0 P 0 ;0
L 1.24355 -2.05516004 1.29458996 -2.05516004 0 P 0 ;0
L 1.2436 -2.05416004 1.29485 -2.05416004 0 P 0 ;0
L 1.24363996 -2.05316004 1.29516998 -2.05316004 0 P 0 ;0
L 1.24368996 -2.05216004 1.29551998 -2.05216004 0 P 0 ;0
L 1.24373002 -2.05116004 1.29586004 -2.05116004 0 P 0 ;0
L 1.24378002 -2.05016004 1.29621004 -2.05016004 0 P 0 ;0
L 1.24383002 -2.04916004 1.29663996 -2.04916004 0 P 0 ;0
L 1.24386998 -2.04816004 1.29708002 -2.04816004 0 P 0 ;0
L 1.24391004 -2.04716004 1.29753002 -2.04716004 0 P 0 ;0
L 1.24396004 -2.04616004 1.29796998 -2.04616004 0 P 0 ;0
L 1.244 -2.04516004 1.29851004 -2.04516004 0 P 0 ;0
L 1.24405 -2.04416004 1.2991 -2.04416004 0 P 0 ;0
L 1.24408996 -2.04316004 1.29975 -2.04316004 0 P 0 ;0
L 1.24413996 -2.04216004 1.3005 -2.04216004 0 P 0 ;0
L 1.24418002 -2.04116004 1.30131998 -2.04116004 0 P 0 ;0
L 1.24423002 -2.04016004 1.30223002 -2.04016004 0 P 0 ;0
L 1.24426998 -2.03916004 1.30326998 -2.03916004 0 P 0 ;0
L 1.24431998 -2.03816004 1.30446004 -2.03816004 0 P 0 ;0
L 1.24436004 -2.03716004 1.30581998 -2.03716004 0 P 0 ;0
L 1.24441004 -2.03616004 1.30738002 -2.03616004 0 P 0 ;0
L 1.24445 -2.03516004 1.30923002 -2.03516004 0 P 0 ;0
L 1.24448996 -2.03416004 1.31156004 -2.03416004 0 P 0 ;0
L 1.24453996 -2.03316004 1.31478996 -2.03316004 0 P 0 ;0
L 1.24458996 -2.03216004 1.32013002 -2.03216004 0 P 0 ;0
L 1.24461998 -2.03116004 1.33481004 -2.03116004 0 P 0 ;0
L 1.24463996 -2.03016004 1.33478002 -2.03016004 0 P 0 ;0
L 1.24466004 -2.02916004 1.33473996 -2.02916004 0 P 0 ;0
L 1.24468002 -2.02816004 1.33471004 -2.02816004 0 P 0 ;0
L 1.2447 -2.02716004 1.33468002 -2.02716004 0 P 0 ;0
L 1.24471998 -2.02616004 1.33463996 -2.02616004 0 P 0 ;0
L 1.24473996 -2.02516004 1.3346 -2.02516004 0 P 0 ;0
L 1.24476004 -2.02416004 1.33456998 -2.02416004 0 P 0 ;0
L 1.24478002 -2.02316004 1.33453002 -2.02316004 0 P 0 ;0
L 1.2448 -2.02216004 1.3345 -2.02216004 0 P 0 ;0
L 1.24481998 -2.02116004 1.33446998 -2.02116004 0 P 0 ;0
L 1.24483996 -2.02016004 1.33443002 -2.02016004 0 P 0 ;0
L 1.24486004 -2.01916004 1.3344 -2.01916004 0 P 0 ;0
L 1.24488002 -2.01816004 1.33436004 -2.01816004 0 P 0 ;0
L 1.2449 -2.01716004 1.33433002 -2.01716004 0 P 0 ;0
L 1.24491998 -2.01616004 1.33428996 -2.01616004 0 P 0 ;0
L 1.24493996 -2.01516004 1.33426004 -2.01516004 0 P 0 ;0
L 1.24496004 -2.01416004 1.33421998 -2.01416004 0 P 0 ;0
L 1.24498002 -2.01316004 1.33418996 -2.01316004 0 P 0 ;0
L 1.245 -2.01216004 1.33415 -2.01216004 0 P 0 ;0
L 1.24501998 -2.01116004 1.33411998 -2.01116004 0 P 0 ;0
L 1.24503996 -2.01016004 1.33408002 -2.01016004 0 P 0 ;0
L 1.24506004 -2.00916004 1.33403996 -2.00916004 0 P 0 ;0
L 1.24508002 -2.00816004 1.334 -2.00816004 0 P 0 ;0
L 1.2451 -2.00716004 1.33396004 -2.00716004 0 P 0 ;0
L 1.24511998 -2.00616004 1.33393002 -2.00616004 0 P 0 ;0
L 1.24513996 -2.00516004 1.29098996 -2.00516004 0 P 0 ;0
L 1.24513996 -2.00416004 1.29033002 -2.00416004 0 P 0 ;0
L 1.24513996 -2.00316004 1.29005 -2.00316004 0 P 0 ;0
L 1.24513996 -2.00216004 1.29005 -2.00216004 0 P 0 ;0
L 1.24513996 -2.00116004 1.29005 -2.00116004 0 P 0 ;0
L 1.24515 -2.00016004 1.29005 -2.00016004 0 P 0 ;0
L 1.24515 -1.99916004 1.29005 -1.99916004 0 P 0 ;0
L 1.24515 -1.99816004 1.29005 -1.99816004 0 P 0 ;0
L 1.24515 -1.99716004 1.29005 -1.99716004 0 P 0 ;0
L 1.24515 -1.99616004 1.29005 -1.99616004 0 P 0 ;0
L 1.24515 -1.99516004 1.29005 -1.99516004 0 P 0 ;0
L 1.16085 -2.02753002 1.1601 -2.04393002 0 P 0 ;0
L 1.1601 -2.04393002 1.15928996 -2.05771998 0 P 0 ;0
L 1.15928996 -2.05771998 1.15883996 -2.06228002 0 P 0 ;0
L 1.15883996 -2.06228002 1.15818002 -2.06681998 0 P 0 ;0
L 1.15818002 -2.06681998 1.15751004 -2.07006998 0 P 0 ;0
L 1.15751004 -2.07006998 1.15661004 -2.07328996 0 P 0 ;0
L 1.15661004 -2.07328996 1.15616004 -2.07453996 0 P 0 ;0
L 1.15616004 -2.07453996 1.15563002 -2.07576998 0 P 0 ;0
L 1.15563002 -2.07576998 1.15501998 -2.07696004 0 P 0 ;0
L 1.15501998 -2.07696004 1.15433002 -2.0781 0 P 0 ;0
L 1.15433002 -2.0781 1.1534 -2.07941998 0 P 0 ;0
L 1.1534 -2.07941998 1.15236004 -2.08066004 0 P 0 ;0
L 1.15236004 -2.08066004 1.15123002 -2.08181998 0 P 0 ;0
L 1.15123002 -2.08181998 1.15001004 -2.08286998 0 P 0 ;0
L 1.15001004 -2.08286998 1.14871004 -2.08383002 0 P 0 ;0
L 1.14871004 -2.08383002 1.14733002 -2.08468002 0 P 0 ;0
L 1.14733002 -2.08468002 1.14591004 -2.0854 0 P 0 ;0
L 1.14591004 -2.0854 1.14443996 -2.086 0 P 0 ;0
L 1.14443996 -2.086 1.14291004 -2.08648002 0 P 0 ;0
L 1.14291004 -2.08648002 1.14136004 -2.08683002 0 P 0 ;0
L 1.14136004 -2.08683002 1.13976998 -2.08703996 0 P 0 ;0
L 1.13976998 -2.08703996 1.13816004 -2.08713002 0 P 0 ;0
L 1.13816004 -2.08713002 1.13656998 -2.08708002 0 P 0 ;0
L 1.13656998 -2.08708002 1.13498996 -2.0869 0 P 0 ;0
L 1.13498996 -2.0869 1.13341998 -2.08658996 0 P 0 ;0
L 1.13341998 -2.08658996 1.13188996 -2.08615 0 P 0 ;0
L 1.13188996 -2.08615 1.1304 -2.08558996 0 P 0 ;0
L 1.1304 -2.08558996 1.12895 -2.08488996 0 P 0 ;0
L 1.12895 -2.08488996 1.12756998 -2.08408002 0 P 0 ;0
L 1.12756998 -2.08408002 1.12625 -2.08315 0 P 0 ;0
L 1.12625 -2.08315 1.12501004 -2.08211998 0 P 0 ;0
L 1.12501004 -2.08211998 1.12386004 -2.081 0 P 0 ;0
L 1.12386004 -2.081 1.12281004 -2.07978002 0 P 0 ;0
L 1.12281004 -2.07978002 1.12183996 -2.07846998 0 P 0 ;0
L 1.12183996 -2.07846998 1.1211 -2.07726004 0 P 0 ;0
L 1.1211 -2.07726004 1.12046998 -2.07598996 0 P 0 ;0
L 1.12046998 -2.07598996 1.11996004 -2.07466998 0 P 0 ;0
L 1.11996004 -2.07466998 1.11955 -2.07331004 0 P 0 ;0
L 1.11955 -2.07331004 1.11926998 -2.07191004 0 P 0 ;0
L 1.11926998 -2.07191004 1.11868002 -2.06693996 0 P 0 ;0
L 1.11868002 -2.06693996 1.11848002 -2.06191004 0 P 0 ;0
L 1.11848002 -2.06191004 1.11871004 -2.05668002 0 P 0 ;0
L 1.11871004 -2.05668002 1.11936004 -2.05148002 0 P 0 ;0
L 1.11936004 -2.05148002 1.11978996 -2.04936998 0 P 0 ;0
L 1.11978996 -2.04936998 1.12036998 -2.0473 0 P 0 ;0
L 1.12036998 -2.0473 1.12108996 -2.04528002 0 P 0 ;0
L 1.12108996 -2.04528002 1.12196004 -2.04331998 0 P 0 ;0
L 1.12196004 -2.04331998 1.1229 -2.04153996 0 P 0 ;0
L 1.1229 -2.04153996 1.12396998 -2.03985 0 P 0 ;0
L 1.12396998 -2.03985 1.12516998 -2.03823002 0 P 0 ;0
L 1.12516998 -2.03823002 1.12735 -2.03573996 0 P 0 ;0
L 1.12735 -2.03573996 1.12973002 -2.03345 0 P 0 ;0
L 1.12973002 -2.03345 1.13223996 -2.03141998 0 P 0 ;0
L 1.13223996 -2.03141998 1.13491998 -2.02961004 0 P 0 ;0
L 1.13491998 -2.02961004 1.13611004 -2.02893002 0 P 0 ;0
L 1.13611004 -2.02893002 1.13735 -2.02833996 0 P 0 ;0
L 1.13735 -2.02833996 1.13861998 -2.02781998 0 P 0 ;0
L 1.13861998 -2.02781998 1.13993996 -2.0274 0 P 0 ;0
L 1.13993996 -2.0274 1.14191004 -2.02693002 0 P 0 ;0
L 1.14191004 -2.02693002 1.14391004 -2.02663002 0 P 0 ;0
L 1.14391004 -2.02663002 1.14935 -2.02626004 0 P 0 ;0
L 1.14935 -2.02626004 1.15471004 -2.0263 0 P 0 ;0
L 1.15471004 -2.0263 1.15591004 -2.02638996 0 P 0 ;0
L 1.15591004 -2.02638996 1.1571 -2.02656998 0 P 0 ;0
L 1.1571 -2.02656998 1.15828002 -2.02683996 0 P 0 ;0
L 1.15828002 -2.02683996 1.16085 -2.02753002 0 P 0 ;0
L 1.13876998 -2.14783002 1.20233002 -2.14783002 0 P 0 ;0
L 1.14236998 -2.14683002 1.20266004 -2.14683002 0 P 0 ;0
L 1.14481004 -2.14583002 1.20296004 -2.14583002 0 P 0 ;0
L 1.1467 -2.14483002 1.20325 -2.14483002 0 P 0 ;0
L 1.14826004 -2.14383002 1.20353002 -2.14383002 0 P 0 ;0
L 1.1496 -2.14283002 1.20373996 -2.14283002 0 P 0 ;0
L 1.15078996 -2.14183002 1.20395 -2.14183002 0 P 0 ;0
L 1.15186004 -2.14083002 1.20415 -2.14083002 0 P 0 ;0
L 1.15278996 -2.13983002 1.20431998 -2.13983002 0 P 0 ;0
L 1.15361998 -2.13883002 1.20446004 -2.13883002 0 P 0 ;0
L 1.15436004 -2.13783002 1.20458002 -2.13783002 0 P 0 ;0
L 1.155 -2.13683002 1.20466998 -2.13683002 0 P 0 ;0
L 1.15556998 -2.13583002 1.20475 -2.13583002 0 P 0 ;0
L 1.15608996 -2.13483002 1.20481998 -2.13483002 0 P 0 ;0
L 1.15653996 -2.13383002 1.20488996 -2.13383002 0 P 0 ;0
L 1.15691004 -2.13283002 1.20496004 -2.13283002 0 P 0 ;0
L 1.15723996 -2.13183002 1.20503002 -2.13183002 0 P 0 ;0
L 1.15751998 -2.13083002 1.2051 -2.13083002 0 P 0 ;0
L 1.15773002 -2.12983002 1.20516004 -2.12983002 0 P 0 ;0
L 1.15793002 -2.12883002 1.20523002 -2.12883002 0 P 0 ;0
L 1.15806004 -2.12783002 1.2053 -2.12783002 0 P 0 ;0
L 1.15816998 -2.12683002 1.20536998 -2.12683002 0 P 0 ;0
L 1.15821004 -2.12583002 1.20543996 -2.12583002 0 P 0 ;0
L 1.11716004 -2.12483002 1.12726004 -2.12483002 0 P 0 ;0
L 1.15823996 -2.12483002 1.20551004 -2.12483002 0 P 0 ;0
L 1.10911998 -2.12383002 1.1352 -2.12383002 0 P 0 ;0
L 1.15821998 -2.12383002 1.20556998 -2.12383002 0 P 0 ;0
L 1.10468996 -2.12283002 1.14018996 -2.12283002 0 P 0 ;0
L 1.1582 -2.12283002 1.20563996 -2.12283002 0 P 0 ;0
L 1.10131004 -2.12183002 1.14366998 -2.12183002 0 P 0 ;0
L 1.15818002 -2.12183002 1.2057 -2.12183002 0 P 0 ;0
L 1.15808996 -2.12083002 1.20576004 -2.12083002 0 P 0 ;0
L 1.15781004 -2.11983002 1.20583002 -2.11983002 0 P 0 ;0
L 1.15721004 -2.11883002 1.20588002 -2.11883002 0 P 0 ;0
L 1.14146004 -2.08883002 1.20758002 -2.08883002 0 P 0 ;0
L 1.14525 -2.08783002 1.20763002 -2.08783002 0 P 0 ;0
L 1.14751004 -2.08683002 1.20768002 -2.08683002 0 P 0 ;0
L 1.14928002 -2.08583002 1.20773002 -2.08583002 0 P 0 ;0
L 1.15073002 -2.08483002 1.20778996 -2.08483002 0 P 0 ;0
L 1.15196004 -2.08383002 1.20783996 -2.08383002 0 P 0 ;0
L 1.13818996 -2.08913002 1.13826998 -2.08913002 0 P 0 ;0
L 1.13826998 -2.08913002 1.13988002 -2.08903996 0 P 0 ;0
L 1.13988002 -2.08903996 1.13996004 -2.08903996 0 P 0 ;0
L 1.13996004 -2.08903996 1.14001004 -2.08903002 0 P 0 ;0
L 1.14001004 -2.08903002 1.14005 -2.08901998 0 P 0 ;0
L 1.14005 -2.08901998 1.14163002 -2.08881004 0 P 0 ;0
L 1.14163002 -2.08881004 1.14166998 -2.0888 0 P 0 ;0
L 1.14166998 -2.0888 1.14171004 -2.0888 0 P 0 ;0
L 1.14171004 -2.0888 1.14178996 -2.08878002 0 P 0 ;0
L 1.14178996 -2.08878002 1.14335 -2.08843002 0 P 0 ;0
L 1.14335 -2.08843002 1.14351004 -2.08838996 0 P 0 ;0
L 1.14351004 -2.08838996 1.14503002 -2.08791004 0 P 0 ;0
L 1.14503002 -2.08791004 1.14511004 -2.08788996 0 P 0 ;0
L 1.14511004 -2.08788996 1.14515 -2.08786998 0 P 0 ;0
L 1.14515 -2.08786998 1.14518996 -2.08786004 0 P 0 ;0
L 1.14518996 -2.08786004 1.14666004 -2.08725 0 P 0 ;0
L 1.14666004 -2.08725 1.14673996 -2.08721998 0 P 0 ;0
L 1.14673996 -2.08721998 1.14678002 -2.0872 0 P 0 ;0
L 1.14678002 -2.0872 1.14681998 -2.08718996 0 P 0 ;0
L 1.14681998 -2.08718996 1.14823996 -2.08646998 0 P 0 ;0
L 1.14823996 -2.08646998 1.14826998 -2.08645 0 P 0 ;0
L 1.14826998 -2.08645 1.14835 -2.08641004 0 P 0 ;0
L 1.14835 -2.08641004 1.14838002 -2.08638002 0 P 0 ;0
L 1.14838002 -2.08638002 1.14976004 -2.08553002 0 P 0 ;0
L 1.14976004 -2.08553002 1.14978996 -2.08551004 0 P 0 ;0
L 1.14978996 -2.08551004 1.14983002 -2.08548996 0 P 0 ;0
L 1.14983002 -2.08548996 1.14988996 -2.08543996 0 P 0 ;0
L 1.14988996 -2.08543996 1.1512 -2.08448996 0 P 0 ;0
L 1.1512 -2.08448996 1.15126004 -2.08443996 0 P 0 ;0
L 1.15126004 -2.08443996 1.15128996 -2.08441004 0 P 0 ;0
L 1.15128996 -2.08441004 1.15131998 -2.08438996 0 P 0 ;0
L 1.15131998 -2.08438996 1.15253996 -2.08333002 0 P 0 ;0
L 1.15253996 -2.08333002 1.15256998 -2.0833 0 P 0 ;0
L 1.15256998 -2.0833 1.1526 -2.08328002 0 P 0 ;0
L 1.1526 -2.08328002 1.15263002 -2.08323996 0 P 0 ;0
L 1.15263002 -2.08323996 1.15266004 -2.08321998 0 P 0 ;0
L 1.15266004 -2.08321998 1.15378996 -2.08206004 0 P 0 ;0
L 1.15378996 -2.08206004 1.15376004 -2.08203996 0 P 0 ;0
L 1.15376004 -2.08203996 1.15381998 -2.08203996 0 P 0 ;0
L 1.15381998 -2.08203996 1.15383996 -2.082 0 P 0 ;0
L 1.15383996 -2.082 1.15386998 -2.08196998 0 P 0 ;0
L 1.15386998 -2.08196998 1.1539 -2.08195 0 P 0 ;0
L 1.1539 -2.08195 1.15493002 -2.08071004 0 P 0 ;0
L 1.15493002 -2.08071004 1.15493002 -2.0807 0 P 0 ;0
L 1.15493002 -2.0807 1.15496004 -2.08066998 0 P 0 ;0
L 1.15496004 -2.08066998 1.15498002 -2.08063996 0 P 0 ;0
L 1.15498002 -2.08063996 1.15501004 -2.08061004 0 P 0 ;0
L 1.15501004 -2.08061004 1.15503002 -2.08058002 0 P 0 ;0
L 1.15503002 -2.08058002 1.15596004 -2.07926004 0 P 0 ;0
L 1.15596004 -2.07926004 1.15603996 -2.07913996 0 P 0 ;0
L 1.15603996 -2.07913996 1.15673002 -2.07798996 0 P 0 ;0
L 1.15673002 -2.07798996 1.15676998 -2.07793002 0 P 0 ;0
L 1.15676998 -2.07793002 1.15678996 -2.07786998 0 P 0 ;0
L 1.15678996 -2.07786998 1.15741004 -2.07668996 0 P 0 ;0
L 1.15741004 -2.07668996 1.15743996 -2.07663002 0 P 0 ;0
L 1.15743996 -2.07663002 1.15746004 -2.07656998 0 P 0 ;0
L 1.15746004 -2.07656998 1.15746998 -2.07656998 0 P 0 ;0
L 1.15746998 -2.07656998 1.158 -2.07533996 0 P 0 ;0
L 1.158 -2.07533996 1.15801004 -2.07531004 0 P 0 ;0
L 1.15801004 -2.07531004 1.15803002 -2.07528002 0 P 0 ;0
L 1.15803002 -2.07528002 1.15805 -2.07521998 0 P 0 ;0
L 1.15805 -2.07521998 1.15848996 -2.07396004 0 P 0 ;0
L 1.15848996 -2.07396004 1.15841004 -2.07393002 0 P 0 ;0
L 1.15841004 -2.07393002 1.15851004 -2.07393002 0 P 0 ;0
L 1.15851004 -2.07393002 1.15851998 -2.0739 0 P 0 ;0
L 1.15851998 -2.0739 1.15853002 -2.07386004 0 P 0 ;0
L 1.15853002 -2.07386004 1.15853996 -2.07383002 0 P 0 ;0
L 1.15853996 -2.07383002 1.15943996 -2.07061004 0 P 0 ;0
L 1.15943996 -2.07061004 1.15945 -2.07058002 0 P 0 ;0
L 1.15945 -2.07058002 1.15946004 -2.07053996 0 P 0 ;0
L 1.15946004 -2.07053996 1.15946998 -2.07051004 0 P 0 ;0
L 1.15946998 -2.07051004 1.15946998 -2.07046998 0 P 0 ;0
L 1.15946998 -2.07046998 1.16013996 -2.06723002 0 P 0 ;0
L 1.16013996 -2.06723002 1.16013996 -2.0672 0 P 0 ;0
L 1.16013996 -2.0672 1.16016004 -2.06713996 0 P 0 ;0
L 1.16016004 -2.06713996 1.16016004 -2.06711004 0 P 0 ;0
L 1.16016004 -2.06711004 1.16081998 -2.06256004 0 P 0 ;0
L 1.16081998 -2.06256004 1.16081998 -2.06253996 0 P 0 ;0
L 1.16081998 -2.06253996 1.16083002 -2.0625 0 P 0 ;0
L 1.16083002 -2.0625 1.16083002 -2.06246998 0 P 0 ;0
L 1.16083002 -2.06246998 1.16126998 -2.05791004 0 P 0 ;0
L 1.16126998 -2.05791004 1.16128002 -2.0579 0 P 0 ;0
L 1.16128002 -2.0579 1.16128002 -2.05783996 0 P 0 ;0
L 1.16128002 -2.05783996 1.1621 -2.04405 0 P 0 ;0
L 1.1621 -2.04405 1.1621 -2.04401998 0 P 0 ;0
L 1.1621 -2.04401998 1.16285 -2.02761998 0 P 0 ;0
L 1.16285 -2.02761998 1.16136998 -2.0256 0 P 0 ;0
L 1.16136998 -2.0256 1.15878996 -2.02491004 0 P 0 ;0
L 1.15878996 -2.02491004 1.15878002 -2.0249 0 P 0 ;0
L 1.15878002 -2.0249 1.15871998 -2.02488996 0 P 0 ;0
L 1.15871998 -2.02488996 1.15755 -2.02461998 0 P 0 ;0
L 1.15755 -2.02461998 1.15746998 -2.0246 0 P 0 ;0
L 1.15746998 -2.0246 1.1574 -2.0246 0 P 0 ;0
L 1.1574 -2.0246 1.15621004 -2.02441004 0 P 0 ;0
L 1.15621004 -2.02441004 1.15616998 -2.02441004 0 P 0 ;0
L 1.15616998 -2.02441004 1.1561 -2.0244 0 P 0 ;0
L 1.1561 -2.0244 1.15606004 -2.02438996 0 P 0 ;0
L 1.15606004 -2.02438996 1.15486004 -2.0243 0 P 0 ;0
L 1.15486004 -2.0243 1.15471998 -2.0243 0 P 0 ;0
L 1.15471998 -2.0243 1.14936004 -2.02426004 0 P 0 ;0
L 1.14936004 -2.02426004 1.14928996 -2.02426004 0 P 0 ;0
L 1.14928996 -2.02426004 1.14925 -2.02426998 0 P 0 ;0
L 1.14925 -2.02426998 1.14921004 -2.02426998 0 P 0 ;0
L 1.14921004 -2.02426998 1.14376998 -2.02463996 0 P 0 ;0
L 1.14376998 -2.02463996 1.1437 -2.02463996 0 P 0 ;0
L 1.1437 -2.02463996 1.14365 -2.02465 0 P 0 ;0
L 1.14365 -2.02465 1.14361004 -2.02465 0 P 0 ;0
L 1.14361004 -2.02465 1.14161998 -2.02495 0 P 0 ;0
L 1.14161998 -2.02495 1.14161004 -2.02495 0 P 0 ;0
L 1.14161004 -2.02495 1.14153002 -2.02496998 0 P 0 ;0
L 1.14153002 -2.02496998 1.14148996 -2.02496998 0 P 0 ;0
L 1.14148996 -2.02496998 1.14143996 -2.02498996 0 P 0 ;0
L 1.14143996 -2.02498996 1.13946998 -2.02545 0 P 0 ;0
L 1.13946998 -2.02545 1.13943996 -2.02546998 0 P 0 ;0
L 1.13943996 -2.02546998 1.1394 -2.02546998 0 P 0 ;0
L 1.1394 -2.02546998 1.13933002 -2.0255 0 P 0 ;0
L 1.13933002 -2.0255 1.13801004 -2.02591998 0 P 0 ;0
L 1.13801004 -2.02591998 1.13798002 -2.02593002 0 P 0 ;0
L 1.13798002 -2.02593002 1.13793996 -2.02593996 0 P 0 ;0
L 1.13793996 -2.02593996 1.13788002 -2.02596998 0 P 0 ;0
L 1.13788002 -2.02596998 1.1366 -2.02648002 0 P 0 ;0
L 1.1366 -2.02648002 1.13653996 -2.0265 0 P 0 ;0
L 1.13653996 -2.0265 1.13648002 -2.02653002 0 P 0 ;0
L 1.13648002 -2.02653002 1.13523996 -2.02713002 0 P 0 ;0
L 1.13523996 -2.02713002 1.13518002 -2.02716004 0 P 0 ;0
L 1.13518002 -2.02716004 1.13515 -2.02716998 0 P 0 ;0
L 1.13515 -2.02716998 1.13511998 -2.02718996 0 P 0 ;0
L 1.13511998 -2.02718996 1.13393002 -2.02786998 0 P 0 ;0
L 1.13393002 -2.02786998 1.13388996 -2.02788996 0 P 0 ;0
L 1.13388996 -2.02788996 1.1338 -2.02795 0 P 0 ;0
L 1.1338 -2.02795 1.13111998 -2.02976004 0 P 0 ;0
L 1.13111998 -2.02976004 1.13105 -2.02981004 0 P 0 ;0
L 1.13105 -2.02981004 1.13101004 -2.02983996 0 P 0 ;0
L 1.13101004 -2.02983996 1.13098002 -2.02986004 0 P 0 ;0
L 1.13098002 -2.02986004 1.12846998 -2.03188996 0 P 0 ;0
L 1.12846998 -2.03188996 1.12838002 -2.03198002 0 P 0 ;0
L 1.12838002 -2.03198002 1.12833996 -2.03201004 0 P 0 ;0
L 1.12833996 -2.03201004 1.12596004 -2.0343 0 P 0 ;0
L 1.12596004 -2.0343 1.12593996 -2.03433002 0 P 0 ;0
L 1.12593996 -2.03433002 1.1259 -2.03436004 0 P 0 ;0
L 1.1259 -2.03436004 1.12588002 -2.03438996 0 P 0 ;0
L 1.12588002 -2.03438996 1.12585 -2.03443002 0 P 0 ;0
L 1.12585 -2.03443002 1.12366998 -2.03691004 0 P 0 ;0
L 1.12366998 -2.03691004 1.12363996 -2.03695 0 P 0 ;0
L 1.12363996 -2.03695 1.12361998 -2.03698002 0 P 0 ;0
L 1.12361998 -2.03698002 1.12358996 -2.03701004 0 P 0 ;0
L 1.12358996 -2.03701004 1.12356998 -2.03703996 0 P 0 ;0
L 1.12356998 -2.03703996 1.12236998 -2.03865 0 P 0 ;0
L 1.12236998 -2.03865 1.12233996 -2.03868996 0 P 0 ;0
L 1.12233996 -2.03868996 1.12233002 -2.03871004 0 P 0 ;0
L 1.12233002 -2.03871004 1.12228996 -2.03878002 0 P 0 ;0
L 1.12228996 -2.03878002 1.12121004 -2.04046998 0 P 0 ;0
L 1.12121004 -2.04046998 1.12118996 -2.0405 0 P 0 ;0
L 1.12118996 -2.0405 1.12116998 -2.04053996 0 P 0 ;0
L 1.12116998 -2.04053996 1.12115 -2.04056998 0 P 0 ;0
L 1.12115 -2.04056998 1.12113996 -2.04061004 0 P 0 ;0
L 1.12113996 -2.04061004 1.12018996 -2.04238002 0 P 0 ;0
L 1.12018996 -2.04238002 1.12016004 -2.04245 0 P 0 ;0
L 1.12016004 -2.04245 1.12013996 -2.04248002 0 P 0 ;0
L 1.12013996 -2.04248002 1.12013002 -2.04251004 0 P 0 ;0
L 1.12013002 -2.04251004 1.11926004 -2.04446998 0 P 0 ;0
L 1.11926004 -2.04446998 1.11925 -2.0445 0 P 0 ;0
L 1.11925 -2.0445 1.11923002 -2.04453996 0 P 0 ;0
L 1.11923002 -2.04453996 1.11921998 -2.04458002 0 P 0 ;0
L 1.11921998 -2.04458002 1.11921004 -2.04461004 0 P 0 ;0
L 1.11921004 -2.04461004 1.11848002 -2.04663002 0 P 0 ;0
L 1.11848002 -2.04663002 1.11846998 -2.04666004 0 P 0 ;0
L 1.11846998 -2.04666004 1.11846004 -2.0467 0 P 0 ;0
L 1.11846004 -2.0467 1.11843996 -2.04676998 0 P 0 ;0
L 1.11843996 -2.04676998 1.11786004 -2.04883996 0 P 0 ;0
L 1.11786004 -2.04883996 1.11785 -2.04886998 0 P 0 ;0
L 1.11785 -2.04886998 1.11783996 -2.04891004 0 P 0 ;0
L 1.11783996 -2.04891004 1.11783996 -2.04893996 0 P 0 ;0
L 1.11783996 -2.04893996 1.11783002 -2.04896998 0 P 0 ;0
L 1.11783002 -2.04896998 1.11783002 -2.04898002 0 P 0 ;0
L 1.11783002 -2.04898002 1.1174 -2.05108002 0 P 0 ;0
L 1.1174 -2.05108002 1.1174 -2.05111998 0 P 0 ;0
L 1.1174 -2.05111998 1.11738996 -2.05116004 0 P 0 ;0
L 1.11738996 -2.05116004 1.11738002 -2.05118996 0 P 0 ;0
L 1.11738002 -2.05118996 1.11738002 -2.05123002 0 P 0 ;0
L 1.11738002 -2.05123002 1.11673002 -2.05643002 0 P 0 ;0
L 1.11673002 -2.05643002 1.11671998 -2.05646998 0 P 0 ;0
L 1.11671998 -2.05646998 1.11671998 -2.05655 0 P 0 ;0
L 1.11671998 -2.05655 1.11671004 -2.05658996 0 P 0 ;0
L 1.11671004 -2.05658996 1.11648996 -2.06181998 0 P 0 ;0
L 1.11648996 -2.06181998 1.11648002 -2.06186998 0 P 0 ;0
L 1.11648002 -2.06186998 1.11648002 -2.06195 0 P 0 ;0
L 1.11648002 -2.06195 1.11648996 -2.06198996 0 P 0 ;0
L 1.11648996 -2.06198996 1.11668002 -2.06696998 0 P 0 ;0
L 1.11668002 -2.06696998 1.11768002 -2.06696998 0 P 0 ;0
L 1.11768002 -2.06696998 1.11668002 -2.06701004 0 P 0 ;0
L 1.11668002 -2.06701004 1.11668002 -2.06713002 0 P 0 ;0
L 1.11668002 -2.06713002 1.11668996 -2.06716998 0 P 0 ;0
L 1.11668996 -2.06716998 1.11728002 -2.07215 0 P 0 ;0
L 1.11728002 -2.07215 1.11728996 -2.07218996 0 P 0 ;0
L 1.11728996 -2.07218996 1.11728996 -2.07223002 0 P 0 ;0
L 1.11728996 -2.07223002 1.11731004 -2.07231004 0 P 0 ;0
L 1.11731004 -2.07231004 1.11758996 -2.07371004 0 P 0 ;0
L 1.11758996 -2.07371004 1.1176 -2.07375 0 P 0 ;0
L 1.1176 -2.07375 1.11761004 -2.0738 0 P 0 ;0
L 1.11761004 -2.0738 1.11761998 -2.07383996 0 P 0 ;0
L 1.11761998 -2.07383996 1.11763996 -2.07388002 0 P 0 ;0
L 1.11763996 -2.07388002 1.11803996 -2.07523996 0 P 0 ;0
L 1.11803996 -2.07523996 1.11806004 -2.07531998 0 P 0 ;0
L 1.11806004 -2.07531998 1.11808002 -2.07536004 0 P 0 ;0
L 1.11808002 -2.07536004 1.11808996 -2.07541004 0 P 0 ;0
L 1.11808996 -2.07541004 1.11861004 -2.07673002 0 P 0 ;0
L 1.11861004 -2.07673002 1.11863996 -2.07681004 0 P 0 ;0
L 1.11863996 -2.07681004 1.11866004 -2.07683996 0 P 0 ;0
L 1.11866004 -2.07683996 1.11868002 -2.07688002 0 P 0 ;0
L 1.11868002 -2.07688002 1.11931004 -2.07815 0 P 0 ;0
L 1.11931004 -2.07815 1.11935 -2.07823002 0 P 0 ;0
L 1.11935 -2.07823002 1.1194 -2.0783 0 P 0 ;0
L 1.1194 -2.0783 1.12013996 -2.07951998 0 P 0 ;0
L 1.12013996 -2.07951998 1.12021004 -2.07961998 0 P 0 ;0
L 1.12021004 -2.07961998 1.12023002 -2.07965 0 P 0 ;0
L 1.12023002 -2.07965 1.12023002 -2.07966004 0 P 0 ;0
L 1.12023002 -2.07966004 1.1212 -2.08096998 0 P 0 ;0
L 1.1212 -2.08096998 1.12123996 -2.08103002 0 P 0 ;0
L 1.12123996 -2.08103002 1.12126998 -2.08106004 0 P 0 ;0
L 1.12126998 -2.08106004 1.12128996 -2.08108996 0 P 0 ;0
L 1.12128996 -2.08108996 1.12235 -2.08231004 0 P 0 ;0
L 1.12235 -2.08231004 1.12238002 -2.08233996 0 P 0 ;0
L 1.12238002 -2.08233996 1.1224 -2.08236998 0 P 0 ;0
L 1.1224 -2.08236998 1.12246004 -2.08243002 0 P 0 ;0
L 1.12246004 -2.08243002 1.12361004 -2.08355 0 P 0 ;0
L 1.12361004 -2.08355 1.12366998 -2.08361004 0 P 0 ;0
L 1.12366998 -2.08361004 1.1237 -2.08363002 0 P 0 ;0
L 1.1237 -2.08363002 1.12373002 -2.08366004 0 P 0 ;0
L 1.12373002 -2.08366004 1.12496998 -2.08468996 0 P 0 ;0
L 1.12496998 -2.08468996 1.125 -2.08471004 0 P 0 ;0
L 1.125 -2.08471004 1.12503002 -2.08473996 0 P 0 ;0
L 1.12503002 -2.08473996 1.12506998 -2.08476004 0 P 0 ;0
L 1.12506998 -2.08476004 1.1251 -2.08478996 0 P 0 ;0
L 1.1251 -2.08478996 1.12641998 -2.08571004 0 P 0 ;0
L 1.12641998 -2.08571004 1.12645 -2.08573002 0 P 0 ;0
L 1.12645 -2.08573002 1.12648002 -2.08576004 0 P 0 ;0
L 1.12648002 -2.08576004 1.12651004 -2.08578002 0 P 0 ;0
L 1.12651004 -2.08578002 1.12655 -2.0858 0 P 0 ;0
L 1.12655 -2.0858 1.12793996 -2.08661004 0 P 0 ;0
L 1.12793996 -2.08661004 1.12801004 -2.08665 0 P 0 ;0
L 1.12801004 -2.08665 1.12805 -2.08666998 0 P 0 ;0
L 1.12805 -2.08666998 1.12808002 -2.08668996 0 P 0 ;0
L 1.12808002 -2.08668996 1.12808996 -2.08668996 0 P 0 ;0
L 1.12808996 -2.08668996 1.12953996 -2.08738996 0 P 0 ;0
L 1.12953996 -2.08738996 1.12961998 -2.08743002 0 P 0 ;0
L 1.12961998 -2.08743002 1.12965 -2.08743996 0 P 0 ;0
L 1.12965 -2.08743996 1.1297 -2.08746004 0 P 0 ;0
L 1.1297 -2.08746004 1.13118002 -2.08801998 0 P 0 ;0
L 1.13118002 -2.08801998 1.13133996 -2.08808002 0 P 0 ;0
L 1.13133996 -2.08808002 1.13286998 -2.08851004 0 P 0 ;0
L 1.13286998 -2.08851004 1.13295 -2.08853996 0 P 0 ;0
L 1.13295 -2.08853996 1.13303996 -2.08855 0 P 0 ;0
L 1.13303996 -2.08855 1.1346 -2.08886004 0 P 0 ;0
L 1.1346 -2.08886004 1.13471998 -2.08888996 0 P 0 ;0
L 1.13471998 -2.08888996 1.13476004 -2.08888996 0 P 0 ;0
L 1.13476004 -2.08888996 1.13633996 -2.08906998 0 P 0 ;0
L 1.13633996 -2.08906998 1.13638996 -2.08908002 0 P 0 ;0
L 1.13638996 -2.08908002 1.13651004 -2.08908002 0 P 0 ;0
L 1.13651004 -2.08908002 1.1381 -2.08913002 0 P 0 ;0
L 1.1381 -2.08913002 1.13818996 -2.08913002 0 P 0 ;0
L 1.31623996 -1.98923996 1.3135 -1.98988002 0 P 0 ;0
L 1.3135 -1.98988002 1.31078996 -1.99071004 0 P 0 ;0
L 1.31078996 -1.99071004 1.30813002 -1.99175 0 P 0 ;0
L 1.30813002 -1.99175 1.30553996 -1.99296998 0 P 0 ;0
L 1.30553996 -1.99296998 1.30308996 -1.99431998 0 P 0 ;0
L 1.30308996 -1.99431998 1.30073996 -1.99585 0 P 0 ;0
L 1.30073996 -1.99585 1.29863996 -1.99746004 0 P 0 ;0
L 1.29863996 -1.99746004 1.29666004 -1.99923996 0 P 0 ;0
L 1.29666004 -1.99923996 1.29205 -2.00375 0 P 0 ;0
L 1.29205 -2.00375 1.29205 -1.99243996 0 P 0 ;0
L 1.29205 -1.99243996 1.24316004 -1.99243996 0 P 0 ;0
L 1.24316004 -1.99243996 1.24313996 -2.00521004 0 P 0 ;0
L 1.24313996 -2.00521004 1.24261004 -2.03151004 0 P 0 ;0
L 1.24261004 -2.03151004 1.24086998 -2.07046004 0 P 0 ;0
L 1.24086998 -2.07046004 1.23873996 -2.10921004 0 P 0 ;0
L 1.23873996 -2.10921004 1.23811998 -2.11641998 0 P 0 ;0
L 1.23811998 -2.11641998 1.23711998 -2.12361998 0 P 0 ;0
L 1.23711998 -2.12361998 1.23655 -2.12716004 0 P 0 ;0
L 1.23655 -2.12716004 1.29205 -2.12716004 0 P 0 ;0
L 1.29205 -2.12716004 1.29206998 -2.11766004 0 P 0 ;0
L 1.29206998 -2.11766004 1.29238996 -2.10283996 0 P 0 ;0
L 1.29238996 -2.10283996 1.29336004 -2.08431004 0 P 0 ;0
L 1.29336004 -2.08431004 1.29463996 -2.06673002 0 P 0 ;0
L 1.29463996 -2.06673002 1.29511004 -2.06253002 0 P 0 ;0
L 1.29511004 -2.06253002 1.29583996 -2.05836004 0 P 0 ;0
L 1.29583996 -2.05836004 1.29683002 -2.05446998 0 P 0 ;0
L 1.29683002 -2.05446998 1.29813996 -2.05068996 0 P 0 ;0
L 1.29813996 -2.05068996 1.29978002 -2.04701998 0 P 0 ;0
L 1.29978002 -2.04701998 1.30056998 -2.04556998 0 P 0 ;0
L 1.30056998 -2.04556998 1.30146998 -2.04418996 0 P 0 ;0
L 1.30146998 -2.04418996 1.30246998 -2.04288002 0 P 0 ;0
L 1.30246998 -2.04288002 1.30356998 -2.04165 0 P 0 ;0
L 1.30356998 -2.04165 1.30475 -2.0405 0 P 0 ;0
L 1.30475 -2.0405 1.30603996 -2.03945 0 P 0 ;0
L 1.30603996 -2.03945 1.30773996 -2.03826004 0 P 0 ;0
L 1.30773996 -2.03826004 1.30953002 -2.03723002 0 P 0 ;0
L 1.30953002 -2.03723002 1.31141004 -2.03635 0 P 0 ;0
L 1.31141004 -2.03635 1.31335 -2.03563002 0 P 0 ;0
L 1.31335 -2.03563002 1.31535 -2.03508002 0 P 0 ;0
L 1.31535 -2.03508002 1.31973996 -2.03423002 0 P 0 ;0
L 1.31973996 -2.03423002 1.32416004 -2.03366998 0 P 0 ;0
L 1.32416004 -2.03366998 1.32863002 -2.0334 0 P 0 ;0
L 1.32863002 -2.0334 1.33688002 -2.03318002 0 P 0 ;0
L 1.33688002 -2.03318002 1.33613002 -2.01151004 0 P 0 ;0
L 1.33613002 -2.01151004 1.33581004 -2.00315 0 P 0 ;0
L 1.33581004 -2.00315 1.33543996 -1.99596004 0 P 0 ;0
L 1.33543996 -1.99596004 1.33508002 -1.98971004 0 P 0 ;0
L 1.33508002 -1.98971004 1.33503996 -1.98945 0 P 0 ;0
L 1.33503996 -1.98945 1.335 -1.98931998 0 P 0 ;0
L 1.335 -1.98931998 1.33496004 -1.9892 0 P 0 ;0
L 1.33496004 -1.9892 1.3349 -1.98908002 0 P 0 ;0
L 1.3349 -1.98908002 1.33483996 -1.98896998 0 P 0 ;0
L 1.33483996 -1.98896998 1.33476998 -1.98886004 0 P 0 ;0
L 1.33476998 -1.98886004 1.33468996 -1.98876004 0 P 0 ;0
L 1.33468996 -1.98876004 1.3346 -1.98866998 0 P 0 ;0
L 1.3346 -1.98866998 1.33451004 -1.98858996 0 P 0 ;0
L 1.33451004 -1.98858996 1.3344 -1.98851998 0 P 0 ;0
L 1.3344 -1.98851998 1.3343 -1.98845 0 P 0 ;0
L 1.3343 -1.98845 1.33418002 -1.98838996 0 P 0 ;0
L 1.33418002 -1.98838996 1.33406998 -1.98833996 0 P 0 ;0
L 1.33406998 -1.98833996 1.33395 -1.9883 0 P 0 ;0
L 1.33395 -1.9883 1.33383002 -1.98828002 0 P 0 ;0
L 1.33383002 -1.98828002 1.3337 -1.98826004 0 P 0 ;0
L 1.3337 -1.98826004 1.33356998 -1.98825 0 P 0 ;0
L 1.33356998 -1.98825 1.32756998 -1.98823002 0 P 0 ;0
L 1.32756998 -1.98823002 1.32135 -1.98853996 0 P 0 ;0
L 1.32135 -1.98853996 1.31878996 -1.98881998 0 P 0 ;0
L 1.31878996 -1.98881998 1.31623996 -1.98923996 0 P 0 ;0
L 1.2389 -2.12516004 1.29006004 -2.12516004 0 P 0 ;0
L 1.23906998 -2.12416004 1.29006004 -2.12416004 0 P 0 ;0
L 1.23921004 -2.12316004 1.29006004 -2.12316004 0 P 0 ;0
L 1.23933996 -2.12216004 1.29006004 -2.12216004 0 P 0 ;0
L 1.23948996 -2.12116004 1.29006004 -2.12116004 0 P 0 ;0
L 1.23961998 -2.12016004 1.29006998 -2.12016004 0 P 0 ;0
L 1.23976004 -2.11916004 1.29006998 -2.11916004 0 P 0 ;0
L 1.2399 -2.11816004 1.29006998 -2.11816004 0 P 0 ;0
L 1.24003996 -2.11716004 1.29008002 -2.11716004 0 P 0 ;0
L 1.24015 -2.11616004 1.2901 -2.11616004 0 P 0 ;0
L 1.24023996 -2.11516004 1.29011998 -2.11516004 0 P 0 ;0
L 1.24033002 -2.11416004 1.29013996 -2.11416004 0 P 0 ;0
L 1.24041004 -2.11316004 1.29016004 -2.11316004 0 P 0 ;0
L 1.24048996 -2.11216004 1.29018996 -2.11216004 0 P 0 ;0
L 1.24058002 -2.11116004 1.29021004 -2.11116004 0 P 0 ;0
L 1.24066998 -2.11016004 1.29023002 -2.11016004 0 P 0 ;0
L 1.24075 -2.10916004 1.29025 -2.10916004 0 P 0 ;0
L 1.2408 -2.10816004 1.29026998 -2.10816004 0 P 0 ;0
L 1.24086004 -2.10716004 1.29028996 -2.10716004 0 P 0 ;0
L 1.24091004 -2.10616004 1.29031998 -2.10616004 0 P 0 ;0
L 1.24096998 -2.10516004 1.29033996 -2.10516004 0 P 0 ;0
L 1.24101998 -2.10416004 1.29036004 -2.10416004 0 P 0 ;0
L 1.24108002 -2.10316004 1.29038002 -2.10316004 0 P 0 ;0
L 1.24113002 -2.10216004 1.29041998 -2.10216004 0 P 0 ;0
L 1.24118002 -2.10116004 1.29046998 -2.10116004 0 P 0 ;0
L 1.24123996 -2.10016004 1.29053002 -2.10016004 0 P 0 ;0
L 1.24128996 -2.09916004 1.29058002 -2.09916004 0 P 0 ;0
L 1.24135 -2.09816004 1.29063002 -2.09816004 0 P 0 ;0
L 1.2414 -2.09716004 1.29068002 -2.09716004 0 P 0 ;0
L 1.24146004 -2.09616004 1.29073996 -2.09616004 0 P 0 ;0
L 1.24151004 -2.09516004 1.29078996 -2.09516004 0 P 0 ;0
L 1.24156998 -2.09416004 1.29083996 -2.09416004 0 P 0 ;0
L 1.24161998 -2.09316004 1.2909 -2.09316004 0 P 0 ;0
L 1.24168002 -2.09216004 1.29095 -2.09216004 0 P 0 ;0
L 1.24173002 -2.09116004 1.291 -2.09116004 0 P 0 ;0
L 1.24178996 -2.09016004 1.29105 -2.09016004 0 P 0 ;0
L 1.24183996 -2.08916004 1.2911 -2.08916004 0 P 0 ;0
L 1.2419 -2.08816004 1.29116004 -2.08816004 0 P 0 ;0
L 1.24196004 -2.08716004 1.29121004 -2.08716004 0 P 0 ;0
L 1.24201004 -2.08616004 1.29126998 -2.08616004 0 P 0 ;0
L 1.24206998 -2.08516004 1.29131998 -2.08516004 0 P 0 ;0
L 1.24211998 -2.08416004 1.29136998 -2.08416004 0 P 0 ;0
L 1.2389 -2.12516004 1.2391 -2.12393002 0 P 0 ;0
L 1.2391 -2.12393002 1.2391 -2.1239 0 P 0 ;0
L 1.2391 -2.1239 1.24011004 -2.11665 0 P 0 ;0
L 1.24011004 -2.11665 1.24073002 -2.10935 0 P 0 ;0
L 1.24073002 -2.10935 1.24073996 -2.10931998 0 P 0 ;0
L 1.24073996 -2.10931998 1.24286004 -2.07056004 0 P 0 ;0
L 1.24286004 -2.07056004 1.24461004 -2.03158002 0 P 0 ;0
L 1.24461004 -2.03158002 1.24513996 -2.00523002 0 P 0 ;0
L 1.24513996 -2.00523002 1.24515 -1.99443996 0 P 0 ;0
L 1.24515 -1.99443996 1.29005 -1.99443996 0 P 0 ;0
L 1.29005 -1.99443996 1.29005 -2.00375 0 P 0 ;0
L 1.29005 -2.00375 1.29128002 -2.0056 0 P 0 ;0
L 1.29128002 -2.0056 1.29345 -2.00518002 0 P 0 ;0
L 1.29345 -2.00518002 1.29803002 -2.0007 0 P 0 ;0
L 1.29803002 -2.0007 1.29991998 -1.999 0 P 0 ;0
L 1.29991998 -1.999 1.30188996 -1.99748996 0 P 0 ;0
L 1.30188996 -1.99748996 1.30411998 -1.99603996 0 P 0 ;0
L 1.30411998 -1.99603996 1.30645 -1.99475 0 P 0 ;0
L 1.30645 -1.99475 1.30891998 -1.99358996 0 P 0 ;0
L 1.30891998 -1.99358996 1.31145 -1.9926 0 P 0 ;0
L 1.31145 -1.9926 1.31401998 -1.99181004 0 P 0 ;0
L 1.31401998 -1.99181004 1.31663996 -1.9912 0 P 0 ;0
L 1.31663996 -1.9912 1.31906004 -1.9908 0 P 0 ;0
L 1.31906004 -1.9908 1.32151004 -1.99053002 0 P 0 ;0
L 1.32151004 -1.99053002 1.32761998 -1.99023002 0 P 0 ;0
L 1.32761998 -1.99023002 1.3331 -1.99025 0 P 0 ;0
L 1.3331 -1.99025 1.33345 -1.99608002 0 P 0 ;0
L 1.33345 -1.99608002 1.33381004 -2.00323002 0 P 0 ;0
L 1.33381004 -2.00323002 1.33413002 -2.01158996 0 P 0 ;0
L 1.33413002 -2.01158996 1.33413002 -2.0116 0 P 0 ;0
L 1.33413002 -2.0116 1.33481998 -2.03123002 0 P 0 ;0
L 1.33481998 -2.03123002 1.32853996 -2.0314 0 P 0 ;0
L 1.32853996 -2.0314 1.32398002 -2.03166998 0 P 0 ;0
L 1.32398002 -2.03166998 1.31941998 -2.03225 0 P 0 ;0
L 1.31941998 -2.03225 1.31488996 -2.03313002 0 P 0 ;0
L 1.31488996 -2.03313002 1.31273996 -2.03373002 0 P 0 ;0
L 1.31273996 -2.03373002 1.31063996 -2.0345 0 P 0 ;0
L 1.31063996 -2.0345 1.3086 -2.03545 0 P 0 ;0
L 1.3086 -2.03545 1.30666004 -2.03656998 0 P 0 ;0
L 1.30666004 -2.03656998 1.30658996 -2.03661998 0 P 0 ;0
L 1.30658996 -2.03661998 1.30483002 -2.03786004 0 P 0 ;0
L 1.30483002 -2.03786004 1.30341998 -2.03901004 0 P 0 ;0
L 1.30341998 -2.03901004 1.30336998 -2.03906004 0 P 0 ;0
L 1.30336998 -2.03906004 1.30211998 -2.04026004 0 P 0 ;0
L 1.30211998 -2.04026004 1.30093002 -2.0416 0 P 0 ;0
L 1.30093002 -2.0416 1.29983002 -2.04303996 0 P 0 ;0
L 1.29983002 -2.04303996 1.29978996 -2.0431 0 P 0 ;0
L 1.29978996 -2.0431 1.29885 -2.04453996 0 P 0 ;0
L 1.29885 -2.04453996 1.29798996 -2.04613002 0 P 0 ;0
L 1.29798996 -2.04613002 1.29631998 -2.04986998 0 P 0 ;0
L 1.29631998 -2.04986998 1.29628002 -2.04995 0 P 0 ;0
L 1.29628002 -2.04995 1.29625 -2.05003002 0 P 0 ;0
L 1.29625 -2.05003002 1.29491998 -2.0539 0 P 0 ;0
L 1.29491998 -2.0539 1.29388996 -2.05793996 0 P 0 ;0
L 1.29388996 -2.05793996 1.29386998 -2.05801998 0 P 0 ;0
L 1.29386998 -2.05801998 1.29313996 -2.06221004 0 P 0 ;0
L 1.29313996 -2.06221004 1.29313002 -2.06223996 0 P 0 ;0
L 1.29313002 -2.06223996 1.29311998 -2.0623 0 P 0 ;0
L 1.29311998 -2.0623 1.29265 -2.06655 0 P 0 ;0
L 1.29265 -2.06655 1.29136998 -2.08418996 0 P 0 ;0
L 1.29136998 -2.08418996 1.29038996 -2.10276998 0 P 0 ;0
L 1.29038996 -2.10276998 1.29006998 -2.11763002 0 P 0 ;0
L 1.29006998 -2.11763002 1.29006004 -2.12516004 0 P 0 ;0
L 1.29006004 -2.12516004 1.2389 -2.12516004 0 P 0 ;0
L 1.09846998 -2.00483002 1.21248002 -2.00483002 0 P 0 ;0
L 1.09838002 -2.12083002 1.14708002 -2.12083002 0 P 0 ;0
L 1.11933002 -2.18283002 1.15161998 -2.18283002 0 P 0 ;0
L 1.11001998 -2.18183002 1.15838002 -2.18183002 0 P 0 ;0
L 1.10246998 -2.18083002 1.16333996 -2.18083002 0 P 0 ;0
L 1.04061004 -1.89731004 1.09978002 -1.89731004 0 P 0 ;0
L 1.03565 -1.89631004 1.09821004 -1.89631004 0 P 0 ;0
L 1.03068996 -1.89531004 1.09661004 -1.89531004 0 P 0 ;0
L 1.02573002 -1.89431004 1.09475 -1.89431004 0 P 0 ;0
L 1.019 -1.89331004 1.09288002 -1.89331004 0 P 0 ;0
L 1.01163996 -1.89231004 1.09101998 -1.89231004 0 P 0 ;0
L 0.99518996 -1.89131004 1.08916004 -1.89131004 0 P 0 ;0
L 0.87011998 -1.88331004 1.07278996 -1.88331004 0 P 0 ;0
L 0.86963996 -1.88231004 1.07053002 -1.88231004 0 P 0 ;0
L 0.86916004 -1.88131004 1.06828002 -1.88131004 0 P 0 ;0
L 0.86863002 -1.88031004 1.06603002 -1.88031004 0 P 0 ;0
L 0.86806998 -1.87931004 1.06351004 -1.87931004 0 P 0 ;0
L 0.8675 -1.87831004 1.06076998 -1.87831004 0 P 0 ;0
L 0.86693002 -1.87731004 1.05803996 -1.87731004 0 P 0 ;0
L 0.86631004 -1.87631004 1.05531004 -1.87631004 0 P 0 ;0
L 0.86563996 -1.87531004 1.05256998 -1.87531004 0 P 0 ;0
L 0.86498002 -1.87431004 1.04983996 -1.87431004 0 P 0 ;0
L 0.86431998 -1.87331004 1.0471 -1.87331004 0 P 0 ;0
L 0.86356004 -1.87231004 1.04376004 -1.87231004 0 P 0 ;0
L 0.86278996 -1.87131004 1.04041998 -1.87131004 0 P 0 ;0
L 0.86203002 -1.87031004 1.03708002 -1.87031004 0 P 0 ;0
L 0.86118996 -1.86931004 1.03373996 -1.86931004 0 P 0 ;0
L 0.8603 -1.86831004 1.0304 -1.86831004 0 P 0 ;0
L 0.85941004 -1.86731004 1.02656998 -1.86731004 0 P 0 ;0
L 0.8585 -1.86631004 1.02231998 -1.86631004 0 P 0 ;0
L 0.85756998 -1.86531004 1.01806998 -1.86531004 0 P 0 ;0
L 0.85663002 -1.86431004 1.01381998 -1.86431004 0 P 0 ;0
L 0.85568996 -1.86331004 1.00931998 -1.86331004 0 P 0 ;0
L 0.85481004 -1.86231004 1.00335 -1.86231004 0 P 0 ;0
L 0.85916998 -1.86131004 0.99738002 -1.86131004 0 P 0 ;0
L 0.86716998 -1.86031004 0.99141998 -1.86031004 0 P 0 ;0
L 0.87476998 -1.89731004 0.89943002 -1.89731004 0 P 0 ;0
L 0.87453996 -1.89631004 0.90426004 -1.89631004 0 P 0 ;0
L 0.87431004 -1.89531004 0.9097 -1.89531004 0 P 0 ;0
L 0.87406998 -1.89431004 0.91608002 -1.89431004 0 P 0 ;0
L 0.87383002 -1.89331004 0.92246004 -1.89331004 0 P 0 ;0
L 0.87355 -1.89231004 0.93086004 -1.89231004 0 P 0 ;0
L 0.87323002 -1.89131004 0.95553002 -1.89131004 0 P 0 ;0
L 0.87291004 -1.89031004 1.08728996 -1.89031004 0 P 0 ;0
L 0.87258996 -1.88931004 1.08543002 -1.88931004 0 P 0 ;0
L 0.87223002 -1.88831004 1.08356998 -1.88831004 0 P 0 ;0
L 0.87183002 -1.88731004 1.0817 -1.88731004 0 P 0 ;0
L 0.87143002 -1.88631004 1.07955 -1.88631004 0 P 0 ;0
L 0.87103002 -1.88531004 1.07728996 -1.88531004 0 P 0 ;0
L 0.8706 -1.88431004 1.07503996 -1.88431004 0 P 0 ;0
L 0.87525 -1.85931004 0.98545 -1.85931004 0 P 0 ;0
L 0.88421004 -1.85831004 0.97621004 -1.85831004 0 P 0 ;0
L 0.89393002 -1.85731004 0.96606998 -1.85731004 0 P 0 ;0
L 0.9106 -1.85631004 0.95203002 -1.85631004 0 P 0 ;0
L 1.08716004 -1.91231004 1.12151004 -1.91231004 0 P 0 ;0
L 1.08486004 -1.91131004 1.12018996 -1.91131004 0 P 0 ;0
L 1.08256004 -1.91031004 1.11886004 -1.91031004 0 P 0 ;0
L 1.08023002 -1.90931004 1.11753996 -1.90931004 0 P 0 ;0
L 1.07738002 -1.90831004 1.11621004 -1.90831004 0 P 0 ;0
L 1.07453002 -1.90731004 1.11488996 -1.90731004 0 P 0 ;0
L 1.07168996 -1.90631004 1.11356998 -1.90631004 0 P 0 ;0
L 1.06883996 -1.90531004 1.11223996 -1.90531004 0 P 0 ;0
L 1.066 -1.90431004 1.11076998 -1.90431004 0 P 0 ;0
L 1.06315 -1.90331004 1.1092 -1.90331004 0 P 0 ;0
L 1.0599 -1.90231004 1.10763002 -1.90231004 0 P 0 ;0
L 1.05611998 -1.90131004 1.10606004 -1.90131004 0 P 0 ;0
L 1.05235 -1.90031004 1.10448996 -1.90031004 0 P 0 ;0
L 1.04856998 -1.89931004 1.10291998 -1.89931004 0 P 0 ;0
L 1.04478996 -1.89831004 1.10135 -1.89831004 0 P 0 ;0
L 0.98815 -2.08316004 1.03726998 -2.08316004 0 P 0 ;0
L 0.98818002 -2.08216004 1.03731004 -2.08216004 0 P 0 ;0
L 0.98821998 -2.08116004 1.03735 -2.08116004 0 P 0 ;0
L 0.98825 -2.08016004 1.03738996 -2.08016004 0 P 0 ;0
L 0.98828002 -2.07916004 1.03743002 -2.07916004 0 P 0 ;0
L 0.98831998 -2.07816004 1.03746998 -2.07816004 0 P 0 ;0
L 0.98835 -2.07716004 1.03751004 -2.07716004 0 P 0 ;0
L 0.98838002 -2.07616004 1.03755 -2.07616004 0 P 0 ;0
L 0.98841998 -2.07516004 1.03758002 -2.07516004 0 P 0 ;0
L 0.98845 -2.07416004 1.03761004 -2.07416004 0 P 0 ;0
L 0.98848002 -2.07316004 1.03763996 -2.07316004 0 P 0 ;0
L 0.98851004 -2.07216004 1.03768002 -2.07216004 0 P 0 ;0
L 0.98855 -2.07116004 1.03771004 -2.07116004 0 P 0 ;0
L 0.98858002 -2.07016004 1.03773996 -2.07016004 0 P 0 ;0
L 0.98858996 -2.06916004 1.03776998 -2.06916004 0 P 0 ;0
L 0.98858996 -2.06816004 1.0378 -2.06816004 0 P 0 ;0
L 0.98858996 -2.06716004 1.03783002 -2.06716004 0 P 0 ;0
L 0.98858002 -2.06616004 1.03786004 -2.06616004 0 P 0 ;0
L 0.98856998 -2.06516004 1.0379 -2.06516004 0 P 0 ;0
L 0.98856998 -2.06416004 1.03793002 -2.06416004 0 P 0 ;0
L 0.98856998 -2.06316004 1.03796004 -2.06316004 0 P 0 ;0
L 0.98856004 -2.06216004 1.03798996 -2.06216004 0 P 0 ;0
L 0.98855 -2.06116004 1.03801998 -2.06116004 0 P 0 ;0
L 0.98855 -2.06016004 1.03805 -2.06016004 0 P 0 ;0
L 0.98853996 -2.05916004 1.03808002 -2.05916004 0 P 0 ;0
L 0.98853996 -2.05816004 1.0381 -2.05816004 0 P 0 ;0
L 0.98853002 -2.05716004 1.03811998 -2.05716004 0 P 0 ;0
L 0.98848002 -2.05616004 1.03815 -2.05616004 0 P 0 ;0
L 0.98841004 -2.05516004 1.03818002 -2.05516004 0 P 0 ;0
L 0.98835 -2.05416004 1.0382 -2.05416004 0 P 0 ;0
L 0.98828002 -2.05316004 1.03821998 -2.05316004 0 P 0 ;0
L 0.98821004 -2.05216004 1.03825 -2.05216004 0 P 0 ;0
L 0.98815 -2.05116004 1.03826998 -2.05116004 0 P 0 ;0
L 0.98808996 -2.05016004 1.03828996 -2.05016004 0 P 0 ;0
L 0.98801998 -2.04916004 1.03831998 -2.04916004 0 P 0 ;0
L 0.98796004 -2.04816004 1.03833996 -2.04816004 0 P 0 ;0
L 0.98788996 -2.04716004 1.03836004 -2.04716004 0 P 0 ;0
L 0.98783002 -2.04616004 1.03838996 -2.04616004 0 P 0 ;0
L 0.98768996 -2.04516004 1.0384 -2.04516004 0 P 0 ;0
L 0.98756004 -2.04416004 1.03841004 -2.04416004 0 P 0 ;0
L 0.98738002 -2.04316004 1.03841998 -2.04316004 0 P 0 ;0
L 0.98716004 -2.04216004 1.03843002 -2.04216004 0 P 0 ;0
L 0.98691998 -2.04116004 1.03843996 -2.04116004 0 P 0 ;0
L 0.98661998 -2.04016004 1.03845 -2.04016004 0 P 0 ;0
L 0.98631998 -2.03916004 1.03846004 -2.03916004 0 P 0 ;0
L 0.98593996 -2.03816004 1.03846998 -2.03816004 0 P 0 ;0
L 0.98546998 -2.03716004 1.03848002 -2.03716004 0 P 0 ;0
L 0.98491004 -2.03616004 1.03846998 -2.03616004 0 P 0 ;0
L 0.98425 -2.03516004 1.03846004 -2.03516004 0 P 0 ;0
L 0.98346004 -2.03416004 1.03846004 -2.03416004 0 P 0 ;0
L 0.98251998 -2.03316004 1.03843996 -2.03316004 0 P 0 ;0
L 0.98138002 -2.03216004 1.03843002 -2.03216004 0 P 0 ;0
L 0.97998996 -2.03116004 1.03841998 -2.03116004 0 P 0 ;0
L 0.97813996 -2.03016004 1.03841004 -2.03016004 0 P 0 ;0
L 0.97491004 -2.02916004 1.0384 -2.02916004 0 P 0 ;0
L 0.94763996 -2.00716004 1.03293996 -2.00716004 0 P 0 ;0
L 0.94978996 -2.00616004 1.03231998 -2.00616004 0 P 0 ;0
L 0.95081004 -2.00516004 1.0317 -2.00516004 0 P 0 ;0
L 0.95183002 -2.00416004 1.03098002 -2.00416004 0 P 0 ;0
L 0.95285 -2.00316004 1.03023002 -2.00316004 0 P 0 ;0
L 0.95388996 -2.00216004 1.02936004 -2.00216004 0 P 0 ;0
L 0.95498002 -2.00116004 1.02841998 -2.00116004 0 P 0 ;0
L 0.95621998 -2.00016004 1.02738996 -2.00016004 0 P 0 ;0
L 0.95761998 -1.99916004 1.0262 -1.99916004 0 P 0 ;0
L 0.9592 -1.99816004 1.02486004 -1.99816004 0 P 0 ;0
L 0.96083996 -1.99716004 1.02335 -1.99716004 0 P 0 ;0
L 0.9627 -1.99616004 1.02161004 -1.99616004 0 P 0 ;0
L 0.96468996 -1.99516004 1.01951998 -1.99516004 0 P 0 ;0
L 0.96685 -1.99416004 1.01683002 -1.99416004 0 P 0 ;0
L 0.96936998 -1.99316004 1.01378002 -1.99316004 0 P 0 ;0
L 0.97236998 -1.99216004 1.00981004 -1.99216004 0 P 0 ;0
L 0.97676004 -1.99116004 1.00456998 -1.99116004 0 P 0 ;0
L 1.06713996 -2.08283002 1.12288002 -2.08283002 0 P 0 ;0
L 1.06698996 -2.08183002 1.12193996 -2.08183002 0 P 0 ;0
L 1.06686004 -2.08083002 1.12108996 -2.08083002 0 P 0 ;0
L 1.06673996 -2.07983002 1.12036004 -2.07983002 0 P 0 ;0
L 1.06661998 -2.07883002 1.11971998 -2.07883002 0 P 0 ;0
L 1.06653002 -2.07783002 1.11916004 -2.07783002 0 P 0 ;0
L 1.06648002 -2.07683002 1.11866004 -2.07683002 0 P 0 ;0
L 1.06641998 -2.07583002 1.11826004 -2.07583002 0 P 0 ;0
L 1.06636998 -2.07483002 1.11791998 -2.07483002 0 P 0 ;0
L 1.06631998 -2.07383002 1.11761998 -2.07383002 0 P 0 ;0
L 1.06626004 -2.07283002 1.11741998 -2.07283002 0 P 0 ;0
L 1.06621004 -2.07183002 1.11723996 -2.07183002 0 P 0 ;0
L 1.06616004 -2.07083002 1.11711998 -2.07083002 0 P 0 ;0
L 1.06616004 -2.06983002 1.11701004 -2.06983002 0 P 0 ;0
L 1.06616004 -2.06883002 1.11688996 -2.06883002 0 P 0 ;0
L 1.06616998 -2.06783002 1.11676998 -2.06783002 0 P 0 ;0
L 1.06618002 -2.06683002 1.11666998 -2.06683002 0 P 0 ;0
L 1.06618996 -2.06583002 1.11663002 -2.06583002 0 P 0 ;0
L 1.0662 -2.06483002 1.11658996 -2.06483002 0 P 0 ;0
L 1.06621004 -2.06383002 1.11656004 -2.06383002 0 P 0 ;0
L 1.06623002 -2.06283002 1.11651998 -2.06283002 0 P 0 ;0
L 1.06631004 -2.06183002 1.11648996 -2.06183002 0 P 0 ;0
L 1.06638002 -2.06083002 1.11653002 -2.06083002 0 P 0 ;0
L 1.06645 -2.05983002 1.11656998 -2.05983002 0 P 0 ;0
L 1.06651998 -2.05883002 1.11661998 -2.05883002 0 P 0 ;0
L 1.06658996 -2.05783002 1.11666004 -2.05783002 0 P 0 ;0
L 1.06666998 -2.05683002 1.11671004 -2.05683002 0 P 0 ;0
L 1.06673996 -2.05583002 1.11681004 -2.05583002 0 P 0 ;0
L 1.06686004 -2.05483002 1.11693002 -2.05483002 0 P 0 ;0
L 1.067 -2.05383002 1.11705 -2.05383002 0 P 0 ;0
L 1.06713996 -2.05283002 1.11718002 -2.05283002 0 P 0 ;0
L 1.06728002 -2.05183002 1.11731004 -2.05183002 0 P 0 ;0
L 1.06741998 -2.05083002 1.11746004 -2.05083002 0 P 0 ;0
L 1.06756004 -2.04983002 1.11766004 -2.04983002 0 P 0 ;0
L 1.0677 -2.04883002 1.11786004 -2.04883002 0 P 0 ;0
L 1.06786004 -2.04783002 1.11813996 -2.04783002 0 P 0 ;0
L 1.06806998 -2.04683002 1.11841998 -2.04683002 0 P 0 ;0
L 1.06828002 -2.04583002 1.11876998 -2.04583002 0 P 0 ;0
L 1.06848996 -2.04483002 1.11913002 -2.04483002 0 P 0 ;0
L 1.06871004 -2.04383002 1.11955 -2.04383002 0 P 0 ;0
L 1.06898996 -2.04283002 1.11998996 -2.04283002 0 P 0 ;0
L 1.06928002 -2.04183002 1.12048002 -2.04183002 0 P 0 ;0
L 1.06956004 -2.04083002 1.12101004 -2.04083002 0 P 0 ;0
L 1.06985 -2.03983002 1.12161998 -2.03983002 0 P 0 ;0
L 1.07021004 -2.03883002 1.12225 -2.03883002 0 P 0 ;0
L 1.07056998 -2.03783002 1.12298002 -2.03783002 0 P 0 ;0
L 1.07093002 -2.03683002 1.12373996 -2.03683002 0 P 0 ;0
L 1.07128996 -2.03583002 1.12461998 -2.03583002 0 P 0 ;0
L 1.07173002 -2.03483002 1.12548996 -2.03483002 0 P 0 ;0
L 1.07216998 -2.03383002 1.12646004 -2.03383002 0 P 0 ;0
L 1.07261998 -2.03283002 1.12748996 -2.03283002 0 P 0 ;0
L 1.07308002 -2.03183002 1.12855 -2.03183002 0 P 0 ;0
L 1.07361998 -2.03083002 1.12978996 -2.03083002 0 P 0 ;0
L 1.09761004 -1.91731004 1.12756998 -1.91731004 0 P 0 ;0
L 1.09566004 -1.91631004 1.12645 -1.91631004 0 P 0 ;0
L 1.09371004 -1.91531004 1.12533002 -1.91531004 0 P 0 ;0
L 1.09176004 -1.91431004 1.12416004 -1.91431004 0 P 0 ;0
L 1.08946004 -1.91331004 1.12283996 -1.91331004 0 P 0 ;0
L 1.07415 -2.02983002 1.13101998 -2.02983002 0 P 0 ;0
L 1.07468996 -2.02883002 1.13248996 -2.02883002 0 P 0 ;0
L 1.07528996 -2.02783002 1.134 -2.02783002 0 P 0 ;0
L 1.07591998 -2.02683002 1.13586004 -2.02683002 0 P 0 ;0
L 1.07656004 -2.02583002 1.13828996 -2.02583002 0 P 0 ;0
L 1.07721004 -2.02483002 1.14243002 -2.02483002 0 P 0 ;0
L 1.07795 -2.02383002 1.21126998 -2.02383002 0 P 0 ;0
L 1.07868002 -2.02283002 1.21133002 -2.02283002 0 P 0 ;0
L 1.07941998 -2.02183002 1.2114 -2.02183002 0 P 0 ;0
L 1.08021004 -2.02083002 1.21146004 -2.02083002 0 P 0 ;0
L 1.08103996 -2.01983002 1.21153002 -2.01983002 0 P 0 ;0
L 1.08186998 -2.01883002 1.2116 -2.01883002 0 P 0 ;0
L 1.08273002 -2.01783002 1.21166004 -2.01783002 0 P 0 ;0
L 1.08366998 -2.01683002 1.21173002 -2.01683002 0 P 0 ;0
L 1.0846 -2.01583002 1.2118 -2.01583002 0 P 0 ;0
L 1.08555 -2.01483002 1.21186004 -2.01483002 0 P 0 ;0
L 1.08661004 -2.01383002 1.21193002 -2.01383002 0 P 0 ;0
L 1.08766998 -2.01283002 1.21198996 -2.01283002 0 P 0 ;0
L 1.08873002 -2.01183002 1.21205 -2.01183002 0 P 0 ;0
L 1.0898 -2.01083002 1.21211998 -2.01083002 0 P 0 ;0
L 1.09098996 -2.00983002 1.21218002 -2.00983002 0 P 0 ;0
L 1.09225 -2.00883002 1.21223996 -2.00883002 0 P 0 ;0
L 1.09358996 -2.00783002 1.2123 -2.00783002 0 P 0 ;0
L 1.09506998 -2.00683002 1.21236004 -2.00683002 0 P 0 ;0
L 1.09668996 -2.00583002 1.21241998 -2.00583002 0 P 0 ;0
L 0.98546998 -2.12516004 1.03548996 -2.12516004 0 P 0 ;0
L 0.98558996 -2.12416004 1.03553996 -2.12416004 0 P 0 ;0
L 0.9857 -2.12316004 1.03558002 -2.12316004 0 P 0 ;0
L 0.98581004 -2.12216004 1.03561998 -2.12216004 0 P 0 ;0
L 0.98591004 -2.12116004 1.03566998 -2.12116004 0 P 0 ;0
L 0.98598996 -2.12016004 1.03571004 -2.12016004 0 P 0 ;0
L 0.98608002 -2.11916004 1.03575 -2.11916004 0 P 0 ;0
L 0.98616998 -2.11816004 1.0358 -2.11816004 0 P 0 ;0
L 0.98625 -2.11716004 1.03583996 -2.11716004 0 P 0 ;0
L 0.98633996 -2.11616004 1.03588002 -2.11616004 0 P 0 ;0
L 0.98641998 -2.11516004 1.03593002 -2.11516004 0 P 0 ;0
L 0.98651004 -2.11416004 1.03596998 -2.11416004 0 P 0 ;0
L 0.9866 -2.11316004 1.03601004 -2.11316004 0 P 0 ;0
L 0.98668002 -2.11216004 1.03605 -2.11216004 0 P 0 ;0
L 0.98676998 -2.11116004 1.0361 -2.11116004 0 P 0 ;0
L 0.98685 -2.11016004 1.03613996 -2.11016004 0 P 0 ;0
L 0.98693996 -2.10916004 1.03618002 -2.10916004 0 P 0 ;0
L 0.987 -2.10816004 1.03623002 -2.10816004 0 P 0 ;0
L 0.98705 -2.10716004 1.03626998 -2.10716004 0 P 0 ;0
L 0.9871 -2.10616004 1.03631004 -2.10616004 0 P 0 ;0
L 0.98716004 -2.10516004 1.03636004 -2.10516004 0 P 0 ;0
L 0.9872 -2.10416004 1.0364 -2.10416004 0 P 0 ;0
L 0.98725 -2.10316004 1.03643996 -2.10316004 0 P 0 ;0
L 0.98731004 -2.10216004 1.03648002 -2.10216004 0 P 0 ;0
L 0.98735 -2.10116004 1.03653002 -2.10116004 0 P 0 ;0
L 0.9874 -2.10016004 1.03656998 -2.10016004 0 P 0 ;0
L 0.98746004 -2.09916004 1.03661004 -2.09916004 0 P 0 ;0
L 0.98751004 -2.09816004 1.03666004 -2.09816004 0 P 0 ;0
L 0.98755 -2.09716004 1.0367 -2.09716004 0 P 0 ;0
L 0.9876 -2.09616004 1.03673996 -2.09616004 0 P 0 ;0
L 0.98766004 -2.09516004 1.03678996 -2.09516004 0 P 0 ;0
L 0.9877 -2.09416004 1.03683002 -2.09416004 0 P 0 ;0
L 0.98775 -2.09316004 1.03686998 -2.09316004 0 P 0 ;0
L 0.98781004 -2.09216004 1.03691998 -2.09216004 0 P 0 ;0
L 0.98785 -2.09116004 1.03696004 -2.09116004 0 P 0 ;0
L 0.9879 -2.09016004 1.037 -2.09016004 0 P 0 ;0
L 0.98796004 -2.08916004 1.03703996 -2.08916004 0 P 0 ;0
L 0.98798996 -2.08816004 1.03706998 -2.08816004 0 P 0 ;0
L 0.98801998 -2.08716004 1.03711004 -2.08716004 0 P 0 ;0
L 0.98805 -2.08616004 1.03715 -2.08616004 0 P 0 ;0
L 0.98808996 -2.08516004 1.03718996 -2.08516004 0 P 0 ;0
L 0.98811998 -2.08416004 1.03723002 -2.08416004 0 P 0 ;0
L 1.08216998 -2.15683002 1.19803996 -2.15683002 0 P 0 ;0
L 1.0821 -2.15583002 1.19861004 -2.15583002 0 P 0 ;0
L 1.08201998 -2.15483002 1.19918002 -2.15483002 0 P 0 ;0
L 1.08195 -2.15383002 1.1997 -2.15383002 0 P 0 ;0
L 1.08188996 -2.15283002 1.20018002 -2.15283002 0 P 0 ;0
L 1.08183002 -2.15183002 1.20066004 -2.15183002 0 P 0 ;0
L 1.08176998 -2.15083002 1.20113996 -2.15083002 0 P 0 ;0
L 1.08171998 -2.14983002 1.20153996 -2.14983002 0 P 0 ;0
L 1.08166004 -2.14883002 1.20193002 -2.14883002 0 P 0 ;0
L 1.0816 -2.14783002 1.11538996 -2.14783002 0 P 0 ;0
L 1.08155 -2.14683002 1.10903002 -2.14683002 0 P 0 ;0
L 1.0815 -2.14583002 1.10415 -2.14583002 0 P 0 ;0
L 1.08146004 -2.14483002 1.09953002 -2.14483002 0 P 0 ;0
L 1.08141004 -2.14383002 1.09563996 -2.14383002 0 P 0 ;0
L 1.08136004 -2.14283002 1.09183996 -2.14283002 0 P 0 ;0
L 1.08131004 -2.14183002 1.08821004 -2.14183002 0 P 0 ;0
L 1.08133002 -2.14083002 1.08471998 -2.14083002 0 P 0 ;0
L 1.09586998 -2.11983002 1.14965 -2.11983002 0 P 0 ;0
L 1.09361998 -2.11883002 1.15221998 -2.11883002 0 P 0 ;0
L 1.09158996 -2.11783002 1.20595 -2.11783002 0 P 0 ;0
L 1.08988002 -2.11683002 1.20601004 -2.11683002 0 P 0 ;0
L 1.08823996 -2.11583002 1.20606998 -2.11583002 0 P 0 ;0
L 1.08678996 -2.11483002 1.20613002 -2.11483002 0 P 0 ;0
L 1.08541004 -2.11383002 1.20618996 -2.11383002 0 P 0 ;0
L 1.08416998 -2.11283002 1.20625 -2.11283002 0 P 0 ;0
L 1.08295 -2.11183002 1.20631004 -2.11183002 0 P 0 ;0
L 1.08188002 -2.11083002 1.20638002 -2.11083002 0 P 0 ;0
L 1.08081998 -2.10983002 1.20643996 -2.10983002 0 P 0 ;0
L 1.07986004 -2.10883002 1.2065 -2.10883002 0 P 0 ;0
L 1.07895 -2.10783002 1.20656004 -2.10783002 0 P 0 ;0
L 1.07803002 -2.10683002 1.20661998 -2.10683002 0 P 0 ;0
L 1.07723996 -2.10583002 1.20666998 -2.10583002 0 P 0 ;0
L 1.07646004 -2.10483002 1.20671998 -2.10483002 0 P 0 ;0
L 1.07568002 -2.10383002 1.20678002 -2.10383002 0 P 0 ;0
L 1.075 -2.10283002 1.20683002 -2.10283002 0 P 0 ;0
L 1.07433002 -2.10183002 1.20688002 -2.10183002 0 P 0 ;0
L 1.07366998 -2.10083002 1.20693996 -2.10083002 0 P 0 ;0
L 1.07308996 -2.09983002 1.20698996 -2.09983002 0 P 0 ;0
L 1.07253002 -2.09883002 1.20705 -2.09883002 0 P 0 ;0
L 1.07198002 -2.09783002 1.2071 -2.09783002 0 P 0 ;0
L 1.07146998 -2.09683002 1.20715 -2.09683002 0 P 0 ;0
L 1.07101998 -2.09583002 1.2072 -2.09583002 0 P 0 ;0
L 1.07056998 -2.09483002 1.20726004 -2.09483002 0 P 0 ;0
L 1.07013002 -2.09383002 1.20731004 -2.09383002 0 P 0 ;0
L 1.06976998 -2.09283002 1.20736004 -2.09283002 0 P 0 ;0
L 1.06941998 -2.09183002 1.20741998 -2.09183002 0 P 0 ;0
L 1.06906004 -2.09083002 1.20746998 -2.09083002 0 P 0 ;0
L 1.06876004 -2.08983002 1.20753002 -2.08983002 0 P 0 ;0
L 1.06848996 -2.08883002 1.13443002 -2.08883002 0 P 0 ;0
L 1.06821998 -2.08783002 1.13068002 -2.08783002 0 P 0 ;0
L 1.06795 -2.08683002 1.12836998 -2.08683002 0 P 0 ;0
L 1.06771998 -2.08583002 1.1266 -2.08583002 0 P 0 ;0
L 1.06753002 -2.08483002 1.12516004 -2.08483002 0 P 0 ;0
L 1.06733002 -2.08383002 1.12393996 -2.08383002 0 P 0 ;0
L 0.90273996 -1.85456998 0.89068996 -1.85558002 0 P 0 ;0
L 0.89068996 -1.85558002 0.87421004 -1.85741998 0 P 0 ;0
L 0.87421004 -1.85741998 0.85783002 -1.85946998 0 P 0 ;0
L 0.85783002 -1.85946998 0.85526998 -1.8599 0 P 0 ;0
L 0.85526998 -1.8599 0.85276004 -1.86055 0 P 0 ;0
L 0.85276004 -1.86055 0.85255 -1.86063996 0 P 0 ;0
L 0.85255 -1.86063996 0.85248996 -1.86068996 0 P 0 ;0
L 0.85248996 -1.86068996 0.85243002 -1.86073002 0 P 0 ;0
L 0.85243002 -1.86073002 0.85238002 -1.86078002 0 P 0 ;0
L 0.85238002 -1.86078002 0.85233002 -1.86083996 0 P 0 ;0
L 0.85233002 -1.86083996 0.85225 -1.86096004 0 P 0 ;0
L 0.85225 -1.86096004 0.85218002 -1.8611 0 P 0 ;0
L 0.85218002 -1.8611 0.85216004 -1.86116998 0 P 0 ;0
L 0.85216004 -1.86116998 0.85215 -1.86123996 0 P 0 ;0
L 0.85215 -1.86123996 0.85213996 -1.86136998 0 P 0 ;0
L 0.85213996 -1.86136998 0.85213002 -1.86148996 0 P 0 ;0
L 0.85213002 -1.86148996 0.85213996 -1.86161998 0 P 0 ;0
L 0.85213996 -1.86161998 0.85215 -1.86173996 0 P 0 ;0
L 0.85215 -1.86173996 0.85218002 -1.86186998 0 P 0 ;0
L 0.85218002 -1.86186998 0.85221004 -1.86198996 0 P 0 ;0
L 0.85221004 -1.86198996 0.85225 -1.8621 0 P 0 ;0
L 0.85225 -1.8621 0.85231004 -1.86221998 0 P 0 ;0
L 0.85231004 -1.86221998 0.85236998 -1.86233002 0 P 0 ;0
L 0.85236998 -1.86233002 0.85281998 -1.863 0 P 0 ;0
L 0.85281998 -1.863 0.8533 -1.86363996 0 P 0 ;0
L 0.8533 -1.86363996 0.85383002 -1.86425 0 P 0 ;0
L 0.85383002 -1.86425 0.85736004 -1.86801998 0 P 0 ;0
L 0.85736004 -1.86801998 0.86013002 -1.87113002 0 P 0 ;0
L 0.86013002 -1.87113002 0.86266004 -1.87443002 0 P 0 ;0
L 0.86266004 -1.87443002 0.86501004 -1.87798996 0 P 0 ;0
L 0.86501004 -1.87798996 0.86711998 -1.88171004 0 P 0 ;0
L 0.86711998 -1.88171004 0.86896998 -1.88553996 0 P 0 ;0
L 0.86896998 -1.88553996 0.87055 -1.8895 0 P 0 ;0
L 0.87055 -1.8895 0.8718 -1.89343002 0 P 0 ;0
L 0.8718 -1.89343002 0.87276004 -1.89745 0 P 0 ;0
L 0.87276004 -1.89745 0.87371004 -1.90195 0 P 0 ;0
L 0.87371004 -1.90195 0.87383002 -1.90236004 0 P 0 ;0
L 0.87383002 -1.90236004 0.87396998 -1.90276004 0 P 0 ;0
L 0.87396998 -1.90276004 0.87416004 -1.90313996 0 P 0 ;0
L 0.87416004 -1.90313996 0.87436998 -1.90351004 0 P 0 ;0
L 0.87436998 -1.90351004 0.87443002 -1.9036 0 P 0 ;0
L 0.87443002 -1.9036 0.87456998 -1.90376004 0 P 0 ;0
L 0.87456998 -1.90376004 0.87465 -1.90381998 0 P 0 ;0
L 0.87465 -1.90381998 0.87473002 -1.90388996 0 P 0 ;0
L 0.87473002 -1.90388996 0.87481998 -1.90393996 0 P 0 ;0
L 0.87481998 -1.90393996 0.87491998 -1.90398996 0 P 0 ;0
L 0.87491998 -1.90398996 0.87501004 -1.90403002 0 P 0 ;0
L 0.87501004 -1.90403002 0.87521004 -1.90408996 0 P 0 ;0
L 0.87521004 -1.90408996 0.87531998 -1.9041 0 P 0 ;0
L 0.87531998 -1.9041 0.87573002 -1.90413002 0 P 0 ;0
L 0.87573002 -1.90413002 0.87613996 -1.90411998 0 P 0 ;0
L 0.87613996 -1.90411998 0.87653996 -1.90408002 0 P 0 ;0
L 0.87653996 -1.90408002 0.87695 -1.90401004 0 P 0 ;0
L 0.87695 -1.90401004 0.90756004 -1.89766998 0 P 0 ;0
L 0.90756004 -1.89766998 0.92603996 -1.89478002 0 P 0 ;0
L 0.92603996 -1.89478002 0.93486004 -1.89393996 0 P 0 ;0
L 0.93486004 -1.89393996 0.94371004 -1.8935 0 P 0 ;0
L 0.94371004 -1.8935 0.97045 -1.89308002 0 P 0 ;0
L 0.97045 -1.89308002 0.99468996 -1.89328996 0 P 0 ;0
L 0.99468996 -1.89328996 1.01021004 -1.89413996 0 P 0 ;0
L 1.01021004 -1.89413996 1.0241 -1.89601998 0 P 0 ;0
L 1.0241 -1.89601998 1.04188002 -1.89961004 0 P 0 ;0
L 1.04188002 -1.89961004 1.06095 -1.90466004 0 P 0 ;0
L 1.06095 -1.90466004 1.07963996 -1.91123002 0 P 0 ;0
L 1.07963996 -1.91123002 1.09093996 -1.91613002 0 P 0 ;0
L 1.09093996 -1.91613002 1.10186998 -1.92175 0 P 0 ;0
L 1.10186998 -1.92175 1.11243996 -1.92806998 0 P 0 ;0
L 1.11243996 -1.92806998 1.12163002 -1.93446998 0 P 0 ;0
L 1.12163002 -1.93446998 1.13033002 -1.94148996 0 P 0 ;0
L 1.13033002 -1.94148996 1.1385 -1.94911004 0 P 0 ;0
L 1.1385 -1.94911004 1.14358996 -1.9546 0 P 0 ;0
L 1.14358996 -1.9546 1.14825 -1.96045 0 P 0 ;0
L 1.14825 -1.96045 1.15246998 -1.96663002 0 P 0 ;0
L 1.15246998 -1.96663002 1.15623002 -1.97316004 0 P 0 ;0
L 1.15623002 -1.97316004 1.15895 -1.97831004 0 P 0 ;0
L 1.15895 -1.97831004 1.17358996 -1.97831004 0 P 0 ;0
L 1.17358996 -1.97831004 1.17135 -1.9726 0 P 0 ;0
L 1.17135 -1.9726 1.16696004 -1.96266998 0 P 0 ;0
L 1.16696004 -1.96266998 1.16171998 -1.95313002 0 P 0 ;0
L 1.16171998 -1.95313002 1.1557 -1.94406998 0 P 0 ;0
L 1.1557 -1.94406998 1.14885 -1.93548002 0 P 0 ;0
L 1.14885 -1.93548002 1.13778996 -1.92378002 0 P 0 ;0
L 1.13778996 -1.92378002 1.12576998 -1.91301998 0 P 0 ;0
L 1.12576998 -1.91301998 1.11283996 -1.90326004 0 P 0 ;0
L 1.11283996 -1.90326004 1.09783002 -1.89368996 0 P 0 ;0
L 1.09783002 -1.89368996 1.08213002 -1.88526998 0 P 0 ;0
L 1.08213002 -1.88526998 1.06576998 -1.87801004 0 P 0 ;0
L 1.06576998 -1.87801004 1.04776004 -1.87141998 0 P 0 ;0
L 1.04776004 -1.87141998 1.02938002 -1.86591998 0 P 0 ;0
L 1.02938002 -1.86591998 1.01058002 -1.8615 0 P 0 ;0
L 1.01058002 -1.8615 0.98441998 -1.85711004 0 P 0 ;0
L 0.98441998 -1.85711004 0.95781004 -1.85448996 0 P 0 ;0
L 0.95781004 -1.85448996 0.93061004 -1.85366004 0 P 0 ;0
L 0.93061004 -1.85366004 0.90273996 -1.85456998 0 P 0 ;0
L 1.16015 -1.97631004 1.15798002 -1.97218996 0 P 0 ;0
L 1.15798002 -1.97218996 1.15796004 -1.97216004 0 P 0 ;0
L 1.15796004 -1.97216004 1.15416004 -1.96556998 0 P 0 ;0
L 1.15416004 -1.96556998 1.15411998 -1.96551004 0 P 0 ;0
L 1.15411998 -1.96551004 1.14986004 -1.95926004 0 P 0 ;0
L 1.14986004 -1.95926004 1.14981998 -1.95921004 0 P 0 ;0
L 1.14981998 -1.95921004 1.14511004 -1.9533 0 P 0 ;0
L 1.14511004 -1.9533 1.13991998 -1.9477 0 P 0 ;0
L 1.13991998 -1.9477 1.13986004 -1.94765 0 P 0 ;0
L 1.13986004 -1.94765 1.13163996 -1.93998002 0 P 0 ;0
L 1.13163996 -1.93998002 1.12283002 -1.93286004 0 P 0 ;0
L 1.12283002 -1.93286004 1.11351998 -1.92638996 0 P 0 ;0
L 1.11351998 -1.92638996 1.10283996 -1.92 0 P 0 ;0
L 1.10283996 -1.92 1.0918 -1.91433002 0 P 0 ;0
L 1.0918 -1.91433002 1.08036998 -1.90936004 0 P 0 ;0
L 1.08036998 -1.90936004 1.06153002 -1.90273996 0 P 0 ;0
L 1.06153002 -1.90273996 1.06146004 -1.90273002 0 P 0 ;0
L 1.06146004 -1.90273002 1.04233002 -1.89766004 0 P 0 ;0
L 1.04233002 -1.89766004 1.02443002 -1.89405 0 P 0 ;0
L 1.02443002 -1.89405 1.0104 -1.89213996 0 P 0 ;0
L 1.0104 -1.89213996 0.99475 -1.89128996 0 P 0 ;0
L 0.99475 -1.89128996 0.97045 -1.89108002 0 P 0 ;0
L 0.97045 -1.89108002 0.94365 -1.8915 0 P 0 ;0
L 0.94365 -1.8915 0.94361998 -1.8915 0 P 0 ;0
L 0.94361998 -1.8915 0.93471998 -1.89195 0 P 0 ;0
L 0.93471998 -1.89195 0.92578996 -1.89278996 0 P 0 ;0
L 0.92578996 -1.89278996 0.9072 -1.89571004 0 P 0 ;0
L 0.9072 -1.89571004 0.87656998 -1.90203996 0 P 0 ;0
L 0.87656998 -1.90203996 0.87626998 -1.9021 0 P 0 ;0
L 0.87626998 -1.9021 0.87601998 -1.90211998 0 P 0 ;0
L 0.87601998 -1.90211998 0.87588996 -1.90213002 0 P 0 ;0
L 0.87588996 -1.90213002 0.87583002 -1.90198996 0 P 0 ;0
L 0.87583002 -1.90198996 0.87573002 -1.90175 0 P 0 ;0
L 0.87573002 -1.90175 0.87566004 -1.90146998 0 P 0 ;0
L 0.87566004 -1.90146998 0.87471004 -1.89701004 0 P 0 ;0
L 0.87471004 -1.89701004 0.8747 -1.89698996 0 P 0 ;0
L 0.8747 -1.89698996 0.87373002 -1.89288996 0 P 0 ;0
L 0.87373002 -1.89288996 0.87243002 -1.88881998 0 P 0 ;0
L 0.87243002 -1.88881998 0.8724 -1.88876004 0 P 0 ;0
L 0.8724 -1.88876004 0.8708 -1.88473996 0 P 0 ;0
L 0.8708 -1.88473996 0.8689 -1.88078002 0 P 0 ;0
L 0.8689 -1.88078002 0.86671998 -1.87693996 0 P 0 ;0
L 0.86671998 -1.87693996 0.86428996 -1.87326004 0 P 0 ;0
L 0.86428996 -1.87326004 0.86166998 -1.86985 0 P 0 ;0
L 0.86166998 -1.86985 0.85883996 -1.86668002 0 P 0 ;0
L 0.85883996 -1.86668002 0.85883002 -1.86666004 0 P 0 ;0
L 0.85883002 -1.86666004 0.85531998 -1.86291004 0 P 0 ;0
L 0.85531998 -1.86291004 0.85486004 -1.86238002 0 P 0 ;0
L 0.85486004 -1.86238002 0.85466004 -1.86211998 0 P 0 ;0
L 0.85466004 -1.86211998 0.8557 -1.86186004 0 P 0 ;0
L 0.8557 -1.86186004 0.85811998 -1.86145 0 P 0 ;0
L 0.85811998 -1.86145 0.87443996 -1.85941004 0 P 0 ;0
L 0.87443996 -1.85941004 0.89088996 -1.85756998 0 P 0 ;0
L 0.89088996 -1.85756998 0.90286004 -1.85656998 0 P 0 ;0
L 0.90286004 -1.85656998 0.93061004 -1.85566004 0 P 0 ;0
L 0.93061004 -1.85566004 0.95768002 -1.85648996 0 P 0 ;0
L 0.95768002 -1.85648996 0.98416004 -1.8591 0 P 0 ;0
L 0.98416004 -1.8591 1.01018996 -1.86346004 0 P 0 ;0
L 1.01018996 -1.86346004 1.02886004 -1.86785 0 P 0 ;0
L 1.02886004 -1.86785 1.04711998 -1.87331998 0 P 0 ;0
L 1.04711998 -1.87331998 1.06501004 -1.87986004 0 P 0 ;0
L 1.06501004 -1.87986004 1.08125 -1.88706998 0 P 0 ;0
L 1.08125 -1.88706998 1.09681004 -1.89541998 0 P 0 ;0
L 1.09681004 -1.89541998 1.1117 -1.9049 0 P 0 ;0
L 1.1117 -1.9049 1.1245 -1.91456998 0 P 0 ;0
L 1.1245 -1.91456998 1.13638996 -1.92521004 0 P 0 ;0
L 1.13638996 -1.92521004 1.14733996 -1.93678996 0 P 0 ;0
L 1.14733996 -1.93678996 1.15408002 -1.94525 0 P 0 ;0
L 1.15408002 -1.94525 1.16001004 -1.95416998 0 P 0 ;0
L 1.16001004 -1.95416998 1.16516004 -1.96355 0 P 0 ;0
L 1.16516004 -1.96355 1.1695 -1.97336998 0 P 0 ;0
L 1.1695 -1.97336998 1.17066004 -1.97631004 0 P 0 ;0
L 1.17066004 -1.97631004 1.16015 -1.97631004 0 P 0 ;0
L 0.87563002 -1.90131004 0.8801 -1.90131004 0 P 0 ;0
L 0.87541004 -1.90031004 0.88493996 -1.90031004 0 P 0 ;0
L 0.8752 -1.89931004 0.88976998 -1.89931004 0 P 0 ;0
L 0.87498996 -1.89831004 0.8946 -1.89831004 0 P 0 ;0
L 0.89423002 -2.08316004 0.94355 -2.08316004 0 P 0 ;0
L 0.89428996 -2.08216004 0.9436 -2.08216004 0 P 0 ;0
L 0.89435 -2.08116004 0.94365 -2.08116004 0 P 0 ;0
L 0.89441004 -2.08016004 0.9437 -2.08016004 0 P 0 ;0
L 0.89446004 -2.07916004 0.94375 -2.07916004 0 P 0 ;0
L 0.89451998 -2.07816004 0.94378996 -2.07816004 0 P 0 ;0
L 0.89458002 -2.07716004 0.94383996 -2.07716004 0 P 0 ;0
L 0.89463996 -2.07616004 0.94388996 -2.07616004 0 P 0 ;0
L 0.8947 -2.07516004 0.94393996 -2.07516004 0 P 0 ;0
L 0.89475 -2.07416004 0.94398002 -2.07416004 0 P 0 ;0
L 0.89481004 -2.07316004 0.94403002 -2.07316004 0 P 0 ;0
L 0.89486998 -2.07216004 0.94408002 -2.07216004 0 P 0 ;0
L 0.89493002 -2.07116004 0.94415 -2.07116004 0 P 0 ;0
L 0.89498996 -2.07016004 0.94426004 -2.07016004 0 P 0 ;0
L 0.89505 -2.06916004 0.94436998 -2.06916004 0 P 0 ;0
L 0.8951 -2.06816004 0.94448002 -2.06816004 0 P 0 ;0
L 0.89516004 -2.06716004 0.94458996 -2.06716004 0 P 0 ;0
L 0.89521998 -2.06616004 0.9447 -2.06616004 0 P 0 ;0
L 0.89526998 -2.06516004 0.94481004 -2.06516004 0 P 0 ;0
L 0.89531004 -2.06416004 0.94491998 -2.06416004 0 P 0 ;0
L 0.89535 -2.06316004 0.94503002 -2.06316004 0 P 0 ;0
L 0.8954 -2.06216004 0.94513996 -2.06216004 0 P 0 ;0
L 0.89543996 -2.06116004 0.94531998 -2.06116004 0 P 0 ;0
L 0.89548996 -2.06016004 0.94551004 -2.06016004 0 P 0 ;0
L 0.89553002 -2.05916004 0.9457 -2.05916004 0 P 0 ;0
L 0.89558002 -2.05816004 0.94588996 -2.05816004 0 P 0 ;0
L 0.89561998 -2.05716004 0.94608002 -2.05716004 0 P 0 ;0
L 0.89566998 -2.05616004 0.94626998 -2.05616004 0 P 0 ;0
L 0.89571004 -2.05516004 0.94646998 -2.05516004 0 P 0 ;0
L 0.89575 -2.05416004 0.94666004 -2.05416004 0 P 0 ;0
L 0.8958 -2.05316004 0.94685 -2.05316004 0 P 0 ;0
L 0.89583996 -2.05216004 0.94708002 -2.05216004 0 P 0 ;0
L 0.89588996 -2.05116004 0.94735 -2.05116004 0 P 0 ;0
L 0.89593996 -2.05016004 0.94761998 -2.05016004 0 P 0 ;0
L 0.89598002 -2.04916004 0.9479 -2.04916004 0 P 0 ;0
L 0.89601998 -2.04816004 0.94825 -2.04816004 0 P 0 ;0
L 0.89606998 -2.04716004 0.94858996 -2.04716004 0 P 0 ;0
L 0.89611004 -2.04616004 0.94893002 -2.04616004 0 P 0 ;0
L 0.89616004 -2.04516004 0.94935 -2.04516004 0 P 0 ;0
L 0.8962 -2.04416004 0.94976998 -2.04416004 0 P 0 ;0
L 0.89625 -2.04316004 0.9502 -2.04316004 0 P 0 ;0
L 0.89628002 -2.04216004 0.95068996 -2.04216004 0 P 0 ;0
L 0.89631004 -2.04116004 0.95118996 -2.04116004 0 P 0 ;0
L 0.89633996 -2.04016004 0.95168996 -2.04016004 0 P 0 ;0
L 0.89638002 -2.03916004 0.95228002 -2.03916004 0 P 0 ;0
L 0.89641004 -2.03816004 0.95291004 -2.03816004 0 P 0 ;0
L 0.89643996 -2.03716004 0.95363002 -2.03716004 0 P 0 ;0
L 0.89646998 -2.03616004 0.95445 -2.03616004 0 P 0 ;0
L 0.89651004 -2.03516004 0.95535 -2.03516004 0 P 0 ;0
L 0.89653996 -2.03416004 0.95636998 -2.03416004 0 P 0 ;0
L 0.89656998 -2.03316004 0.95756998 -2.03316004 0 P 0 ;0
L 0.8966 -2.03216004 0.95893996 -2.03216004 0 P 0 ;0
L 0.89663996 -2.03116004 0.96055 -2.03116004 0 P 0 ;0
L 0.89666998 -2.03016004 0.96278002 -2.03016004 0 P 0 ;0
L 0.8967 -2.02916004 0.96676004 -2.02916004 0 P 0 ;0
L 0.89673996 -2.02816004 1.03838996 -2.02816004 0 P 0 ;0
L 0.89676998 -2.02716004 1.03838002 -2.02716004 0 P 0 ;0
L 0.8968 -2.02616004 1.03833996 -2.02616004 0 P 0 ;0
L 0.89683996 -2.02516004 1.03828996 -2.02516004 0 P 0 ;0
L 0.89686998 -2.02416004 1.03823002 -2.02416004 0 P 0 ;0
L 0.8969 -2.02316004 1.03816004 -2.02316004 0 P 0 ;0
L 0.89693996 -2.02216004 1.0381 -2.02216004 0 P 0 ;0
L 0.89696998 -2.02116004 1.03803996 -2.02116004 0 P 0 ;0
L 0.897 -2.02016004 1.0379 -2.02016004 0 P 0 ;0
L 0.89703002 -2.01916004 1.03773996 -2.01916004 0 P 0 ;0
L 0.89706004 -2.01816004 1.03751998 -2.01816004 0 P 0 ;0
L 0.89708996 -2.01716004 1.03728002 -2.01716004 0 P 0 ;0
L 0.89711998 -2.01616004 1.03698996 -2.01616004 0 P 0 ;0
L 0.89713996 -2.01516004 1.03668002 -2.01516004 0 P 0 ;0
L 0.89716998 -2.01416004 1.03631004 -2.01416004 0 P 0 ;0
L 0.8972 -2.01316004 1.03591998 -2.01316004 0 P 0 ;0
L 0.89721998 -2.01216004 1.03548996 -2.01216004 0 P 0 ;0
L 0.89725 -2.01116004 1.03505 -2.01116004 0 P 0 ;0
L 0.89726998 -2.01016004 1.03458002 -2.01016004 0 P 0 ;0
L 0.8973 -2.00916004 1.03405 -2.00916004 0 P 0 ;0
L 0.89733002 -2.00816004 1.03351998 -2.00816004 0 P 0 ;0
L 0.89736004 -2.00716004 0.94676004 -2.00716004 0 P 0 ;0
L 0.89738002 -2.00616004 0.9461 -2.00616004 0 P 0 ;0
L 0.89741004 -2.00516004 0.94563996 -2.00516004 0 P 0 ;0
L 0.89743996 -2.00416004 0.94563996 -2.00416004 0 P 0 ;0
L 0.89746004 -2.00316004 0.94563996 -2.00316004 0 P 0 ;0
L 0.89748996 -2.00216004 0.94563996 -2.00216004 0 P 0 ;0
L 0.89751004 -2.00116004 0.94563996 -2.00116004 0 P 0 ;0
L 0.89753996 -2.00016004 0.94563996 -2.00016004 0 P 0 ;0
L 0.89756998 -1.99916004 0.94563996 -1.99916004 0 P 0 ;0
L 0.8976 -1.99816004 0.94563996 -1.99816004 0 P 0 ;0
L 0.89761998 -1.99716004 0.94563996 -1.99716004 0 P 0 ;0
L 0.89765 -1.99616004 0.94563996 -1.99616004 0 P 0 ;0
L 0.89768002 -1.99516004 0.94563996 -1.99516004 0 P 0 ;0
L 0.97546998 -1.98933996 0.97236998 -1.99006004 0 P 0 ;0
L 0.97236998 -1.99006004 0.96931998 -1.99103002 0 P 0 ;0
L 0.96931998 -1.99103002 0.96603002 -1.99233002 0 P 0 ;0
L 0.96603002 -1.99233002 0.96281004 -1.99383002 0 P 0 ;0
L 0.96281004 -1.99383002 0.95976004 -1.99546998 0 P 0 ;0
L 0.95976004 -1.99546998 0.95681004 -1.99728996 0 P 0 ;0
L 0.95681004 -1.99728996 0.95521004 -1.99841004 0 P 0 ;0
L 0.95521004 -1.99841004 0.95368996 -1.99963002 0 P 0 ;0
L 0.95368996 -1.99963002 0.95223996 -2.00095 0 P 0 ;0
L 0.95223996 -2.00095 0.94763996 -2.00546998 0 P 0 ;0
L 0.94763996 -2.00546998 0.94763996 -1.99243996 0 P 0 ;0
L 0.94763996 -1.99243996 0.89575 -1.99243996 0 P 0 ;0
L 0.89575 -1.99243996 0.89505 -2.01878002 0 P 0 ;0
L 0.89505 -2.01878002 0.89423996 -2.04316004 0 P 0 ;0
L 0.89423996 -2.04316004 0.89321998 -2.0661 0 P 0 ;0
L 0.89321998 -2.0661 0.89198996 -2.08728996 0 P 0 ;0
L 0.89198996 -2.08728996 0.89055 -2.1063 0 P 0 ;0
L 0.89055 -2.1063 0.88993996 -2.11358002 0 P 0 ;0
L 0.88993996 -2.11358002 0.88943002 -2.11988002 0 P 0 ;0
L 0.88943002 -2.11988002 0.88898996 -2.12533996 0 P 0 ;0
L 0.88898996 -2.12533996 0.88896004 -2.12613002 0 P 0 ;0
L 0.88896004 -2.12613002 0.88896998 -2.12621004 0 P 0 ;0
L 0.88896998 -2.12621004 0.88898002 -2.12625 0 P 0 ;0
L 0.88898002 -2.12625 0.88898996 -2.12628002 0 P 0 ;0
L 0.88898996 -2.12628002 0.88901998 -2.12636004 0 P 0 ;0
L 0.88901998 -2.12636004 0.88903996 -2.12638996 0 P 0 ;0
L 0.88903996 -2.12638996 0.88906998 -2.12641998 0 P 0 ;0
L 0.88906998 -2.12641998 0.88908996 -2.12645 0 P 0 ;0
L 0.88908996 -2.12645 0.88911998 -2.12646998 0 P 0 ;0
L 0.88911998 -2.12646998 0.88915 -2.1265 0 P 0 ;0
L 0.88915 -2.1265 0.88921004 -2.12653996 0 P 0 ;0
L 0.88921004 -2.12653996 0.88925 -2.12655 0 P 0 ;0
L 0.88925 -2.12655 0.88928002 -2.12656004 0 P 0 ;0
L 0.88928002 -2.12656004 0.88931998 -2.12658002 0 P 0 ;0
L 0.88931998 -2.12658002 0.8894 -2.12658002 0 P 0 ;0
L 0.8894 -2.12658002 0.89648002 -2.12686998 0 P 0 ;0
L 0.89648002 -2.12686998 0.90518996 -2.1271 0 P 0 ;0
L 0.90518996 -2.1271 0.9165 -2.12716004 0 P 0 ;0
L 0.9165 -2.12716004 0.94403996 -2.12716004 0 P 0 ;0
L 0.94403996 -2.12716004 0.94468996 -2.10135 0 P 0 ;0
L 0.94468996 -2.10135 0.9461 -2.07171998 0 P 0 ;0
L 0.9461 -2.07171998 0.94713002 -2.06233002 0 P 0 ;0
L 0.94713002 -2.06233002 0.9489 -2.05308002 0 P 0 ;0
L 0.9489 -2.05308002 0.94975 -2.04995 0 P 0 ;0
L 0.94975 -2.04995 0.9508 -2.04688996 0 P 0 ;0
L 0.9508 -2.04688996 0.95205 -2.0439 0 P 0 ;0
L 0.95205 -2.0439 0.95351004 -2.041 0 P 0 ;0
L 0.95351004 -2.041 0.9544 -2.03951004 0 P 0 ;0
L 0.9544 -2.03951004 0.95541998 -2.03811004 0 P 0 ;0
L 0.95541998 -2.03811004 0.95655 -2.03678996 0 P 0 ;0
L 0.95655 -2.03678996 0.95778996 -2.03556998 0 P 0 ;0
L 0.95778996 -2.03556998 0.95911998 -2.03446998 0 P 0 ;0
L 0.95911998 -2.03446998 0.96056998 -2.03346998 0 P 0 ;0
L 0.96056998 -2.03346998 0.96151004 -2.03291004 0 P 0 ;0
L 0.96151004 -2.03291004 0.96248996 -2.03243002 0 P 0 ;0
L 0.96248996 -2.03243002 0.96351004 -2.03201998 0 P 0 ;0
L 0.96351004 -2.03201998 0.96455 -2.03168996 0 P 0 ;0
L 0.96455 -2.03168996 0.96613002 -2.0313 0 P 0 ;0
L 0.96613002 -2.0313 0.96773002 -2.03101998 0 P 0 ;0
L 0.96773002 -2.03101998 0.96935 -2.03086004 0 P 0 ;0
L 0.96935 -2.03086004 0.97095 -2.03081004 0 P 0 ;0
L 0.97095 -2.03081004 0.97255 -2.03086998 0 P 0 ;0
L 0.97255 -2.03086998 0.97413002 -2.03105 0 P 0 ;0
L 0.97413002 -2.03105 0.97513002 -2.03123996 0 P 0 ;0
L 0.97513002 -2.03123996 0.9761 -2.03151004 0 P 0 ;0
L 0.9761 -2.03151004 0.97706004 -2.03186004 0 P 0 ;0
L 0.97706004 -2.03186004 0.97796998 -2.0323 0 P 0 ;0
L 0.97796998 -2.0323 0.97885 -2.0328 0 P 0 ;0
L 0.97885 -2.0328 0.97968002 -2.03336998 0 P 0 ;0
L 0.97968002 -2.03336998 0.98046998 -2.03398996 0 P 0 ;0
L 0.98046998 -2.03398996 0.98121998 -2.03468002 0 P 0 ;0
L 0.98121998 -2.03468002 0.98191004 -2.03541998 0 P 0 ;0
L 0.98191004 -2.03541998 0.98253996 -2.0362 0 P 0 ;0
L 0.98253996 -2.0362 0.9831 -2.03703002 0 P 0 ;0
L 0.9831 -2.03703002 0.9836 -2.03788996 0 P 0 ;0
L 0.9836 -2.03788996 0.98403996 -2.0388 0 P 0 ;0
L 0.98403996 -2.0388 0.9844 -2.03973996 0 P 0 ;0
L 0.9844 -2.03973996 0.98505 -2.04188996 0 P 0 ;0
L 0.98505 -2.04188996 0.98553002 -2.04408002 0 P 0 ;0
L 0.98553002 -2.04408002 0.98583002 -2.0463 0 P 0 ;0
L 0.98583002 -2.0463 0.98653002 -2.05705 0 P 0 ;0
L 0.98653002 -2.05705 0.9866 -2.06961004 0 P 0 ;0
L 0.9866 -2.06961004 0.98596004 -2.08908002 0 P 0 ;0
L 0.98596004 -2.08908002 0.98498002 -2.10858002 0 P 0 ;0
L 0.98498002 -2.10858002 0.98388002 -2.12146998 0 P 0 ;0
L 0.98388002 -2.12146998 0.98323002 -2.12716004 0 P 0 ;0
L 0.98323002 -2.12716004 1.03741004 -2.12716004 0 P 0 ;0
L 1.03741004 -2.12716004 1.03896004 -2.09103002 0 P 0 ;0
L 1.03896004 -2.09103002 1.03956004 -2.0759 0 P 0 ;0
L 1.03956004 -2.0759 1.04005 -2.06025 0 P 0 ;0
L 1.04005 -2.06025 1.04038996 -2.04626004 0 P 0 ;0
L 1.04038996 -2.04626004 1.04048002 -2.03698996 0 P 0 ;0
L 1.04048002 -2.03698996 1.04036998 -2.02651998 0 P 0 ;0
L 1.04036998 -2.02651998 1.04003996 -2.02096998 0 P 0 ;0
L 1.04003996 -2.02096998 1.03975 -2.01895 0 P 0 ;0
L 1.03975 -2.01895 1.0393 -2.01693996 0 P 0 ;0
L 1.0393 -2.01693996 1.03868996 -2.01483996 0 P 0 ;0
L 1.03868996 -2.01483996 1.03793996 -2.01278002 0 P 0 ;0
L 1.03793996 -2.01278002 1.03658996 -2.00968002 0 P 0 ;0
L 1.03658996 -2.00968002 1.03501004 -2.00668996 0 P 0 ;0
L 1.03501004 -2.00668996 1.0332 -2.0038 0 P 0 ;0
L 1.0332 -2.0038 1.03186998 -2.002 0 P 0 ;0
L 1.03186998 -2.002 1.0304 -2.0003 0 P 0 ;0
L 1.0304 -2.0003 1.0288 -1.99873002 0 P 0 ;0
L 1.0288 -1.99873002 1.02708002 -1.99728996 0 P 0 ;0
L 1.02708002 -1.99728996 1.02518002 -1.99593002 0 P 0 ;0
L 1.02518002 -1.99593002 1.02318002 -1.99471998 0 P 0 ;0
L 1.02318002 -1.99471998 1.0211 -1.99365 0 P 0 ;0
L 1.0211 -1.99365 1.01893002 -1.99273996 0 P 0 ;0
L 1.01893002 -1.99273996 1.01358996 -1.99098996 0 P 0 ;0
L 1.01358996 -1.99098996 1.0081 -1.98971004 0 P 0 ;0
L 1.0081 -1.98971004 1.00428996 -1.98908996 0 P 0 ;0
L 1.00428996 -1.98908996 1.00043996 -1.98868002 0 P 0 ;0
L 1.00043996 -1.98868002 0.99138002 -1.98826004 0 P 0 ;0
L 0.99138002 -1.98826004 0.98251998 -1.98846998 0 P 0 ;0
L 0.98251998 -1.98846998 0.97898996 -1.98878996 0 P 0 ;0
L 0.97898996 -1.98878996 0.97546998 -1.98933996 0 P 0 ;0
L 0.91651004 -2.12516004 0.94208996 -2.12516004 0 P 0 ;0
L 0.8911 -2.12416004 0.94211004 -2.12416004 0 P 0 ;0
L 0.89118002 -2.12316004 0.94213996 -2.12316004 0 P 0 ;0
L 0.89125 -2.12216004 0.94216004 -2.12216004 0 P 0 ;0
L 0.89133002 -2.12116004 0.94218996 -2.12116004 0 P 0 ;0
L 0.89141004 -2.12016004 0.94221004 -2.12016004 0 P 0 ;0
L 0.89148996 -2.11916004 0.94223996 -2.11916004 0 P 0 ;0
L 0.89156998 -2.11816004 0.94226998 -2.11816004 0 P 0 ;0
L 0.89166004 -2.11716004 0.94228996 -2.11716004 0 P 0 ;0
L 0.89173996 -2.11616004 0.94231004 -2.11616004 0 P 0 ;0
L 0.89181998 -2.11516004 0.94233996 -2.11516004 0 P 0 ;0
L 0.8919 -2.11416004 0.94236004 -2.11416004 0 P 0 ;0
L 0.89198002 -2.11316004 0.94238996 -2.11316004 0 P 0 ;0
L 0.89206998 -2.11216004 0.94241998 -2.11216004 0 P 0 ;0
L 0.89215 -2.11116004 0.94243996 -2.11116004 0 P 0 ;0
L 0.89223002 -2.11016004 0.94246998 -2.11016004 0 P 0 ;0
L 0.89231998 -2.10916004 0.94248996 -2.10916004 0 P 0 ;0
L 0.8924 -2.10816004 0.94251998 -2.10816004 0 P 0 ;0
L 0.89248002 -2.10716004 0.94255 -2.10716004 0 P 0 ;0
L 0.89256998 -2.10616004 0.94256998 -2.10616004 0 P 0 ;0
L 0.89263996 -2.10516004 0.94258996 -2.10516004 0 P 0 ;0
L 0.89271004 -2.10416004 0.94261998 -2.10416004 0 P 0 ;0
L 0.89278996 -2.10316004 0.94263996 -2.10316004 0 P 0 ;0
L 0.89286998 -2.10216004 0.94266998 -2.10216004 0 P 0 ;0
L 0.89293996 -2.10116004 0.9427 -2.10116004 0 P 0 ;0
L 0.89301998 -2.10016004 0.94275 -2.10016004 0 P 0 ;0
L 0.89308996 -2.09916004 0.94278996 -2.09916004 0 P 0 ;0
L 0.89316998 -2.09816004 0.94283996 -2.09816004 0 P 0 ;0
L 0.89325 -2.09716004 0.94288996 -2.09716004 0 P 0 ;0
L 0.89331998 -2.09616004 0.94293996 -2.09616004 0 P 0 ;0
L 0.8934 -2.09516004 0.94298002 -2.09516004 0 P 0 ;0
L 0.89346998 -2.09416004 0.94303002 -2.09416004 0 P 0 ;0
L 0.89355 -2.09316004 0.94308002 -2.09316004 0 P 0 ;0
L 0.89361998 -2.09216004 0.94313002 -2.09216004 0 P 0 ;0
L 0.8937 -2.09116004 0.94318002 -2.09116004 0 P 0 ;0
L 0.89378002 -2.09016004 0.94321998 -2.09016004 0 P 0 ;0
L 0.89385 -2.08916004 0.94326998 -2.08916004 0 P 0 ;0
L 0.89393002 -2.08816004 0.94331998 -2.08816004 0 P 0 ;0
L 0.894 -2.08716004 0.94336004 -2.08716004 0 P 0 ;0
L 0.89406004 -2.08616004 0.94341004 -2.08616004 0 P 0 ;0
L 0.89411998 -2.08516004 0.94346004 -2.08516004 0 P 0 ;0
L 0.89418002 -2.08416004 0.94351004 -2.08416004 0 P 0 ;0
L 0.91651004 -2.12516004 0.90521998 -2.1251 0 P 0 ;0
L 0.90521998 -2.1251 0.89655 -2.12486998 0 P 0 ;0
L 0.89655 -2.12486998 0.89106004 -2.12465 0 P 0 ;0
L 0.89106004 -2.12465 0.89141998 -2.12003996 0 P 0 ;0
L 0.89141998 -2.12003996 0.89193996 -2.11373996 0 P 0 ;0
L 0.89193996 -2.11373996 0.89253996 -2.10645 0 P 0 ;0
L 0.89253996 -2.10645 0.89398002 -2.08741998 0 P 0 ;0
L 0.89398002 -2.08741998 0.89521998 -2.06621998 0 P 0 ;0
L 0.89521998 -2.06621998 0.89521998 -2.06618996 0 P 0 ;0
L 0.89521998 -2.06618996 0.89623996 -2.04323002 0 P 0 ;0
L 0.89623996 -2.04323002 0.89703996 -2.01883002 0 P 0 ;0
L 0.89703996 -2.01883002 0.8977 -1.99443996 0 P 0 ;0
L 0.8977 -1.99443996 0.94563996 -1.99443996 0 P 0 ;0
L 0.94563996 -1.99443996 0.94563996 -2.00546998 0 P 0 ;0
L 0.94563996 -2.00546998 0.94686004 -2.00731004 0 P 0 ;0
L 0.94686004 -2.00731004 0.94903002 -2.00688996 0 P 0 ;0
L 0.94903002 -2.00688996 0.95361998 -2.00241004 0 P 0 ;0
L 0.95361998 -2.00241004 0.95498996 -2.00115 0 P 0 ;0
L 0.95498996 -2.00115 0.95641998 -2.00001004 0 P 0 ;0
L 0.95641998 -2.00001004 0.9579 -1.99896004 0 P 0 ;0
L 0.9579 -1.99896004 0.96076004 -1.9972 0 P 0 ;0
L 0.96076004 -1.9972 0.9637 -1.99561998 0 P 0 ;0
L 0.9637 -1.99561998 0.96683002 -1.99416998 0 P 0 ;0
L 0.96683002 -1.99416998 0.96998996 -1.99291998 0 P 0 ;0
L 0.96998996 -1.99291998 0.9729 -1.99198996 0 P 0 ;0
L 0.9729 -1.99198996 0.97586004 -1.9913 0 P 0 ;0
L 0.97586004 -1.9913 0.97923002 -1.99076998 0 P 0 ;0
L 0.97923002 -1.99076998 0.98263002 -1.99046998 0 P 0 ;0
L 0.98263002 -1.99046998 0.99136004 -1.99026004 0 P 0 ;0
L 0.99136004 -1.99026004 1.00028996 -1.99066998 0 P 0 ;0
L 1.00028996 -1.99066998 1.00403002 -1.99108002 0 P 0 ;0
L 1.00403002 -1.99108002 1.00771004 -1.99166998 0 P 0 ;0
L 1.00771004 -1.99166998 1.01305 -1.99291998 0 P 0 ;0
L 1.01305 -1.99291998 1.01823002 -1.99461998 0 P 0 ;0
L 1.01823002 -1.99461998 1.02026004 -1.99546998 0 P 0 ;0
L 1.02026004 -1.99546998 1.02221004 -1.99646998 0 P 0 ;0
L 1.02221004 -1.99646998 1.02408002 -1.9976 0 P 0 ;0
L 1.02408002 -1.9976 1.02585 -1.99886998 0 P 0 ;0
L 1.02585 -1.99886998 1.02746004 -2.00021004 0 P 0 ;0
L 1.02746004 -2.00021004 1.02893996 -2.00166998 0 P 0 ;0
L 1.02893996 -2.00166998 1.03031004 -2.00325 0 P 0 ;0
L 1.03031004 -2.00325 1.03155 -2.00493002 0 P 0 ;0
L 1.03155 -2.00493002 1.03326998 -2.00768002 0 P 0 ;0
L 1.03326998 -2.00768002 1.03478002 -2.01055 0 P 0 ;0
L 1.03478002 -2.01055 1.03608002 -2.01351998 0 P 0 ;0
L 1.03608002 -2.01351998 1.03678996 -2.01546998 0 P 0 ;0
L 1.03678996 -2.01546998 1.03736004 -2.01743002 0 P 0 ;0
L 1.03736004 -2.01743002 1.03778002 -2.0193 0 P 0 ;0
L 1.03778002 -2.0193 1.03805 -2.02116998 0 P 0 ;0
L 1.03805 -2.02116998 1.03836998 -2.02658996 0 P 0 ;0
L 1.03836998 -2.02658996 1.03848002 -2.03698996 0 P 0 ;0
L 1.03848002 -2.03698996 1.03838996 -2.04623002 0 P 0 ;0
L 1.03838996 -2.04623002 1.03805 -2.06018996 0 P 0 ;0
L 1.03805 -2.06018996 1.03756004 -2.07583002 0 P 0 ;0
L 1.03756004 -2.07583002 1.03696998 -2.09095 0 P 0 ;0
L 1.03696998 -2.09095 1.03548996 -2.12516004 0 P 0 ;0
L 1.03548996 -2.12516004 0.98546998 -2.12516004 0 P 0 ;0
L 0.98546998 -2.12516004 0.98586998 -2.12166004 0 P 0 ;0
L 0.98586998 -2.12166004 0.98696998 -2.10871998 0 P 0 ;0
L 0.98696998 -2.10871998 0.98796004 -2.08916004 0 P 0 ;0
L 0.98796004 -2.08916004 0.9886 -2.06963002 0 P 0 ;0
L 0.9886 -2.06963002 0.98853002 -2.05698002 0 P 0 ;0
L 0.98853002 -2.05698002 0.98781998 -2.0461 0 P 0 ;0
L 0.98781998 -2.0461 0.9875 -2.04373002 0 P 0 ;0
L 0.9875 -2.04373002 0.98748002 -2.04365 0 P 0 ;0
L 0.98748002 -2.04365 0.98698996 -2.04138996 0 P 0 ;0
L 0.98698996 -2.04138996 0.9863 -2.03908002 0 P 0 ;0
L 0.9863 -2.03908002 0.98588002 -2.038 0 P 0 ;0
L 0.98588002 -2.038 0.98538002 -2.03696004 0 P 0 ;0
L 0.98538002 -2.03696004 0.9848 -2.03596004 0 P 0 ;0
L 0.9848 -2.03596004 0.98413996 -2.03501004 0 P 0 ;0
L 0.98413996 -2.03501004 0.98341998 -2.03411004 0 P 0 ;0
L 0.98341998 -2.03411004 0.98336998 -2.03405 0 P 0 ;0
L 0.98336998 -2.03405 0.98263002 -2.03326004 0 P 0 ;0
L 0.98263002 -2.03326004 0.98176998 -2.03246998 0 P 0 ;0
L 0.98176998 -2.03246998 0.98086998 -2.03175 0 P 0 ;0
L 0.98086998 -2.03175 0.97991004 -2.0311 0 P 0 ;0
L 0.97991004 -2.0311 0.9789 -2.03051998 0 P 0 ;0
L 0.9789 -2.03051998 0.97783002 -2.03001998 0 P 0 ;0
L 0.97783002 -2.03001998 0.97673002 -2.02961004 0 P 0 ;0
L 0.97673002 -2.02961004 0.97663996 -2.02958002 0 P 0 ;0
L 0.97663996 -2.02958002 0.97558996 -2.02928996 0 P 0 ;0
L 0.97558996 -2.02928996 0.97443002 -2.02906998 0 P 0 ;0
L 0.97443002 -2.02906998 0.9727 -2.02888002 0 P 0 ;0
L 0.9727 -2.02888002 0.97261998 -2.02886998 0 P 0 ;0
L 0.97261998 -2.02886998 0.97096004 -2.02881004 0 P 0 ;0
L 0.97096004 -2.02881004 0.96921004 -2.02886004 0 P 0 ;0
L 0.96921004 -2.02886004 0.96745 -2.02903996 0 P 0 ;0
L 0.96745 -2.02903996 0.96571004 -2.02933996 0 P 0 ;0
L 0.96571004 -2.02933996 0.964 -2.02976004 0 P 0 ;0
L 0.964 -2.02976004 0.96283002 -2.03013996 0 P 0 ;0
L 0.96283002 -2.03013996 0.96168002 -2.0306 0 P 0 ;0
L 0.96168002 -2.0306 0.96056998 -2.03115 0 P 0 ;0
L 0.96056998 -2.03115 0.95948996 -2.03178002 0 P 0 ;0
L 0.95948996 -2.03178002 0.95791004 -2.03286998 0 P 0 ;0
L 0.95791004 -2.03286998 0.95645 -2.03408996 0 P 0 ;0
L 0.95645 -2.03408996 0.95508996 -2.03541998 0 P 0 ;0
L 0.95508996 -2.03541998 0.95383996 -2.03686998 0 P 0 ;0
L 0.95383996 -2.03686998 0.9538 -2.03693002 0 P 0 ;0
L 0.9538 -2.03693002 0.95273002 -2.03841004 0 P 0 ;0
L 0.95273002 -2.03841004 0.95175 -2.04003996 0 P 0 ;0
L 0.95175 -2.04003996 0.95023002 -2.04306004 0 P 0 ;0
L 0.95023002 -2.04306004 0.94896004 -2.04611004 0 P 0 ;0
L 0.94896004 -2.04611004 0.94893002 -2.04616998 0 P 0 ;0
L 0.94893002 -2.04616998 0.94783002 -2.04936004 0 P 0 ;0
L 0.94783002 -2.04936004 0.94695 -2.05263002 0 P 0 ;0
L 0.94695 -2.05263002 0.94515 -2.06203002 0 P 0 ;0
L 0.94515 -2.06203002 0.9441 -2.07156004 0 P 0 ;0
L 0.9441 -2.07156004 0.9427 -2.10128002 0 P 0 ;0
L 0.9427 -2.10128002 0.94208996 -2.12516004 0 P 0 ;0
L 0.94208996 -2.12516004 0.91651004 -2.12516004 0 P 0 ;0
L 0.93143002 -2.21261998 1.00578996 -2.21261998 0 P 0 ;0
L 0.94051004 -2.21161998 1.00803002 -2.21161998 0 P 0 ;0
L 0.94941998 -2.21061998 1.01026004 -2.21061998 0 P 0 ;0
L 0.9555 -2.20961998 1.0125 -2.20961998 0 P 0 ;0
L 0.96158002 -2.20861998 1.01473996 -2.20861998 0 P 0 ;0
L 0.96766004 -2.20761998 1.01696998 -2.20761998 0 P 0 ;0
L 0.97373002 -2.20661998 1.01921004 -2.20661998 0 P 0 ;0
L 0.97981004 -2.20561998 1.02145 -2.20561998 0 P 0 ;0
L 0.98498996 -2.20461998 1.02368996 -2.20461998 0 P 0 ;0
L 0.98973996 -2.20361998 1.02591998 -2.20361998 0 P 0 ;0
L 0.99448996 -2.20261998 1.02816004 -2.20261998 0 P 0 ;0
L 0.99923996 -2.20161998 1.0304 -2.20161998 0 P 0 ;0
L 1.00398996 -2.20061998 1.03243996 -2.20061998 0 P 0 ;0
L 1.00875 -2.19961998 1.0344 -2.19961998 0 P 0 ;0
L 1.01348996 -2.19861998 1.03636998 -2.19861998 0 P 0 ;0
L 1.0178 -2.19761998 1.03833996 -2.19761998 0 P 0 ;0
L 1.02168996 -2.19661998 1.04031004 -2.19661998 0 P 0 ;0
L 1.02558002 -2.19561998 1.04228002 -2.19561998 0 P 0 ;0
L 1.02946998 -2.19461998 1.04415 -2.19461998 0 P 0 ;0
L 1.03336004 -2.19361998 1.04596998 -2.19361998 0 P 0 ;0
L 1.03725 -2.19261998 1.04778996 -2.19261998 0 P 0 ;0
L 1.04113996 -2.19161998 1.0496 -2.19161998 0 P 0 ;0
L 1.14356998 -1.98926998 1.13261004 -1.99086004 0 P 0 ;0
L 1.13261004 -1.99086004 1.12165 -1.9934 0 P 0 ;0
L 1.12165 -1.9934 1.11125 -1.99673002 0 P 0 ;0
L 1.11125 -1.99673002 1.10658002 -1.99858996 0 P 0 ;0
L 1.10658002 -1.99858996 1.10198996 -2.00071004 0 P 0 ;0
L 1.10198996 -2.00071004 1.09653002 -2.00358996 0 P 0 ;0
L 1.09653002 -2.00358996 1.09436998 -2.00488996 0 P 0 ;0
L 1.09436998 -2.00488996 1.09226004 -2.00631004 0 P 0 ;0
L 1.09226004 -2.00631004 1.09028002 -2.00781004 0 P 0 ;0
L 1.09028002 -2.00781004 1.08836998 -2.00941998 0 P 0 ;0
L 1.08836998 -2.00941998 1.08405 -2.0135 0 P 0 ;0
L 1.08405 -2.0135 1.08096998 -2.01678996 0 P 0 ;0
L 1.08096998 -2.01678996 1.07808002 -2.02026998 0 P 0 ;0
L 1.07808002 -2.02026998 1.0754 -2.02393002 0 P 0 ;0
L 1.0754 -2.02393002 1.07313996 -2.02748002 0 P 0 ;0
L 1.07313996 -2.02748002 1.07116004 -2.03118996 0 P 0 ;0
L 1.07116004 -2.03118996 1.06943996 -2.03505 0 P 0 ;0
L 1.06943996 -2.03505 1.06795 -2.03918996 0 P 0 ;0
L 1.06795 -2.03918996 1.06673996 -2.04343996 0 P 0 ;0
L 1.06673996 -2.04343996 1.06583002 -2.04778002 0 P 0 ;0
L 1.06583002 -2.04778002 1.06476998 -2.05538996 0 P 0 ;0
L 1.06476998 -2.05538996 1.06421004 -2.06306004 0 P 0 ;0
L 1.06421004 -2.06306004 1.06415 -2.07076004 0 P 0 ;0
L 1.06415 -2.07076004 1.06456998 -2.0785 0 P 0 ;0
L 1.06456998 -2.0785 1.06508996 -2.08276004 0 P 0 ;0
L 1.06508996 -2.08276004 1.06591004 -2.08696004 0 P 0 ;0
L 1.06591004 -2.08696004 1.06703002 -2.09108002 0 P 0 ;0
L 1.06703002 -2.09108002 1.06833002 -2.09473002 0 P 0 ;0
L 1.06833002 -2.09473002 1.06991998 -2.09823996 0 P 0 ;0
L 1.06991998 -2.09823996 1.0718 -2.10161998 0 P 0 ;0
L 1.0718 -2.10161998 1.07398002 -2.10491998 0 P 0 ;0
L 1.07398002 -2.10491998 1.07641998 -2.10803002 0 P 0 ;0
L 1.07641998 -2.10803002 1.07908996 -2.11095 0 P 0 ;0
L 1.07908996 -2.11095 1.08175 -2.11345 0 P 0 ;0
L 1.08175 -2.11345 1.08458996 -2.11573996 0 P 0 ;0
L 1.08458996 -2.11573996 1.08758996 -2.1178 0 P 0 ;0
L 1.08758996 -2.1178 1.09073002 -2.11963996 0 P 0 ;0
L 1.09073002 -2.11963996 1.094 -2.12123996 0 P 0 ;0
L 1.094 -2.12123996 1.0986 -2.12306998 0 P 0 ;0
L 1.0986 -2.12306998 1.10331004 -2.12456004 0 P 0 ;0
L 1.10331004 -2.12456004 1.10811004 -2.12568996 0 P 0 ;0
L 1.10811004 -2.12568996 1.11298002 -2.12646998 0 P 0 ;0
L 1.11298002 -2.12646998 1.1182 -2.12693002 0 P 0 ;0
L 1.1182 -2.12693002 1.12343996 -2.12703002 0 P 0 ;0
L 1.12343996 -2.12703002 1.12866998 -2.12676004 0 P 0 ;0
L 1.12866998 -2.12676004 1.13388002 -2.12613002 0 P 0 ;0
L 1.13388002 -2.12613002 1.14086004 -2.12473996 0 P 0 ;0
L 1.14086004 -2.12473996 1.1477 -2.12273996 0 P 0 ;0
L 1.1477 -2.12273996 1.15433996 -2.12015 0 P 0 ;0
L 1.15433996 -2.12015 1.1545 -2.12008996 0 P 0 ;0
L 1.1545 -2.12008996 1.15466004 -2.12003996 0 P 0 ;0
L 1.15466004 -2.12003996 1.15483002 -2.12001004 0 P 0 ;0
L 1.15483002 -2.12001004 1.15498996 -2.11998996 0 P 0 ;0
L 1.15498996 -2.11998996 1.15533002 -2.11998996 0 P 0 ;0
L 1.15533002 -2.11998996 1.15538996 -2.12 0 P 0 ;0
L 1.15538996 -2.12 1.15545 -2.12001998 0 P 0 ;0
L 1.15545 -2.12001998 1.15551004 -2.12003002 0 P 0 ;0
L 1.15551004 -2.12003002 1.15556004 -2.12006004 0 P 0 ;0
L 1.15556004 -2.12006004 1.15561004 -2.12008002 0 P 0 ;0
L 1.15561004 -2.12008002 1.15566004 -2.12011004 0 P 0 ;0
L 1.15566004 -2.12011004 1.15571004 -2.12015 0 P 0 ;0
L 1.15571004 -2.12015 1.15575 -2.12018996 0 P 0 ;0
L 1.15575 -2.12018996 1.15578996 -2.12023996 0 P 0 ;0
L 1.15578996 -2.12023996 1.15583002 -2.12028002 0 P 0 ;0
L 1.15583002 -2.12028002 1.15586004 -2.12033996 0 P 0 ;0
L 1.15586004 -2.12033996 1.15588002 -2.12038996 0 P 0 ;0
L 1.15588002 -2.12038996 1.15591004 -2.12043996 0 P 0 ;0
L 1.15591004 -2.12043996 1.15601998 -2.12076004 0 P 0 ;0
L 1.15601998 -2.12076004 1.1561 -2.12108002 0 P 0 ;0
L 1.1561 -2.12108002 1.15616004 -2.12141998 0 P 0 ;0
L 1.15616004 -2.12141998 1.15618002 -2.12175 0 P 0 ;0
L 1.15618002 -2.12175 1.15623996 -2.12505 0 P 0 ;0
L 1.15623996 -2.12505 1.15616004 -2.12688002 0 P 0 ;0
L 1.15616004 -2.12688002 1.15593002 -2.12871004 0 P 0 ;0
L 1.15593002 -2.12871004 1.15553996 -2.13051998 0 P 0 ;0
L 1.15553996 -2.13051998 1.15516004 -2.1318 0 P 0 ;0
L 1.15516004 -2.1318 1.1547 -2.13305 0 P 0 ;0
L 1.1547 -2.13305 1.15415 -2.13426004 0 P 0 ;0
L 1.15415 -2.13426004 1.15351004 -2.13545 0 P 0 ;0
L 1.15351004 -2.13545 1.15278996 -2.1366 0 P 0 ;0
L 1.15278996 -2.1366 1.15198002 -2.13768996 0 P 0 ;0
L 1.15198002 -2.13768996 1.15111004 -2.13873002 0 P 0 ;0
L 1.15111004 -2.13873002 1.15016004 -2.13971004 0 P 0 ;0
L 1.15016004 -2.13971004 1.14876004 -2.14096004 0 P 0 ;0
L 1.14876004 -2.14096004 1.14726004 -2.1421 0 P 0 ;0
L 1.14726004 -2.1421 1.14566998 -2.14311004 0 P 0 ;0
L 1.14566998 -2.14311004 1.144 -2.144 0 P 0 ;0
L 1.144 -2.144 1.14226004 -2.14476004 0 P 0 ;0
L 1.14226004 -2.14476004 1.14046004 -2.14536998 0 P 0 ;0
L 1.14046004 -2.14536998 1.13863002 -2.14583002 0 P 0 ;0
L 1.13863002 -2.14583002 1.13676004 -2.14613996 0 P 0 ;0
L 1.13676004 -2.14613996 1.13041998 -2.14663996 0 P 0 ;0
L 1.13041998 -2.14663996 1.12403996 -2.1466 0 P 0 ;0
L 1.12403996 -2.1466 1.11621998 -2.14593996 0 P 0 ;0
L 1.11621998 -2.14593996 1.10843996 -2.14471004 0 P 0 ;0
L 1.10843996 -2.14471004 1.09946998 -2.14276998 0 P 0 ;0
L 1.09946998 -2.14276998 1.0905 -2.14041004 0 P 0 ;0
L 1.0905 -2.14041004 1.07963996 -2.13728996 0 P 0 ;0
L 1.07963996 -2.13728996 1.07936004 -2.1401 0 P 0 ;0
L 1.07936004 -2.1401 1.07931004 -2.14103996 0 P 0 ;0
L 1.07931004 -2.14103996 1.07931998 -2.14198002 0 P 0 ;0
L 1.07931998 -2.14198002 1.07956998 -2.14735 0 P 0 ;0
L 1.07956998 -2.14735 1.07993996 -2.15375 0 P 0 ;0
L 1.07993996 -2.15375 1.08045 -2.16081998 0 P 0 ;0
L 1.08045 -2.16081998 1.08181004 -2.17873002 0 P 0 ;0
L 1.08181004 -2.17873002 1.08996004 -2.18061004 0 P 0 ;0
L 1.08996004 -2.18061004 1.09951004 -2.18246004 0 P 0 ;0
L 1.09951004 -2.18246004 1.11243996 -2.18416998 0 P 0 ;0
L 1.11243996 -2.18416998 1.1254 -2.18543002 0 P 0 ;0
L 1.1254 -2.18543002 1.13508002 -2.18583002 0 P 0 ;0
L 1.13508002 -2.18583002 1.14765 -2.18528996 0 P 0 ;0
L 1.14765 -2.18528996 1.15368002 -2.18461004 0 P 0 ;0
L 1.15368002 -2.18461004 1.15971004 -2.18363996 0 P 0 ;0
L 1.15971004 -2.18363996 1.16521004 -2.18248002 0 P 0 ;0
L 1.16521004 -2.18248002 1.17063996 -2.18103002 0 P 0 ;0
L 1.17063996 -2.18103002 1.17528996 -2.17946998 0 P 0 ;0
L 1.17528996 -2.17946998 1.17978002 -2.17753996 0 P 0 ;0
L 1.17978002 -2.17753996 1.18216998 -2.1763 0 P 0 ;0
L 1.18216998 -2.1763 1.18446004 -2.17488996 0 P 0 ;0
L 1.18446004 -2.17488996 1.18663996 -2.17331004 0 P 0 ;0
L 1.18663996 -2.17331004 1.18871004 -2.17156004 0 P 0 ;0
L 1.18871004 -2.17156004 1.19161004 -2.16871998 0 P 0 ;0
L 1.19161004 -2.16871998 1.19431004 -2.16568996 0 P 0 ;0
L 1.19431004 -2.16568996 1.19678996 -2.16246998 0 P 0 ;0
L 1.19678996 -2.16246998 1.19908996 -2.15901998 0 P 0 ;0
L 1.19908996 -2.15901998 1.20113996 -2.15543996 0 P 0 ;0
L 1.20113996 -2.15543996 1.20295 -2.15171004 0 P 0 ;0
L 1.20295 -2.15171004 1.20435 -2.14815 0 P 0 ;0
L 1.20435 -2.14815 1.20543996 -2.14448996 0 P 0 ;0
L 1.20543996 -2.14448996 1.20621004 -2.14073996 0 P 0 ;0
L 1.20621004 -2.14073996 1.20651998 -2.13855 0 P 0 ;0
L 1.20651998 -2.13855 1.20671998 -2.13633996 0 P 0 ;0
L 1.20671998 -2.13633996 1.20761998 -2.12321004 0 P 0 ;0
L 1.20761998 -2.12321004 1.20858002 -2.10753996 0 P 0 ;0
L 1.20858002 -2.10753996 1.20951004 -2.09021998 0 P 0 ;0
L 1.20951004 -2.09021998 1.21048002 -2.07166004 0 P 0 ;0
L 1.21048002 -2.07166004 1.21156004 -2.05228002 0 P 0 ;0
L 1.21156004 -2.05228002 1.21258002 -2.03478996 0 P 0 ;0
L 1.21258002 -2.03478996 1.21333002 -2.02286004 0 P 0 ;0
L 1.21333002 -2.02286004 1.21393996 -2.01373996 0 P 0 ;0
L 1.21393996 -2.01373996 1.21443996 -2.00568996 0 P 0 ;0
L 1.21443996 -2.00568996 1.21485 -1.99883996 0 P 0 ;0
L 1.21485 -1.99883996 1.2149 -1.99721004 0 P 0 ;0
L 1.2149 -1.99721004 1.21488996 -1.99703996 0 P 0 ;0
L 1.21488996 -1.99703996 1.21486998 -1.99686004 0 P 0 ;0
L 1.21486998 -1.99686004 1.21483996 -1.99668996 0 P 0 ;0
L 1.21483996 -1.99668996 1.21478996 -1.99653002 0 P 0 ;0
L 1.21478996 -1.99653002 1.21473002 -1.99636998 0 P 0 ;0
L 1.21473002 -1.99636998 1.21466004 -1.99621004 0 P 0 ;0
L 1.21466004 -1.99621004 1.21458002 -1.99606004 0 P 0 ;0
L 1.21458002 -1.99606004 1.21448002 -1.99591004 0 P 0 ;0
L 1.21448002 -1.99591004 1.21433002 -1.99571998 0 P 0 ;0
L 1.21433002 -1.99571998 1.21416998 -1.99553996 0 P 0 ;0
L 1.21416998 -1.99553996 1.21398996 -1.99538002 0 P 0 ;0
L 1.21398996 -1.99538002 1.21378996 -1.99523996 0 P 0 ;0
L 1.21378996 -1.99523996 1.21358002 -1.99511004 0 P 0 ;0
L 1.21358002 -1.99511004 1.21336004 -1.995 0 P 0 ;0
L 1.21336004 -1.995 1.21261004 -1.99468996 0 P 0 ;0
L 1.21261004 -1.99468996 1.21183996 -1.99443996 0 P 0 ;0
L 1.21183996 -1.99443996 1.21105 -1.99423002 0 P 0 ;0
L 1.21105 -1.99423002 1.20593996 -1.99318002 0 P 0 ;0
L 1.20593996 -1.99318002 1.18996998 -1.99065 0 P 0 ;0
L 1.18996998 -1.99065 1.17318996 -1.98908002 0 P 0 ;0
L 1.17318996 -1.98908002 1.15718996 -1.98858002 0 P 0 ;0
L 1.15718996 -1.98858002 1.1504 -1.98876004 0 P 0 ;0
L 1.1504 -1.98876004 1.14356998 -1.98926998 0 P 0 ;0
L 1.04503996 -2.19061998 1.05141998 -2.19061998 0 P 0 ;0
L 1.04893002 -2.18961998 1.05323002 -2.18961998 0 P 0 ;0
L 1.05263002 -2.18861998 1.05503996 -2.18861998 0 P 0 ;0
L 1.05628996 -2.18761998 1.05676004 -2.18761998 0 P 0 ;0
L 1.09645 -2.17983002 1.16738002 -2.17983002 0 P 0 ;0
L 1.09126004 -2.17883002 1.17091004 -2.17883002 0 P 0 ;0
L 1.0868 -2.17783002 1.17386998 -2.17783002 0 P 0 ;0
L 1.08368002 -2.17683002 1.17636004 -2.17683002 0 P 0 ;0
L 1.0836 -2.17583002 1.1787 -2.17583002 0 P 0 ;0
L 1.08351998 -2.17483002 1.18066998 -2.17483002 0 P 0 ;0
L 1.08345 -2.17383002 1.18236998 -2.17383002 0 P 0 ;0
L 1.08336998 -2.17283002 1.1839 -2.17283002 0 P 0 ;0
L 1.08328996 -2.17183002 1.18526998 -2.17183002 0 P 0 ;0
L 1.08321998 -2.17083002 1.18646998 -2.17083002 0 P 0 ;0
L 1.08313996 -2.16983002 1.18761998 -2.16983002 0 P 0 ;0
L 1.08306998 -2.16883002 1.18863996 -2.16883002 0 P 0 ;0
L 1.08298996 -2.16783002 1.18966004 -2.16783002 0 P 0 ;0
L 1.08291998 -2.16683002 1.19061004 -2.16683002 0 P 0 ;0
L 1.08283996 -2.16583002 1.1915 -2.16583002 0 P 0 ;0
L 1.08276004 -2.16483002 1.19238996 -2.16483002 0 P 0 ;0
L 1.08268996 -2.16383002 1.19321004 -2.16383002 0 P 0 ;0
L 1.08261004 -2.16283002 1.19398002 -2.16283002 0 P 0 ;0
L 1.08253002 -2.16183002 1.19476004 -2.16183002 0 P 0 ;0
L 1.08246004 -2.16083002 1.19548002 -2.16083002 0 P 0 ;0
L 1.08238002 -2.15983002 1.19613996 -2.15983002 0 P 0 ;0
L 1.08231004 -2.15883002 1.19681004 -2.15883002 0 P 0 ;0
L 1.08223996 -2.15783002 1.19746004 -2.15783002 0 P 0 ;0
L 1.13506998 -2.18383002 1.12553002 -2.18343996 0 P 0 ;0
L 1.12553002 -2.18343996 1.11266004 -2.18218002 0 P 0 ;0
L 1.11266004 -2.18218002 1.09983002 -2.18048002 0 P 0 ;0
L 1.09983002 -2.18048002 1.09036998 -2.17866004 0 P 0 ;0
L 1.09036998 -2.17866004 1.0837 -2.17711004 0 P 0 ;0
L 1.0837 -2.17711004 1.08245 -2.16066998 0 P 0 ;0
L 1.08245 -2.16066998 1.08193996 -2.15361998 0 P 0 ;0
L 1.08193996 -2.15361998 1.08156998 -2.14726004 0 P 0 ;0
L 1.08156998 -2.14726004 1.08131998 -2.14191004 0 P 0 ;0
L 1.08131998 -2.14191004 1.08131004 -2.14108996 0 P 0 ;0
L 1.08131004 -2.14108996 1.08136004 -2.14026004 0 P 0 ;0
L 1.08136004 -2.14026004 1.0814 -2.13986998 0 P 0 ;0
L 1.0814 -2.13986998 1.08996004 -2.14233002 0 P 0 ;0
L 1.08996004 -2.14233002 1.08996998 -2.14233996 0 P 0 ;0
L 1.08996998 -2.14233996 1.08998996 -2.14233996 0 P 0 ;0
L 1.08998996 -2.14233996 1.099 -2.14471998 0 P 0 ;0
L 1.099 -2.14471998 1.10806998 -2.14668002 0 P 0 ;0
L 1.10806998 -2.14668002 1.11598002 -2.14791998 0 P 0 ;0
L 1.11598002 -2.14791998 1.12395 -2.1486 0 P 0 ;0
L 1.12395 -2.1486 1.13048996 -2.14863996 0 P 0 ;0
L 1.13048996 -2.14863996 1.137 -2.14811998 0 P 0 ;0
L 1.137 -2.14811998 1.13903002 -2.14778996 0 P 0 ;0
L 1.13903002 -2.14778996 1.14103002 -2.14728996 0 P 0 ;0
L 1.14103002 -2.14728996 1.14298002 -2.14661998 0 P 0 ;0
L 1.14298002 -2.14661998 1.14486998 -2.14581004 0 P 0 ;0
L 1.14486998 -2.14581004 1.14668002 -2.14483996 0 P 0 ;0
L 1.14668002 -2.14483996 1.1484 -2.14373996 0 P 0 ;0
L 1.1484 -2.14373996 1.15003002 -2.1425 0 P 0 ;0
L 1.15003002 -2.1425 1.15155 -2.14115 0 P 0 ;0
L 1.15155 -2.14115 1.1526 -2.14006998 0 P 0 ;0
L 1.1526 -2.14006998 1.15263996 -2.14001998 0 P 0 ;0
L 1.15263996 -2.14001998 1.15356004 -2.13893002 0 P 0 ;0
L 1.15356004 -2.13893002 1.15443996 -2.13771998 0 P 0 ;0
L 1.15443996 -2.13771998 1.15523002 -2.13646004 0 P 0 ;0
L 1.15523002 -2.13646004 1.15593996 -2.13515 0 P 0 ;0
L 1.15593996 -2.13515 1.15655 -2.13381004 0 P 0 ;0
L 1.15655 -2.13381004 1.15706004 -2.13243002 0 P 0 ;0
L 1.15706004 -2.13243002 1.15748002 -2.13101004 0 P 0 ;0
L 1.15748002 -2.13101004 1.1579 -2.12905 0 P 0 ;0
L 1.1579 -2.12905 1.15816004 -2.12706004 0 P 0 ;0
L 1.15816004 -2.12706004 1.15825 -2.12506998 0 P 0 ;0
L 1.15825 -2.12506998 1.15818002 -2.12165 0 P 0 ;0
L 1.15818002 -2.12165 1.15813996 -2.12118002 0 P 0 ;0
L 1.15813996 -2.12118002 1.15813002 -2.1211 0 P 0 ;0
L 1.15813002 -2.1211 1.15806004 -2.12068002 0 P 0 ;0
L 1.15806004 -2.12068002 1.15793996 -2.12018996 0 P 0 ;0
L 1.15793996 -2.12018996 1.15778002 -2.11973002 0 P 0 ;0
L 1.15778002 -2.11973002 1.1577 -2.11953002 0 P 0 ;0
L 1.1577 -2.11953002 1.15758996 -2.11933002 0 P 0 ;0
L 1.15758996 -2.11933002 1.15746998 -2.11913996 0 P 0 ;0
L 1.15746998 -2.11913996 1.15733002 -2.11895 0 P 0 ;0
L 1.15733002 -2.11895 1.15716998 -2.11878002 0 P 0 ;0
L 1.15716998 -2.11878002 1.157 -2.11863002 0 P 0 ;0
L 1.157 -2.11863002 1.15681998 -2.11848996 0 P 0 ;0
L 1.15681998 -2.11848996 1.15663002 -2.11836004 0 P 0 ;0
L 1.15663002 -2.11836004 1.15641998 -2.11825 0 P 0 ;0
L 1.15641998 -2.11825 1.15621004 -2.11816004 0 P 0 ;0
L 1.15621004 -2.11816004 1.15598996 -2.11808996 0 P 0 ;0
L 1.15598996 -2.11808996 1.15576998 -2.11803996 0 P 0 ;0
L 1.15576998 -2.11803996 1.15553002 -2.118 0 P 0 ;0
L 1.15553002 -2.118 1.15518002 -2.11798002 0 P 0 ;0
L 1.15518002 -2.11798002 1.15483996 -2.11798996 0 P 0 ;0
L 1.15483996 -2.11798996 1.15451004 -2.11803002 0 P 0 ;0
L 1.15451004 -2.11803002 1.15418002 -2.1181 0 P 0 ;0
L 1.15418002 -2.1181 1.15386004 -2.1182 0 P 0 ;0
L 1.15386004 -2.1182 1.15361004 -2.11828996 0 P 0 ;0
L 1.15361004 -2.11828996 1.14705 -2.12083996 0 P 0 ;0
L 1.14705 -2.12083996 1.14038996 -2.12278996 0 P 0 ;0
L 1.14038996 -2.12278996 1.13356004 -2.12416004 0 P 0 ;0
L 1.13356004 -2.12416004 1.1285 -2.12476998 0 P 0 ;0
L 1.1285 -2.12476998 1.12341004 -2.12501998 0 P 0 ;0
L 1.12341004 -2.12501998 1.11831004 -2.12493002 0 P 0 ;0
L 1.11831004 -2.12493002 1.11323002 -2.12448996 0 P 0 ;0
L 1.11323002 -2.12448996 1.10848996 -2.12373002 0 P 0 ;0
L 1.10848996 -2.12373002 1.10383996 -2.12263002 0 P 0 ;0
L 1.10383996 -2.12263002 1.09926998 -2.12118996 0 P 0 ;0
L 1.09926998 -2.12118996 1.09481004 -2.11941004 0 P 0 ;0
L 1.09481004 -2.11941004 1.09168002 -2.11788002 0 P 0 ;0
L 1.09168002 -2.11788002 1.08866004 -2.11611998 0 P 0 ;0
L 1.08866004 -2.11611998 1.08578002 -2.11413002 0 P 0 ;0
L 1.08578002 -2.11413002 1.08306998 -2.11193996 0 P 0 ;0
L 1.08306998 -2.11193996 1.08051998 -2.10955 0 P 0 ;0
L 1.08051998 -2.10955 1.07793996 -2.10673002 0 P 0 ;0
L 1.07793996 -2.10673002 1.07561004 -2.10373996 0 P 0 ;0
L 1.07561004 -2.10373996 1.07351004 -2.10058002 0 P 0 ;0
L 1.07351004 -2.10058002 1.07171004 -2.09733996 0 P 0 ;0
L 1.07171004 -2.09733996 1.07018002 -2.09396998 0 P 0 ;0
L 1.07018002 -2.09396998 1.06893996 -2.09048002 0 P 0 ;0
L 1.06893996 -2.09048002 1.06786004 -2.0865 0 P 0 ;0
L 1.06786004 -2.0865 1.06706004 -2.08243996 0 P 0 ;0
L 1.06706004 -2.08243996 1.06656004 -2.07833002 0 P 0 ;0
L 1.06656004 -2.07833002 1.06615 -2.07071004 0 P 0 ;0
L 1.06615 -2.07071004 1.06621004 -2.06313996 0 P 0 ;0
L 1.06621004 -2.06313996 1.06675 -2.0556 0 P 0 ;0
L 1.06675 -2.0556 1.0678 -2.04813002 0 P 0 ;0
L 1.0678 -2.04813002 1.06868996 -2.04391998 0 P 0 ;0
L 1.06868996 -2.04391998 1.06985 -2.03981004 0 P 0 ;0
L 1.06985 -2.03981004 1.0713 -2.03578996 0 P 0 ;0
L 1.0713 -2.03578996 1.07296004 -2.03206998 0 P 0 ;0
L 1.07296004 -2.03206998 1.07486998 -2.02848996 0 P 0 ;0
L 1.07486998 -2.02848996 1.07705 -2.02506004 0 P 0 ;0
L 1.07705 -2.02506004 1.07966004 -2.0215 0 P 0 ;0
L 1.07966004 -2.0215 1.08246998 -2.01811004 0 P 0 ;0
L 1.08246998 -2.01811004 1.08546998 -2.01491004 0 P 0 ;0
L 1.08546998 -2.01491004 1.0897 -2.01091004 0 P 0 ;0
L 1.0897 -2.01091004 1.09153002 -2.00936998 0 P 0 ;0
L 1.09153002 -2.00936998 1.09341998 -2.00793996 0 P 0 ;0
L 1.09341998 -2.00793996 1.09545 -2.00658002 0 P 0 ;0
L 1.09545 -2.00658002 1.09751004 -2.00533996 0 P 0 ;0
L 1.09751004 -2.00533996 1.10288002 -2.0025 0 P 0 ;0
L 1.10288002 -2.0025 1.10736998 -2.00043002 0 P 0 ;0
L 1.10736998 -2.00043002 1.11193002 -1.99861004 0 P 0 ;0
L 1.11193002 -1.99861004 1.12218002 -1.99533002 0 P 0 ;0
L 1.12218002 -1.99533002 1.13298002 -1.99281998 0 P 0 ;0
L 1.13298002 -1.99281998 1.14378996 -1.99126004 0 P 0 ;0
L 1.14378996 -1.99126004 1.1505 -1.99075 0 P 0 ;0
L 1.1505 -1.99075 1.15718002 -1.99058996 0 P 0 ;0
L 1.15718002 -1.99058996 1.17306998 -1.99108002 0 P 0 ;0
L 1.17306998 -1.99108002 1.18971998 -1.99263002 0 P 0 ;0
L 1.18971998 -1.99263002 1.20558002 -1.99515 0 P 0 ;0
L 1.20558002 -1.99515 1.21058996 -1.99618002 0 P 0 ;0
L 1.21058996 -1.99618002 1.21126998 -1.99636004 0 P 0 ;0
L 1.21126998 -1.99636004 1.21191998 -1.99656998 0 P 0 ;0
L 1.21191998 -1.99656998 1.21253002 -1.99681998 0 P 0 ;0
L 1.21253002 -1.99681998 1.21261004 -1.99686004 0 P 0 ;0
L 1.21261004 -1.99686004 1.21266004 -1.99688996 0 P 0 ;0
L 1.21266004 -1.99688996 1.21271998 -1.99693002 0 P 0 ;0
L 1.21271998 -1.99693002 1.21281998 -1.99703002 0 P 0 ;0
L 1.21281998 -1.99703002 1.21286004 -1.99708996 0 P 0 ;0
L 1.21286004 -1.99708996 1.21288002 -1.99711004 0 P 0 ;0
L 1.21288002 -1.99711004 1.21288002 -1.99711998 0 P 0 ;0
L 1.21288002 -1.99711998 1.21288996 -1.99715 0 P 0 ;0
L 1.21288996 -1.99715 1.2129 -1.99716998 0 P 0 ;0
L 1.2129 -1.99716998 1.2129 -1.99721998 0 P 0 ;0
L 1.2129 -1.99721998 1.21285 -1.99875 0 P 0 ;0
L 1.21285 -1.99875 1.21243996 -2.00556998 0 P 0 ;0
L 1.21243996 -2.00556998 1.21193996 -2.01361004 0 P 0 ;0
L 1.21193996 -2.01361004 1.21133996 -2.02273002 0 P 0 ;0
L 1.21133996 -2.02273002 1.21133996 -2.02273996 0 P 0 ;0
L 1.21133996 -2.02273996 1.21058996 -2.03468002 0 P 0 ;0
L 1.21058996 -2.03468002 1.20956004 -2.05216998 0 P 0 ;0
L 1.20956004 -2.05216998 1.20848996 -2.07156004 0 P 0 ;0
L 1.20848996 -2.07156004 1.20848996 -2.07156998 0 P 0 ;0
L 1.20848996 -2.07156998 1.20751004 -2.09011004 0 P 0 ;0
L 1.20751004 -2.09011004 1.20658996 -2.10743996 0 P 0 ;0
L 1.20658996 -2.10743996 1.20561998 -2.12308996 0 P 0 ;0
L 1.20561998 -2.12308996 1.20473002 -2.13618996 0 P 0 ;0
L 1.20473002 -2.13618996 1.20453002 -2.13831998 0 P 0 ;0
L 1.20453002 -2.13831998 1.20423996 -2.14041004 0 P 0 ;0
L 1.20423996 -2.14041004 1.2035 -2.144 0 P 0 ;0
L 1.2035 -2.144 1.20246004 -2.1475 0 P 0 ;0
L 1.20246004 -2.1475 1.20111998 -2.1509 0 P 0 ;0
L 1.20111998 -2.1509 1.19936998 -2.1545 0 P 0 ;0
L 1.19936998 -2.1545 1.19738002 -2.15796998 0 P 0 ;0
L 1.19738002 -2.15796998 1.19516004 -2.1613 0 P 0 ;0
L 1.19516004 -2.1613 1.19276998 -2.16441004 0 P 0 ;0
L 1.19276998 -2.16441004 1.19016004 -2.16733996 0 P 0 ;0
L 1.19016004 -2.16733996 1.18736004 -2.17008002 0 P 0 ;0
L 1.18736004 -2.17008002 1.1854 -2.17173996 0 P 0 ;0
L 1.1854 -2.17173996 1.18335 -2.17323002 0 P 0 ;0
L 1.18335 -2.17323002 1.18118002 -2.17456004 0 P 0 ;0
L 1.18118002 -2.17456004 1.17893002 -2.17573002 0 P 0 ;0
L 1.17893002 -2.17573002 1.17456998 -2.1776 0 P 0 ;0
L 1.17456998 -2.1776 1.17006998 -2.17911998 0 P 0 ;0
L 1.17006998 -2.17911998 1.16473996 -2.18053002 0 P 0 ;0
L 1.16473996 -2.18053002 1.15935 -2.18166998 0 P 0 ;0
L 1.15935 -2.18166998 1.15341998 -2.18263002 0 P 0 ;0
L 1.15341998 -2.18263002 1.1475 -2.18328996 0 P 0 ;0
L 1.1475 -2.18328996 1.13506998 -2.18383002 0 P 0 ;0
L 0.90491998 -2.21461998 1.00131004 -2.21461998 0 P 0 ;0
L 0.92235 -2.21361998 1.00355 -2.21361998 0 P 0 ;0
L 0.76925 -1.8965 0.85586998 -1.8965 0 P 0 ;0
L 0.76958996 -1.8955 0.85556004 -1.8955 0 P 0 ;0
L 0.76995 -1.8945 0.85521004 -1.8945 0 P 0 ;0
L 0.77031004 -1.8935 0.85486004 -1.8935 0 P 0 ;0
L 0.77071004 -1.8925 0.85443996 -1.8925 0 P 0 ;0
L 0.77115 -1.8915 0.85401004 -1.8915 0 P 0 ;0
L 0.7716 -1.8905 0.85355 -1.8905 0 P 0 ;0
L 0.77206004 -1.8895 0.85303002 -1.8895 0 P 0 ;0
L 0.7726 -1.8885 0.85251004 -1.8885 0 P 0 ;0
L 0.77313996 -1.8875 0.85198996 -1.8875 0 P 0 ;0
L 0.77368996 -1.8865 0.85138002 -1.8865 0 P 0 ;0
L 0.77433002 -1.8855 0.85073996 -1.8855 0 P 0 ;0
L 0.77496004 -1.8845 0.85011004 -1.8845 0 P 0 ;0
L 0.77561998 -1.8835 0.84943002 -1.8835 0 P 0 ;0
L 0.77636004 -1.8825 0.84866998 -1.8825 0 P 0 ;0
L 0.77711004 -1.8815 0.84791004 -1.8815 0 P 0 ;0
L 0.7779 -1.8805 0.84713002 -1.8805 0 P 0 ;0
L 0.77876998 -1.8795 0.84623002 -1.8795 0 P 0 ;0
L 0.77963996 -1.8785 0.84533002 -1.8785 0 P 0 ;0
L 0.7806 -1.8775 0.8444 -1.8775 0 P 0 ;0
L 0.78161004 -1.8765 0.84335 -1.8765 0 P 0 ;0
L 0.78265 -1.8755 0.84228996 -1.8755 0 P 0 ;0
L 0.78381998 -1.8745 0.84108996 -1.8745 0 P 0 ;0
L 0.78498996 -1.8735 0.83986998 -1.8735 0 P 0 ;0
L 0.78635 -1.8725 0.83848002 -1.8725 0 P 0 ;0
L 0.78773002 -1.8715 0.83706004 -1.8715 0 P 0 ;0
L 0.78933002 -1.8705 0.83541998 -1.8705 0 P 0 ;0
L 0.791 -1.8695 0.83366004 -1.8695 0 P 0 ;0
L 0.793 -1.8685 0.83171998 -1.8685 0 P 0 ;0
L 0.79525 -1.8675 0.82941998 -1.8675 0 P 0 ;0
L 0.79791998 -1.8665 0.82671004 -1.8665 0 P 0 ;0
L 0.80143996 -1.8655 0.82328996 -1.8655 0 P 0 ;0
L 0.80705 -1.8645 0.81776004 -1.8645 0 P 0 ;0
L 0.74543002 -1.89661998 0.75033002 -1.89661998 0 P 0 ;0
L 0.74751004 -1.89561998 0.75058996 -1.89561998 0 P 0 ;0
L 0.74958996 -1.89461998 0.75086004 -1.89461998 0 P 0 ;0
L 0.76733996 -1.9125 0.85751998 -1.9125 0 P 0 ;0
L 0.76728996 -1.9115 0.85756004 -1.9115 0 P 0 ;0
L 0.76723996 -1.9105 0.85758996 -1.9105 0 P 0 ;0
L 0.76721998 -1.9095 0.85763002 -1.9095 0 P 0 ;0
L 0.76725 -1.9085 0.85761004 -1.9085 0 P 0 ;0
L 0.76728002 -1.9075 0.85756998 -1.9075 0 P 0 ;0
L 0.76731004 -1.9065 0.85753002 -1.9065 0 P 0 ;0
L 0.76741998 -1.9055 0.85748996 -1.9055 0 P 0 ;0
L 0.76753996 -1.9045 0.85738002 -1.9045 0 P 0 ;0
L 0.76766004 -1.9035 0.85726004 -1.9035 0 P 0 ;0
L 0.76781998 -1.9025 0.85713996 -1.9025 0 P 0 ;0
L 0.76801998 -1.9015 0.85701004 -1.9015 0 P 0 ;0
L 0.76821004 -1.9005 0.85683002 -1.9005 0 P 0 ;0
L 0.76841998 -1.8995 0.85661998 -1.8995 0 P 0 ;0
L 0.7687 -1.8985 0.85641004 -1.8985 0 P 0 ;0
L 0.76896998 -1.8975 0.85613996 -1.8975 0 P 0 ;0
L 0.76751004 -2.08325 0.8416 -2.08325 0 P 0 ;0
L 0.76761998 -2.08225 0.84161998 -2.08225 0 P 0 ;0
L 0.76773996 -2.08125 0.84166998 -2.08125 0 P 0 ;0
L 0.76786004 -2.08025 0.84171998 -2.08025 0 P 0 ;0
L 0.76796998 -2.07925 0.84176998 -2.07925 0 P 0 ;0
L 0.76808002 -2.07825 0.84181004 -2.07825 0 P 0 ;0
L 0.76818002 -2.07725 0.84186004 -2.07725 0 P 0 ;0
L 0.76828996 -2.07625 0.8419 -2.07625 0 P 0 ;0
L 0.76838996 -2.07525 0.84195 -2.07525 0 P 0 ;0
L 0.76848996 -2.07425 0.842 -2.07425 0 P 0 ;0
L 0.7686 -2.07325 0.84205 -2.07325 0 P 0 ;0
L 0.7687 -2.07225 0.84208996 -2.07225 0 P 0 ;0
L 0.7688 -2.07125 0.84213996 -2.07125 0 P 0 ;0
L 0.7689 -2.07025 0.84218002 -2.07025 0 P 0 ;0
L 0.76901004 -2.06925 0.84223002 -2.06925 0 P 0 ;0
L 0.76911004 -2.06825 0.84228002 -2.06825 0 P 0 ;0
L 0.76921004 -2.06725 0.84233002 -2.06725 0 P 0 ;0
L 0.76931998 -2.06625 0.84236998 -2.06625 0 P 0 ;0
L 0.76941998 -2.06525 0.84241998 -2.06525 0 P 0 ;0
L 0.76948996 -2.06425 0.84246004 -2.06425 0 P 0 ;0
L 0.76956004 -2.06325 0.84251004 -2.06325 0 P 0 ;0
L 0.76963002 -2.06225 0.84256004 -2.06225 0 P 0 ;0
L 0.7697 -2.06125 0.8426 -2.06125 0 P 0 ;0
L 0.76976998 -2.06025 0.84265 -2.06025 0 P 0 ;0
L 0.76983996 -2.05925 0.8427 -2.05925 0 P 0 ;0
L 0.76991004 -2.05825 0.84273996 -2.05825 0 P 0 ;0
L 0.76996998 -2.05725 0.84278996 -2.05725 0 P 0 ;0
L 0.77001004 -2.05625 0.84283996 -2.05625 0 P 0 ;0
L 0.77003996 -2.05525 0.84288002 -2.05525 0 P 0 ;0
L 0.77008002 -2.05425 0.84295 -2.05425 0 P 0 ;0
L 0.77011998 -2.05325 0.84303996 -2.05325 0 P 0 ;0
L 0.77016004 -2.05225 0.84311998 -2.05225 0 P 0 ;0
L 0.77018996 -2.05125 0.84321004 -2.05125 0 P 0 ;0
L 0.77023002 -2.05025 0.8433 -2.05025 0 P 0 ;0
L 0.77026998 -2.04925 0.84338002 -2.04925 0 P 0 ;0
L 0.77031004 -2.04825 0.84346998 -2.04825 0 P 0 ;0
L 0.77033996 -2.04725 0.84356004 -2.04725 0 P 0 ;0
L 0.77038002 -2.04625 0.84363996 -2.04625 0 P 0 ;0
L 0.77041004 -2.04525 0.84373002 -2.04525 0 P 0 ;0
L 0.77043996 -2.04425 0.84381004 -2.04425 0 P 0 ;0
L 0.77046004 -2.04325 0.8439 -2.04325 0 P 0 ;0
L 0.77048002 -2.04225 0.84398996 -2.04225 0 P 0 ;0
L 0.77051004 -2.04125 0.84406998 -2.04125 0 P 0 ;0
L 0.77053002 -2.04025 0.84416004 -2.04025 0 P 0 ;0
L 0.77055 -2.03925 0.84425 -2.03925 0 P 0 ;0
L 0.77058002 -2.03825 0.84433002 -2.03825 0 P 0 ;0
L 0.7706 -2.03725 0.84441998 -2.03725 0 P 0 ;0
L 0.77061998 -2.03625 0.84451004 -2.03625 0 P 0 ;0
L 0.77065 -2.03525 0.84458996 -2.03525 0 P 0 ;0
L 0.77066998 -2.03425 0.84468002 -2.03425 0 P 0 ;0
L 0.7707 -2.03325 0.84476998 -2.03325 0 P 0 ;0
L 0.77071998 -2.03225 0.84485 -2.03225 0 P 0 ;0
L 0.77073002 -2.03125 0.84493996 -2.03125 0 P 0 ;0
L 0.77073996 -2.03025 0.84503002 -2.03025 0 P 0 ;0
L 0.79986004 -1.8638 0.79643996 -1.86486998 0 P 0 ;0
L 0.79643996 -1.86486998 0.79311998 -1.86621004 0 P 0 ;0
L 0.79311998 -1.86621004 0.78991004 -1.86781004 0 P 0 ;0
L 0.78991004 -1.86781004 0.78683996 -1.86966998 0 P 0 ;0
L 0.78683996 -1.86966998 0.78391998 -1.87178002 0 P 0 ;0
L 0.78391998 -1.87178002 0.78111998 -1.87416998 0 P 0 ;0
L 0.78111998 -1.87416998 0.7785 -1.87676004 0 P 0 ;0
L 0.7785 -1.87676004 0.77608002 -1.87953996 0 P 0 ;0
L 0.77608002 -1.87953996 0.77386998 -1.8825 0 P 0 ;0
L 0.77386998 -1.8825 0.77188002 -1.88561998 0 P 0 ;0
L 0.77188002 -1.88561998 0.77013996 -1.88886004 0 P 0 ;0
L 0.77013996 -1.88886004 0.76863996 -1.89221004 0 P 0 ;0
L 0.76863996 -1.89221004 0.7674 -1.89566998 0 P 0 ;0
L 0.7674 -1.89566998 0.76643002 -1.89921004 0 P 0 ;0
L 0.76643002 -1.89921004 0.76571004 -1.90283996 0 P 0 ;0
L 0.76571004 -1.90283996 0.76531004 -1.90636004 0 P 0 ;0
L 0.76531004 -1.90636004 0.7652 -1.90991004 0 P 0 ;0
L 0.7652 -1.90991004 0.76538996 -1.91345 0 P 0 ;0
L 0.76538996 -1.91345 0.76586998 -1.91696998 0 P 0 ;0
L 0.76586998 -1.91696998 0.76663996 -1.92046004 0 P 0 ;0
L 0.76663996 -1.92046004 0.76803002 -1.92493996 0 P 0 ;0
L 0.76803002 -1.92493996 0.76978002 -1.9293 0 P 0 ;0
L 0.76978002 -1.9293 0.77106998 -1.93193996 0 P 0 ;0
L 0.77106998 -1.93193996 0.77253002 -1.93448002 0 P 0 ;0
L 0.77253002 -1.93448002 0.77416004 -1.93693996 0 P 0 ;0
L 0.77416004 -1.93693996 0.77593002 -1.93923002 0 P 0 ;0
L 0.77593002 -1.93923002 0.77783996 -1.94141004 0 P 0 ;0
L 0.77783996 -1.94141004 0.77988996 -1.94345 0 P 0 ;0
L 0.77988996 -1.94345 0.78216004 -1.94545 0 P 0 ;0
L 0.78216004 -1.94545 0.78453996 -1.9473 0 P 0 ;0
L 0.78453996 -1.9473 0.78703002 -1.94901998 0 P 0 ;0
L 0.78703002 -1.94901998 0.79016998 -1.95088002 0 P 0 ;0
L 0.79016998 -1.95088002 0.79343996 -1.95248996 0 P 0 ;0
L 0.79343996 -1.95248996 0.79683002 -1.95383996 0 P 0 ;0
L 0.79683002 -1.95383996 0.80031998 -1.95491998 0 P 0 ;0
L 0.80031998 -1.95491998 0.80391004 -1.95573996 0 P 0 ;0
L 0.80391004 -1.95573996 0.80751998 -1.95626004 0 P 0 ;0
L 0.80751998 -1.95626004 0.81116004 -1.9565 0 P 0 ;0
L 0.81116004 -1.9565 0.81481004 -1.95646004 0 P 0 ;0
L 0.81481004 -1.95646004 0.81843996 -1.95613002 0 P 0 ;0
L 0.81843996 -1.95613002 0.82205 -1.95551004 0 P 0 ;0
L 0.82205 -1.95551004 0.82561998 -1.95461004 0 P 0 ;0
L 0.82561998 -1.95461004 0.82911004 -1.95345 0 P 0 ;0
L 0.82911004 -1.95345 0.83248996 -1.95201004 0 P 0 ;0
L 0.83248996 -1.95201004 0.83576004 -1.95031998 0 P 0 ;0
L 0.83576004 -1.95031998 0.83891998 -1.94836004 0 P 0 ;0
L 0.83891998 -1.94836004 0.84191998 -1.94616998 0 P 0 ;0
L 0.84191998 -1.94616998 0.84475 -1.94375 0 P 0 ;0
L 0.84475 -1.94375 0.84738996 -1.94113996 0 P 0 ;0
L 0.84738996 -1.94113996 0.84983002 -1.93833996 0 P 0 ;0
L 0.84983002 -1.93833996 0.85206998 -1.93533996 0 P 0 ;0
L 0.85206998 -1.93533996 0.8536 -1.93291998 0 P 0 ;0
L 0.8536 -1.93291998 0.85496004 -1.93041004 0 P 0 ;0
L 0.85496004 -1.93041004 0.85613996 -1.9278 0 P 0 ;0
L 0.85613996 -1.9278 0.85711998 -1.92511004 0 P 0 ;0
L 0.85711998 -1.92511004 0.85823002 -1.92123002 0 P 0 ;0
L 0.85823002 -1.92123002 0.85901998 -1.91726998 0 P 0 ;0
L 0.85901998 -1.91726998 0.85948996 -1.91323996 0 P 0 ;0
L 0.85948996 -1.91323996 0.85963996 -1.90918002 0 P 0 ;0
L 0.85963996 -1.90918002 0.85946998 -1.90513002 0 P 0 ;0
L 0.85946998 -1.90513002 0.85898002 -1.9011 0 P 0 ;0
L 0.85898002 -1.9011 0.85841998 -1.89826004 0 P 0 ;0
L 0.85841998 -1.89826004 0.85766004 -1.89546004 0 P 0 ;0
L 0.85766004 -1.89546004 0.85671004 -1.89273002 0 P 0 ;0
L 0.85671004 -1.89273002 0.85556998 -1.89006004 0 P 0 ;0
L 0.85556998 -1.89006004 0.85361998 -1.88631004 0 P 0 ;0
L 0.85361998 -1.88631004 0.85136004 -1.88273996 0 P 0 ;0
L 0.85136004 -1.88273996 0.84881004 -1.87938002 0 P 0 ;0
L 0.84881004 -1.87938002 0.84596998 -1.87623002 0 P 0 ;0
L 0.84596998 -1.87623002 0.84355 -1.87393996 0 P 0 ;0
L 0.84355 -1.87393996 0.84096998 -1.87181998 0 P 0 ;0
L 0.84096998 -1.87181998 0.83826004 -1.86988996 0 P 0 ;0
L 0.83826004 -1.86988996 0.83541004 -1.86815 0 P 0 ;0
L 0.83541004 -1.86815 0.83243996 -1.86661004 0 P 0 ;0
L 0.83243996 -1.86661004 0.82938996 -1.86531004 0 P 0 ;0
L 0.82938996 -1.86531004 0.82625 -1.86423002 0 P 0 ;0
L 0.82625 -1.86423002 0.82303996 -1.86336004 0 P 0 ;0
L 0.82303996 -1.86336004 0.81978002 -1.86273002 0 P 0 ;0
L 0.81978002 -1.86273002 0.81646998 -1.86233002 0 P 0 ;0
L 0.81646998 -1.86233002 0.81228996 -1.86215 0 P 0 ;0
L 0.81228996 -1.86215 0.80811004 -1.86233996 0 P 0 ;0
L 0.80811004 -1.86233996 0.80396004 -1.86288996 0 P 0 ;0
L 0.80396004 -1.86288996 0.79986004 -1.8638 0 P 0 ;0
L 0.80308996 -1.9535 0.82186004 -1.9535 0 P 0 ;0
L 0.79926004 -1.9525 0.82563996 -1.9525 0 P 0 ;0
L 0.79636004 -1.9515 0.82856998 -1.9515 0 P 0 ;0
L 0.79393002 -1.9505 0.83093996 -1.9505 0 P 0 ;0
L 0.7919 -1.9495 0.83298996 -1.9495 0 P 0 ;0
L 0.79008002 -1.9485 0.8349 -1.9485 0 P 0 ;0
L 0.78838996 -1.9475 0.83651004 -1.9475 0 P 0 ;0
L 0.7869 -1.9465 0.83806998 -1.9465 0 P 0 ;0
L 0.78548002 -1.9455 0.83943996 -1.9455 0 P 0 ;0
L 0.7842 -1.9445 0.84078996 -1.9445 0 P 0 ;0
L 0.78298002 -1.9435 0.84196998 -1.9435 0 P 0 ;0
L 0.78183996 -1.9425 0.84313996 -1.9425 0 P 0 ;0
L 0.78076998 -1.9415 0.84418996 -1.9415 0 P 0 ;0
L 0.77976004 -1.9405 0.8452 -1.9405 0 P 0 ;0
L 0.77883002 -1.9395 0.84616998 -1.9395 0 P 0 ;0
L 0.77793996 -1.9385 0.84703996 -1.9385 0 P 0 ;0
L 0.77711998 -1.9375 0.84791004 -1.9375 0 P 0 ;0
L 0.77635 -1.9365 0.84871004 -1.9365 0 P 0 ;0
L 0.77561004 -1.9355 0.84945 -1.9355 0 P 0 ;0
L 0.77493996 -1.9345 0.8502 -1.9345 0 P 0 ;0
L 0.77428002 -1.9335 0.85086998 -1.9335 0 P 0 ;0
L 0.7737 -1.9325 0.8515 -1.9325 0 P 0 ;0
L 0.77311998 -1.9315 0.8521 -1.9315 0 P 0 ;0
L 0.77258996 -1.9305 0.85263996 -1.9305 0 P 0 ;0
L 0.7721 -1.9295 0.85318002 -1.9295 0 P 0 ;0
L 0.77161004 -1.9285 0.85363002 -1.9285 0 P 0 ;0
L 0.77121004 -1.9275 0.85408002 -1.9275 0 P 0 ;0
L 0.77081004 -1.9265 0.85448002 -1.9265 0 P 0 ;0
L 0.77041004 -1.9255 0.85485 -1.9255 0 P 0 ;0
L 0.77001004 -1.9245 0.85521998 -1.9245 0 P 0 ;0
L 0.76968002 -1.9235 0.8555 -1.9235 0 P 0 ;0
L 0.76936998 -1.9225 0.85578996 -1.9225 0 P 0 ;0
L 0.76906004 -1.9215 0.85606998 -1.9215 0 P 0 ;0
L 0.76875 -1.9205 0.85633002 -1.9205 0 P 0 ;0
L 0.76848002 -1.9195 0.85653002 -1.9195 0 P 0 ;0
L 0.76826004 -1.9185 0.85673002 -1.9185 0 P 0 ;0
L 0.76803002 -1.9175 0.85693002 -1.9175 0 P 0 ;0
L 0.76783002 -1.9165 0.85708996 -1.9165 0 P 0 ;0
L 0.76768996 -1.9155 0.85721004 -1.9155 0 P 0 ;0
L 0.76755 -1.9145 0.85733002 -1.9145 0 P 0 ;0
L 0.76741998 -1.9135 0.85745 -1.9135 0 P 0 ;0
L 0.81121004 -1.9545 0.80773002 -1.95426998 0 P 0 ;0
L 0.80773002 -1.95426998 0.80426998 -1.95376998 0 P 0 ;0
L 0.80426998 -1.95376998 0.80083996 -1.95298996 0 P 0 ;0
L 0.80083996 -1.95298996 0.7975 -1.95195 0 P 0 ;0
L 0.7975 -1.95195 0.79426004 -1.95066004 0 P 0 ;0
L 0.79426004 -1.95066004 0.79111998 -1.94911998 0 P 0 ;0
L 0.79111998 -1.94911998 0.78811004 -1.94733002 0 P 0 ;0
L 0.78811004 -1.94733002 0.78573002 -1.94568996 0 P 0 ;0
L 0.78573002 -1.94568996 0.78343996 -1.9439 0 P 0 ;0
L 0.78343996 -1.9439 0.78126004 -1.94198996 0 P 0 ;0
L 0.78126004 -1.94198996 0.7793 -1.94003996 0 P 0 ;0
L 0.7793 -1.94003996 0.77746998 -1.93796004 0 P 0 ;0
L 0.77746998 -1.93796004 0.77578996 -1.93576998 0 P 0 ;0
L 0.77578996 -1.93576998 0.77423002 -1.93343002 0 P 0 ;0
L 0.77423002 -1.93343002 0.77283996 -1.931 0 P 0 ;0
L 0.77283996 -1.931 0.77161004 -1.92848996 0 P 0 ;0
L 0.77161004 -1.92848996 0.76991998 -1.92426998 0 P 0 ;0
L 0.76991998 -1.92426998 0.76858002 -1.91993996 0 P 0 ;0
L 0.76858002 -1.91993996 0.76783996 -1.91661998 0 P 0 ;0
L 0.76783996 -1.91661998 0.76738002 -1.91326998 0 P 0 ;0
L 0.76738002 -1.91326998 0.76721004 -1.90988996 0 P 0 ;0
L 0.76721004 -1.90988996 0.76731004 -1.90651004 0 P 0 ;0
L 0.76731004 -1.90651004 0.7677 -1.90315 0 P 0 ;0
L 0.7677 -1.90315 0.76838002 -1.89966998 0 P 0 ;0
L 0.76838002 -1.89966998 0.76931004 -1.89626998 0 P 0 ;0
L 0.76931004 -1.89626998 0.7705 -1.89296004 0 P 0 ;0
L 0.7705 -1.89296004 0.77193996 -1.88973996 0 P 0 ;0
L 0.77193996 -1.88973996 0.7736 -1.88663996 0 P 0 ;0
L 0.7736 -1.88663996 0.77551004 -1.88363996 0 P 0 ;0
L 0.77551004 -1.88363996 0.77763002 -1.8808 0 P 0 ;0
L 0.77763002 -1.8808 0.77996004 -1.87813002 0 P 0 ;0
L 0.77996004 -1.87813002 0.78246998 -1.87565 0 P 0 ;0
L 0.78246998 -1.87565 0.78516004 -1.87336004 0 P 0 ;0
L 0.78516004 -1.87336004 0.78795 -1.87133996 0 P 0 ;0
L 0.78795 -1.87133996 0.79088002 -1.86956004 0 P 0 ;0
L 0.79088002 -1.86956004 0.79393996 -1.86803002 0 P 0 ;0
L 0.79393996 -1.86803002 0.79711004 -1.86675 0 P 0 ;0
L 0.79711004 -1.86675 0.80038002 -1.86573002 0 P 0 ;0
L 0.80038002 -1.86573002 0.80431004 -1.86486004 0 P 0 ;0
L 0.80431004 -1.86486004 0.80828996 -1.86433996 0 P 0 ;0
L 0.80828996 -1.86433996 0.8123 -1.86416004 0 P 0 ;0
L 0.8123 -1.86416004 0.81631004 -1.86431998 0 P 0 ;0
L 0.81631004 -1.86431998 0.81946998 -1.86471004 0 P 0 ;0
L 0.81946998 -1.86471004 0.82258996 -1.86531004 0 P 0 ;0
L 0.82258996 -1.86531004 0.82566004 -1.86613996 0 P 0 ;0
L 0.82566004 -1.86613996 0.82866998 -1.86718002 0 P 0 ;0
L 0.82866998 -1.86718002 0.83158996 -1.86843002 0 P 0 ;0
L 0.83158996 -1.86843002 0.83443002 -1.86988996 0 P 0 ;0
L 0.83443002 -1.86988996 0.83716004 -1.87156004 0 P 0 ;0
L 0.83716004 -1.87156004 0.83976004 -1.87341004 0 P 0 ;0
L 0.83976004 -1.87341004 0.84223002 -1.87543996 0 P 0 ;0
L 0.84223002 -1.87543996 0.84453996 -1.87763002 0 P 0 ;0
L 0.84453996 -1.87763002 0.84726998 -1.88065 0 P 0 ;0
L 0.84726998 -1.88065 0.84971998 -1.88388002 0 P 0 ;0
L 0.84971998 -1.88388002 0.85188996 -1.88731004 0 P 0 ;0
L 0.85188996 -1.88731004 0.85376004 -1.89091004 0 P 0 ;0
L 0.85376004 -1.89091004 0.85483996 -1.89345 0 P 0 ;0
L 0.85483996 -1.89345 0.85575 -1.89605 0 P 0 ;0
L 0.85575 -1.89605 0.85646998 -1.89871004 0 P 0 ;0
L 0.85646998 -1.89871004 0.857 -1.90141004 0 P 0 ;0
L 0.857 -1.90141004 0.85748002 -1.9053 0 P 0 ;0
L 0.85748002 -1.9053 0.85763996 -1.90918996 0 P 0 ;0
L 0.85763996 -1.90918996 0.8575 -1.91308002 0 P 0 ;0
L 0.8575 -1.91308002 0.85703996 -1.91696004 0 P 0 ;0
L 0.85703996 -1.91696004 0.85628002 -1.92076004 0 P 0 ;0
L 0.85628002 -1.92076004 0.85521998 -1.92448996 0 P 0 ;0
L 0.85521998 -1.92448996 0.85428002 -1.92705 0 P 0 ;0
L 0.85428002 -1.92705 0.85316998 -1.92951998 0 P 0 ;0
L 0.85316998 -1.92951998 0.85188002 -1.93191004 0 P 0 ;0
L 0.85188002 -1.93191004 0.85041998 -1.9342 0 P 0 ;0
L 0.85041998 -1.9342 0.84826998 -1.93708002 0 P 0 ;0
L 0.84826998 -1.93708002 0.84593002 -1.93976998 0 P 0 ;0
L 0.84593002 -1.93976998 0.8434 -1.94228002 0 P 0 ;0
L 0.8434 -1.94228002 0.84068002 -1.9446 0 P 0 ;0
L 0.84068002 -1.9446 0.8378 -1.9467 0 P 0 ;0
L 0.8378 -1.9467 0.83476998 -1.94858002 0 P 0 ;0
L 0.83476998 -1.94858002 0.83163996 -1.9502 0 P 0 ;0
L 0.83163996 -1.9502 0.8284 -1.95158002 0 P 0 ;0
L 0.8284 -1.95158002 0.82506004 -1.95268996 0 P 0 ;0
L 0.82506004 -1.95268996 0.82163996 -1.95356004 0 P 0 ;0
L 0.82163996 -1.95356004 0.81818002 -1.95413996 0 P 0 ;0
L 0.81818002 -1.95413996 0.8147 -1.95446004 0 P 0 ;0
L 0.8147 -1.95446004 0.81121004 -1.9545 0 P 0 ;0
L 0.77075 -2.02925 0.84511004 -2.02925 0 P 0 ;0
L 0.77076004 -2.02825 0.8452 -2.02825 0 P 0 ;0
L 0.77076998 -2.02725 0.84528996 -2.02725 0 P 0 ;0
L 0.77078002 -2.02625 0.84536998 -2.02625 0 P 0 ;0
L 0.77078996 -2.02525 0.84548996 -2.02525 0 P 0 ;0
L 0.7708 -2.02425 0.84561998 -2.02425 0 P 0 ;0
L 0.77081004 -2.02325 0.84575 -2.02325 0 P 0 ;0
L 0.77081998 -2.02225 0.84588002 -2.02225 0 P 0 ;0
L 0.77083002 -2.02125 0.84601004 -2.02125 0 P 0 ;0
L 0.77083996 -2.02025 0.84613996 -2.02025 0 P 0 ;0
L 0.77085 -2.01925 0.84626004 -2.01925 0 P 0 ;0
L 0.77085 -2.01825 0.84638996 -2.01825 0 P 0 ;0
L 0.77085 -2.01725 0.84651998 -2.01725 0 P 0 ;0
L 0.77086004 -2.01625 0.84663996 -2.01625 0 P 0 ;0
L 0.77086004 -2.01525 0.84676998 -2.01525 0 P 0 ;0
L 0.77086004 -2.01425 0.8469 -2.01425 0 P 0 ;0
L 0.77086004 -2.01325 0.84703002 -2.01325 0 P 0 ;0
L 0.77086004 -2.01225 0.84716004 -2.01225 0 P 0 ;0
L 0.77086004 -2.01125 0.84728996 -2.01125 0 P 0 ;0
L 0.77086004 -2.01025 0.84741004 -2.01025 0 P 0 ;0
L 0.77086998 -2.00925 0.84753996 -2.00925 0 P 0 ;0
L 0.77086998 -2.00825 0.84766998 -2.00825 0 P 0 ;0
L 0.77086998 -2.00725 0.84778996 -2.00725 0 P 0 ;0
L 0.77086998 -2.00625 0.84791998 -2.00625 0 P 0 ;0
L 0.77086998 -2.00525 0.84805 -2.00525 0 P 0 ;0
L 0.77086998 -2.00425 0.84818002 -2.00425 0 P 0 ;0
L 0.77088002 -2.00325 0.84831004 -2.00325 0 P 0 ;0
L 0.77088002 -2.00225 0.84843996 -2.00225 0 P 0 ;0
L 0.77088002 -2.00125 0.84856004 -2.00125 0 P 0 ;0
L 0.77088002 -2.00025 0.84868996 -2.00025 0 P 0 ;0
L 0.77088002 -1.99925 0.84881998 -1.99925 0 P 0 ;0
L 0.77088002 -1.99825 0.84896004 -1.99825 0 P 0 ;0
L 0.77088002 -1.99725 0.84911004 -1.99725 0 P 0 ;0
L 0.77088996 -1.99625 0.84926998 -1.99625 0 P 0 ;0
L 0.77088996 -1.99525 0.84941998 -1.99525 0 P 0 ;0
L 0.77088996 -1.99425 0.84956998 -1.99425 0 P 0 ;0
L 0.77088996 -1.99325 0.84971998 -1.99325 0 P 0 ;0
L 0.77088996 -1.99225 0.84986998 -1.99225 0 P 0 ;0
L 0.77088996 -1.99125 0.85003002 -1.99125 0 P 0 ;0
L 0.7709 -1.99025 0.85018002 -1.99025 0 P 0 ;0
L 0.7709 -1.98925 0.85033002 -1.98925 0 P 0 ;0
L 0.76885 -2.01878002 0.76871998 -2.03201998 0 P 0 ;0
L 0.76871998 -2.03201998 0.7684 -2.04553996 0 P 0 ;0
L 0.7684 -2.04553996 0.76796004 -2.05751004 0 P 0 ;0
L 0.76796004 -2.05751004 0.76741004 -2.06523002 0 P 0 ;0
L 0.76741004 -2.06523002 0.76596004 -2.07933996 0 P 0 ;0
L 0.76596004 -2.07933996 0.7636 -2.09918002 0 P 0 ;0
L 0.7636 -2.09918002 0.76116004 -2.119 0 P 0 ;0
L 0.76116004 -2.119 0.76011998 -2.12526004 0 P 0 ;0
L 0.76011998 -2.12526004 0.75948996 -2.12825 0 P 0 ;0
L 0.75948996 -2.12825 0.84418002 -2.12825 0 P 0 ;0
L 0.84418002 -2.12825 0.84361998 -2.10788002 0 P 0 ;0
L 0.84361998 -2.10788002 0.8436 -2.08276004 0 P 0 ;0
L 0.8436 -2.08276004 0.8449 -2.05491998 0 P 0 ;0
L 0.8449 -2.05491998 0.84736004 -2.02641004 0 P 0 ;0
L 0.84736004 -2.02641004 0.85083996 -1.99923002 0 P 0 ;0
L 0.85083996 -1.99923002 0.85268996 -1.987 0 P 0 ;0
L 0.85268996 -1.987 0.7689 -1.987 0 P 0 ;0
L 0.7689 -1.987 0.76885 -2.01878002 0 P 0 ;0
L 0.76195 -2.12625 0.84211998 -2.12625 0 P 0 ;0
L 0.76213996 -2.12525 0.8421 -2.12525 0 P 0 ;0
L 0.76231004 -2.12425 0.84206998 -2.12425 0 P 0 ;0
L 0.76248002 -2.12325 0.84203996 -2.12325 0 P 0 ;0
L 0.76263996 -2.12225 0.84201004 -2.12225 0 P 0 ;0
L 0.76281004 -2.12125 0.84198996 -2.12125 0 P 0 ;0
L 0.76296998 -2.12025 0.84196004 -2.12025 0 P 0 ;0
L 0.76313996 -2.11925 0.84193002 -2.11925 0 P 0 ;0
L 0.76326998 -2.11825 0.8419 -2.11825 0 P 0 ;0
L 0.76338996 -2.11725 0.84188002 -2.11725 0 P 0 ;0
L 0.76351004 -2.11625 0.84185 -2.11625 0 P 0 ;0
L 0.76363996 -2.11525 0.84181998 -2.11525 0 P 0 ;0
L 0.76376004 -2.11425 0.84178996 -2.11425 0 P 0 ;0
L 0.76388002 -2.11325 0.84176998 -2.11325 0 P 0 ;0
L 0.76401004 -2.11225 0.84173996 -2.11225 0 P 0 ;0
L 0.76413002 -2.11125 0.84171004 -2.11125 0 P 0 ;0
L 0.76425 -2.11025 0.84168002 -2.11025 0 P 0 ;0
L 0.76438002 -2.10925 0.84166004 -2.10925 0 P 0 ;0
L 0.7645 -2.10825 0.84163002 -2.10825 0 P 0 ;0
L 0.76461998 -2.10725 0.84161998 -2.10725 0 P 0 ;0
L 0.76475 -2.10625 0.84161998 -2.10625 0 P 0 ;0
L 0.76486998 -2.10525 0.84161998 -2.10525 0 P 0 ;0
L 0.76498996 -2.10425 0.84161998 -2.10425 0 P 0 ;0
L 0.76511998 -2.10325 0.84161998 -2.10325 0 P 0 ;0
L 0.76523996 -2.10225 0.84161998 -2.10225 0 P 0 ;0
L 0.76536004 -2.10125 0.84161998 -2.10125 0 P 0 ;0
L 0.76548996 -2.10025 0.84161998 -2.10025 0 P 0 ;0
L 0.76561004 -2.09925 0.84161998 -2.09925 0 P 0 ;0
L 0.76573002 -2.09825 0.84161004 -2.09825 0 P 0 ;0
L 0.76583996 -2.09725 0.84161004 -2.09725 0 P 0 ;0
L 0.76596998 -2.09625 0.84161004 -2.09625 0 P 0 ;0
L 0.76608996 -2.09525 0.84161004 -2.09525 0 P 0 ;0
L 0.7662 -2.09425 0.84161004 -2.09425 0 P 0 ;0
L 0.76631998 -2.09325 0.84161004 -2.09325 0 P 0 ;0
L 0.76643996 -2.09225 0.84161004 -2.09225 0 P 0 ;0
L 0.76656004 -2.09125 0.84161004 -2.09125 0 P 0 ;0
L 0.76668002 -2.09025 0.84161004 -2.09025 0 P 0 ;0
L 0.76678996 -2.08925 0.84161004 -2.08925 0 P 0 ;0
L 0.76691998 -2.08825 0.84161004 -2.08825 0 P 0 ;0
L 0.76703002 -2.08725 0.84161004 -2.08725 0 P 0 ;0
L 0.76715 -2.08625 0.8416 -2.08625 0 P 0 ;0
L 0.76726998 -2.08525 0.8416 -2.08525 0 P 0 ;0
L 0.76738996 -2.08425 0.8416 -2.08425 0 P 0 ;0
L 0.76195 -2.12625 0.76208002 -2.12561998 0 P 0 ;0
L 0.76208002 -2.12561998 0.76313996 -2.11928996 0 P 0 ;0
L 0.76313996 -2.11928996 0.76558996 -2.09941998 0 P 0 ;0
L 0.76558996 -2.09941998 0.76558996 -2.09941004 0 P 0 ;0
L 0.76558996 -2.09941004 0.76793996 -2.07956004 0 P 0 ;0
L 0.76793996 -2.07956004 0.7694 -2.0654 0 P 0 ;0
L 0.7694 -2.0654 0.76941004 -2.06536004 0 P 0 ;0
L 0.76941004 -2.06536004 0.76996004 -2.05761998 0 P 0 ;0
L 0.76996004 -2.05761998 0.76996004 -2.05758996 0 P 0 ;0
L 0.76996004 -2.05758996 0.7704 -2.0456 0 P 0 ;0
L 0.7704 -2.0456 0.77071998 -2.03206004 0 P 0 ;0
L 0.77071998 -2.03206004 0.77085 -2.01878002 0 P 0 ;0
L 0.77085 -2.01878002 0.7709 -1.989 0 P 0 ;0
L 0.7709 -1.989 0.85036004 -1.989 0 P 0 ;0
L 0.85036004 -1.989 0.84886004 -1.99895 0 P 0 ;0
L 0.84886004 -1.99895 0.84538002 -2.02618996 0 P 0 ;0
L 0.84538002 -2.02618996 0.8429 -2.05478996 0 P 0 ;0
L 0.8429 -2.05478996 0.8416 -2.08271004 0 P 0 ;0
L 0.8416 -2.08271004 0.84161998 -2.10791004 0 P 0 ;0
L 0.84161998 -2.10791004 0.84211998 -2.12625 0 P 0 ;0
L 0.84211998 -2.12625 0.76195 -2.12625 0 P 0 ;0
L 0.71628996 -1.91261998 0.74938002 -1.91261998 0 P 0 ;0
L 0.71783002 -1.91161998 0.74933002 -1.91161998 0 P 0 ;0
L 0.71953002 -1.91061998 0.74931004 -1.91061998 0 P 0 ;0
L 0.72133002 -1.90961998 0.74928996 -1.90961998 0 P 0 ;0
L 0.72313996 -1.90861998 0.74926998 -1.90861998 0 P 0 ;0
L 0.72493996 -1.90761998 0.74928996 -1.90761998 0 P 0 ;0
L 0.72673996 -1.90661998 0.74931998 -1.90661998 0 P 0 ;0
L 0.72855 -1.90561998 0.74935 -1.90561998 0 P 0 ;0
L 0.73035 -1.90461998 0.74938996 -1.90461998 0 P 0 ;0
L 0.73215 -1.90361998 0.74946998 -1.90361998 0 P 0 ;0
L 0.73396004 -1.90261998 0.74953996 -1.90261998 0 P 0 ;0
L 0.73576004 -1.90161998 0.74961998 -1.90161998 0 P 0 ;0
L 0.73756998 -1.90061998 0.74973996 -1.90061998 0 P 0 ;0
L 0.73943002 -1.89961998 0.74986004 -1.89961998 0 P 0 ;0
L 0.74141998 -1.89861998 0.74998996 -1.89861998 0 P 0 ;0
L 0.74341004 -1.89761998 0.75015 -1.89761998 0 P 0 ;0
L 0.59843002 -2.08361998 0.6754 -2.08361998 0 P 0 ;0
L 0.59846004 -2.08261998 0.67538996 -2.08261998 0 P 0 ;0
L 0.59848002 -2.08161998 0.67538002 -2.08161998 0 P 0 ;0
L 0.59851004 -2.08061998 0.67538002 -2.08061998 0 P 0 ;0
L 0.59853002 -2.07961998 0.67546004 -2.07961998 0 P 0 ;0
L 0.59856004 -2.07861998 0.67553996 -2.07861998 0 P 0 ;0
L 0.59861998 -2.07761998 0.67561004 -2.07761998 0 P 0 ;0
L 0.5987 -2.07661998 0.67568996 -2.07661998 0 P 0 ;0
L 0.59878002 -2.07561998 0.67576004 -2.07561998 0 P 0 ;0
L 0.59885 -2.07461998 0.67583996 -2.07461998 0 P 0 ;0
L 0.59893002 -2.07361998 0.67591998 -2.07361998 0 P 0 ;0
L 0.59901004 -2.07261998 0.67598996 -2.07261998 0 P 0 ;0
L 0.59908002 -2.07161998 0.67606998 -2.07161998 0 P 0 ;0
L 0.59916004 -2.07061998 0.67613996 -2.07061998 0 P 0 ;0
L 0.59923002 -2.06961998 0.67621004 -2.06961998 0 P 0 ;0
L 0.59936004 -2.06861998 0.6763 -2.06861998 0 P 0 ;0
L 0.59948996 -2.06761998 0.67645 -2.06761998 0 P 0 ;0
L 0.59963002 -2.06661998 0.6766 -2.06661998 0 P 0 ;0
L 0.59976998 -2.06561998 0.67676004 -2.06561998 0 P 0 ;0
L 0.5999 -2.06461998 0.67691998 -2.06461998 0 P 0 ;0
L 0.60003002 -2.06361998 0.67706998 -2.06361998 0 P 0 ;0
L 0.60016998 -2.06261998 0.6773 -2.06261998 0 P 0 ;0
L 0.60031004 -2.06161998 0.67753002 -2.06161998 0 P 0 ;0
L 0.60051004 -2.06061998 0.67776004 -2.06061998 0 P 0 ;0
L 0.60071004 -2.05961998 0.67798996 -2.05961998 0 P 0 ;0
L 0.60091998 -2.05861998 0.67823002 -2.05861998 0 P 0 ;0
L 0.60111998 -2.05761998 0.67853002 -2.05761998 0 P 0 ;0
L 0.60133002 -2.05661998 0.67883996 -2.05661998 0 P 0 ;0
L 0.60153996 -2.05561998 0.67913996 -2.05561998 0 P 0 ;0
L 0.60173996 -2.05461998 0.67945 -2.05461998 0 P 0 ;0
L 0.60195 -2.05361998 0.67975 -2.05361998 0 P 0 ;0
L 0.60223002 -2.05261998 0.68006004 -2.05261998 0 P 0 ;0
L 0.60251004 -2.05161998 0.68036004 -2.05161998 0 P 0 ;0
L 0.60278996 -2.05061998 0.68066998 -2.05061998 0 P 0 ;0
L 0.60306004 -2.04961998 0.68096998 -2.04961998 0 P 0 ;0
L 0.60333996 -2.04861998 0.68135 -2.04861998 0 P 0 ;0
L 0.60361998 -2.04761998 0.68173002 -2.04761998 0 P 0 ;0
L 0.6039 -2.04661998 0.68211004 -2.04661998 0 P 0 ;0
L 0.60418002 -2.04561998 0.68248996 -2.04561998 0 P 0 ;0
L 0.60453002 -2.04461998 0.68288002 -2.04461998 0 P 0 ;0
L 0.60488002 -2.04361998 0.68326004 -2.04361998 0 P 0 ;0
L 0.60523002 -2.04261998 0.68363996 -2.04261998 0 P 0 ;0
L 0.60556998 -2.04161998 0.68401998 -2.04161998 0 P 0 ;0
L 0.60591998 -2.04061998 0.6844 -2.04061998 0 P 0 ;0
L 0.60626998 -2.03961998 0.68486004 -2.03961998 0 P 0 ;0
L 0.60661998 -2.03861998 0.68531998 -2.03861998 0 P 0 ;0
L 0.60698996 -2.03761998 0.68578002 -2.03761998 0 P 0 ;0
L 0.60743002 -2.03661998 0.68623996 -2.03661998 0 P 0 ;0
L 0.60786004 -2.03561998 0.6867 -2.03561998 0 P 0 ;0
L 0.60828996 -2.03461998 0.68716004 -2.03461998 0 P 0 ;0
L 0.60873002 -2.03361998 0.68761998 -2.03361998 0 P 0 ;0
L 0.60916004 -2.03261998 0.68808996 -2.03261998 0 P 0 ;0
L 0.60958996 -2.03161998 0.68856998 -2.03161998 0 P 0 ;0
L 0.61003002 -2.03061998 0.68911004 -2.03061998 0 P 0 ;0
L 0.61046004 -2.02961998 0.68965 -2.02961998 0 P 0 ;0
L 0.61088996 -2.02861998 0.69018996 -2.02861998 0 P 0 ;0
L 0.61133002 -2.02761998 0.69073002 -2.02761998 0 P 0 ;0
L 0.61176004 -2.02661998 0.69126998 -2.02661998 0 P 0 ;0
L 0.6122 -2.02561998 0.69181004 -2.02561998 0 P 0 ;0
L 0.61263002 -2.02461998 0.69235 -2.02461998 0 P 0 ;0
L 0.61306004 -2.02361998 0.69288002 -2.02361998 0 P 0 ;0
L 0.61348996 -2.02261998 0.69346998 -2.02261998 0 P 0 ;0
L 0.61393002 -2.02161998 0.69408996 -2.02161998 0 P 0 ;0
L 0.61436004 -2.02061998 0.6947 -2.02061998 0 P 0 ;0
L 0.61478996 -2.01961998 0.69531998 -2.01961998 0 P 0 ;0
L 0.61531004 -2.01861998 0.69593996 -2.01861998 0 P 0 ;0
L 0.61583996 -2.01761998 0.69656004 -2.01761998 0 P 0 ;0
L 0.61636004 -2.01661998 0.69718002 -2.01661998 0 P 0 ;0
L 0.61688002 -2.01561998 0.69778996 -2.01561998 0 P 0 ;0
L 0.6174 -2.01461998 0.69841998 -2.01461998 0 P 0 ;0
L 0.61791998 -2.01361998 0.69911998 -2.01361998 0 P 0 ;0
L 0.61843996 -2.01261998 0.69981998 -2.01261998 0 P 0 ;0
L 0.61896004 -2.01161998 0.70051998 -2.01161998 0 P 0 ;0
L 0.61948002 -2.01061998 0.70123002 -2.01061998 0 P 0 ;0
L 0.62 -2.00961998 0.70193002 -2.00961998 0 P 0 ;0
L 0.62051998 -2.00861998 0.70263002 -2.00861998 0 P 0 ;0
L 0.62103996 -2.00761998 0.70333002 -2.00761998 0 P 0 ;0
L 0.62163996 -2.00661998 0.70403996 -2.00661998 0 P 0 ;0
L 0.62225 -2.00561998 0.70483002 -2.00561998 0 P 0 ;0
L 0.62285 -2.00461998 0.70565 -2.00461998 0 P 0 ;0
L 0.62346004 -2.00361998 0.70646004 -2.00361998 0 P 0 ;0
L 0.62406004 -2.00261998 0.70726998 -2.00261998 0 P 0 ;0
L 0.62466004 -2.00161998 0.70808996 -2.00161998 0 P 0 ;0
L 0.62526998 -2.00061998 0.7089 -2.00061998 0 P 0 ;0
L 0.62586998 -1.99961998 0.70971004 -1.99961998 0 P 0 ;0
L 0.62648002 -1.99861998 0.71053002 -1.99861998 0 P 0 ;0
L 0.62708002 -1.99761998 0.71133996 -1.99761998 0 P 0 ;0
L 0.62768996 -1.99661998 0.71216004 -1.99661998 0 P 0 ;0
L 0.62831998 -1.99561998 0.71296998 -1.99561998 0 P 0 ;0
L 0.62901004 -1.99461998 0.71378996 -1.99461998 0 P 0 ;0
L 0.62971004 -1.99361998 0.71466004 -1.99361998 0 P 0 ;0
L 0.6304 -1.99261998 0.71561004 -1.99261998 0 P 0 ;0
L 0.6311 -1.99161998 0.71656998 -1.99161998 0 P 0 ;0
L 0.63178996 -1.99061998 0.71753002 -1.99061998 0 P 0 ;0
L 0.63248996 -1.98961998 0.71848996 -1.98961998 0 P 0 ;0
L 0.63318002 -1.98861998 0.71945 -1.98861998 0 P 0 ;0
L 0.63388002 -1.98761998 0.72041004 -1.98761998 0 P 0 ;0
L 0.63456998 -1.98661998 0.72136998 -1.98661998 0 P 0 ;0
L 0.63526998 -1.98561998 0.72233002 -1.98561998 0 P 0 ;0
L 0.63598002 -1.98461998 0.72328996 -1.98461998 0 P 0 ;0
L 0.63678996 -1.98361998 0.72425 -1.98361998 0 P 0 ;0
L 0.6376 -1.98261998 0.72521004 -1.98261998 0 P 0 ;0
L 0.63841004 -1.98161998 0.72628002 -1.98161998 0 P 0 ;0
L 0.63921998 -1.98061998 0.72738996 -1.98061998 0 P 0 ;0
L 0.64003002 -1.97961998 0.7285 -1.97961998 0 P 0 ;0
L 0.64083996 -1.97861998 0.72961004 -1.97861998 0 P 0 ;0
L 0.64165 -1.97761998 0.73071004 -1.97761998 0 P 0 ;0
L 0.64246004 -1.97661998 0.73181998 -1.97661998 0 P 0 ;0
L 0.64326998 -1.97561998 0.73293002 -1.97561998 0 P 0 ;0
L 0.64406998 -1.97461998 0.73403996 -1.97461998 0 P 0 ;0
L 0.64488002 -1.97361998 0.73515 -1.97361998 0 P 0 ;0
L 0.64568996 -1.97261998 0.73625 -1.97261998 0 P 0 ;0
L 0.6465 -1.97161998 0.73736004 -1.97161998 0 P 0 ;0
L 0.64731004 -1.97061998 0.73848002 -1.97061998 0 P 0 ;0
L 0.64811998 -1.96961998 0.73973002 -1.96961998 0 P 0 ;0
L 0.64893002 -1.96861998 0.74098996 -1.96861998 0 P 0 ;0
L 0.64981004 -1.96761998 0.74225 -1.96761998 0 P 0 ;0
L 0.65076004 -1.96661998 0.74351004 -1.96661998 0 P 0 ;0
L 0.65171004 -1.96561998 0.74476998 -1.96561998 0 P 0 ;0
L 0.65266998 -1.96461998 0.74603002 -1.96461998 0 P 0 ;0
L 0.65361998 -1.96361998 0.74728996 -1.96361998 0 P 0 ;0
L 0.65458002 -1.96261998 0.74855 -1.96261998 0 P 0 ;0
L 0.65553002 -1.96161998 0.74981004 -1.96161998 0 P 0 ;0
L 0.65648996 -1.96061998 0.75106004 -1.96061998 0 P 0 ;0
L 0.65743996 -1.95961998 0.75233996 -1.95961998 0 P 0 ;0
L 0.6584 -1.95861998 0.7537 -1.95861998 0 P 0 ;0
L 0.65935 -1.95761998 0.75506004 -1.95761998 0 P 0 ;0
L 0.66031004 -1.95661998 0.75641998 -1.95661998 0 P 0 ;0
L 0.66126004 -1.95561998 0.75778996 -1.95561998 0 P 0 ;0
L 0.66221004 -1.95461998 0.75916004 -1.95461998 0 P 0 ;0
L 0.66316998 -1.95361998 0.76053996 -1.95361998 0 P 0 ;0
L 0.66411998 -1.95261998 0.76193996 -1.95261998 0 P 0 ;0
L 0.66523002 -1.95161998 0.76333996 -1.95161998 0 P 0 ;0
L 0.66636004 -1.95061998 0.76406998 -1.95061998 0 P 0 ;0
L 0.66746998 -1.94961998 0.76355 -1.94961998 0 P 0 ;0
L 0.6686 -1.94861998 0.76291998 -1.94861998 0 P 0 ;0
L 0.66971004 -1.94761998 0.76226998 -1.94761998 0 P 0 ;0
L 0.67083996 -1.94661998 0.76161998 -1.94661998 0 P 0 ;0
L 0.67196004 -1.94561998 0.76096998 -1.94561998 0 P 0 ;0
L 0.67306998 -1.94461998 0.76033002 -1.94461998 0 P 0 ;0
L 0.6742 -1.94361998 0.75968996 -1.94361998 0 P 0 ;0
L 0.67531004 -1.94261998 0.75905 -1.94261998 0 P 0 ;0
L 0.67643996 -1.94161998 0.75846004 -1.94161998 0 P 0 ;0
L 0.67755 -1.94061998 0.75788996 -1.94061998 0 P 0 ;0
L 0.67868002 -1.93961998 0.75731998 -1.93961998 0 P 0 ;0
L 0.67978996 -1.93861998 0.75676998 -1.93861998 0 P 0 ;0
L 0.68091998 -1.93761998 0.75626998 -1.93761998 0 P 0 ;0
L 0.68221004 -1.93661998 0.75576998 -1.93661998 0 P 0 ;0
L 0.68353002 -1.93561998 0.75528002 -1.93561998 0 P 0 ;0
L 0.68483996 -1.93461998 0.75483996 -1.93461998 0 P 0 ;0
L 0.68616004 -1.93361998 0.75441004 -1.93361998 0 P 0 ;0
L 0.68746998 -1.93261998 0.75398002 -1.93261998 0 P 0 ;0
L 0.68878002 -1.93161998 0.7536 -1.93161998 0 P 0 ;0
L 0.6901 -1.93061998 0.75323996 -1.93061998 0 P 0 ;0
L 0.69141004 -1.92961998 0.75286998 -1.92961998 0 P 0 ;0
L 0.69271998 -1.92861998 0.75253996 -1.92861998 0 P 0 ;0
L 0.69403002 -1.92761998 0.75223002 -1.92761998 0 P 0 ;0
L 0.69535 -1.92661998 0.75193002 -1.92661998 0 P 0 ;0
L 0.69666004 -1.92561998 0.75163002 -1.92561998 0 P 0 ;0
L 0.69796998 -1.92461998 0.75138002 -1.92461998 0 P 0 ;0
L 0.69936998 -1.92361998 0.75113996 -1.92361998 0 P 0 ;0
L 0.70091004 -1.92261998 0.75088996 -1.92261998 0 P 0 ;0
L 0.70243996 -1.92161998 0.75066004 -1.92161998 0 P 0 ;0
L 0.70398002 -1.92061998 0.75046004 -1.92061998 0 P 0 ;0
L 0.70551998 -1.91961998 0.75026004 -1.91961998 0 P 0 ;0
L 0.70706004 -1.91861998 0.75006998 -1.91861998 0 P 0 ;0
L 0.7086 -1.91761998 0.7499 -1.91761998 0 P 0 ;0
L 0.71013996 -1.91661998 0.74976998 -1.91661998 0 P 0 ;0
L 0.71166998 -1.91561998 0.74961998 -1.91561998 0 P 0 ;0
L 0.71321004 -1.91461998 0.74951998 -1.91461998 0 P 0 ;0
L 0.71475 -1.91361998 0.74945 -1.91361998 0 P 0 ;0
L 0.61556998 -2.15661998 0.70655 -2.15661998 0 P 0 ;0
L 0.61503002 -2.15561998 0.7056 -2.15561998 0 P 0 ;0
L 0.61448996 -2.15461998 0.70465 -2.15461998 0 P 0 ;0
L 0.61395 -2.15361998 0.7037 -2.15361998 0 P 0 ;0
L 0.61341004 -2.15261998 0.70273996 -2.15261998 0 P 0 ;0
L 0.61286998 -2.15161998 0.70178996 -2.15161998 0 P 0 ;0
L 0.61233002 -2.15061998 0.70095 -2.15061998 0 P 0 ;0
L 0.61188002 -2.14961998 0.70015 -2.14961998 0 P 0 ;0
L 0.61143002 -2.14861998 0.69935 -2.14861998 0 P 0 ;0
L 0.61098002 -2.14761998 0.69855 -2.14761998 0 P 0 ;0
L 0.61053002 -2.14661998 0.69775 -2.14661998 0 P 0 ;0
L 0.61008002 -2.14561998 0.69695 -2.14561998 0 P 0 ;0
L 0.60963002 -2.14461998 0.69615 -2.14461998 0 P 0 ;0
L 0.60918002 -2.14361998 0.69535 -2.14361998 0 P 0 ;0
L 0.60873002 -2.14261998 0.69455 -2.14261998 0 P 0 ;0
L 0.60831004 -2.14161998 0.69381998 -2.14161998 0 P 0 ;0
L 0.60793996 -2.14061998 0.69315 -2.14061998 0 P 0 ;0
L 0.60756998 -2.13961998 0.69248002 -2.13961998 0 P 0 ;0
L 0.60721004 -2.13861998 0.69181004 -2.13861998 0 P 0 ;0
L 0.60683996 -2.13761998 0.69115 -2.13761998 0 P 0 ;0
L 0.60646998 -2.13661998 0.69048002 -2.13661998 0 P 0 ;0
L 0.60611004 -2.13561998 0.68981004 -2.13561998 0 P 0 ;0
L 0.60573996 -2.13461998 0.68918002 -2.13461998 0 P 0 ;0
L 0.60538002 -2.13361998 0.68863002 -2.13361998 0 P 0 ;0
L 0.60503996 -2.13261998 0.68808002 -2.13261998 0 P 0 ;0
L 0.60476004 -2.13161998 0.68753002 -2.13161998 0 P 0 ;0
L 0.60446998 -2.13061998 0.68698002 -2.13061998 0 P 0 ;0
L 0.60418002 -2.12961998 0.68643002 -2.12961998 0 P 0 ;0
L 0.6039 -2.12861998 0.68588002 -2.12861998 0 P 0 ;0
L 0.60361004 -2.12761998 0.68533002 -2.12761998 0 P 0 ;0
L 0.60331998 -2.12661998 0.68486004 -2.12661998 0 P 0 ;0
L 0.60303002 -2.12561998 0.68441998 -2.12561998 0 P 0 ;0
L 0.60275 -2.12461998 0.68396998 -2.12461998 0 P 0 ;0
L 0.60246004 -2.12361998 0.68353002 -2.12361998 0 P 0 ;0
L 0.60218002 -2.12261998 0.68308996 -2.12261998 0 P 0 ;0
L 0.60188996 -2.12161998 0.68263996 -2.12161998 0 P 0 ;0
L 0.60166998 -2.12061998 0.6822 -2.12061998 0 P 0 ;0
L 0.60145 -2.11961998 0.68176004 -2.11961998 0 P 0 ;0
L 0.60123002 -2.11861998 0.68138996 -2.11861998 0 P 0 ;0
L 0.60101004 -2.11761998 0.68105 -2.11761998 0 P 0 ;0
L 0.60078002 -2.11661998 0.68071004 -2.11661998 0 P 0 ;0
L 0.6006 -2.11561998 0.68036004 -2.11561998 0 P 0 ;0
L 0.60043002 -2.11461998 0.68001998 -2.11461998 0 P 0 ;0
L 0.60025 -2.11361998 0.67968002 -2.11361998 0 P 0 ;0
L 0.60008002 -2.11261998 0.67933002 -2.11261998 0 P 0 ;0
L 0.59991004 -2.11161998 0.67898996 -2.11161998 0 P 0 ;0
L 0.59976004 -2.11061998 0.6787 -2.11061998 0 P 0 ;0
L 0.59963996 -2.10961998 0.67845 -2.10961998 0 P 0 ;0
L 0.59951004 -2.10861998 0.6782 -2.10861998 0 P 0 ;0
L 0.59938002 -2.10761998 0.67795 -2.10761998 0 P 0 ;0
L 0.59925 -2.10661998 0.6777 -2.10661998 0 P 0 ;0
L 0.59913002 -2.10561998 0.67746004 -2.10561998 0 P 0 ;0
L 0.59905 -2.10461998 0.67721004 -2.10461998 0 P 0 ;0
L 0.59896998 -2.10361998 0.67696004 -2.10361998 0 P 0 ;0
L 0.59888002 -2.10261998 0.67671004 -2.10261998 0 P 0 ;0
L 0.5988 -2.10161998 0.67653996 -2.10161998 0 P 0 ;0
L 0.59871998 -2.10061998 0.67638002 -2.10061998 0 P 0 ;0
L 0.59866998 -2.09961998 0.67621004 -2.09961998 0 P 0 ;0
L 0.59863996 -2.09861998 0.67605 -2.09861998 0 P 0 ;0
L 0.59861004 -2.09761998 0.67588996 -2.09761998 0 P 0 ;0
L 0.59858996 -2.09661998 0.6758 -2.09661998 0 P 0 ;0
L 0.59856004 -2.09561998 0.67571004 -2.09561998 0 P 0 ;0
L 0.59853002 -2.09461998 0.67563002 -2.09461998 0 P 0 ;0
L 0.5985 -2.09361998 0.67553996 -2.09361998 0 P 0 ;0
L 0.59846998 -2.09261998 0.67546004 -2.09261998 0 P 0 ;0
L 0.59843996 -2.09161998 0.67546004 -2.09161998 0 P 0 ;0
L 0.59841998 -2.09061998 0.67545 -2.09061998 0 P 0 ;0
L 0.59838002 -2.08961998 0.67543996 -2.08961998 0 P 0 ;0
L 0.59836004 -2.08861998 0.67543002 -2.08861998 0 P 0 ;0
L 0.59833002 -2.08761998 0.67543002 -2.08761998 0 P 0 ;0
L 0.59835 -2.08661998 0.67541998 -2.08661998 0 P 0 ;0
L 0.59836998 -2.08561998 0.67541004 -2.08561998 0 P 0 ;0
L 0.5984 -2.08461998 0.67541004 -2.08461998 0 P 0 ;0
L 0.80005 -2.25161998 0.85543996 -2.25161998 0 P 0 ;0
L 0.78651998 -2.25061998 0.86596004 -2.25061998 0 P 0 ;0
L 0.77878996 -2.24961998 0.87636004 -2.24961998 0 P 0 ;0
L 0.77106004 -2.24861998 0.88285 -2.24861998 0 P 0 ;0
L 0.76398996 -2.24761998 0.88933996 -2.24761998 0 P 0 ;0
L 0.75891998 -2.24661998 0.89583996 -2.24661998 0 P 0 ;0
L 0.73781004 -1.8982 0.71738996 -1.90951998 0 P 0 ;0
L 0.71738996 -1.90951998 0.69766998 -1.92233996 0 P 0 ;0
L 0.69766998 -1.92233996 0.67971004 -1.93601998 0 P 0 ;0
L 0.67971004 -1.93601998 0.66278996 -1.95113002 0 P 0 ;0
L 0.66278996 -1.95113002 0.64786998 -1.96675 0 P 0 ;0
L 0.64786998 -1.96675 0.63423996 -1.98358996 0 P 0 ;0
L 0.63423996 -1.98358996 0.62643996 -1.99483002 0 P 0 ;0
L 0.62643996 -1.99483002 0.61933996 -2.00655 0 P 0 ;0
L 0.61933996 -2.00655 0.61298996 -2.01873996 0 P 0 ;0
L 0.61298996 -2.01873996 0.60503002 -2.03713002 0 P 0 ;0
L 0.60503002 -2.03713002 0.60225 -2.04506004 0 P 0 ;0
L 0.60225 -2.04506004 0.59998996 -2.05323002 0 P 0 ;0
L 0.59998996 -2.05323002 0.59833996 -2.0612 0 P 0 ;0
L 0.59833996 -2.0612 0.59725 -2.06928996 0 P 0 ;0
L 0.59725 -2.06928996 0.59656998 -2.07833996 0 P 0 ;0
L 0.59656998 -2.07833996 0.59633002 -2.0875 0 P 0 ;0
L 0.59633002 -2.0875 0.59668996 -2.10036998 0 P 0 ;0
L 0.59668996 -2.10036998 0.59715 -2.10596004 0 P 0 ;0
L 0.59715 -2.10596004 0.59786004 -2.11151004 0 P 0 ;0
L 0.59786004 -2.11151004 0.59878996 -2.11686998 0 P 0 ;0
L 0.59878996 -2.11686998 0.59996998 -2.1222 0 P 0 ;0
L 0.59996998 -2.1222 0.60326998 -2.13368996 0 P 0 ;0
L 0.60326998 -2.13368996 0.60656998 -2.1427 0 P 0 ;0
L 0.60656998 -2.1427 0.6105 -2.15143996 0 P 0 ;0
L 0.6105 -2.15143996 0.61505 -2.15988002 0 P 0 ;0
L 0.61505 -2.15988002 0.62023996 -2.16803996 0 P 0 ;0
L 0.62023996 -2.16803996 0.62828996 -2.17873002 0 P 0 ;0
L 0.62828996 -2.17873002 0.63718996 -2.18871004 0 P 0 ;0
L 0.63718996 -2.18871004 0.64693002 -2.19795 0 P 0 ;0
L 0.64693002 -2.19795 0.6582 -2.20701998 0 P 0 ;0
L 0.6582 -2.20701998 0.67011004 -2.21518996 0 P 0 ;0
L 0.67011004 -2.21518996 0.68261004 -2.22243002 0 P 0 ;0
L 0.68261004 -2.22243002 0.69673996 -2.22936004 0 P 0 ;0
L 0.69673996 -2.22936004 0.71123002 -2.23543996 0 P 0 ;0
L 0.71123002 -2.23543996 0.72611998 -2.24066998 0 P 0 ;0
L 0.72611998 -2.24066998 0.74536004 -2.24598996 0 P 0 ;0
L 0.74536004 -2.24598996 0.76493002 -2.24985 0 P 0 ;0
L 0.76493002 -2.24985 0.78671998 -2.25266998 0 P 0 ;0
L 0.78671998 -2.25266998 0.80863002 -2.25425 0 P 0 ;0
L 0.80863002 -2.25425 0.83146004 -2.25463002 0 P 0 ;0
L 0.83146004 -2.25463002 0.85418002 -2.25375 0 P 0 ;0
L 0.85418002 -2.25375 0.87641004 -2.25163996 0 P 0 ;0
L 0.87641004 -2.25163996 0.89853002 -2.24823002 0 P 0 ;0
L 0.89853002 -2.24823002 0.93045 -2.24101998 0 P 0 ;0
L 0.93045 -2.24101998 0.96466004 -2.23063002 0 P 0 ;0
L 0.96466004 -2.23063002 0.99911004 -2.2178 0 P 0 ;0
L 0.99911004 -2.2178 1.03183002 -2.20318002 0 P 0 ;0
L 1.03183002 -2.20318002 1.04391998 -2.19703002 0 P 0 ;0
L 1.04391998 -2.19703002 1.05581004 -2.19048996 0 P 0 ;0
L 1.05581004 -2.19048996 1.06676004 -2.18411998 0 P 0 ;0
L 1.06676004 -2.18411998 1.06681004 -2.18408996 0 P 0 ;0
L 1.06681004 -2.18408996 1.06685 -2.18405 0 P 0 ;0
L 1.06685 -2.18405 1.0669 -2.18401004 0 P 0 ;0
L 1.0669 -2.18401004 1.06693996 -2.18396998 0 P 0 ;0
L 1.06693996 -2.18396998 1.06696998 -2.18391998 0 P 0 ;0
L 1.06696998 -2.18391998 1.06701004 -2.18386998 0 P 0 ;0
L 1.06701004 -2.18386998 1.06703002 -2.18381998 0 P 0 ;0
L 1.06703002 -2.18381998 1.06706004 -2.18376004 0 P 0 ;0
L 1.06706004 -2.18376004 1.06706998 -2.18371004 0 P 0 ;0
L 1.06706998 -2.18371004 1.06708996 -2.18365 0 P 0 ;0
L 1.06708996 -2.18365 1.06708996 -2.18358996 0 P 0 ;0
L 1.06708996 -2.18358996 1.0671 -2.18353002 0 P 0 ;0
L 1.0671 -2.18353002 1.0671 -2.18346998 0 P 0 ;0
L 1.0671 -2.18346998 1.06708996 -2.18341004 0 P 0 ;0
L 1.06708996 -2.18341004 1.06706998 -2.18336004 0 P 0 ;0
L 1.06706998 -2.18336004 1.06706004 -2.1833 0 P 0 ;0
L 1.06706004 -2.1833 1.06703002 -2.18323996 0 P 0 ;0
L 1.06703002 -2.18323996 1.06701004 -2.18318996 0 P 0 ;0
L 1.06701004 -2.18318996 1.06696998 -2.18313996 0 P 0 ;0
L 1.06696998 -2.18313996 1.06693996 -2.18308996 0 P 0 ;0
L 1.06693996 -2.18308996 1.06688002 -2.18303002 0 P 0 ;0
L 1.06688002 -2.18303002 1.06678996 -2.18296998 0 P 0 ;0
L 1.06678996 -2.18296998 1.06673002 -2.18295 0 P 0 ;0
L 1.06673002 -2.18295 1.0667 -2.18295 0 P 0 ;0
L 1.0667 -2.18295 1.06666004 -2.18293996 0 P 0 ;0
L 1.06666004 -2.18293996 1.0666 -2.18293996 0 P 0 ;0
L 1.0666 -2.18293996 1.06656998 -2.18295 0 P 0 ;0
L 1.06656998 -2.18295 1.06653002 -2.18295 0 P 0 ;0
L 1.06653002 -2.18295 1.06153002 -2.1842 0 P 0 ;0
L 1.06153002 -2.1842 1.05583996 -2.18566998 0 P 0 ;0
L 1.05583996 -2.18566998 1.04916998 -2.1875 0 P 0 ;0
L 1.04916998 -2.1875 1.0153 -2.1962 0 P 0 ;0
L 1.0153 -2.1962 0.9814 -2.20333996 0 P 0 ;0
L 0.9814 -2.20333996 0.94881998 -2.2087 0 P 0 ;0
L 0.94881998 -2.2087 0.9189 -2.21198996 0 P 0 ;0
L 0.9189 -2.21198996 0.90113996 -2.21278996 0 P 0 ;0
L 0.90113996 -2.21278996 0.87738002 -2.21265 0 P 0 ;0
L 0.87738002 -2.21265 0.854 -2.21183002 0 P 0 ;0
L 0.854 -2.21183002 0.83788996 -2.21033996 0 P 0 ;0
L 0.83788996 -2.21033996 0.8174 -2.20693002 0 P 0 ;0
L 0.8174 -2.20693002 0.79708996 -2.2023 0 P 0 ;0
L 0.79708996 -2.2023 0.7769 -2.19641004 0 P 0 ;0
L 0.7769 -2.19641004 0.76433002 -2.19183996 0 P 0 ;0
L 0.76433002 -2.19183996 0.75208996 -2.18638002 0 P 0 ;0
L 0.75208996 -2.18638002 0.74026998 -2.18006998 0 P 0 ;0
L 0.74026998 -2.18006998 0.72886998 -2.17291004 0 P 0 ;0
L 0.72886998 -2.17291004 0.71961998 -2.16603002 0 P 0 ;0
L 0.71961998 -2.16603002 0.71098996 -2.15838996 0 P 0 ;0
L 0.71098996 -2.15838996 0.70303002 -2.15003002 0 P 0 ;0
L 0.70303002 -2.15003002 0.6958 -2.14098996 0 P 0 ;0
L 0.6958 -2.14098996 0.69106998 -2.1339 0 P 0 ;0
L 0.69106998 -2.1339 0.68696004 -2.12643002 0 P 0 ;0
L 0.68696004 -2.12643002 0.68351004 -2.11863002 0 P 0 ;0
L 0.68351004 -2.11863002 0.68073996 -2.11056004 0 P 0 ;0
L 0.68073996 -2.11056004 0.67866004 -2.10218996 0 P 0 ;0
L 0.67866004 -2.10218996 0.67788002 -2.09741998 0 P 0 ;0
L 0.67788002 -2.09741998 0.67746004 -2.0926 0 P 0 ;0
L 0.67746004 -2.0926 0.67738002 -2.08076004 0 P 0 ;0
L 0.67738002 -2.08076004 0.67828002 -2.06891004 0 P 0 ;0
L 0.67828002 -2.06891004 0.67903002 -2.06403996 0 P 0 ;0
L 0.67903002 -2.06403996 0.68013002 -2.05923996 0 P 0 ;0
L 0.68013002 -2.05923996 0.68288002 -2.05021998 0 P 0 ;0
L 0.68288002 -2.05021998 0.68623996 -2.04141004 0 P 0 ;0
L 0.68623996 -2.04141004 0.69018002 -2.03286004 0 P 0 ;0
L 0.69018002 -2.03286004 0.69486004 -2.02418002 0 P 0 ;0
L 0.69486004 -2.02418002 0.70003996 -2.0158 0 P 0 ;0
L 0.70003996 -2.0158 0.70573002 -2.00768996 0 P 0 ;0
L 0.70573002 -2.00768996 0.7158 -1.99531998 0 P 0 ;0
L 0.7158 -1.99531998 0.72681004 -1.98385 0 P 0 ;0
L 0.72681004 -1.98385 0.73971004 -1.9722 0 P 0 ;0
L 0.73971004 -1.9722 0.7533 -1.9614 0 P 0 ;0
L 0.7533 -1.9614 0.75753996 -1.95828002 0 P 0 ;0
L 0.75753996 -1.95828002 0.76138002 -1.95548002 0 P 0 ;0
L 0.76138002 -1.95548002 0.76463002 -1.95316004 0 P 0 ;0
L 0.76463002 -1.95316004 0.76516004 -1.95281004 0 P 0 ;0
L 0.76516004 -1.95281004 0.7657 -1.95248996 0 P 0 ;0
L 0.7657 -1.95248996 0.76578002 -1.95243996 0 P 0 ;0
L 0.76578002 -1.95243996 0.76586004 -1.95238002 0 P 0 ;0
L 0.76586004 -1.95238002 0.76593002 -1.95231998 0 P 0 ;0
L 0.76593002 -1.95231998 0.766 -1.95223996 0 P 0 ;0
L 0.766 -1.95223996 0.76606004 -1.95216998 0 P 0 ;0
L 0.76606004 -1.95216998 0.76616004 -1.95201004 0 P 0 ;0
L 0.76616004 -1.95201004 0.7662 -1.95191998 0 P 0 ;0
L 0.7662 -1.95191998 0.76626004 -1.95173996 0 P 0 ;0
L 0.76626004 -1.95173996 0.76628002 -1.95163996 0 P 0 ;0
L 0.76628002 -1.95163996 0.7663 -1.95143002 0 P 0 ;0
L 0.7663 -1.95143002 0.7663 -1.95121004 0 P 0 ;0
L 0.7663 -1.95121004 0.76628996 -1.951 0 P 0 ;0
L 0.76628996 -1.951 0.76625 -1.95078996 0 P 0 ;0
L 0.76625 -1.95078996 0.7662 -1.95058002 0 P 0 ;0
L 0.7662 -1.95058002 0.76613002 -1.95036998 0 P 0 ;0
L 0.76613002 -1.95036998 0.76583002 -1.94966998 0 P 0 ;0
L 0.76583002 -1.94966998 0.76548996 -1.94896998 0 P 0 ;0
L 0.76548996 -1.94896998 0.76508996 -1.9483 0 P 0 ;0
L 0.76508996 -1.9483 0.76253002 -1.94436004 0 P 0 ;0
L 0.76253002 -1.94436004 0.76056998 -1.94126998 0 P 0 ;0
L 0.76056998 -1.94126998 0.75871998 -1.93806004 0 P 0 ;0
L 0.75871998 -1.93806004 0.75716998 -1.93496998 0 P 0 ;0
L 0.75716998 -1.93496998 0.7558 -1.93178002 0 P 0 ;0
L 0.7558 -1.93178002 0.7546 -1.92853996 0 P 0 ;0
L 0.7546 -1.92853996 0.75358996 -1.92521004 0 P 0 ;0
L 0.75358996 -1.92521004 0.7527 -1.92161998 0 P 0 ;0
L 0.7527 -1.92161998 0.75196998 -1.91796004 0 P 0 ;0
L 0.75196998 -1.91796004 0.75155 -1.91496004 0 P 0 ;0
L 0.75155 -1.91496004 0.75133002 -1.91193002 0 P 0 ;0
L 0.75133002 -1.91193002 0.75126998 -1.9085 0 P 0 ;0
L 0.75126998 -1.9085 0.75136004 -1.90506004 0 P 0 ;0
L 0.75136004 -1.90506004 0.75161004 -1.90181998 0 P 0 ;0
L 0.75161004 -1.90181998 0.752 -1.8986 0 P 0 ;0
L 0.752 -1.8986 0.75228996 -1.89701998 0 P 0 ;0
L 0.75228996 -1.89701998 0.75268996 -1.89546998 0 P 0 ;0
L 0.75268996 -1.89546998 0.7532 -1.89395 0 P 0 ;0
L 0.7532 -1.89395 0.75358996 -1.89281998 0 P 0 ;0
L 0.75358996 -1.89281998 0.75373002 -1.89231998 0 P 0 ;0
L 0.75373002 -1.89231998 0.75383996 -1.8918 0 P 0 ;0
L 0.75383996 -1.8918 0.75391998 -1.89138996 0 P 0 ;0
L 0.75391998 -1.89138996 0.75396998 -1.89098996 0 P 0 ;0
L 0.75396998 -1.89098996 0.75396998 -1.89086004 0 P 0 ;0
L 0.75396998 -1.89086004 0.75393996 -1.89076998 0 P 0 ;0
L 0.75393996 -1.89076998 0.7539 -1.89071004 0 P 0 ;0
L 0.7539 -1.89071004 0.75386004 -1.89066998 0 P 0 ;0
L 0.75386004 -1.89066998 0.75381004 -1.89063002 0 P 0 ;0
L 0.75381004 -1.89063002 0.75378996 -1.89061004 0 P 0 ;0
L 0.75378996 -1.89061004 0.75373002 -1.89058996 0 P 0 ;0
L 0.75373002 -1.89058996 0.75368002 -1.89056998 0 P 0 ;0
L 0.75368002 -1.89056998 0.75356004 -1.89056998 0 P 0 ;0
L 0.75356004 -1.89056998 0.75346998 -1.8906 0 P 0 ;0
L 0.75346998 -1.8906 0.74898002 -1.8927 0 P 0 ;0
L 0.74898002 -1.8927 0.74383002 -1.89518002 0 P 0 ;0
L 0.74383002 -1.89518002 0.73781004 -1.8982 0 P 0 ;0
L 0.69776998 -2.22761998 0.96701004 -2.22761998 0 P 0 ;0
L 0.6957 -2.22661998 0.96968996 -2.22661998 0 P 0 ;0
L 0.69366998 -2.22561998 0.97238002 -2.22561998 0 P 0 ;0
L 0.69163002 -2.22461998 0.97506004 -2.22461998 0 P 0 ;0
L 0.68958996 -2.22361998 0.97775 -2.22361998 0 P 0 ;0
L 0.68756004 -2.22261998 0.98043002 -2.22261998 0 P 0 ;0
L 0.68551998 -2.22161998 0.98311004 -2.22161998 0 P 0 ;0
L 0.68348996 -2.22061998 0.9858 -2.22061998 0 P 0 ;0
L 0.68176998 -2.21961998 0.98848002 -2.21961998 0 P 0 ;0
L 0.68003996 -2.21861998 0.99116998 -2.21861998 0 P 0 ;0
L 0.67831004 -2.21761998 0.99385 -2.21761998 0 P 0 ;0
L 0.67658002 -2.21661998 0.99653996 -2.21661998 0 P 0 ;0
L 0.67485 -2.21561998 0.99908002 -2.21561998 0 P 0 ;0
L 0.67311998 -2.21461998 0.87665 -2.21461998 0 P 0 ;0
L 0.6714 -2.21361998 0.85166004 -2.21361998 0 P 0 ;0
L 0.6699 -2.21261998 0.84083002 -2.21261998 0 P 0 ;0
L 0.66845 -2.21161998 0.8334 -2.21161998 0 P 0 ;0
L 0.66698996 -2.21061998 0.8274 -2.21061998 0 P 0 ;0
L 0.66553002 -2.20961998 0.82138996 -2.20961998 0 P 0 ;0
L 0.66406998 -2.20861998 0.81583002 -2.20861998 0 P 0 ;0
L 0.66261998 -2.20761998 0.81143996 -2.20761998 0 P 0 ;0
L 0.66116004 -2.20661998 0.80706004 -2.20661998 0 P 0 ;0
L 0.6597 -2.20561998 0.80266998 -2.20561998 0 P 0 ;0
L 0.65841004 -2.20461998 0.79828996 -2.20461998 0 P 0 ;0
L 0.65716998 -2.20361998 0.79448996 -2.20361998 0 P 0 ;0
L 0.65593002 -2.20261998 0.79106004 -2.20261998 0 P 0 ;0
L 0.65468996 -2.20161998 0.78763996 -2.20161998 0 P 0 ;0
L 0.83143002 -2.25261998 0.80871998 -2.25225 0 P 0 ;0
L 0.80871998 -2.25225 0.78691998 -2.25066998 0 P 0 ;0
L 0.78691998 -2.25066998 0.76525 -2.24786998 0 P 0 ;0
L 0.76525 -2.24786998 0.74581998 -2.24403996 0 P 0 ;0
L 0.74581998 -2.24403996 0.72671004 -2.23876004 0 P 0 ;0
L 0.72671004 -2.23876004 0.71196004 -2.23356998 0 P 0 ;0
L 0.71196004 -2.23356998 0.69756998 -2.22753996 0 P 0 ;0
L 0.69756998 -2.22753996 0.68355 -2.22066004 0 P 0 ;0
L 0.68355 -2.22066004 0.67118002 -2.2135 0 P 0 ;0
L 0.67118002 -2.2135 0.65938996 -2.20541004 0 P 0 ;0
L 0.65938996 -2.20541004 0.64825 -2.19643996 0 P 0 ;0
L 0.64825 -2.19643996 0.63861998 -2.18731998 0 P 0 ;0
L 0.63861998 -2.18731998 0.62983002 -2.17746998 0 P 0 ;0
L 0.62983002 -2.17746998 0.62188996 -2.1669 0 P 0 ;0
L 0.62188996 -2.1669 0.61678002 -2.15886998 0 P 0 ;0
L 0.61678002 -2.15886998 0.6123 -2.15056004 0 P 0 ;0
L 0.6123 -2.15056004 0.60841998 -2.14193996 0 P 0 ;0
L 0.60841998 -2.14193996 0.60516998 -2.13306998 0 P 0 ;0
L 0.60516998 -2.13306998 0.60191004 -2.12171004 0 P 0 ;0
L 0.60191004 -2.12171004 0.60075 -2.11648002 0 P 0 ;0
L 0.60075 -2.11648002 0.59983996 -2.11121004 0 P 0 ;0
L 0.59983996 -2.11121004 0.59913996 -2.10576004 0 P 0 ;0
L 0.59913996 -2.10576004 0.59868996 -2.10026004 0 P 0 ;0
L 0.59868996 -2.10026004 0.59833002 -2.0875 0 P 0 ;0
L 0.59833002 -2.0875 0.59856998 -2.07843996 0 P 0 ;0
L 0.59856998 -2.07843996 0.59923996 -2.0695 0 P 0 ;0
L 0.59923996 -2.0695 0.60031998 -2.06153996 0 P 0 ;0
L 0.60031998 -2.06153996 0.60193002 -2.05368996 0 P 0 ;0
L 0.60193002 -2.05368996 0.60416004 -2.04566004 0 P 0 ;0
L 0.60416004 -2.04566004 0.60688996 -2.03786004 0 P 0 ;0
L 0.60688996 -2.03786004 0.6148 -2.01961004 0 P 0 ;0
L 0.6148 -2.01961004 0.62108996 -2.00753002 0 P 0 ;0
L 0.62108996 -2.00753002 0.62811998 -1.99591998 0 P 0 ;0
L 0.62811998 -1.99591998 0.63583996 -1.98478996 0 P 0 ;0
L 0.63583996 -1.98478996 0.64936998 -1.96808002 0 P 0 ;0
L 0.64936998 -1.96808002 0.66418002 -1.95256998 0 P 0 ;0
L 0.66418002 -1.95256998 0.68098002 -1.93756004 0 P 0 ;0
L 0.68098002 -1.93756004 0.69881998 -1.92398002 0 P 0 ;0
L 0.69881998 -1.92398002 0.71841998 -1.91123996 0 P 0 ;0
L 0.71841998 -1.91123996 0.73875 -1.89996998 0 P 0 ;0
L 0.73875 -1.89996998 0.74471004 -1.89696998 0 P 0 ;0
L 0.74471004 -1.89696998 0.74983002 -1.89451004 0 P 0 ;0
L 0.74983002 -1.89451004 0.7511 -1.89391004 0 P 0 ;0
L 0.7511 -1.89391004 0.75076998 -1.89488996 0 P 0 ;0
L 0.75076998 -1.89488996 0.75033996 -1.89658996 0 P 0 ;0
L 0.75033996 -1.89658996 0.75003002 -1.8983 0 P 0 ;0
L 0.75003002 -1.8983 0.74961998 -1.90161998 0 P 0 ;0
L 0.74961998 -1.90161998 0.74936004 -1.90496004 0 P 0 ;0
L 0.74936004 -1.90496004 0.74926998 -1.9085 0 P 0 ;0
L 0.74926998 -1.9085 0.74933002 -1.91201998 0 P 0 ;0
L 0.74933002 -1.91201998 0.74956004 -1.91516998 0 P 0 ;0
L 0.74956004 -1.91516998 0.75 -1.91828996 0 P 0 ;0
L 0.75 -1.91828996 0.75075 -1.92205 0 P 0 ;0
L 0.75075 -1.92205 0.75166004 -1.92573996 0 P 0 ;0
L 0.75166004 -1.92573996 0.7527 -1.92916998 0 P 0 ;0
L 0.7527 -1.92916998 0.75393996 -1.93253002 0 P 0 ;0
L 0.75393996 -1.93253002 0.75536004 -1.93581998 0 P 0 ;0
L 0.75536004 -1.93581998 0.75696004 -1.939 0 P 0 ;0
L 0.75696004 -1.939 0.75885 -1.94231004 0 P 0 ;0
L 0.75885 -1.94231004 0.76083996 -1.94543996 0 P 0 ;0
L 0.76083996 -1.94543996 0.76338996 -1.94933996 0 P 0 ;0
L 0.76338996 -1.94933996 0.76371998 -1.94991998 0 P 0 ;0
L 0.76371998 -1.94991998 0.76401004 -1.9505 0 P 0 ;0
L 0.76401004 -1.9505 0.76423996 -1.95103002 0 P 0 ;0
L 0.76423996 -1.95103002 0.76408996 -1.95111004 0 P 0 ;0
L 0.76408996 -1.95111004 0.76348996 -1.95151004 0 P 0 ;0
L 0.76348996 -1.95151004 0.76021004 -1.95386004 0 P 0 ;0
L 0.76021004 -1.95386004 0.7602 -1.95386998 0 P 0 ;0
L 0.7602 -1.95386998 0.75636998 -1.95666004 0 P 0 ;0
L 0.75636998 -1.95666004 0.75636004 -1.95666998 0 P 0 ;0
L 0.75636004 -1.95666998 0.75635 -1.95666998 0 P 0 ;0
L 0.75635 -1.95666998 0.75208996 -1.95981004 0 P 0 ;0
L 0.75208996 -1.95981004 0.73841004 -1.97066998 0 P 0 ;0
L 0.73841004 -1.97066998 0.72541004 -1.98241004 0 P 0 ;0
L 0.72541004 -1.98241004 0.7143 -1.994 0 P 0 ;0
L 0.7143 -1.994 0.71425 -1.99406004 0 P 0 ;0
L 0.71425 -1.99406004 0.70413996 -2.00648002 0 P 0 ;0
L 0.70413996 -2.00648002 0.69836998 -2.01468996 0 P 0 ;0
L 0.69836998 -2.01468996 0.69313002 -2.02318002 0 P 0 ;0
L 0.69313002 -2.02318002 0.68838996 -2.03196004 0 P 0 ;0
L 0.68838996 -2.03196004 0.68438996 -2.04063996 0 P 0 ;0
L 0.68438996 -2.04063996 0.68098996 -2.04958002 0 P 0 ;0
L 0.68098996 -2.04958002 0.6782 -2.05873002 0 P 0 ;0
L 0.6782 -2.05873002 0.67706004 -2.06366004 0 P 0 ;0
L 0.67706004 -2.06366004 0.67628996 -2.06866998 0 P 0 ;0
L 0.67628996 -2.06866998 0.67538002 -2.08068996 0 P 0 ;0
L 0.67538002 -2.08068996 0.67546004 -2.09268996 0 P 0 ;0
L 0.67546004 -2.09268996 0.67588996 -2.09766998 0 P 0 ;0
L 0.67588996 -2.09766998 0.6767 -2.10258996 0 P 0 ;0
L 0.6767 -2.10258996 0.67881998 -2.11111998 0 P 0 ;0
L 0.67881998 -2.11111998 0.68163996 -2.11936004 0 P 0 ;0
L 0.68163996 -2.11936004 0.68516004 -2.12731998 0 P 0 ;0
L 0.68516004 -2.12731998 0.68935 -2.13493996 0 P 0 ;0
L 0.68935 -2.13493996 0.69418002 -2.14216998 0 P 0 ;0
L 0.69418002 -2.14216998 0.70153002 -2.15135 0 P 0 ;0
L 0.70153002 -2.15135 0.7096 -2.15983002 0 P 0 ;0
L 0.7096 -2.15983002 0.71836004 -2.16758996 0 P 0 ;0
L 0.71836004 -2.16758996 0.71843002 -2.16763996 0 P 0 ;0
L 0.71843002 -2.16763996 0.72773996 -2.17456004 0 P 0 ;0
L 0.72773996 -2.17456004 0.73926998 -2.1818 0 P 0 ;0
L 0.73926998 -2.1818 0.75121004 -2.18818002 0 P 0 ;0
L 0.75121004 -2.18818002 0.75128002 -2.18821004 0 P 0 ;0
L 0.75128002 -2.18821004 0.76358002 -2.19368996 0 P 0 ;0
L 0.76358002 -2.19368996 0.77628002 -2.19831004 0 P 0 ;0
L 0.77628002 -2.19831004 0.79658996 -2.20423996 0 P 0 ;0
L 0.79658996 -2.20423996 0.81701004 -2.20888996 0 P 0 ;0
L 0.81701004 -2.20888996 0.83763996 -2.21233002 0 P 0 ;0
L 0.83763996 -2.21233002 0.85388002 -2.21383002 0 P 0 ;0
L 0.85388002 -2.21383002 0.87733996 -2.21465 0 P 0 ;0
L 0.87733996 -2.21465 0.90118002 -2.21478996 0 P 0 ;0
L 0.90118002 -2.21478996 0.91906004 -2.21398996 0 P 0 ;0
L 0.91906004 -2.21398996 0.94908996 -2.21068002 0 P 0 ;0
L 0.94908996 -2.21068002 0.98176998 -2.2053 0 P 0 ;0
L 0.98176998 -2.2053 1.01575 -2.19815 0 P 0 ;0
L 1.01575 -2.19815 1.04968002 -2.18943002 0 P 0 ;0
L 1.04968002 -2.18943002 1.05633996 -2.18761004 0 P 0 ;0
L 1.05633996 -2.18761004 1.05713996 -2.1874 0 P 0 ;0
L 1.05713996 -2.1874 1.05483002 -2.18875 0 P 0 ;0
L 1.05483002 -2.18875 1.04298996 -2.19526004 0 P 0 ;0
L 1.04298996 -2.19526004 1.03096998 -2.20136998 0 P 0 ;0
L 1.03096998 -2.20136998 0.99835 -2.21595 0 P 0 ;0
L 0.99835 -2.21595 0.96401998 -2.22873996 0 P 0 ;0
L 0.96401998 -2.22873996 0.92993996 -2.23908002 0 P 0 ;0
L 0.92993996 -2.23908002 0.89816004 -2.24626004 0 P 0 ;0
L 0.89816004 -2.24626004 0.87616004 -2.24965 0 P 0 ;0
L 0.87616004 -2.24965 0.85405 -2.25176004 0 P 0 ;0
L 0.85405 -2.25176004 0.83143002 -2.25261998 0 P 0 ;0
L 0.65345 -2.20061998 0.78421004 -2.20061998 0 P 0 ;0
L 0.65221004 -2.19961998 0.78078002 -2.19961998 0 P 0 ;0
L 0.65096004 -2.19861998 0.77735 -2.19861998 0 P 0 ;0
L 0.64971998 -2.19761998 0.77438996 -2.19761998 0 P 0 ;0
L 0.64848002 -2.19661998 0.77163996 -2.19661998 0 P 0 ;0
L 0.64738996 -2.19561998 0.76888996 -2.19561998 0 P 0 ;0
L 0.64633996 -2.19461998 0.76613996 -2.19461998 0 P 0 ;0
L 0.64528002 -2.19361998 0.76343002 -2.19361998 0 P 0 ;0
L 0.64421998 -2.19261998 0.76118996 -2.19261998 0 P 0 ;0
L 0.64316998 -2.19161998 0.75893996 -2.19161998 0 P 0 ;0
L 0.64211004 -2.19061998 0.7567 -2.19061998 0 P 0 ;0
L 0.64106004 -2.18961998 0.75446004 -2.18961998 0 P 0 ;0
L 0.64 -2.18861998 0.75221004 -2.18861998 0 P 0 ;0
L 0.63895 -2.18761998 0.75018002 -2.18761998 0 P 0 ;0
L 0.63801004 -2.18661998 0.74831004 -2.18661998 0 P 0 ;0
L 0.63711004 -2.18561998 0.74643002 -2.18561998 0 P 0 ;0
L 0.63621998 -2.18461998 0.74456004 -2.18461998 0 P 0 ;0
L 0.63533002 -2.18361998 0.74268002 -2.18361998 0 P 0 ;0
L 0.63443996 -2.18261998 0.74081004 -2.18261998 0 P 0 ;0
L 0.63353996 -2.18161998 0.73898996 -2.18161998 0 P 0 ;0
L 0.63265 -2.18061998 0.73738996 -2.18061998 0 P 0 ;0
L 0.63176004 -2.17961998 0.7358 -2.17961998 0 P 0 ;0
L 0.63086998 -2.17861998 0.73421004 -2.17861998 0 P 0 ;0
L 0.62996998 -2.17761998 0.73261998 -2.17761998 0 P 0 ;0
L 0.6292 -2.17661998 0.73103002 -2.17661998 0 P 0 ;0
L 0.62845 -2.17561998 0.72943996 -2.17561998 0 P 0 ;0
L 0.6277 -2.17461998 0.72783996 -2.17461998 0 P 0 ;0
L 0.62693996 -2.17361998 0.72648002 -2.17361998 0 P 0 ;0
L 0.62618996 -2.17261998 0.72513996 -2.17261998 0 P 0 ;0
L 0.62543996 -2.17161998 0.72378996 -2.17161998 0 P 0 ;0
L 0.62468996 -2.17061998 0.72245 -2.17061998 0 P 0 ;0
L 0.62393996 -2.16961998 0.7211 -2.16961998 0 P 0 ;0
L 0.62318002 -2.16861998 0.71976004 -2.16861998 0 P 0 ;0
L 0.62243996 -2.16761998 0.71841004 -2.16761998 0 P 0 ;0
L 0.62171004 -2.16661998 0.71726998 -2.16661998 0 P 0 ;0
L 0.62108002 -2.16561998 0.71613996 -2.16561998 0 P 0 ;0
L 0.62043996 -2.16461998 0.71501004 -2.16461998 0 P 0 ;0
L 0.61981004 -2.16361998 0.71388002 -2.16361998 0 P 0 ;0
L 0.61916998 -2.16261998 0.71276004 -2.16261998 0 P 0 ;0
L 0.61853002 -2.16161998 0.71163002 -2.16161998 0 P 0 ;0
L 0.6179 -2.16061998 0.7105 -2.16061998 0 P 0 ;0
L 0.61726004 -2.15961998 0.7094 -2.15961998 0 P 0 ;0
L 0.61665 -2.15861998 0.70845 -2.15861998 0 P 0 ;0
L 0.61611004 -2.15761998 0.7075 -2.15761998 0 P 0 ;0
L 0.75383996 -2.24561998 0.901 -2.24561998 0 P 0 ;0
L 0.74876998 -2.24461998 0.90541998 -2.24461998 0 P 0 ;0
L 0.74431004 -2.24361998 0.90985 -2.24361998 0 P 0 ;0
L 0.7407 -2.24261998 0.91426998 -2.24261998 0 P 0 ;0
L 0.73708002 -2.24161998 0.9187 -2.24161998 0 P 0 ;0
L 0.73346998 -2.24061998 0.92311998 -2.24061998 0 P 0 ;0
L 0.72986004 -2.23961998 0.92753996 -2.23961998 0 P 0 ;0
L 0.72633996 -2.23861998 0.93145 -2.23861998 0 P 0 ;0
L 0.72348996 -2.23761998 0.93473996 -2.23761998 0 P 0 ;0
L 0.72063996 -2.23661998 0.93803996 -2.23661998 0 P 0 ;0
L 0.7178 -2.23561998 0.94133002 -2.23561998 0 P 0 ;0
L 0.71495 -2.23461998 0.94461998 -2.23461998 0 P 0 ;0
L 0.7121 -2.23361998 0.94791998 -2.23361998 0 P 0 ;0
L 0.70968996 -2.23261998 0.95121004 -2.23261998 0 P 0 ;0
L 0.70731004 -2.23161998 0.95451004 -2.23161998 0 P 0 ;0
L 0.70491998 -2.23061998 0.9578 -2.23061998 0 P 0 ;0
L 0.70253996 -2.22961998 0.9611 -2.22961998 0 P 0 ;0
L 0.70015 -2.22861998 0.96431998 -2.22861998 0 P 0 ;0
P 7.17716998 5.7874 22 P 0 0;5=22
P 7.17716998 0.23621998 22 P 0 0;5=22
P 0.22245 0.68898002 21 P 0 0;5=23
P 0.22245 5.11811004 21 P 0 0;5=23
P 12.68701998 5.15748002 21 P 0 0;5=23
P 12.68701998 0.72835 21 P 0 0;5=23
P 6.11811004 1.52756004 21 P 0 0;5=23
P 6.11811004 4.20473002 21 P 0 0;5=23
P 4.83268002 4.22441004 21 P 0 0;5=23
P 2.24606004 4.22441004 21 P 0 0;5=23
P 0.96063002 4.20473002 21 P 0 0;5=23
P 0.96063002 1.52756004 21 P 0 0;5=23
P 2.24606004 1.50786998 21 P 0 0;5=23
P 4.83268002 1.50786998 21 P 0 0;5=23
P 6.04921004 2.58268002 20 P 0 0;5=24
P 1.05905 2.58268002 29 P 0 0;5=25
P 12.12205 1.52756004 21 P 0 0;5=23
P 12.12205 4.20473002 21 P 0 0;5=23
P 10.83661998 4.22441004 21 P 0 0;5=23
P 8.25 4.22441004 21 P 0 0;5=23
P 6.96456998 4.20473002 21 P 0 0;5=23
P 6.96456998 1.52756004 21 P 0 0;5=23
P 8.25 1.50786998 21 P 0 0;5=23
P 10.83661998 1.50786998 21 P 0 0;5=23
P 12.05315 2.58268002 20 P 0 0;5=24
P 7.06298996 2.58268002 29 P 0 0;5=25
P 12.33465 5.69528002 17 P 0 0;5=26
P 3.58311004 4.91851004 13 P 0 0;5=27
P 2.72091004 4.91851004 13 P 0 0;5=27
P 9.58665 4.91851004 13 P 0 0;5=27
P 8.72445 4.91851004 13 P 0 0;5=27
P 2.41851004 4.91851004 13 P 0 0;5=27
P 1.55631004 4.91851004 13 P 0 0;5=27
P 8.42205 4.91851004 13 P 0 0;5=27
P 7.55985 4.91851004 13 P 0 0;5=27
P 0.22243996 1.79331004 15 P 0 0;5=28
P 0.22243996 4.67323002 15 P 0 0;5=28
P 12.687 1.83268002 15 P 0 0;5=28
P 12.687 4.7126 15 P 0 0;5=28
P 0.7687 5.62008002 9 P 0 0;5=29
P 1.47736004 5.62008002 9 P 0 0;5=29
L 0.67881998 -0.44173002 0.69063002 -0.44173002 1 P 0 
A 0.69063002 -0.44173002 0.69851398 -0.41810512 0.69851004 -0.43123179 1 P 0 Y
A 0.69851398 -0.41810512 0.70638002 -0.44173002 0.69851004 -0.43122844 1 P 0 Y
L 0.70638002 -0.44173002 0.71818996 -0.44173002 1 P 0 
L 0.76211004 -0.44173002 0.76211004 -0.41673002 2 P 0 ;0,4,6=30,8=0.000000
L 0.76211004 -0.41673002 0.77197707 -0.43464675 2 P 0 ;0,4,6=30,8=0.000000
L 0.77197707 -0.43464675 0.75864311 -0.43464675 2 P 0 ;0,4,6=30,8=0.000000
L 0.74717677 -0.43798091 0.74557707 -0.44006378 2 P 0 ;0,4,6=30,8=0.000000
L 0.74557707 -0.44006378 0.74371033 -0.44131348 2 P 0 ;0,4,6=30,8=0.000000
L 0.74371033 -0.44131348 0.74131033 -0.44173002 2 P 0 ;0,4,6=30,8=0.000000
L 0.74131033 -0.44173002 0.73890984 -0.44089695 2 P 0 ;0,4,6=30,8=0.000000
L 0.73890984 -0.44089695 0.7370436 -0.43923061 2 P 0 ;0,4,6=30,8=0.000000
L 0.7370436 -0.43923061 0.73571004 -0.43631378 2 P 0 ;0,4,6=30,8=0.000000
L 0.73571004 -0.43631378 0.73544341 -0.43298041 2 P 0 ;0,4,6=30,8=0.000000
L 0.73544341 -0.43298041 0.73597667 -0.42964705 2 P 0 ;0,4,6=30,8=0.000000
L 0.73597667 -0.42964705 0.73731024 -0.42756339 2 P 0 ;0,4,6=30,8=0.000000
L 0.73731024 -0.42756339 0.73917697 -0.42589705 2 P 0 ;0,4,6=30,8=0.000000
L 0.73917697 -0.42589705 0.74104321 -0.42548051 2 P 0 ;0,4,6=30,8=0.000000
L 0.74104321 -0.42548051 0.74291004 -0.42589705 2 P 0 ;0,4,6=30,8=0.000000
L 0.74291004 -0.42589705 0.74530994 -0.42756339 2 P 0 ;0,4,6=30,8=0.000000
L 0.74530994 -0.42756339 0.74451014 -0.41673002 2 P 0 ;0,4,6=30,8=0.000000
L 0.74451014 -0.41673002 0.73731024 -0.41673002 2 P 0 ;0,4,6=30,8=0.000000
L 0.75202343 -0.15583002 0.75202343 -0.18083002 2 P 0 ;0,4,6=31,8=0.000000
L 0.75202343 -0.18083002 0.74135659 -0.18083002 2 P 0 ;0,4,6=31,8=0.000000
L 0.72269026 -0.18083002 0.72269026 -0.15583002 2 P 0 ;0,4,6=31,8=0.000000
L 0.72269026 -0.15583002 0.72589006 -0.16082972 2 P 0 ;0,4,6=31,8=0.000000
L 0.72589006 -0.18083002 0.71949045 -0.18083002 2 P 0 ;0,4,6=31,8=0.000000
L 0.70375679 -0.15999665 0.70215669 -0.15749715 2 P 0 ;0,4,6=31,8=0.000000
L 0.70215669 -0.15749715 0.70028996 -0.15624665 2 P 0 ;0,4,6=31,8=0.000000
L 0.70028996 -0.15624665 0.69815659 -0.15583002 2 P 0 ;0,4,6=31,8=0.000000
L 0.69815659 -0.15583002 0.69548996 -0.15666319 2 P 0 ;0,4,6=31,8=0.000000
L 0.69548996 -0.15666319 0.69362323 -0.15874685 2 P 0 ;0,4,6=31,8=0.000000
L 0.69362323 -0.15874685 0.69308996 -0.16124636 2 P 0 ;0,4,6=31,8=0.000000
L 0.69308996 -0.16124636 0.69335659 -0.16374734 2 P 0 ;0,4,6=31,8=0.000000
L 0.69335659 -0.16374734 0.69442352 -0.16583022 2 P 0 ;0,4,6=31,8=0.000000
L 0.69442352 -0.16583022 0.69975669 -0.16999675 2 P 0 ;0,4,6=31,8=0.000000
L 0.69975669 -0.16999675 0.70215669 -0.17291358 2 P 0 ;0,4,6=31,8=0.000000
L 0.70215669 -0.17291358 0.70375679 -0.17708091 2 P 0 ;0,4,6=31,8=0.000000
L 0.70375679 -0.17708091 0.70429006 -0.18083002 2 P 0 ;0,4,6=31,8=0.000000
L 0.70429006 -0.18083002 0.69308996 -0.18083002 2 P 0 ;0,4,6=31,8=0.000000
L 0.82881998 -0.44173002 0.84063002 -0.44173002 1 P 0 
A 0.84063002 -0.44173002 0.84851398 -0.41810512 0.84851004 -0.43123179 1 P 0 Y
A 0.84851398 -0.41810512 0.85638002 -0.44173002 0.84851004 -0.43122844 1 P 0 Y
L 0.85638002 -0.44173002 0.86818996 -0.44173002 1 P 0 
L 0.91211004 -0.44173002 0.91211004 -0.41673002 2 P 0 ;0,4,6=30,8=0.000000
L 0.91211004 -0.41673002 0.92197707 -0.43464675 2 P 0 ;0,4,6=30,8=0.000000
L 0.92197707 -0.43464675 0.90864311 -0.43464675 2 P 0 ;0,4,6=30,8=0.000000
L 0.89717677 -0.43798091 0.89557707 -0.44006378 2 P 0 ;0,4,6=30,8=0.000000
L 0.89557707 -0.44006378 0.89371033 -0.44131348 2 P 0 ;0,4,6=30,8=0.000000
L 0.89371033 -0.44131348 0.89131033 -0.44173002 2 P 0 ;0,4,6=30,8=0.000000
L 0.89131033 -0.44173002 0.88890984 -0.44089695 2 P 0 ;0,4,6=30,8=0.000000
L 0.88890984 -0.44089695 0.8870436 -0.43923061 2 P 0 ;0,4,6=30,8=0.000000
L 0.8870436 -0.43923061 0.88571004 -0.43631378 2 P 0 ;0,4,6=30,8=0.000000
L 0.88571004 -0.43631378 0.88544341 -0.43298041 2 P 0 ;0,4,6=30,8=0.000000
L 0.88544341 -0.43298041 0.88597667 -0.42964705 2 P 0 ;0,4,6=30,8=0.000000
L 0.88597667 -0.42964705 0.88731024 -0.42756339 2 P 0 ;0,4,6=30,8=0.000000
L 0.88731024 -0.42756339 0.88917697 -0.42589705 2 P 0 ;0,4,6=30,8=0.000000
L 0.88917697 -0.42589705 0.89104321 -0.42548051 2 P 0 ;0,4,6=30,8=0.000000
L 0.89104321 -0.42548051 0.89291004 -0.42589705 2 P 0 ;0,4,6=30,8=0.000000
L 0.89291004 -0.42589705 0.89530994 -0.42756339 2 P 0 ;0,4,6=30,8=0.000000
L 0.89530994 -0.42756339 0.89451014 -0.41673002 2 P 0 ;0,4,6=30,8=0.000000
L 0.89451014 -0.41673002 0.88731024 -0.41673002 2 P 0 ;0,4,6=30,8=0.000000
L 0.90202343 -0.15583002 0.90202343 -0.18083002 2 P 0 ;0,4,6=32,8=0.000000
L 0.90202343 -0.18083002 0.89135659 -0.18083002 2 P 0 ;0,4,6=32,8=0.000000
L 0.87269026 -0.18083002 0.87269026 -0.15583002 2 P 0 ;0,4,6=32,8=0.000000
L 0.87269026 -0.15583002 0.87589006 -0.16082972 2 P 0 ;0,4,6=32,8=0.000000
L 0.87589006 -0.18083002 0.86949045 -0.18083002 2 P 0 ;0,4,6=32,8=0.000000
L 0.84869026 -0.15583002 0.85082362 -0.15666319 2 P 0 ;0,4,6=32,8=0.000000
L 0.85082362 -0.15666319 0.85242333 -0.15874685 2 P 0 ;0,4,6=32,8=0.000000
L 0.85242333 -0.15874685 0.85349016 -0.16124636 2 P 0 ;0,4,6=32,8=0.000000
L 0.85349016 -0.16124636 0.85429006 -0.16458051 2 P 0 ;0,4,6=32,8=0.000000
L 0.85429006 -0.16458051 0.85455669 -0.16833041 2 P 0 ;0,4,6=32,8=0.000000
L 0.85455669 -0.16833041 0.85429006 -0.17208041 2 P 0 ;0,4,6=32,8=0.000000
L 0.85429006 -0.17208041 0.85349016 -0.17541378 2 P 0 ;0,4,6=32,8=0.000000
L 0.85349016 -0.17541378 0.85242333 -0.17791398 2 P 0 ;0,4,6=32,8=0.000000
L 0.85242333 -0.17791398 0.85082362 -0.17999695 2 P 0 ;0,4,6=32,8=0.000000
L 0.85082362 -0.17999695 0.84869026 -0.18083002 2 P 0 ;0,4,6=32,8=0.000000
L 0.84869026 -0.18083002 0.84655689 -0.17999695 2 P 0 ;0,4,6=32,8=0.000000
L 0.84655689 -0.17999695 0.84495669 -0.17791398 2 P 0 ;0,4,6=32,8=0.000000
L 0.84495669 -0.17791398 0.84388986 -0.17541378 2 P 0 ;0,4,6=32,8=0.000000
L 0.84388986 -0.17541378 0.84308996 -0.17208041 2 P 0 ;0,4,6=32,8=0.000000
L 0.84308996 -0.17208041 0.84282333 -0.16833041 2 P 0 ;0,4,6=32,8=0.000000
L 0.84282333 -0.16833041 0.84308996 -0.16458051 2 P 0 ;0,4,6=32,8=0.000000
L 0.84308996 -0.16458051 0.84388986 -0.16124636 2 P 0 ;0,4,6=32,8=0.000000
L 0.84388986 -0.16124636 0.84495669 -0.15874685 2 P 0 ;0,4,6=32,8=0.000000
L 0.84495669 -0.15874685 0.84655689 -0.15666319 2 P 0 ;0,4,6=32,8=0.000000
L 0.84655689 -0.15666319 0.84869026 -0.15583002 2 P 0 ;0,4,6=32,8=0.000000
L 0.98381998 -0.44173002 0.99563002 -0.44173002 1 P 0 
A 0.99563002 -0.44173002 1.00351398 -0.41810512 1.00351004 -0.43123179 1 P 0 Y
A 1.00351398 -0.41810512 1.01138002 -0.44173002 1.00351004 -0.43122844 1 P 0 Y
L 1.01138002 -0.44173002 1.02318996 -0.44173002 1 P 0 
L 1.06711004 -0.44173002 1.06711004 -0.41673002 2 P 0 ;0,4,6=30,8=0.000000
L 1.06711004 -0.41673002 1.07697707 -0.43464675 2 P 0 ;0,4,6=30,8=0.000000
L 1.07697707 -0.43464675 1.06364311 -0.43464675 2 P 0 ;0,4,6=30,8=0.000000
L 1.05217677 -0.43798091 1.05057707 -0.44006378 2 P 0 ;0,4,6=30,8=0.000000
L 1.05057707 -0.44006378 1.04871033 -0.44131348 2 P 0 ;0,4,6=30,8=0.000000
L 1.04871033 -0.44131348 1.04631033 -0.44173002 2 P 0 ;0,4,6=30,8=0.000000
L 1.04631033 -0.44173002 1.04390984 -0.44089695 2 P 0 ;0,4,6=30,8=0.000000
L 1.04390984 -0.44089695 1.0420436 -0.43923061 2 P 0 ;0,4,6=30,8=0.000000
L 1.0420436 -0.43923061 1.04071004 -0.43631378 2 P 0 ;0,4,6=30,8=0.000000
L 1.04071004 -0.43631378 1.04044341 -0.43298041 2 P 0 ;0,4,6=30,8=0.000000
L 1.04044341 -0.43298041 1.04097667 -0.42964705 2 P 0 ;0,4,6=30,8=0.000000
L 1.04097667 -0.42964705 1.04231024 -0.42756339 2 P 0 ;0,4,6=30,8=0.000000
L 1.04231024 -0.42756339 1.04417697 -0.42589705 2 P 0 ;0,4,6=30,8=0.000000
L 1.04417697 -0.42589705 1.04604321 -0.42548051 2 P 0 ;0,4,6=30,8=0.000000
L 1.04604321 -0.42548051 1.04791004 -0.42589705 2 P 0 ;0,4,6=30,8=0.000000
L 1.04791004 -0.42589705 1.05030994 -0.42756339 2 P 0 ;0,4,6=30,8=0.000000
L 1.05030994 -0.42756339 1.04951014 -0.41673002 2 P 0 ;0,4,6=30,8=0.000000
L 1.04951014 -0.41673002 1.04231024 -0.41673002 2 P 0 ;0,4,6=30,8=0.000000
L 1.0426435 -0.15416998 1.0426435 -0.17916998 2 P 0 ;0,4,6=33,8=0.000000
L 1.0426435 -0.17916998 1.03197667 -0.17916998 2 P 0 ;0,4,6=33,8=0.000000
L 1.01917677 -0.17542087 1.01757707 -0.17750374 2 P 0 ;0,4,6=33,8=0.000000
L 1.01757707 -0.17750374 1.01571033 -0.17875344 2 P 0 ;0,4,6=33,8=0.000000
L 1.01571033 -0.17875344 1.01331033 -0.17916998 2 P 0 ;0,4,6=33,8=0.000000
L 1.01331033 -0.17916998 1.01090984 -0.17833691 2 P 0 ;0,4,6=33,8=0.000000
L 1.01090984 -0.17833691 1.0090436 -0.17667057 2 P 0 ;0,4,6=33,8=0.000000
L 1.0090436 -0.17667057 1.00771004 -0.17375374 2 P 0 ;0,4,6=33,8=0.000000
L 1.00771004 -0.17375374 1.00744341 -0.17042037 2 P 0 ;0,4,6=33,8=0.000000
L 1.00744341 -0.17042037 1.00797667 -0.16708701 2 P 0 ;0,4,6=33,8=0.000000
L 1.00797667 -0.16708701 1.00931024 -0.16500335 2 P 0 ;0,4,6=33,8=0.000000
L 1.00931024 -0.16500335 1.01117697 -0.16333701 2 P 0 ;0,4,6=33,8=0.000000
L 1.01117697 -0.16333701 1.01304321 -0.16292047 2 P 0 ;0,4,6=33,8=0.000000
L 1.01304321 -0.16292047 1.01491004 -0.16333701 2 P 0 ;0,4,6=33,8=0.000000
L 1.01491004 -0.16333701 1.01730994 -0.16500335 2 P 0 ;0,4,6=33,8=0.000000
L 1.01730994 -0.16500335 1.01651014 -0.15416998 2 P 0 ;0,4,6=33,8=0.000000
L 1.01651014 -0.15416998 1.00931024 -0.15416998 2 P 0 ;0,4,6=33,8=0.000000
L 1.12881998 -0.44173002 1.14063002 -0.44173002 1 P 0 
A 1.14063002 -0.44173002 1.14851398 -0.41810512 1.14851004 -0.43123179 1 P 0 Y
A 1.14851398 -0.41810512 1.15638002 -0.44173002 1.14851004 -0.43122844 1 P 0 Y
L 1.15638002 -0.44173002 1.16818996 -0.44173002 1 P 0 
L 1.21211004 -0.44173002 1.21211004 -0.41673002 2 P 0 ;0,4,6=30,8=0.000000
L 1.21211004 -0.41673002 1.22197707 -0.43464675 2 P 0 ;0,4,6=30,8=0.000000
L 1.22197707 -0.43464675 1.20864311 -0.43464675 2 P 0 ;0,4,6=30,8=0.000000
L 1.19717677 -0.43798091 1.19557707 -0.44006378 2 P 0 ;0,4,6=30,8=0.000000
L 1.19557707 -0.44006378 1.19371033 -0.44131348 2 P 0 ;0,4,6=30,8=0.000000
L 1.19371033 -0.44131348 1.19131033 -0.44173002 2 P 0 ;0,4,6=30,8=0.000000
L 1.19131033 -0.44173002 1.18890984 -0.44089695 2 P 0 ;0,4,6=30,8=0.000000
L 1.18890984 -0.44089695 1.1870436 -0.43923061 2 P 0 ;0,4,6=30,8=0.000000
L 1.1870436 -0.43923061 1.18571004 -0.43631378 2 P 0 ;0,4,6=30,8=0.000000
L 1.18571004 -0.43631378 1.18544341 -0.43298041 2 P 0 ;0,4,6=30,8=0.000000
L 1.18544341 -0.43298041 1.18597667 -0.42964705 2 P 0 ;0,4,6=30,8=0.000000
L 1.18597667 -0.42964705 1.18731024 -0.42756339 2 P 0 ;0,4,6=30,8=0.000000
L 1.18731024 -0.42756339 1.18917697 -0.42589705 2 P 0 ;0,4,6=30,8=0.000000
L 1.18917697 -0.42589705 1.19104321 -0.42548051 2 P 0 ;0,4,6=30,8=0.000000
L 1.19104321 -0.42548051 1.19291004 -0.42589705 2 P 0 ;0,4,6=30,8=0.000000
L 1.19291004 -0.42589705 1.19530994 -0.42756339 2 P 0 ;0,4,6=30,8=0.000000
L 1.19530994 -0.42756339 1.19451014 -0.41673002 2 P 0 ;0,4,6=30,8=0.000000
L 1.19451014 -0.41673002 1.18731024 -0.41673002 2 P 0 ;0,4,6=30,8=0.000000
L 1.1926435 -0.15416998 1.1926435 -0.17916998 2 P 0 ;0,4,6=34,8=0.000000
L 1.1926435 -0.17916998 1.18197667 -0.17916998 2 P 0 ;0,4,6=34,8=0.000000
L 1.16917677 -0.17417037 1.16757707 -0.17708711 2 P 0 ;0,4,6=34,8=0.000000
L 1.16757707 -0.17708711 1.1654437 -0.17875344 2 P 0 ;0,4,6=34,8=0.000000
L 1.1654437 -0.17875344 1.16304321 -0.17916998 2 P 0 ;0,4,6=34,8=0.000000
L 1.16304321 -0.17916998 1.16090984 -0.17875344 2 P 0 ;0,4,6=34,8=0.000000
L 1.16090984 -0.17875344 1.15877648 -0.17667057 2 P 0 ;0,4,6=34,8=0.000000
L 1.15877648 -0.17667057 1.15744341 -0.17417037 2 P 0 ;0,4,6=34,8=0.000000
L 1.15744341 -0.17417037 1.15717687 -0.17167008 2 P 0 ;0,4,6=34,8=0.000000
L 1.15717687 -0.17167008 1.15771004 -0.16875404 2 P 0 ;0,4,6=34,8=0.000000
L 1.15771004 -0.16875404 1.15957677 -0.16667037 2 P 0 ;0,4,6=34,8=0.000000
L 1.15957677 -0.16667037 1.1614436 -0.16583652 2 P 0 ;0,4,6=34,8=0.000000
L 1.1614436 -0.16583652 1.1638435 -0.16583652 2 P 0 ;0,4,6=34,8=0.000000
L 1.1614436 -0.16583652 1.15984341 -0.16458671 2 P 0 ;0,4,6=34,8=0.000000
L 1.15984341 -0.16458671 1.15850994 -0.16250384 2 P 0 ;0,4,6=34,8=0.000000
L 1.15850994 -0.16250384 1.15797667 -0.16000364 2 P 0 ;0,4,6=34,8=0.000000
L 1.15797667 -0.16000364 1.15850994 -0.15750344 2 P 0 ;0,4,6=34,8=0.000000
L 1.15850994 -0.15750344 1.15984341 -0.15542057 2 P 0 ;0,4,6=34,8=0.000000
L 1.15984341 -0.15542057 1.16224341 -0.15416998 2 P 0 ;0,4,6=34,8=0.000000
L 1.16224341 -0.15416998 1.16464341 -0.15458661 2 P 0 ;0,4,6=34,8=0.000000
L 1.16464341 -0.15458661 1.16704341 -0.15625364 2 P 0 ;0,4,6=34,8=0.000000
L 1.27881998 -0.44173002 1.29063002 -0.44173002 1 P 0 
A 1.29063002 -0.44173002 1.29851398 -0.41810512 1.29851004 -0.43123179 1 P 0 Y
A 1.29851398 -0.41810512 1.30638002 -0.44173002 1.29851004 -0.43122844 1 P 0 Y
L 1.30638002 -0.44173002 1.31818996 -0.44173002 1 P 0 
L 1.36211004 -0.44173002 1.36211004 -0.41673002 2 P 0 ;0,4,6=30,8=0.000000
L 1.36211004 -0.41673002 1.37197707 -0.43464675 2 P 0 ;0,4,6=30,8=0.000000
L 1.37197707 -0.43464675 1.35864311 -0.43464675 2 P 0 ;0,4,6=30,8=0.000000
L 1.34717677 -0.43798091 1.34557707 -0.44006378 2 P 0 ;0,4,6=30,8=0.000000
L 1.34557707 -0.44006378 1.34371033 -0.44131348 2 P 0 ;0,4,6=30,8=0.000000
L 1.34371033 -0.44131348 1.34131033 -0.44173002 2 P 0 ;0,4,6=30,8=0.000000
L 1.34131033 -0.44173002 1.33890984 -0.44089695 2 P 0 ;0,4,6=30,8=0.000000
L 1.33890984 -0.44089695 1.3370436 -0.43923061 2 P 0 ;0,4,6=30,8=0.000000
L 1.3370436 -0.43923061 1.33571004 -0.43631378 2 P 0 ;0,4,6=30,8=0.000000
L 1.33571004 -0.43631378 1.33544341 -0.43298041 2 P 0 ;0,4,6=30,8=0.000000
L 1.33544341 -0.43298041 1.33597667 -0.42964705 2 P 0 ;0,4,6=30,8=0.000000
L 1.33597667 -0.42964705 1.33731024 -0.42756339 2 P 0 ;0,4,6=30,8=0.000000
L 1.33731024 -0.42756339 1.33917697 -0.42589705 2 P 0 ;0,4,6=30,8=0.000000
L 1.33917697 -0.42589705 1.34104321 -0.42548051 2 P 0 ;0,4,6=30,8=0.000000
L 1.34104321 -0.42548051 1.34291004 -0.42589705 2 P 0 ;0,4,6=30,8=0.000000
L 1.34291004 -0.42589705 1.34530994 -0.42756339 2 P 0 ;0,4,6=30,8=0.000000
L 1.34530994 -0.42756339 1.34451014 -0.41673002 2 P 0 ;0,4,6=30,8=0.000000
L 1.34451014 -0.41673002 1.33731024 -0.41673002 2 P 0 ;0,4,6=30,8=0.000000
L 1.3426435 -0.15416998 1.3426435 -0.17916998 2 P 0 ;0,4,6=35,8=0.000000
L 1.3426435 -0.17916998 1.33197667 -0.17916998 2 P 0 ;0,4,6=35,8=0.000000
L 1.31331033 -0.17916998 1.31331033 -0.15416998 2 P 0 ;0,4,6=35,8=0.000000
L 1.31331033 -0.15416998 1.31651014 -0.15916969 2 P 0 ;0,4,6=35,8=0.000000
L 1.31651014 -0.17916998 1.31011053 -0.17916998 2 P 0 ;0,4,6=35,8=0.000000
L 0.68881998 6.42326998 0.70063002 6.42326998 1 P 0 
A 0.70063002 6.42326998 0.70851398 6.44689488 0.70851004 6.43376821 1 P 0 Y
A 0.70851398 6.44689488 0.71638002 6.42326998 0.70851004 6.43377156 1 P 0 Y
L 0.71638002 6.42326998 0.72818996 6.42326998 1 P 0 
L 0.77531033 6.42326998 0.7734436 6.42368652 2 P 0 ;0,4,6=36,8=0.000000
L 0.7734436 6.42368652 0.77131024 6.42493622 2 P 0 ;0,4,6=36,8=0.000000
L 0.77131024 6.42493622 0.76997667 6.42701909 2 P 0 ;0,4,6=36,8=0.000000
L 0.76997667 6.42701909 0.76944341 6.42993671 2 P 0 ;0,4,6=36,8=0.000000
L 0.76944341 6.42993671 0.76997667 6.43285276 2 P 0 ;0,4,6=36,8=0.000000
L 0.76997667 6.43285276 0.77157677 6.43535295 2 P 0 ;0,4,6=36,8=0.000000
L 0.77157677 6.43535295 0.77397677 6.43660344 2 P 0 ;0,4,6=36,8=0.000000
L 0.77397677 6.43660344 0.77664341 6.43660344 2 P 0 ;0,4,6=36,8=0.000000
L 0.77664341 6.43660344 0.7782435 6.43743661 2 P 0 ;0,4,6=36,8=0.000000
L 0.7782435 6.43743661 0.77957707 6.43951949 2 P 0 ;0,4,6=36,8=0.000000
L 0.77957707 6.43951949 0.78011024 6.44243632 2 P 0 ;0,4,6=36,8=0.000000
L 0.78011024 6.44243632 0.77930994 6.44535315 2 P 0 ;0,4,6=36,8=0.000000
L 0.77930994 6.44535315 0.7774437 6.44743681 2 P 0 ;0,4,6=36,8=0.000000
L 0.7774437 6.44743681 0.77531033 6.44826998 2 P 0 ;0,4,6=36,8=0.000000
L 0.77531033 6.44826998 0.77317697 6.44743681 2 P 0 ;0,4,6=36,8=0.000000
L 0.77317697 6.44743681 0.77131024 6.44535315 2 P 0 ;0,4,6=36,8=0.000000
L 0.77131024 6.44535315 0.77050994 6.44243632 2 P 0 ;0,4,6=36,8=0.000000
L 0.77050994 6.44243632 0.7710436 6.43951949 2 P 0 ;0,4,6=36,8=0.000000
L 0.7710436 6.43951949 0.77237667 6.43743661 2 P 0 ;0,4,6=36,8=0.000000
L 0.77237667 6.43743661 0.77397677 6.43660344 2 P 0 ;0,4,6=36,8=0.000000
L 0.77397677 6.43660344 0.77664341 6.43660344 2 P 0 ;0,4,6=36,8=0.000000
L 0.77664341 6.43660344 0.77904341 6.43535295 2 P 0 ;0,4,6=36,8=0.000000
L 0.77904341 6.43535295 0.7806435 6.43285276 2 P 0 ;0,4,6=36,8=0.000000
L 0.7806435 6.43285276 0.78117677 6.42993671 2 P 0 ;0,4,6=36,8=0.000000
L 0.78117677 6.42993671 0.7806435 6.42701909 2 P 0 ;0,4,6=36,8=0.000000
L 0.7806435 6.42701909 0.77930994 6.42493622 2 P 0 ;0,4,6=36,8=0.000000
L 0.77930994 6.42493622 0.77717657 6.42368652 2 P 0 ;0,4,6=36,8=0.000000
L 0.77717657 6.42368652 0.77531033 6.42326998 2 P 0 ;0,4,6=36,8=0.000000
L 0.75717677 6.42701909 0.75557707 6.42493622 2 P 0 ;0,4,6=36,8=0.000000
L 0.75557707 6.42493622 0.75371033 6.42368652 2 P 0 ;0,4,6=36,8=0.000000
L 0.75371033 6.42368652 0.75131033 6.42326998 2 P 0 ;0,4,6=36,8=0.000000
L 0.75131033 6.42326998 0.74890984 6.42410305 2 P 0 ;0,4,6=36,8=0.000000
L 0.74890984 6.42410305 0.7470436 6.42576939 2 P 0 ;0,4,6=36,8=0.000000
L 0.7470436 6.42576939 0.74571004 6.42868622 2 P 0 ;0,4,6=36,8=0.000000
L 0.74571004 6.42868622 0.74544341 6.43201959 2 P 0 ;0,4,6=36,8=0.000000
L 0.74544341 6.43201959 0.74597667 6.43535295 2 P 0 ;0,4,6=36,8=0.000000
L 0.74597667 6.43535295 0.74731024 6.43743661 2 P 0 ;0,4,6=36,8=0.000000
L 0.74731024 6.43743661 0.74917697 6.43910295 2 P 0 ;0,4,6=36,8=0.000000
L 0.74917697 6.43910295 0.75104321 6.43951949 2 P 0 ;0,4,6=36,8=0.000000
L 0.75104321 6.43951949 0.75291004 6.43910295 2 P 0 ;0,4,6=36,8=0.000000
L 0.75291004 6.43910295 0.75530994 6.43743661 2 P 0 ;0,4,6=36,8=0.000000
L 0.75530994 6.43743661 0.75451014 6.44826998 2 P 0 ;0,4,6=36,8=0.000000
L 0.75451014 6.44826998 0.74731024 6.44826998 2 P 0 ;0,4,6=36,8=0.000000
L 0.88202343 6.44916998 0.88202343 6.42416998 2 P 0 ;0,4,6=31,8=0.000000
L 0.88202343 6.42416998 0.87135659 6.42416998 2 P 0 ;0,4,6=31,8=0.000000
L 0.85269026 6.42416998 0.85269026 6.44916998 2 P 0 ;0,4,6=31,8=0.000000
L 0.85269026 6.44916998 0.85589006 6.44417028 2 P 0 ;0,4,6=31,8=0.000000
L 0.85589006 6.42416998 0.84949045 6.42416998 2 P 0 ;0,4,6=31,8=0.000000
L 0.83375679 6.44500335 0.83215669 6.44750285 2 P 0 ;0,4,6=31,8=0.000000
L 0.83215669 6.44750285 0.83028996 6.44875335 2 P 0 ;0,4,6=31,8=0.000000
L 0.83028996 6.44875335 0.82815659 6.44916998 2 P 0 ;0,4,6=31,8=0.000000
L 0.82815659 6.44916998 0.82548996 6.44833681 2 P 0 ;0,4,6=31,8=0.000000
L 0.82548996 6.44833681 0.82362323 6.44625315 2 P 0 ;0,4,6=31,8=0.000000
L 0.82362323 6.44625315 0.82308996 6.44375364 2 P 0 ;0,4,6=31,8=0.000000
L 0.82308996 6.44375364 0.82335659 6.44125266 2 P 0 ;0,4,6=31,8=0.000000
L 0.82335659 6.44125266 0.82442352 6.43916978 2 P 0 ;0,4,6=31,8=0.000000
L 0.82442352 6.43916978 0.82975669 6.43500325 2 P 0 ;0,4,6=31,8=0.000000
L 0.82975669 6.43500325 0.83215669 6.43208642 2 P 0 ;0,4,6=31,8=0.000000
L 0.83215669 6.43208642 0.83375679 6.42791909 2 P 0 ;0,4,6=31,8=0.000000
L 0.83375679 6.42791909 0.83429006 6.42416998 2 P 0 ;0,4,6=31,8=0.000000
L 0.83429006 6.42416998 0.82308996 6.42416998 2 P 0 ;0,4,6=31,8=0.000000
L 0.91881998 6.42326998 0.93063002 6.42326998 1 P 0 
A 0.93063002 6.42326998 0.93851398 6.44689488 0.93851004 6.43376821 1 P 0 Y
A 0.93851398 6.44689488 0.94638002 6.42326998 0.93851004 6.43377156 1 P 0 Y
L 0.94638002 6.42326998 0.95818996 6.42326998 1 P 0 
L 1.00531033 6.42326998 1.0034436 6.42368652 2 P 0 ;0,4,6=36,8=0.000000
L 1.0034436 6.42368652 1.00131024 6.42493622 2 P 0 ;0,4,6=36,8=0.000000
L 1.00131024 6.42493622 0.99997667 6.42701909 2 P 0 ;0,4,6=36,8=0.000000
L 0.99997667 6.42701909 0.99944341 6.42993671 2 P 0 ;0,4,6=36,8=0.000000
L 0.99944341 6.42993671 0.99997667 6.43285276 2 P 0 ;0,4,6=36,8=0.000000
L 0.99997667 6.43285276 1.00157677 6.43535295 2 P 0 ;0,4,6=36,8=0.000000
L 1.00157677 6.43535295 1.00397677 6.43660344 2 P 0 ;0,4,6=36,8=0.000000
L 1.00397677 6.43660344 1.00664341 6.43660344 2 P 0 ;0,4,6=36,8=0.000000
L 1.00664341 6.43660344 1.0082435 6.43743661 2 P 0 ;0,4,6=36,8=0.000000
L 1.0082435 6.43743661 1.00957707 6.43951949 2 P 0 ;0,4,6=36,8=0.000000
L 1.00957707 6.43951949 1.01011024 6.44243632 2 P 0 ;0,4,6=36,8=0.000000
L 1.01011024 6.44243632 1.00930994 6.44535315 2 P 0 ;0,4,6=36,8=0.000000
L 1.00930994 6.44535315 1.0074437 6.44743681 2 P 0 ;0,4,6=36,8=0.000000
L 1.0074437 6.44743681 1.00531033 6.44826998 2 P 0 ;0,4,6=36,8=0.000000
L 1.00531033 6.44826998 1.00317697 6.44743681 2 P 0 ;0,4,6=36,8=0.000000
L 1.00317697 6.44743681 1.00131024 6.44535315 2 P 0 ;0,4,6=36,8=0.000000
L 1.00131024 6.44535315 1.00050994 6.44243632 2 P 0 ;0,4,6=36,8=0.000000
L 1.00050994 6.44243632 1.0010436 6.43951949 2 P 0 ;0,4,6=36,8=0.000000
L 1.0010436 6.43951949 1.00237667 6.43743661 2 P 0 ;0,4,6=36,8=0.000000
L 1.00237667 6.43743661 1.00397677 6.43660344 2 P 0 ;0,4,6=36,8=0.000000
L 1.00397677 6.43660344 1.00664341 6.43660344 2 P 0 ;0,4,6=36,8=0.000000
L 1.00664341 6.43660344 1.00904341 6.43535295 2 P 0 ;0,4,6=36,8=0.000000
L 1.00904341 6.43535295 1.0106435 6.43285276 2 P 0 ;0,4,6=36,8=0.000000
L 1.0106435 6.43285276 1.01117677 6.42993671 2 P 0 ;0,4,6=36,8=0.000000
L 1.01117677 6.42993671 1.0106435 6.42701909 2 P 0 ;0,4,6=36,8=0.000000
L 1.0106435 6.42701909 1.00930994 6.42493622 2 P 0 ;0,4,6=36,8=0.000000
L 1.00930994 6.42493622 1.00717657 6.42368652 2 P 0 ;0,4,6=36,8=0.000000
L 1.00717657 6.42368652 1.00531033 6.42326998 2 P 0 ;0,4,6=36,8=0.000000
L 0.98717677 6.42701909 0.98557707 6.42493622 2 P 0 ;0,4,6=36,8=0.000000
L 0.98557707 6.42493622 0.98371033 6.42368652 2 P 0 ;0,4,6=36,8=0.000000
L 0.98371033 6.42368652 0.98131033 6.42326998 2 P 0 ;0,4,6=36,8=0.000000
L 0.98131033 6.42326998 0.97890984 6.42410305 2 P 0 ;0,4,6=36,8=0.000000
L 0.97890984 6.42410305 0.9770436 6.42576939 2 P 0 ;0,4,6=36,8=0.000000
L 0.9770436 6.42576939 0.97571004 6.42868622 2 P 0 ;0,4,6=36,8=0.000000
L 0.97571004 6.42868622 0.97544341 6.43201959 2 P 0 ;0,4,6=36,8=0.000000
L 0.97544341 6.43201959 0.97597667 6.43535295 2 P 0 ;0,4,6=36,8=0.000000
L 0.97597667 6.43535295 0.97731024 6.43743661 2 P 0 ;0,4,6=36,8=0.000000
L 0.97731024 6.43743661 0.97917697 6.43910295 2 P 0 ;0,4,6=36,8=0.000000
L 0.97917697 6.43910295 0.98104321 6.43951949 2 P 0 ;0,4,6=36,8=0.000000
L 0.98104321 6.43951949 0.98291004 6.43910295 2 P 0 ;0,4,6=36,8=0.000000
L 0.98291004 6.43910295 0.98530994 6.43743661 2 P 0 ;0,4,6=36,8=0.000000
L 0.98530994 6.43743661 0.98451014 6.44826998 2 P 0 ;0,4,6=36,8=0.000000
L 0.98451014 6.44826998 0.97731024 6.44826998 2 P 0 ;0,4,6=36,8=0.000000
L 1.10202343 6.44916998 1.10202343 6.42416998 2 P 0 ;0,4,6=32,8=0.000000
L 1.10202343 6.42416998 1.09135659 6.42416998 2 P 0 ;0,4,6=32,8=0.000000
L 1.07269026 6.42416998 1.07269026 6.44916998 2 P 0 ;0,4,6=32,8=0.000000
L 1.07269026 6.44916998 1.07589006 6.44417028 2 P 0 ;0,4,6=32,8=0.000000
L 1.07589006 6.42416998 1.06949045 6.42416998 2 P 0 ;0,4,6=32,8=0.000000
L 1.04869026 6.44916998 1.05082362 6.44833681 2 P 0 ;0,4,6=32,8=0.000000
L 1.05082362 6.44833681 1.05242333 6.44625315 2 P 0 ;0,4,6=32,8=0.000000
L 1.05242333 6.44625315 1.05349016 6.44375364 2 P 0 ;0,4,6=32,8=0.000000
L 1.05349016 6.44375364 1.05429006 6.44041949 2 P 0 ;0,4,6=32,8=0.000000
L 1.05429006 6.44041949 1.05455669 6.43666959 2 P 0 ;0,4,6=32,8=0.000000
L 1.05455669 6.43666959 1.05429006 6.43291959 2 P 0 ;0,4,6=32,8=0.000000
L 1.05429006 6.43291959 1.05349016 6.42958622 2 P 0 ;0,4,6=32,8=0.000000
L 1.05349016 6.42958622 1.05242333 6.42708602 2 P 0 ;0,4,6=32,8=0.000000
L 1.05242333 6.42708602 1.05082362 6.42500305 2 P 0 ;0,4,6=32,8=0.000000
L 1.05082362 6.42500305 1.04869026 6.42416998 2 P 0 ;0,4,6=32,8=0.000000
L 1.04869026 6.42416998 1.04655689 6.42500305 2 P 0 ;0,4,6=32,8=0.000000
L 1.04655689 6.42500305 1.04495669 6.42708602 2 P 0 ;0,4,6=32,8=0.000000
L 1.04495669 6.42708602 1.04388986 6.42958622 2 P 0 ;0,4,6=32,8=0.000000
L 1.04388986 6.42958622 1.04308996 6.43291959 2 P 0 ;0,4,6=32,8=0.000000
L 1.04308996 6.43291959 1.04282333 6.43666959 2 P 0 ;0,4,6=32,8=0.000000
L 1.04282333 6.43666959 1.04308996 6.44041949 2 P 0 ;0,4,6=32,8=0.000000
L 1.04308996 6.44041949 1.04388986 6.44375364 2 P 0 ;0,4,6=32,8=0.000000
L 1.04388986 6.44375364 1.04495669 6.44625315 2 P 0 ;0,4,6=32,8=0.000000
L 1.04495669 6.44625315 1.04655689 6.44833681 2 P 0 ;0,4,6=32,8=0.000000
L 1.04655689 6.44833681 1.04869026 6.44916998 2 P 0 ;0,4,6=32,8=0.000000
L 1.59881998 6.42326998 1.61063002 6.42326998 1 P 0 
A 1.61063002 6.42326998 1.61851398 6.44689488 1.61851004 6.43376821 1 P 0 Y
A 1.61851398 6.44689488 1.62638002 6.42326998 1.61851004 6.43377156 1 P 0 Y
L 1.62638002 6.42326998 1.63818996 6.42326998 1 P 0 
L 1.68531033 6.42326998 1.6834436 6.42368652 2 P 0 ;0,4,6=36,8=0.000000
L 1.6834436 6.42368652 1.68131024 6.42493622 2 P 0 ;0,4,6=36,8=0.000000
L 1.68131024 6.42493622 1.67997667 6.42701909 2 P 0 ;0,4,6=36,8=0.000000
L 1.67997667 6.42701909 1.67944341 6.42993671 2 P 0 ;0,4,6=36,8=0.000000
L 1.67944341 6.42993671 1.67997667 6.43285276 2 P 0 ;0,4,6=36,8=0.000000
L 1.67997667 6.43285276 1.68157677 6.43535295 2 P 0 ;0,4,6=36,8=0.000000
L 1.68157677 6.43535295 1.68397677 6.43660344 2 P 0 ;0,4,6=36,8=0.000000
L 1.68397677 6.43660344 1.68664341 6.43660344 2 P 0 ;0,4,6=36,8=0.000000
L 1.68664341 6.43660344 1.6882435 6.43743661 2 P 0 ;0,4,6=36,8=0.000000
L 1.6882435 6.43743661 1.68957707 6.43951949 2 P 0 ;0,4,6=36,8=0.000000
L 1.68957707 6.43951949 1.69011024 6.44243632 2 P 0 ;0,4,6=36,8=0.000000
L 1.69011024 6.44243632 1.68930994 6.44535315 2 P 0 ;0,4,6=36,8=0.000000
L 1.68930994 6.44535315 1.6874437 6.44743681 2 P 0 ;0,4,6=36,8=0.000000
L 1.6874437 6.44743681 1.68531033 6.44826998 2 P 0 ;0,4,6=36,8=0.000000
L 1.68531033 6.44826998 1.68317697 6.44743681 2 P 0 ;0,4,6=36,8=0.000000
L 1.68317697 6.44743681 1.68131024 6.44535315 2 P 0 ;0,4,6=36,8=0.000000
L 1.68131024 6.44535315 1.68050994 6.44243632 2 P 0 ;0,4,6=36,8=0.000000
L 1.68050994 6.44243632 1.6810436 6.43951949 2 P 0 ;0,4,6=36,8=0.000000
L 1.6810436 6.43951949 1.68237667 6.43743661 2 P 0 ;0,4,6=36,8=0.000000
L 1.68237667 6.43743661 1.68397677 6.43660344 2 P 0 ;0,4,6=36,8=0.000000
L 1.68397677 6.43660344 1.68664341 6.43660344 2 P 0 ;0,4,6=36,8=0.000000
L 1.68664341 6.43660344 1.68904341 6.43535295 2 P 0 ;0,4,6=36,8=0.000000
L 1.68904341 6.43535295 1.6906435 6.43285276 2 P 0 ;0,4,6=36,8=0.000000
L 1.6906435 6.43285276 1.69117677 6.42993671 2 P 0 ;0,4,6=36,8=0.000000
L 1.69117677 6.42993671 1.6906435 6.42701909 2 P 0 ;0,4,6=36,8=0.000000
L 1.6906435 6.42701909 1.68930994 6.42493622 2 P 0 ;0,4,6=36,8=0.000000
L 1.68930994 6.42493622 1.68717657 6.42368652 2 P 0 ;0,4,6=36,8=0.000000
L 1.68717657 6.42368652 1.68531033 6.42326998 2 P 0 ;0,4,6=36,8=0.000000
L 1.66717677 6.42701909 1.66557707 6.42493622 2 P 0 ;0,4,6=36,8=0.000000
L 1.66557707 6.42493622 1.66371033 6.42368652 2 P 0 ;0,4,6=36,8=0.000000
L 1.66371033 6.42368652 1.66131033 6.42326998 2 P 0 ;0,4,6=36,8=0.000000
L 1.66131033 6.42326998 1.65890984 6.42410305 2 P 0 ;0,4,6=36,8=0.000000
L 1.65890984 6.42410305 1.6570436 6.42576939 2 P 0 ;0,4,6=36,8=0.000000
L 1.6570436 6.42576939 1.65571004 6.42868622 2 P 0 ;0,4,6=36,8=0.000000
L 1.65571004 6.42868622 1.65544341 6.43201959 2 P 0 ;0,4,6=36,8=0.000000
L 1.65544341 6.43201959 1.65597667 6.43535295 2 P 0 ;0,4,6=36,8=0.000000
L 1.65597667 6.43535295 1.65731024 6.43743661 2 P 0 ;0,4,6=36,8=0.000000
L 1.65731024 6.43743661 1.65917697 6.43910295 2 P 0 ;0,4,6=36,8=0.000000
L 1.65917697 6.43910295 1.66104321 6.43951949 2 P 0 ;0,4,6=36,8=0.000000
L 1.66104321 6.43951949 1.66291004 6.43910295 2 P 0 ;0,4,6=36,8=0.000000
L 1.66291004 6.43910295 1.66530994 6.43743661 2 P 0 ;0,4,6=36,8=0.000000
L 1.66530994 6.43743661 1.66451014 6.44826998 2 P 0 ;0,4,6=36,8=0.000000
L 1.66451014 6.44826998 1.65731024 6.44826998 2 P 0 ;0,4,6=36,8=0.000000
L 1.78202343 6.44916998 1.78202343 6.42416998 2 P 0 ;0,4,6=35,8=0.000000
L 1.78202343 6.42416998 1.77135659 6.42416998 2 P 0 ;0,4,6=35,8=0.000000
L 1.75269026 6.42416998 1.75269026 6.44916998 2 P 0 ;0,4,6=35,8=0.000000
L 1.75269026 6.44916998 1.75589006 6.44417028 2 P 0 ;0,4,6=35,8=0.000000
L 1.75589006 6.42416998 1.74949045 6.42416998 2 P 0 ;0,4,6=35,8=0.000000
L 1.37381998 6.42326998 1.38563002 6.42326998 1 P 0 
A 1.38563002 6.42326998 1.39351398 6.44689488 1.39351004 6.43376821 1 P 0 Y
A 1.39351398 6.44689488 1.40138002 6.42326998 1.39351004 6.43377156 1 P 0 Y
L 1.40138002 6.42326998 1.41318996 6.42326998 1 P 0 
L 1.46031033 6.42326998 1.4584436 6.42368652 2 P 0 ;0,4,6=36,8=0.000000
L 1.4584436 6.42368652 1.45631024 6.42493622 2 P 0 ;0,4,6=36,8=0.000000
L 1.45631024 6.42493622 1.45497667 6.42701909 2 P 0 ;0,4,6=36,8=0.000000
L 1.45497667 6.42701909 1.45444341 6.42993671 2 P 0 ;0,4,6=36,8=0.000000
L 1.45444341 6.42993671 1.45497667 6.43285276 2 P 0 ;0,4,6=36,8=0.000000
L 1.45497667 6.43285276 1.45657677 6.43535295 2 P 0 ;0,4,6=36,8=0.000000
L 1.45657677 6.43535295 1.45897677 6.43660344 2 P 0 ;0,4,6=36,8=0.000000
L 1.45897677 6.43660344 1.46164341 6.43660344 2 P 0 ;0,4,6=36,8=0.000000
L 1.46164341 6.43660344 1.4632435 6.43743661 2 P 0 ;0,4,6=36,8=0.000000
L 1.4632435 6.43743661 1.46457707 6.43951949 2 P 0 ;0,4,6=36,8=0.000000
L 1.46457707 6.43951949 1.46511024 6.44243632 2 P 0 ;0,4,6=36,8=0.000000
L 1.46511024 6.44243632 1.46430994 6.44535315 2 P 0 ;0,4,6=36,8=0.000000
L 1.46430994 6.44535315 1.4624437 6.44743681 2 P 0 ;0,4,6=36,8=0.000000
L 1.4624437 6.44743681 1.46031033 6.44826998 2 P 0 ;0,4,6=36,8=0.000000
L 1.46031033 6.44826998 1.45817697 6.44743681 2 P 0 ;0,4,6=36,8=0.000000
L 1.45817697 6.44743681 1.45631024 6.44535315 2 P 0 ;0,4,6=36,8=0.000000
L 1.45631024 6.44535315 1.45550994 6.44243632 2 P 0 ;0,4,6=36,8=0.000000
L 1.45550994 6.44243632 1.4560436 6.43951949 2 P 0 ;0,4,6=36,8=0.000000
L 1.4560436 6.43951949 1.45737667 6.43743661 2 P 0 ;0,4,6=36,8=0.000000
L 1.45737667 6.43743661 1.45897677 6.43660344 2 P 0 ;0,4,6=36,8=0.000000
L 1.45897677 6.43660344 1.46164341 6.43660344 2 P 0 ;0,4,6=36,8=0.000000
L 1.46164341 6.43660344 1.46404341 6.43535295 2 P 0 ;0,4,6=36,8=0.000000
L 1.46404341 6.43535295 1.4656435 6.43285276 2 P 0 ;0,4,6=36,8=0.000000
L 1.4656435 6.43285276 1.46617677 6.42993671 2 P 0 ;0,4,6=36,8=0.000000
L 1.46617677 6.42993671 1.4656435 6.42701909 2 P 0 ;0,4,6=36,8=0.000000
L 1.4656435 6.42701909 1.46430994 6.42493622 2 P 0 ;0,4,6=36,8=0.000000
L 1.46430994 6.42493622 1.46217657 6.42368652 2 P 0 ;0,4,6=36,8=0.000000
L 1.46217657 6.42368652 1.46031033 6.42326998 2 P 0 ;0,4,6=36,8=0.000000
L 1.44217677 6.42701909 1.44057707 6.42493622 2 P 0 ;0,4,6=36,8=0.000000
L 1.44057707 6.42493622 1.43871033 6.42368652 2 P 0 ;0,4,6=36,8=0.000000
L 1.43871033 6.42368652 1.43631033 6.42326998 2 P 0 ;0,4,6=36,8=0.000000
L 1.43631033 6.42326998 1.43390984 6.42410305 2 P 0 ;0,4,6=36,8=0.000000
L 1.43390984 6.42410305 1.4320436 6.42576939 2 P 0 ;0,4,6=36,8=0.000000
L 1.4320436 6.42576939 1.43071004 6.42868622 2 P 0 ;0,4,6=36,8=0.000000
L 1.43071004 6.42868622 1.43044341 6.43201959 2 P 0 ;0,4,6=36,8=0.000000
L 1.43044341 6.43201959 1.43097667 6.43535295 2 P 0 ;0,4,6=36,8=0.000000
L 1.43097667 6.43535295 1.43231024 6.43743661 2 P 0 ;0,4,6=36,8=0.000000
L 1.43231024 6.43743661 1.43417697 6.43910295 2 P 0 ;0,4,6=36,8=0.000000
L 1.43417697 6.43910295 1.43604321 6.43951949 2 P 0 ;0,4,6=36,8=0.000000
L 1.43604321 6.43951949 1.43791004 6.43910295 2 P 0 ;0,4,6=36,8=0.000000
L 1.43791004 6.43910295 1.44030994 6.43743661 2 P 0 ;0,4,6=36,8=0.000000
L 1.44030994 6.43743661 1.43951014 6.44826998 2 P 0 ;0,4,6=36,8=0.000000
L 1.43951014 6.44826998 1.43231024 6.44826998 2 P 0 ;0,4,6=36,8=0.000000
L 1.55702343 6.44916998 1.55702343 6.42416998 2 P 0 ;0,4,6=34,8=0.000000
L 1.55702343 6.42416998 1.54635659 6.42416998 2 P 0 ;0,4,6=34,8=0.000000
L 1.53355669 6.42916959 1.53195699 6.42625285 2 P 0 ;0,4,6=34,8=0.000000
L 1.53195699 6.42625285 1.52982362 6.42458652 2 P 0 ;0,4,6=34,8=0.000000
L 1.52982362 6.42458652 1.52742313 6.42416998 2 P 0 ;0,4,6=34,8=0.000000
L 1.52742313 6.42416998 1.52528976 6.42458652 2 P 0 ;0,4,6=34,8=0.000000
L 1.52528976 6.42458652 1.5231564 6.42666939 2 P 0 ;0,4,6=34,8=0.000000
L 1.5231564 6.42666939 1.52182333 6.42916959 2 P 0 ;0,4,6=34,8=0.000000
L 1.52182333 6.42916959 1.52155679 6.43166988 2 P 0 ;0,4,6=34,8=0.000000
L 1.52155679 6.43166988 1.52208996 6.43458593 2 P 0 ;0,4,6=34,8=0.000000
L 1.52208996 6.43458593 1.52395669 6.43666959 2 P 0 ;0,4,6=34,8=0.000000
L 1.52395669 6.43666959 1.52582352 6.43750344 2 P 0 ;0,4,6=34,8=0.000000
L 1.52582352 6.43750344 1.52822343 6.43750344 2 P 0 ;0,4,6=34,8=0.000000
L 1.52582352 6.43750344 1.52422333 6.43875325 2 P 0 ;0,4,6=34,8=0.000000
L 1.52422333 6.43875325 1.52288986 6.44083612 2 P 0 ;0,4,6=34,8=0.000000
L 1.52288986 6.44083612 1.52235659 6.44333632 2 P 0 ;0,4,6=34,8=0.000000
L 1.52235659 6.44333632 1.52288986 6.44583652 2 P 0 ;0,4,6=34,8=0.000000
L 1.52288986 6.44583652 1.52422333 6.44791939 2 P 0 ;0,4,6=34,8=0.000000
L 1.52422333 6.44791939 1.52662333 6.44916998 2 P 0 ;0,4,6=34,8=0.000000
L 1.52662333 6.44916998 1.52902333 6.44875335 2 P 0 ;0,4,6=34,8=0.000000
L 1.52902333 6.44875335 1.53142333 6.44708632 2 P 0 ;0,4,6=34,8=0.000000
L 1.14881998 6.42326998 1.16063002 6.42326998 1 P 0 
A 1.16063002 6.42326998 1.16851398 6.44689488 1.16851004 6.43376821 1 P 0 Y
A 1.16851398 6.44689488 1.17638002 6.42326998 1.16851004 6.43377156 1 P 0 Y
L 1.17638002 6.42326998 1.18818996 6.42326998 1 P 0 
L 1.23531033 6.42326998 1.2334436 6.42368652 2 P 0 ;0,4,6=36,8=0.000000
L 1.2334436 6.42368652 1.23131024 6.42493622 2 P 0 ;0,4,6=36,8=0.000000
L 1.23131024 6.42493622 1.22997667 6.42701909 2 P 0 ;0,4,6=36,8=0.000000
L 1.22997667 6.42701909 1.22944341 6.42993671 2 P 0 ;0,4,6=36,8=0.000000
L 1.22944341 6.42993671 1.22997667 6.43285276 2 P 0 ;0,4,6=36,8=0.000000
L 1.22997667 6.43285276 1.23157677 6.43535295 2 P 0 ;0,4,6=36,8=0.000000
L 1.23157677 6.43535295 1.23397677 6.43660344 2 P 0 ;0,4,6=36,8=0.000000
L 1.23397677 6.43660344 1.23664341 6.43660344 2 P 0 ;0,4,6=36,8=0.000000
L 1.23664341 6.43660344 1.2382435 6.43743661 2 P 0 ;0,4,6=36,8=0.000000
L 1.2382435 6.43743661 1.23957707 6.43951949 2 P 0 ;0,4,6=36,8=0.000000
L 1.23957707 6.43951949 1.24011024 6.44243632 2 P 0 ;0,4,6=36,8=0.000000
L 1.24011024 6.44243632 1.23930994 6.44535315 2 P 0 ;0,4,6=36,8=0.000000
L 1.23930994 6.44535315 1.2374437 6.44743681 2 P 0 ;0,4,6=36,8=0.000000
L 1.2374437 6.44743681 1.23531033 6.44826998 2 P 0 ;0,4,6=36,8=0.000000
L 1.23531033 6.44826998 1.23317697 6.44743681 2 P 0 ;0,4,6=36,8=0.000000
L 1.23317697 6.44743681 1.23131024 6.44535315 2 P 0 ;0,4,6=36,8=0.000000
L 1.23131024 6.44535315 1.23050994 6.44243632 2 P 0 ;0,4,6=36,8=0.000000
L 1.23050994 6.44243632 1.2310436 6.43951949 2 P 0 ;0,4,6=36,8=0.000000
L 1.2310436 6.43951949 1.23237667 6.43743661 2 P 0 ;0,4,6=36,8=0.000000
L 1.23237667 6.43743661 1.23397677 6.43660344 2 P 0 ;0,4,6=36,8=0.000000
L 1.23397677 6.43660344 1.23664341 6.43660344 2 P 0 ;0,4,6=36,8=0.000000
L 1.23664341 6.43660344 1.23904341 6.43535295 2 P 0 ;0,4,6=36,8=0.000000
L 1.23904341 6.43535295 1.2406435 6.43285276 2 P 0 ;0,4,6=36,8=0.000000
L 1.2406435 6.43285276 1.24117677 6.42993671 2 P 0 ;0,4,6=36,8=0.000000
L 1.24117677 6.42993671 1.2406435 6.42701909 2 P 0 ;0,4,6=36,8=0.000000
L 1.2406435 6.42701909 1.23930994 6.42493622 2 P 0 ;0,4,6=36,8=0.000000
L 1.23930994 6.42493622 1.23717657 6.42368652 2 P 0 ;0,4,6=36,8=0.000000
L 1.23717657 6.42368652 1.23531033 6.42326998 2 P 0 ;0,4,6=36,8=0.000000
L 1.21717677 6.42701909 1.21557707 6.42493622 2 P 0 ;0,4,6=36,8=0.000000
L 1.21557707 6.42493622 1.21371033 6.42368652 2 P 0 ;0,4,6=36,8=0.000000
L 1.21371033 6.42368652 1.21131033 6.42326998 2 P 0 ;0,4,6=36,8=0.000000
L 1.21131033 6.42326998 1.20890984 6.42410305 2 P 0 ;0,4,6=36,8=0.000000
L 1.20890984 6.42410305 1.2070436 6.42576939 2 P 0 ;0,4,6=36,8=0.000000
L 1.2070436 6.42576939 1.20571004 6.42868622 2 P 0 ;0,4,6=36,8=0.000000
L 1.20571004 6.42868622 1.20544341 6.43201959 2 P 0 ;0,4,6=36,8=0.000000
L 1.20544341 6.43201959 1.20597667 6.43535295 2 P 0 ;0,4,6=36,8=0.000000
L 1.20597667 6.43535295 1.20731024 6.43743661 2 P 0 ;0,4,6=36,8=0.000000
L 1.20731024 6.43743661 1.20917697 6.43910295 2 P 0 ;0,4,6=36,8=0.000000
L 1.20917697 6.43910295 1.21104321 6.43951949 2 P 0 ;0,4,6=36,8=0.000000
L 1.21104321 6.43951949 1.21291004 6.43910295 2 P 0 ;0,4,6=36,8=0.000000
L 1.21291004 6.43910295 1.21530994 6.43743661 2 P 0 ;0,4,6=36,8=0.000000
L 1.21530994 6.43743661 1.21451014 6.44826998 2 P 0 ;0,4,6=36,8=0.000000
L 1.21451014 6.44826998 1.20731024 6.44826998 2 P 0 ;0,4,6=36,8=0.000000
L 1.33202343 6.44916998 1.33202343 6.42416998 2 P 0 ;0,4,6=33,8=0.000000
L 1.33202343 6.42416998 1.32135659 6.42416998 2 P 0 ;0,4,6=33,8=0.000000
L 1.30855669 6.42791909 1.30695699 6.42583622 2 P 0 ;0,4,6=33,8=0.000000
L 1.30695699 6.42583622 1.30509026 6.42458652 2 P 0 ;0,4,6=33,8=0.000000
L 1.30509026 6.42458652 1.30269026 6.42416998 2 P 0 ;0,4,6=33,8=0.000000
L 1.30269026 6.42416998 1.30028976 6.42500305 2 P 0 ;0,4,6=33,8=0.000000
L 1.30028976 6.42500305 1.29842352 6.42666939 2 P 0 ;0,4,6=33,8=0.000000
L 1.29842352 6.42666939 1.29708996 6.42958622 2 P 0 ;0,4,6=33,8=0.000000
L 1.29708996 6.42958622 1.29682333 6.43291959 2 P 0 ;0,4,6=33,8=0.000000
L 1.29682333 6.43291959 1.29735659 6.43625295 2 P 0 ;0,4,6=33,8=0.000000
L 1.29735659 6.43625295 1.29869016 6.43833661 2 P 0 ;0,4,6=33,8=0.000000
L 1.29869016 6.43833661 1.30055689 6.44000295 2 P 0 ;0,4,6=33,8=0.000000
L 1.30055689 6.44000295 1.30242313 6.44041949 2 P 0 ;0,4,6=33,8=0.000000
L 1.30242313 6.44041949 1.30428996 6.44000295 2 P 0 ;0,4,6=33,8=0.000000
L 1.30428996 6.44000295 1.30668986 6.43833661 2 P 0 ;0,4,6=33,8=0.000000
L 1.30668986 6.43833661 1.30589006 6.44916998 2 P 0 ;0,4,6=33,8=0.000000
L 1.30589006 6.44916998 1.29869016 6.44916998 2 P 0 ;0,4,6=33,8=0.000000
L 0.0349 -2.3038 0.0349 -1.0038 5 P 0 ;0
L 0.0349 -1.0038 4.5349 -1.0038 5 P 0 ;0
L 4.5349 -1.0038 4.5349 -2.3038 5 P 0 ;0
L 4.5349 -2.3038 0.0349 -2.3038 5 P 0 ;0
L 0.0349 -1.6038 4.5349 -1.6038 5 P 0 ;0
L 0.0349 -1.8038 4.5349 -1.8038 5 P 0 ;0
L 2.4349 -2.1038 4.0349 -2.1038 5 P 0 ;0
L 2.4349 -2.3038 2.4349 -1.8038 5 P 0 ;0
L 3.2349 -2.1038 3.2349 -1.8038 5 P 0 ;0
L 4.0349 -2.3038 4.0349 -1.8038 5 P 0 ;0
L 0.0723999 -1.6844687 0.07906663 -1.69030079 2 P 0 ;0,6=37,8=0.000000
L 0.07906663 -1.69030079 0.08656654 -1.6938 2 P 0 ;0,6=37,8=0.000000
L 0.08656654 -1.6938 0.09323337 -1.6938 2 P 0 ;0,6=37,8=0.000000
L 0.09323337 -1.6938 0.0999001 -1.69030079 2 P 0 ;0,6=37,8=0.000000
L 0.0999001 -1.69030079 0.10490059 -1.6844687 2 P 0 ;0,6=37,8=0.000000
L 0.10490059 -1.6844687 0.1074 -1.67629951 2 P 0 ;0,6=37,8=0.000000
L 0.1074 -1.67629951 0.10573376 -1.66813455 2 P 0 ;0,6=37,8=0.000000
L 0.10573376 -1.66813455 0.10156644 -1.66113396 2 P 0 ;0,6=37,8=0.000000
L 0.10156644 -1.66113396 0.09406654 -1.65646614 2 P 0 ;0,6=37,8=0.000000
L 0.09406654 -1.65646614 0.08406713 -1.65413327 2 P 0 ;0,6=37,8=0.000000
L 0.08406713 -1.65413327 0.07823346 -1.64946762 2 P 0 ;0,6=37,8=0.000000
L 0.07823346 -1.64946762 0.07573248 -1.64130059 2 P 0 ;0,6=37,8=0.000000
L 0.07573248 -1.64130059 0.0774003 -1.63313356 2 P 0 ;0,6=37,8=0.000000
L 0.0774003 -1.63313356 0.08156614 -1.62730148 2 P 0 ;0,6=37,8=0.000000
L 0.08156614 -1.62730148 0.0873997 -1.6238 2 P 0 ;0,6=37,8=0.000000
L 0.0873997 -1.6238 0.09323337 -1.6238 2 P 0 ;0,6=37,8=0.000000
L 0.09323337 -1.6238 0.09906693 -1.62613287 2 P 0 ;0,6=37,8=0.000000
L 0.09906693 -1.62613287 0.10406742 -1.63196713 2 P 0 ;0,6=37,8=0.000000
L 0.1383999 -1.6938 0.1383999 -1.6238 2 P 0 ;0,6=37,8=0.000000
L 0.1734 -1.6238 0.1734 -1.6938 2 P 0 ;0,6=37,8=0.000000
L 0.1734 -1.65880108 0.1383999 -1.65880108 2 P 0 ;0,6=37,8=0.000000
L 0.23856683 -1.6938 0.20523307 -1.6938 2 P 0 ;0,6=37,8=0.000000
L 0.20523307 -1.6938 0.20523307 -1.6238 2 P 0 ;0,6=37,8=0.000000
L 0.20523307 -1.6238 0.23856683 -1.6238 2 P 0 ;0,6=37,8=0.000000
L 0.22523337 -1.65763258 0.20523307 -1.65763258 2 P 0 ;0,6=37,8=0.000000
L 0.30456683 -1.6938 0.27123307 -1.6938 2 P 0 ;0,6=37,8=0.000000
L 0.27123307 -1.6938 0.27123307 -1.6238 2 P 0 ;0,6=37,8=0.000000
L 0.27123307 -1.6238 0.30456683 -1.6238 2 P 0 ;0,6=37,8=0.000000
L 0.29123337 -1.65763258 0.27123307 -1.65763258 2 P 0 ;0,6=37,8=0.000000
L 0.35389921 -1.6238 0.35389921 -1.6938 2 P 0 ;0,6=37,8=0.000000
L 0.33473356 -1.6238 0.37306634 -1.6238 2 P 0 ;0,6=37,8=0.000000
L 0.09489921 -1.7188 0.09489921 -1.7888 2 P 0 ;0,6=38,8=0.000000
L 0.07573356 -1.7188 0.11406634 -1.7188 2 P 0 ;0,6=38,8=0.000000
L 0.1508998 -1.7188 0.17089862 -1.7188 2 P 0 ;0,6=38,8=0.000000
L 0.16089921 -1.7188 0.16089921 -1.7888 2 P 0 ;0,6=38,8=0.000000
L 0.1508998 -1.7888 0.17089862 -1.7888 2 P 0 ;0,6=38,8=0.000000
L 0.22689921 -1.7188 0.22689921 -1.7888 2 P 0 ;0,6=38,8=0.000000
L 0.20773356 -1.7188 0.24606634 -1.7188 2 P 0 ;0,6=38,8=0.000000
L 0.27623307 -1.7188 0.27623307 -1.7888 2 P 0 ;0,6=38,8=0.000000
L 0.27623307 -1.7888 0.30956683 -1.7888 2 P 0 ;0,6=38,8=0.000000
L 0.37556683 -1.7888 0.34223307 -1.7888 2 P 0 ;0,6=38,8=0.000000
L 0.34223307 -1.7888 0.34223307 -1.7188 2 P 0 ;0,6=38,8=0.000000
L 0.34223307 -1.7188 0.37556683 -1.7188 2 P 0 ;0,6=38,8=0.000000
L 0.36223337 -1.75263258 0.34223307 -1.75263258 2 P 0 ;0,6=38,8=0.000000
L 2.5438999 -1.96813563 2.5519 -1.97480089 2 P 0 ;0,6=39,8=0.000000
L 2.5519 -1.97480089 2.5608999 -1.9788 2 P 0 ;0,6=39,8=0.000000
L 2.5608999 -1.9788 2.5689 -1.9788 2 P 0 ;0,6=39,8=0.000000
L 2.5689 -1.9788 2.5769001 -1.97480089 2 P 0 ;0,6=39,8=0.000000
L 2.5769001 -1.97480089 2.58290069 -1.96813563 2 P 0 ;0,6=39,8=0.000000
L 2.58290069 -1.96813563 2.5859 -1.95879941 2 P 0 ;0,6=39,8=0.000000
L 2.5859 -1.95879941 2.58390049 -1.94946811 2 P 0 ;0,6=39,8=0.000000
L 2.58390049 -1.94946811 2.5788997 -1.94146732 2 P 0 ;0,6=39,8=0.000000
L 2.5788997 -1.94146732 2.5698998 -1.93613278 2 P 0 ;0,6=39,8=0.000000
L 2.5698998 -1.93613278 2.55790049 -1.93346663 2 P 0 ;0,6=39,8=0.000000
L 2.55790049 -1.93346663 2.5509002 -1.92813445 2 P 0 ;0,6=39,8=0.000000
L 2.5509002 -1.92813445 2.54789902 -1.91880069 2 P 0 ;0,6=39,8=0.000000
L 2.54789902 -1.91880069 2.54990039 -1.90946683 2 P 0 ;0,6=39,8=0.000000
L 2.54990039 -1.90946683 2.55489931 -1.90280167 2 P 0 ;0,6=39,8=0.000000
L 2.55489931 -1.90280167 2.5618997 -1.8988 2 P 0 ;0,6=39,8=0.000000
L 2.5618997 -1.8988 2.5689 -1.8988 2 P 0 ;0,6=39,8=0.000000
L 2.5689 -1.8988 2.57590039 -1.90146614 2 P 0 ;0,6=39,8=0.000000
L 2.57590039 -1.90146614 2.58190089 -1.90813386 2 P 0 ;0,6=39,8=0.000000
L 2.6648998 -1.90546772 2.65889931 -1.90146614 2 P 0 ;0,6=39,8=0.000000
L 2.65889931 -1.90146614 2.65190079 -1.8988 2 P 0 ;0,6=39,8=0.000000
L 2.65190079 -1.8988 2.64390069 -1.8988 2 P 0 ;0,6=39,8=0.000000
L 2.64390069 -1.8988 2.63489892 -1.90280167 2 P 0 ;0,6=39,8=0.000000
L 2.63489892 -1.90280167 2.62790039 -1.90946683 2 P 0 ;0,6=39,8=0.000000
L 2.62790039 -1.90946683 2.62289961 -1.91746762 2 P 0 ;0,6=39,8=0.000000
L 2.62289961 -1.91746762 2.61889862 -1.93080049 2 P 0 ;0,6=39,8=0.000000
L 2.61889862 -1.93080049 2.61789892 -1.94280039 2 P 0 ;0,6=39,8=0.000000
L 2.61789892 -1.94280039 2.6199003 -1.9548003 2 P 0 ;0,6=39,8=0.000000
L 2.6199003 -1.9548003 2.62289961 -1.96280098 2 P 0 ;0,6=39,8=0.000000
L 2.62289961 -1.96280098 2.6289002 -1.97080177 2 P 0 ;0,6=39,8=0.000000
L 2.6289002 -1.97080177 2.63590049 -1.97613396 2 P 0 ;0,6=39,8=0.000000
L 2.63590049 -1.97613396 2.64289902 -1.9788 2 P 0 ;0,6=39,8=0.000000
L 2.64289902 -1.9788 2.64989941 -1.9788 2 P 0 ;0,6=39,8=0.000000
L 2.64989941 -1.9788 2.6568997 -1.97613396 2 P 0 ;0,6=39,8=0.000000
L 2.6568997 -1.97613396 2.6629003 -1.97213484 2 P 0 ;0,6=39,8=0.000000
L 2.6629003 -1.97213484 2.66790098 -1.96680266 2 P 0 ;0,6=39,8=0.000000
L 2.69589892 -1.9788 2.72089902 -1.8988 2 P 0 ;0,6=39,8=0.000000
L 2.72089902 -1.8988 2.74590098 -1.9788 2 P 0 ;0,6=39,8=0.000000
L 2.73689931 -1.95080118 2.70489882 -1.95080118 2 P 0 ;0,6=39,8=0.000000
L 2.77889961 -1.8988 2.77889961 -1.9788 2 P 0 ;0,6=39,8=0.000000
L 2.77889961 -1.9788 2.8189003 -1.9788 2 P 0 ;0,6=39,8=0.000000
L 2.8969003 -1.9788 2.85689961 -1.9788 2 P 0 ;0,6=39,8=0.000000
L 2.85689961 -1.9788 2.85689961 -1.8988 2 P 0 ;0,6=39,8=0.000000
L 2.85689961 -1.8988 2.8969003 -1.8988 2 P 0 ;0,6=39,8=0.000000
L 2.8809 -1.93746575 2.85689961 -1.93746575 2 P 0 ;0,6=39,8=0.000000
L 3.03289902 -1.9788 3.03289902 -1.8988 2 P 0 ;0,6=39,8=0.000000
L 3.03289902 -1.8988 3.0208998 -1.91479911 2 P 0 ;0,6=39,8=0.000000
L 3.0208998 -1.9788 3.04489833 -1.9788 2 P 0 ;0,6=39,8=0.000000
L 3.11089902 -1.98146604 3.10889951 -1.98013297 2 P 0 ;0,6=39,8=0.000000
L 3.10889951 -1.98013297 3.10889951 -1.97746703 2 P 0 ;0,6=39,8=0.000000
L 3.10889951 -1.97746703 3.11089902 -1.97613396 2 P 0 ;0,6=39,8=0.000000
L 3.11089902 -1.97613396 3.11290039 -1.97746703 2 P 0 ;0,6=39,8=0.000000
L 3.11290039 -1.97746703 3.11290039 -1.98013297 2 P 0 ;0,6=39,8=0.000000
L 3.11290039 -1.98013297 3.11089902 -1.98146604 2 P 0 ;0,6=39,8=0.000000
L 3.11089902 -1.945469 3.10889951 -1.94413346 2 P 0 ;0,6=39,8=0.000000
L 3.10889951 -1.94413346 3.10889951 -1.94146732 2 P 0 ;0,6=39,8=0.000000
L 3.10889951 -1.94146732 3.11089902 -1.94013435 2 P 0 ;0,6=39,8=0.000000
L 3.11089902 -1.94013435 3.11290039 -1.94146732 2 P 0 ;0,6=39,8=0.000000
L 3.11290039 -1.94146732 3.11290039 -1.94413346 2 P 0 ;0,6=39,8=0.000000
L 3.11290039 -1.94413346 3.11089902 -1.945469 2 P 0 ;0,6=39,8=0.000000
L 3.18889902 -1.9788 3.18889902 -1.8988 2 P 0 ;0,6=39,8=0.000000
L 3.18889902 -1.8988 3.1768998 -1.91479911 2 P 0 ;0,6=39,8=0.000000
L 3.1768998 -1.9788 3.20089833 -1.9788 2 P 0 ;0,6=39,8=0.000000
L 2.5138999 -2.23313563 2.5219 -2.23980089 2 P 0 ;0,6=37,8=0.000000
L 2.5219 -2.23980089 2.5308999 -2.2438 2 P 0 ;0,6=37,8=0.000000
L 2.5308999 -2.2438 2.5389 -2.2438 2 P 0 ;0,6=37,8=0.000000
L 2.5389 -2.2438 2.5469001 -2.23980089 2 P 0 ;0,6=37,8=0.000000
L 2.5469001 -2.23980089 2.55290069 -2.23313563 2 P 0 ;0,6=37,8=0.000000
L 2.55290069 -2.23313563 2.5559 -2.22379941 2 P 0 ;0,6=37,8=0.000000
L 2.5559 -2.22379941 2.55390049 -2.21446811 2 P 0 ;0,6=37,8=0.000000
L 2.55390049 -2.21446811 2.5488997 -2.20646732 2 P 0 ;0,6=37,8=0.000000
L 2.5488997 -2.20646732 2.5398998 -2.20113278 2 P 0 ;0,6=37,8=0.000000
L 2.5398998 -2.20113278 2.52790049 -2.19846663 2 P 0 ;0,6=37,8=0.000000
L 2.52790049 -2.19846663 2.5209002 -2.19313445 2 P 0 ;0,6=37,8=0.000000
L 2.5209002 -2.19313445 2.51789902 -2.18380069 2 P 0 ;0,6=37,8=0.000000
L 2.51789902 -2.18380069 2.51990039 -2.17446683 2 P 0 ;0,6=37,8=0.000000
L 2.51990039 -2.17446683 2.52489931 -2.16780167 2 P 0 ;0,6=37,8=0.000000
L 2.52489931 -2.16780167 2.5318997 -2.1638 2 P 0 ;0,6=37,8=0.000000
L 2.5318997 -2.1638 2.5389 -2.1638 2 P 0 ;0,6=37,8=0.000000
L 2.5389 -2.1638 2.54590039 -2.16646614 2 P 0 ;0,6=37,8=0.000000
L 2.54590039 -2.16646614 2.55190089 -2.17313386 2 P 0 ;0,6=37,8=0.000000
L 2.5918999 -2.2438 2.5918999 -2.1638 2 P 0 ;0,6=37,8=0.000000
L 2.6339 -2.1638 2.6339 -2.2438 2 P 0 ;0,6=37,8=0.000000
L 2.6339 -2.20380128 2.5918999 -2.20380128 2 P 0 ;0,6=37,8=0.000000
L 2.7109003 -2.2438 2.67089961 -2.2438 2 P 0 ;0,6=37,8=0.000000
L 2.67089961 -2.2438 2.67089961 -2.1638 2 P 0 ;0,6=37,8=0.000000
L 2.67089961 -2.1638 2.7109003 -2.1638 2 P 0 ;0,6=37,8=0.000000
L 2.6949 -2.20246575 2.67089961 -2.20246575 2 P 0 ;0,6=37,8=0.000000
L 2.7889003 -2.2438 2.74889961 -2.2438 2 P 0 ;0,6=37,8=0.000000
L 2.74889961 -2.2438 2.74889961 -2.1638 2 P 0 ;0,6=37,8=0.000000
L 2.74889961 -2.1638 2.7889003 -2.1638 2 P 0 ;0,6=37,8=0.000000
L 2.7729 -2.20246575 2.74889961 -2.20246575 2 P 0 ;0,6=37,8=0.000000
L 2.84689902 -2.1638 2.84689902 -2.2438 2 P 0 ;0,6=37,8=0.000000
L 2.8239003 -2.1638 2.86989961 -2.1638 2 P 0 ;0,6=37,8=0.000000
L 3.29489961 -1.9238 3.29489961 -2.0038 2 P 0 ;0,6=40,8=0.000000
L 3.29489961 -2.0038 3.3349003 -2.0038 2 P 0 ;0,6=40,8=0.000000
L 3.36789892 -2.0038 3.39289902 -1.9238 2 P 0 ;0,6=40,8=0.000000
L 3.39289902 -1.9238 3.41790098 -2.0038 2 P 0 ;0,6=40,8=0.000000
L 3.40889931 -1.97580118 3.37689882 -1.97580118 2 P 0 ;0,6=40,8=0.000000
L 3.47089902 -2.0038 3.47089902 -1.96780039 2 P 0 ;0,6=40,8=0.000000
L 3.47089902 -1.96780039 3.45089961 -1.9238 2 P 0 ;0,6=40,8=0.000000
L 3.4909003 -1.9238 3.47089902 -1.96780039 2 P 0 ;0,6=40,8=0.000000
L 3.5689003 -2.0038 3.52889961 -2.0038 2 P 0 ;0,6=40,8=0.000000
L 3.52889961 -2.0038 3.52889961 -1.9238 2 P 0 ;0,6=40,8=0.000000
L 3.52889961 -1.9238 3.5689003 -1.9238 2 P 0 ;0,6=40,8=0.000000
L 3.5529 -1.96246575 3.52889961 -1.96246575 2 P 0 ;0,6=40,8=0.000000
L 3.60689961 -2.0038 3.60689961 -1.9238 2 P 0 ;0,6=40,8=0.000000
L 3.60689961 -1.9238 3.6318998 -1.9238 2 P 0 ;0,6=40,8=0.000000
L 3.6318998 -1.9238 3.6398999 -1.92780167 2 P 0 ;0,6=40,8=0.000000
L 3.6398999 -1.92780167 3.64490069 -1.93313386 2 P 0 ;0,6=40,8=0.000000
L 3.64490069 -1.93313386 3.6469003 -1.94380069 2 P 0 ;0,6=40,8=0.000000
L 3.6469003 -1.94380069 3.64490069 -1.95446752 2 P 0 ;0,6=40,8=0.000000
L 3.64490069 -1.95446752 3.6389001 -1.96113278 2 P 0 ;0,6=40,8=0.000000
L 3.6389001 -1.96113278 3.6318998 -1.96513435 2 P 0 ;0,6=40,8=0.000000
L 3.6318998 -1.96513435 3.60689961 -1.96513435 2 P 0 ;0,6=40,8=0.000000
L 3.6318998 -1.96513435 3.6469003 -2.0038 2 P 0 ;0,6=40,8=0.000000
L 3.33989902 -2.2538 3.33189892 -2.25246703 2 P 0 ;0,6=41,8=0.000000
L 3.33189892 -2.25246703 3.32490039 -2.24713484 2 P 0 ;0,6=41,8=0.000000
L 3.32490039 -2.24713484 3.3188999 -2.23913406 2 P 0 ;0,6=41,8=0.000000
L 3.3188999 -2.23913406 3.31489892 -2.2298003 2 P 0 ;0,6=41,8=0.000000
L 3.31489892 -2.2298003 3.31289931 -2.21913346 2 P 0 ;0,6=41,8=0.000000
L 3.31289931 -2.21913346 3.31289931 -2.20846663 2 P 0 ;0,6=41,8=0.000000
L 3.31289931 -2.20846663 3.31489892 -2.1977998 2 P 0 ;0,6=41,8=0.000000
L 3.31489892 -2.1977998 3.3188999 -2.18846604 2 P 0 ;0,6=41,8=0.000000
L 3.3188999 -2.18846604 3.32490039 -2.18046772 2 P 0 ;0,6=41,8=0.000000
L 3.32490039 -2.18046772 3.33189892 -2.17513307 2 P 0 ;0,6=41,8=0.000000
L 3.33189892 -2.17513307 3.33989902 -2.1738 2 P 0 ;0,6=41,8=0.000000
L 3.33989902 -2.1738 3.34789911 -2.17513307 2 P 0 ;0,6=41,8=0.000000
L 3.34789911 -2.17513307 3.35489951 -2.18046772 2 P 0 ;0,6=41,8=0.000000
L 3.35489951 -2.18046772 3.3609 -2.18846604 2 P 0 ;0,6=41,8=0.000000
L 3.3609 -2.18846604 3.36490098 -2.1977998 2 P 0 ;0,6=41,8=0.000000
L 3.36490098 -2.1977998 3.36690059 -2.20846663 2 P 0 ;0,6=41,8=0.000000
L 3.36690059 -2.20846663 3.36690059 -2.21913346 2 P 0 ;0,6=41,8=0.000000
L 3.36690059 -2.21913346 3.36490098 -2.2298003 2 P 0 ;0,6=41,8=0.000000
L 3.36490098 -2.2298003 3.3609 -2.23913406 2 P 0 ;0,6=41,8=0.000000
L 3.3609 -2.23913406 3.35489951 -2.24713484 2 P 0 ;0,6=41,8=0.000000
L 3.35489951 -2.24713484 3.34789911 -2.25246703 2 P 0 ;0,6=41,8=0.000000
L 3.34789911 -2.25246703 3.33989902 -2.2538 2 P 0 ;0,6=41,8=0.000000
L 3.39889941 -2.2538 3.39889941 -2.1738 2 P 0 ;0,6=41,8=0.000000
L 3.39889941 -2.1738 3.43690049 -2.1738 2 P 0 ;0,6=41,8=0.000000
L 3.4228998 -2.21246575 3.39889941 -2.21246575 2 P 0 ;0,6=41,8=0.000000
L 0.16489872 -1.0538 0.16489872 -1.1538 2 P 0 ;0,6=38,8=0.000000
L 0.13423376 -1.0538 0.19556614 -1.0538 2 P 0 ;0,6=38,8=0.000000
L 0.2588997 -1.0538 0.29089774 -1.0538 2 P 0 ;0,6=38,8=0.000000
L 0.27489872 -1.0538 0.27489872 -1.1538 2 P 0 ;0,6=38,8=0.000000
L 0.2588997 -1.1538 0.29089774 -1.1538 2 P 0 ;0,6=38,8=0.000000
L 0.38489872 -1.0538 0.38489872 -1.1538 2 P 0 ;0,6=38,8=0.000000
L 0.35423376 -1.0538 0.41556614 -1.0538 2 P 0 ;0,6=38,8=0.000000
L 0.46823287 -1.0538 0.46823287 -1.1538 2 P 0 ;0,6=38,8=0.000000
L 0.46823287 -1.1538 0.52156703 -1.1538 2 P 0 ;0,6=38,8=0.000000
L 0.63156703 -1.1538 0.57823287 -1.1538 2 P 0 ;0,6=38,8=0.000000
L 0.57823287 -1.1538 0.57823287 -1.0538 2 P 0 ;0,6=38,8=0.000000
L 0.57823287 -1.0538 0.63156703 -1.0538 2 P 0 ;0,6=38,8=0.000000
L 0.61023337 -1.10213219 0.57823287 -1.10213219 2 P 0 ;0,6=38,8=0.000000
L 4.18989892 -1.9538 4.21489902 -1.8738 2 P 0 ;0,6=42,8=0.000000
L 4.21489902 -1.8738 4.23990098 -1.9538 2 P 0 ;0,6=42,8=0.000000
L 4.23089931 -1.92580118 4.19889882 -1.92580118 2 P 0 ;0,6=42,8=0.000000
L 4.27289961 -1.9538 4.27289961 -1.8738 2 P 0 ;0,6=42,8=0.000000
L 4.27289961 -1.8738 4.2978998 -1.8738 2 P 0 ;0,6=42,8=0.000000
L 4.2978998 -1.8738 4.3058999 -1.87780167 2 P 0 ;0,6=42,8=0.000000
L 4.3058999 -1.87780167 4.31090069 -1.88313386 2 P 0 ;0,6=42,8=0.000000
L 4.31090069 -1.88313386 4.3129003 -1.89380069 2 P 0 ;0,6=42,8=0.000000
L 4.3129003 -1.89380069 4.31090069 -1.90446752 2 P 0 ;0,6=42,8=0.000000
L 4.31090069 -1.90446752 4.3049001 -1.91113278 2 P 0 ;0,6=42,8=0.000000
L 4.3049001 -1.91113278 4.2978998 -1.91513435 2 P 0 ;0,6=42,8=0.000000
L 4.2978998 -1.91513435 4.27289961 -1.91513435 2 P 0 ;0,6=42,8=0.000000
L 4.2978998 -1.91513435 4.3129003 -1.9538 2 P 0 ;0,6=42,8=0.000000
L 4.37089902 -1.8738 4.37089902 -1.9538 2 P 0 ;0,6=42,8=0.000000
L 4.3479003 -1.8738 4.39389961 -1.8738 2 P 0 ;0,6=42,8=0.000000
L 3.61989892 -2.2538 3.61989892 -2.1638 2 P 0 ;0,6=43,8=0.000000
L 3.61989892 -2.1638 3.6058997 -2.18179892 2 P 0 ;0,6=43,8=0.000000
L 3.6058997 -2.2538 3.63389803 -2.2538 2 P 0 ;0,6=43,8=0.000000
L 3.68773268 -2.17879961 3.69473337 -2.16980148 2 P 0 ;0,6=43,8=0.000000
L 3.69473337 -2.16980148 3.70290039 -2.1652997 2 P 0 ;0,6=43,8=0.000000
L 3.70290039 -2.1652997 3.71223386 -2.1638 2 P 0 ;0,6=43,8=0.000000
L 3.71223386 -2.1638 3.7239002 -2.16679941 2 P 0 ;0,6=43,8=0.000000
L 3.7239002 -2.16679941 3.73206722 -2.17430059 2 P 0 ;0,6=43,8=0.000000
L 3.73206722 -2.17430059 3.7344001 -2.18329862 2 P 0 ;0,6=43,8=0.000000
L 3.7344001 -2.18329862 3.73323366 -2.19230217 2 P 0 ;0,6=43,8=0.000000
L 3.73323366 -2.19230217 3.72856585 -2.19980059 2 P 0 ;0,6=43,8=0.000000
L 3.72856585 -2.19980059 3.70523317 -2.2148001 2 P 0 ;0,6=43,8=0.000000
L 3.70523317 -2.2148001 3.69473337 -2.22530069 2 P 0 ;0,6=43,8=0.000000
L 3.69473337 -2.22530069 3.68773268 -2.24030295 2 P 0 ;0,6=43,8=0.000000
L 3.68773268 -2.24030295 3.6853998 -2.2538 2 P 0 ;0,6=43,8=0.000000
L 3.6853998 -2.2538 3.7344001 -2.2538 2 P 0 ;0,6=43,8=0.000000
L 1.44056762 -1.70579931 1.4358998 -1.7013003 2 P 0 ;0,4,6=44,8=0.000000
L 1.4358998 -1.7013003 1.43240059 -1.69380187 2 P 0 ;0,4,6=44,8=0.000000
L 1.43240059 -1.69380187 1.43006565 -1.68329862 2 P 0 ;0,4,6=44,8=0.000000
L 1.43006565 -1.68329862 1.43240059 -1.67430059 2 P 0 ;0,4,6=44,8=0.000000
L 1.43240059 -1.67430059 1.43706624 -1.66830187 2 P 0 ;0,4,6=44,8=0.000000
L 1.43706624 -1.66830187 1.44523327 -1.6638 2 P 0 ;0,4,6=44,8=0.000000
L 1.44523327 -1.6638 1.47673297 -1.6638 2 P 0 ;0,4,6=44,8=0.000000
L 1.47673297 -1.6638 1.47673297 -1.7538 2 P 0 ;0,4,6=44,8=0.000000
L 1.47673297 -1.7538 1.43823268 -1.7538 2 P 0 ;0,4,6=44,8=0.000000
L 1.43823268 -1.7538 1.43006565 -1.74780138 2 P 0 ;0,4,6=44,8=0.000000
L 1.43006565 -1.74780138 1.4253999 -1.73880049 2 P 0 ;0,4,6=44,8=0.000000
L 1.4253999 -1.73880049 1.42306713 -1.7283 2 P 0 ;0,4,6=44,8=0.000000
L 1.42306713 -1.7283 1.4253999 -1.71780226 2 P 0 ;0,4,6=44,8=0.000000
L 1.4253999 -1.71780226 1.43240059 -1.70880138 2 P 0 ;0,4,6=44,8=0.000000
L 1.43240059 -1.70880138 1.44056762 -1.70579931 2 P 0 ;0,4,6=44,8=0.000000
L 1.44056762 -1.70579931 1.47673297 -1.70579931 2 P 0 ;0,4,6=44,8=0.000000
L 1.35990108 -1.7538 1.36923455 -1.75230039 2 P 0 ;0,4,6=44,8=0.000000
L 1.36923455 -1.75230039 1.37739951 -1.74630167 2 P 0 ;0,4,6=44,8=0.000000
L 1.37739951 -1.74630167 1.3844002 -1.73730079 2 P 0 ;0,4,6=44,8=0.000000
L 1.3844002 -1.73730079 1.38906791 -1.7268003 2 P 0 ;0,4,6=44,8=0.000000
L 1.38906791 -1.7268003 1.39140079 -1.7148001 2 P 0 ;0,4,6=44,8=0.000000
L 1.39140079 -1.7148001 1.39140079 -1.7028 2 P 0 ;0,4,6=44,8=0.000000
L 1.39140079 -1.7028 1.38906791 -1.6907998 2 P 0 ;0,4,6=44,8=0.000000
L 1.38906791 -1.6907998 1.3844002 -1.68029931 2 P 0 ;0,4,6=44,8=0.000000
L 1.3844002 -1.68029931 1.37739951 -1.67130118 2 P 0 ;0,4,6=44,8=0.000000
L 1.37739951 -1.67130118 1.36923455 -1.6652997 2 P 0 ;0,4,6=44,8=0.000000
L 1.36923455 -1.6652997 1.35990108 -1.6638 2 P 0 ;0,4,6=44,8=0.000000
L 1.35990108 -1.6638 1.35056762 -1.6652997 2 P 0 ;0,4,6=44,8=0.000000
L 1.35056762 -1.6652997 1.34240059 -1.67130118 2 P 0 ;0,4,6=44,8=0.000000
L 1.34240059 -1.67130118 1.3353999 -1.68029931 2 P 0 ;0,4,6=44,8=0.000000
L 1.3353999 -1.68029931 1.33073219 -1.6907998 2 P 0 ;0,4,6=44,8=0.000000
L 1.33073219 -1.6907998 1.32839931 -1.7028 2 P 0 ;0,4,6=44,8=0.000000
L 1.32839931 -1.7028 1.32839931 -1.7148001 2 P 0 ;0,4,6=44,8=0.000000
L 1.32839931 -1.7148001 1.33073219 -1.7268003 2 P 0 ;0,4,6=44,8=0.000000
L 1.33073219 -1.7268003 1.3353999 -1.73730079 2 P 0 ;0,4,6=44,8=0.000000
L 1.3353999 -1.73730079 1.34240059 -1.74630167 2 P 0 ;0,4,6=44,8=0.000000
L 1.34240059 -1.74630167 1.35056762 -1.75230039 2 P 0 ;0,4,6=44,8=0.000000
L 1.35056762 -1.75230039 1.35990108 -1.7538 2 P 0 ;0,4,6=44,8=0.000000
L 1.26990108 -1.6638 1.26990108 -1.7538 2 P 0 ;0,4,6=44,8=0.000000
L 1.29673297 -1.6638 1.24306713 -1.6638 2 P 0 ;0,4,6=44,8=0.000000
L 1.17990108 -1.6638 1.17990108 -1.7538 2 P 0 ;0,4,6=44,8=0.000000
L 1.20673297 -1.6638 1.15306713 -1.6638 2 P 0 ;0,4,6=44,8=0.000000
L 1.08990108 -1.7538 1.09923455 -1.75230039 2 P 0 ;0,4,6=44,8=0.000000
L 1.09923455 -1.75230039 1.10739951 -1.74630167 2 P 0 ;0,4,6=44,8=0.000000
L 1.10739951 -1.74630167 1.1144002 -1.73730079 2 P 0 ;0,4,6=44,8=0.000000
L 1.1144002 -1.73730079 1.11906791 -1.7268003 2 P 0 ;0,4,6=44,8=0.000000
L 1.11906791 -1.7268003 1.12140079 -1.7148001 2 P 0 ;0,4,6=44,8=0.000000
L 1.12140079 -1.7148001 1.12140079 -1.7028 2 P 0 ;0,4,6=44,8=0.000000
L 1.12140079 -1.7028 1.11906791 -1.6907998 2 P 0 ;0,4,6=44,8=0.000000
L 1.11906791 -1.6907998 1.1144002 -1.68029931 2 P 0 ;0,4,6=44,8=0.000000
L 1.1144002 -1.68029931 1.10739951 -1.67130118 2 P 0 ;0,4,6=44,8=0.000000
L 1.10739951 -1.67130118 1.09923455 -1.6652997 2 P 0 ;0,4,6=44,8=0.000000
L 1.09923455 -1.6652997 1.08990108 -1.6638 2 P 0 ;0,4,6=44,8=0.000000
L 1.08990108 -1.6638 1.08056762 -1.6652997 2 P 0 ;0,4,6=44,8=0.000000
L 1.08056762 -1.6652997 1.07240059 -1.67130118 2 P 0 ;0,4,6=44,8=0.000000
L 1.07240059 -1.67130118 1.0653999 -1.68029931 2 P 0 ;0,4,6=44,8=0.000000
L 1.0653999 -1.68029931 1.06073219 -1.6907998 2 P 0 ;0,4,6=44,8=0.000000
L 1.06073219 -1.6907998 1.05839931 -1.7028 2 P 0 ;0,4,6=44,8=0.000000
L 1.05839931 -1.7028 1.05839931 -1.7148001 2 P 0 ;0,4,6=44,8=0.000000
L 1.05839931 -1.7148001 1.06073219 -1.7268003 2 P 0 ;0,4,6=44,8=0.000000
L 1.06073219 -1.7268003 1.0653999 -1.73730079 2 P 0 ;0,4,6=44,8=0.000000
L 1.0653999 -1.73730079 1.07240059 -1.74630167 2 P 0 ;0,4,6=44,8=0.000000
L 1.07240059 -1.74630167 1.08056762 -1.75230039 2 P 0 ;0,4,6=44,8=0.000000
L 1.08056762 -1.75230039 1.08990108 -1.7538 2 P 0 ;0,4,6=44,8=0.000000
L 1.03023435 -1.7538 1.03023435 -1.6638 2 P 0 ;0,4,6=44,8=0.000000
L 1.03023435 -1.6638 0.99990108 -1.73880049 2 P 0 ;0,4,6=44,8=0.000000
L 0.99990108 -1.73880049 0.96956575 -1.6638 2 P 0 ;0,4,6=44,8=0.000000
L 0.96956575 -1.6638 0.96956575 -1.7538 2 P 0 ;0,4,6=44,8=0.000000
L 0.8444002 -1.74180266 0.83506663 -1.74930098 2 P 0 ;0,4,6=44,8=0.000000
L 0.83506663 -1.74930098 0.82456683 -1.7538 2 P 0 ;0,4,6=44,8=0.000000
L 0.82456683 -1.7538 0.81523327 -1.7538 2 P 0 ;0,4,6=44,8=0.000000
L 0.81523327 -1.7538 0.8058998 -1.74930098 2 P 0 ;0,4,6=44,8=0.000000
L 0.8058998 -1.74930098 0.79889921 -1.74180266 2 P 0 ;0,4,6=44,8=0.000000
L 0.79889921 -1.74180266 0.7953999 -1.73129941 2 P 0 ;0,4,6=44,8=0.000000
L 0.7953999 -1.73129941 0.79773278 -1.72080157 2 P 0 ;0,4,6=44,8=0.000000
L 0.79773278 -1.72080157 0.80356703 -1.71180079 2 P 0 ;0,4,6=44,8=0.000000
L 0.80356703 -1.71180079 0.81406693 -1.70579931 2 P 0 ;0,4,6=44,8=0.000000
L 0.81406693 -1.70579931 0.82806604 -1.7028 2 P 0 ;0,4,6=44,8=0.000000
L 0.82806604 -1.7028 0.83623307 -1.69680128 2 P 0 ;0,4,6=44,8=0.000000
L 0.83623307 -1.69680128 0.83973445 -1.68630069 2 P 0 ;0,4,6=44,8=0.000000
L 0.83973445 -1.68630069 0.83739951 -1.6758002 2 P 0 ;0,4,6=44,8=0.000000
L 0.83739951 -1.6758002 0.83156742 -1.66830187 2 P 0 ;0,4,6=44,8=0.000000
L 0.83156742 -1.66830187 0.82340039 -1.6638 2 P 0 ;0,4,6=44,8=0.000000
L 0.82340039 -1.6638 0.81523327 -1.6638 2 P 0 ;0,4,6=44,8=0.000000
L 0.81523327 -1.6638 0.80706624 -1.66679941 2 P 0 ;0,4,6=44,8=0.000000
L 0.80706624 -1.66679941 0.80006565 -1.67430059 2 P 0 ;0,4,6=44,8=0.000000
L 0.7439003 -1.6638 0.71590197 -1.6638 2 P 0 ;0,4,6=44,8=0.000000
L 0.72990108 -1.6638 0.72990108 -1.7538 2 P 0 ;0,4,6=44,8=0.000000
L 0.7439003 -1.7538 0.71590197 -1.7538 2 P 0 ;0,4,6=44,8=0.000000
L 0.66556654 -1.7538 0.66556654 -1.6638 2 P 0 ;0,4,6=44,8=0.000000
L 0.66556654 -1.6638 0.64223396 -1.6638 2 P 0 ;0,4,6=44,8=0.000000
L 0.64223396 -1.6638 0.63290049 -1.66830187 2 P 0 ;0,4,6=44,8=0.000000
L 0.63290049 -1.66830187 0.6258998 -1.67430059 2 P 0 ;0,4,6=44,8=0.000000
L 0.6258998 -1.67430059 0.62006565 -1.68329862 2 P 0 ;0,4,6=44,8=0.000000
L 0.62006565 -1.68329862 0.6153999 -1.69380187 2 P 0 ;0,4,6=44,8=0.000000
L 0.6153999 -1.69380187 0.61423356 -1.70880138 2 P 0 ;0,4,6=44,8=0.000000
L 0.61423356 -1.70880138 0.6153999 -1.72380098 2 P 0 ;0,4,6=44,8=0.000000
L 0.6153999 -1.72380098 0.62006565 -1.73430148 2 P 0 ;0,4,6=44,8=0.000000
L 0.62006565 -1.73430148 0.6258998 -1.74330226 2 P 0 ;0,4,6=44,8=0.000000
L 0.6258998 -1.74330226 0.63290049 -1.74930098 2 P 0 ;0,4,6=44,8=0.000000
L 0.63290049 -1.74930098 0.64223396 -1.7538 2 P 0 ;0,4,6=44,8=0.000000
L 0.64223396 -1.7538 0.66556654 -1.7538 2 P 0 ;0,4,6=44,8=0.000000
L 0.52656634 -1.7538 0.57323376 -1.7538 2 P 0 ;0,4,6=44,8=0.000000
L 0.57323376 -1.7538 0.57323376 -1.6638 2 P 0 ;0,4,6=44,8=0.000000
L 0.57323376 -1.6638 0.52656634 -1.6638 2 P 0 ;0,4,6=44,8=0.000000
L 0.54523327 -1.70729902 0.57323376 -1.70729902 2 P 0 ;0,4,6=44,8=0.000000
L 3.76989892 -2.0038 3.76989892 -1.9138 2 P 0 ;0,6=43,8=0.000000
L 3.76989892 -1.9138 3.7558997 -1.93179892 2 P 0 ;0,6=43,8=0.000000
L 3.7558997 -2.0038 3.78389803 -2.0038 2 P 0 ;0,6=43,8=0.000000
L 3.83773268 -1.92879961 3.84473337 -1.91980148 2 P 0 ;0,6=43,8=0.000000
L 3.84473337 -1.91980148 3.85290039 -1.9152997 2 P 0 ;0,6=43,8=0.000000
L 3.85290039 -1.9152997 3.86223386 -1.9138 2 P 0 ;0,6=43,8=0.000000
L 3.86223386 -1.9138 3.8739002 -1.91679941 2 P 0 ;0,6=43,8=0.000000
L 3.8739002 -1.91679941 3.88206722 -1.92430059 2 P 0 ;0,6=43,8=0.000000
L 3.88206722 -1.92430059 3.8844001 -1.93329862 2 P 0 ;0,6=43,8=0.000000
L 3.8844001 -1.93329862 3.88323366 -1.94230217 2 P 0 ;0,6=43,8=0.000000
L 3.88323366 -1.94230217 3.87856585 -1.94980059 2 P 0 ;0,6=43,8=0.000000
L 3.87856585 -1.94980059 3.85523317 -1.9648001 2 P 0 ;0,6=43,8=0.000000
L 3.85523317 -1.9648001 3.84473337 -1.97530069 2 P 0 ;0,6=43,8=0.000000
L 3.84473337 -1.97530069 3.83773268 -1.99030295 2 P 0 ;0,6=43,8=0.000000
L 3.83773268 -1.99030295 3.8353998 -2.0038 2 P 0 ;0,6=43,8=0.000000
L 3.8353998 -2.0038 3.8844001 -2.0038 2 P 0 ;0,6=43,8=0.000000
L 3.01989892 -2.2538 3.01989892 -2.1638 2 P 0 ;0,6=43,8=0.000000
L 3.01989892 -2.1638 3.0058997 -2.18179892 2 P 0 ;0,6=43,8=0.000000
L 3.0058997 -2.2538 3.03389803 -2.2538 2 P 0 ;0,6=43,8=0.000000
L 3.08773268 -2.17879961 3.09473337 -2.16980148 2 P 0 ;0,6=43,8=0.000000
L 3.09473337 -2.16980148 3.10290039 -2.1652997 2 P 0 ;0,6=43,8=0.000000
L 3.10290039 -2.1652997 3.11223386 -2.1638 2 P 0 ;0,6=43,8=0.000000
L 3.11223386 -2.1638 3.1239002 -2.16679941 2 P 0 ;0,6=43,8=0.000000
L 3.1239002 -2.16679941 3.13206722 -2.17430059 2 P 0 ;0,6=43,8=0.000000
L 3.13206722 -2.17430059 3.1344001 -2.18329862 2 P 0 ;0,6=43,8=0.000000
L 3.1344001 -2.18329862 3.13323366 -2.19230217 2 P 0 ;0,6=43,8=0.000000
L 3.13323366 -2.19230217 3.12856585 -2.19980059 2 P 0 ;0,6=43,8=0.000000
L 3.12856585 -2.19980059 3.10523317 -2.2148001 2 P 0 ;0,6=43,8=0.000000
L 3.10523317 -2.2148001 3.09473337 -2.22530069 2 P 0 ;0,6=43,8=0.000000
L 3.09473337 -2.22530069 3.08773268 -2.24030295 2 P 0 ;0,6=43,8=0.000000
L 3.08773268 -2.24030295 3.0853998 -2.2538 2 P 0 ;0,6=43,8=0.000000
L 3.0853998 -2.2538 3.1344001 -2.2538 2 P 0 ;0,6=43,8=0.000000
L 0.59099833 -1.36499882 0.5990003 -1.35750039 2 P 0 ;0,6=45,8=0.000000
L 0.5990003 -1.35750039 0.60499902 -1.34500315 2 P 0 ;0,6=45,8=0.000000
L 0.60499902 -1.34500315 0.60900187 -1.32749764 2 P 0 ;0,6=45,8=0.000000
L 0.60900187 -1.32749764 0.60499902 -1.31250089 2 P 0 ;0,6=45,8=0.000000
L 0.60499902 -1.31250089 0.59700079 -1.30250305 2 P 0 ;0,6=45,8=0.000000
L 0.59700079 -1.30250305 0.5830001 -1.295 2 P 0 ;0,6=45,8=0.000000
L 0.5830001 -1.295 0.52900059 -1.295 2 P 0 ;0,6=45,8=0.000000
L 0.52900059 -1.295 0.52900059 -1.445 2 P 0 ;0,6=45,8=0.000000
L 0.52900059 -1.445 0.59500118 -1.445 2 P 0 ;0,6=45,8=0.000000
L 0.59500118 -1.445 0.60900187 -1.43500217 2 P 0 ;0,6=45,8=0.000000
L 0.60900187 -1.43500217 0.6170001 -1.42000079 2 P 0 ;0,6=45,8=0.000000
L 0.6170001 -1.42000079 0.62099931 -1.4025 2 P 0 ;0,6=45,8=0.000000
L 0.62099931 -1.4025 0.6170001 -1.38500374 2 P 0 ;0,6=45,8=0.000000
L 0.6170001 -1.38500374 0.60499902 -1.37000236 2 P 0 ;0,6=45,8=0.000000
L 0.60499902 -1.37000236 0.59099833 -1.36499882 2 P 0 ;0,6=45,8=0.000000
L 0.59099833 -1.36499882 0.52900059 -1.36499882 2 P 0 ;0,6=45,8=0.000000
L 0.77100138 -1.445 0.77100138 -1.34500315 2 P 0 ;0,6=45,8=0.000000
L 0.77100138 -1.36249941 0.76299951 -1.35250148 2 P 0 ;0,6=45,8=0.000000
L 0.76299951 -1.35250148 0.75099833 -1.34750256 2 P 0 ;0,6=45,8=0.000000
L 0.75099833 -1.34750256 0.73700138 -1.34500315 2 P 0 ;0,6=45,8=0.000000
L 0.73700138 -1.34500315 0.72300069 -1.35000207 2 P 0 ;0,6=45,8=0.000000
L 0.72300069 -1.35000207 0.71099961 -1.3599999 2 P 0 ;0,6=45,8=0.000000
L 0.71099961 -1.3599999 0.70299764 -1.37500128 2 P 0 ;0,6=45,8=0.000000
L 0.70299764 -1.37500128 0.69899852 -1.39500157 2 P 0 ;0,6=45,8=0.000000
L 0.69899852 -1.39500157 0.70299764 -1.41500187 2 P 0 ;0,6=45,8=0.000000
L 0.70299764 -1.41500187 0.71099961 -1.43000325 2 P 0 ;0,6=45,8=0.000000
L 0.71099961 -1.43000325 0.72300069 -1.44000108 2 P 0 ;0,6=45,8=0.000000
L 0.72300069 -1.44000108 0.73700138 -1.445 2 P 0 ;0,6=45,8=0.000000
L 0.73700138 -1.445 0.75099833 -1.44250059 2 P 0 ;0,6=45,8=0.000000
L 0.75099833 -1.44250059 0.76299951 -1.43500217 2 P 0 ;0,6=45,8=0.000000
L 0.76299951 -1.43500217 0.77100138 -1.42500433 2 P 0 ;0,6=45,8=0.000000
L 0.86700039 -1.445 0.86700039 -1.34500315 2 P 0 ;0,6=45,8=0.000000
L 0.86700039 -1.36499882 0.87699833 -1.35500098 2 P 0 ;0,6=45,8=0.000000
L 0.87699833 -1.35500098 0.8869998 -1.34750256 2 P 0 ;0,6=45,8=0.000000
L 0.8869998 -1.34750256 0.90100049 -1.34500315 2 P 0 ;0,6=45,8=0.000000
L 0.90100049 -1.34500315 0.91099833 -1.34750256 2 P 0 ;0,6=45,8=0.000000
L 0.91099833 -1.34750256 0.92299951 -1.35500098 2 P 0 ;0,6=45,8=0.000000
L 1.02700039 -1.445 1.02700039 -1.34500315 2 P 0 ;0,6=45,8=0.000000
L 1.02700039 -1.36499882 1.03699833 -1.35500098 2 P 0 ;0,6=45,8=0.000000
L 1.03699833 -1.35500098 1.0469998 -1.34750256 2 P 0 ;0,6=45,8=0.000000
L 1.0469998 -1.34750256 1.06100049 -1.34500315 2 P 0 ;0,6=45,8=0.000000
L 1.06100049 -1.34500315 1.07099833 -1.34750256 2 P 0 ;0,6=45,8=0.000000
L 1.07099833 -1.34750256 1.08299951 -1.35500098 2 P 0 ;0,6=45,8=0.000000
L 1.18500089 -1.37750069 1.24900187 -1.37750069 2 P 0 ;0,6=45,8=0.000000
L 1.24900187 -1.37750069 1.24299951 -1.3599999 2 P 0 ;0,6=45,8=0.000000
L 1.24299951 -1.3599999 1.23300157 -1.35000207 2 P 0 ;0,6=45,8=0.000000
L 1.23300157 -1.35000207 1.21900089 -1.34500315 2 P 0 ;0,6=45,8=0.000000
L 1.21900089 -1.34500315 1.2050003 -1.34750256 2 P 0 ;0,6=45,8=0.000000
L 1.2050003 -1.34750256 1.19299911 -1.35500098 2 P 0 ;0,6=45,8=0.000000
L 1.19299911 -1.35500098 1.18500089 -1.37250177 2 P 0 ;0,6=45,8=0.000000
L 1.18500089 -1.37250177 1.18099803 -1.38750315 2 P 0 ;0,6=45,8=0.000000
L 1.18099803 -1.38750315 1.18099803 -1.4025 2 P 0 ;0,6=45,8=0.000000
L 1.18099803 -1.4025 1.18500089 -1.41750138 2 P 0 ;0,6=45,8=0.000000
L 1.18500089 -1.41750138 1.19499872 -1.43250276 2 P 0 ;0,6=45,8=0.000000
L 1.19499872 -1.43250276 1.2069998 -1.44250059 2 P 0 ;0,6=45,8=0.000000
L 1.2069998 -1.44250059 1.22100049 -1.445 2 P 0 ;0,6=45,8=0.000000
L 1.22100049 -1.445 1.23500118 -1.44000108 2 P 0 ;0,6=45,8=0.000000
L 1.23500118 -1.44000108 1.24900187 -1.42500433 2 P 0 ;0,6=45,8=0.000000
L 1.37499813 -1.445 1.37499813 -1.295 2 P 0 ;0,6=45,8=0.000000
L 1.50500089 -1.37750069 1.56900187 -1.37750069 2 P 0 ;0,6=45,8=0.000000
L 1.56900187 -1.37750069 1.56299951 -1.3599999 2 P 0 ;0,6=45,8=0.000000
L 1.56299951 -1.3599999 1.55300157 -1.35000207 2 P 0 ;0,6=45,8=0.000000
L 1.55300157 -1.35000207 1.53900089 -1.34500315 2 P 0 ;0,6=45,8=0.000000
L 1.53900089 -1.34500315 1.5250003 -1.34750256 2 P 0 ;0,6=45,8=0.000000
L 1.5250003 -1.34750256 1.51299911 -1.35500098 2 P 0 ;0,6=45,8=0.000000
L 1.51299911 -1.35500098 1.50500089 -1.37250177 2 P 0 ;0,6=45,8=0.000000
L 1.50500089 -1.37250177 1.50099803 -1.38750315 2 P 0 ;0,6=45,8=0.000000
L 1.50099803 -1.38750315 1.50099803 -1.4025 2 P 0 ;0,6=45,8=0.000000
L 1.50099803 -1.4025 1.50500089 -1.41750138 2 P 0 ;0,6=45,8=0.000000
L 1.50500089 -1.41750138 1.51499872 -1.43250276 2 P 0 ;0,6=45,8=0.000000
L 1.51499872 -1.43250276 1.5269998 -1.44250059 2 P 0 ;0,6=45,8=0.000000
L 1.5269998 -1.44250059 1.54100049 -1.445 2 P 0 ;0,6=45,8=0.000000
L 1.54100049 -1.445 1.55500118 -1.44000108 2 P 0 ;0,6=45,8=0.000000
L 1.55500118 -1.44000108 1.56900187 -1.42500433 2 P 0 ;0,6=45,8=0.000000
L 1.6529998 -1.48999951 1.66500089 -1.49499843 2 P 0 ;0,6=45,8=0.000000
L 1.66500089 -1.49499843 1.68100108 -1.48999951 2 P 0 ;0,6=45,8=0.000000
L 1.68100108 -1.48999951 1.69099902 -1.48000167 2 P 0 ;0,6=45,8=0.000000
L 1.69099902 -1.48000167 1.69900089 -1.4674997 2 P 0 ;0,6=45,8=0.000000
L 1.69900089 -1.4674997 1.71099833 -1.42750374 2 P 0 ;0,6=45,8=0.000000
L 1.71099833 -1.42750374 1.7370001 -1.34500315 2 P 0 ;0,6=45,8=0.000000
L 1.67299911 -1.34500315 1.71099833 -1.42750374 2 P 0 ;0,6=45,8=0.000000
L 1.82500089 -1.37750069 1.88900187 -1.37750069 2 P 0 ;0,6=45,8=0.000000
L 1.88900187 -1.37750069 1.88299951 -1.3599999 2 P 0 ;0,6=45,8=0.000000
L 1.88299951 -1.3599999 1.87300157 -1.35000207 2 P 0 ;0,6=45,8=0.000000
L 1.87300157 -1.35000207 1.85900089 -1.34500315 2 P 0 ;0,6=45,8=0.000000
L 1.85900089 -1.34500315 1.8450003 -1.34750256 2 P 0 ;0,6=45,8=0.000000
L 1.8450003 -1.34750256 1.83299911 -1.35500098 2 P 0 ;0,6=45,8=0.000000
L 1.83299911 -1.35500098 1.82500089 -1.37250177 2 P 0 ;0,6=45,8=0.000000
L 1.82500089 -1.37250177 1.82099803 -1.38750315 2 P 0 ;0,6=45,8=0.000000
L 1.82099803 -1.38750315 1.82099803 -1.4025 2 P 0 ;0,6=45,8=0.000000
L 1.82099803 -1.4025 1.82500089 -1.41750138 2 P 0 ;0,6=45,8=0.000000
L 1.82500089 -1.41750138 1.83499872 -1.43250276 2 P 0 ;0,6=45,8=0.000000
L 1.83499872 -1.43250276 1.8469998 -1.44250059 2 P 0 ;0,6=45,8=0.000000
L 1.8469998 -1.44250059 1.86100049 -1.445 2 P 0 ;0,6=45,8=0.000000
L 1.86100049 -1.445 1.87500118 -1.44000108 2 P 0 ;0,6=45,8=0.000000
L 1.87500118 -1.44000108 1.88900187 -1.42500433 2 P 0 ;0,6=45,8=0.000000
L 2.18699921 -1.37000236 2.22700167 -1.37000236 2 P 0 ;0,6=45,8=0.000000
L 2.22700167 -1.37000236 2.22700167 -1.41500187 2 P 0 ;0,6=45,8=0.000000
L 2.22700167 -1.41500187 2.21500059 -1.43000325 2 P 0 ;0,6=45,8=0.000000
L 2.21500059 -1.43000325 2.2009999 -1.44000108 2 P 0 ;0,6=45,8=0.000000
L 2.2009999 -1.44000108 2.18100049 -1.445 2 P 0 ;0,6=45,8=0.000000
L 2.18100049 -1.445 2.16100108 -1.44000108 2 P 0 ;0,6=45,8=0.000000
L 2.16100108 -1.44000108 2.14700039 -1.43000325 2 P 0 ;0,6=45,8=0.000000
L 2.14700039 -1.43000325 2.13499931 -1.41500187 2 P 0 ;0,6=45,8=0.000000
L 2.13499931 -1.41500187 2.12699734 -1.39750108 2 P 0 ;0,6=45,8=0.000000
L 2.12699734 -1.39750108 2.12299823 -1.37750069 2 P 0 ;0,6=45,8=0.000000
L 2.12299823 -1.37750069 2.12299823 -1.3599999 2 P 0 ;0,6=45,8=0.000000
L 2.12299823 -1.3599999 2.12699734 -1.34500315 2 P 0 ;0,6=45,8=0.000000
L 2.12699734 -1.34500315 2.13499931 -1.32749764 2 P 0 ;0,6=45,8=0.000000
L 2.13499931 -1.32749764 2.14700039 -1.31250089 2 P 0 ;0,6=45,8=0.000000
L 2.14700039 -1.31250089 2.15899783 -1.30250305 2 P 0 ;0,6=45,8=0.000000
L 2.15899783 -1.30250305 2.17499813 -1.295 2 P 0 ;0,6=45,8=0.000000
L 2.17499813 -1.295 2.18899882 -1.295 2 P 0 ;0,6=45,8=0.000000
L 2.18899882 -1.295 2.20499902 -1.29999902 2 P 0 ;0,6=45,8=0.000000
L 2.20499902 -1.29999902 2.2170001 -1.31000138 2 P 0 ;0,6=45,8=0.000000
L 2.29699892 -1.31999931 2.309 -1.30500246 2 P 0 ;0,6=45,8=0.000000
L 2.309 -1.30500246 2.32300069 -1.29749951 2 P 0 ;0,6=45,8=0.000000
L 2.32300069 -1.29749951 2.33900089 -1.295 2 P 0 ;0,6=45,8=0.000000
L 2.33900089 -1.295 2.3590003 -1.29999902 2 P 0 ;0,6=45,8=0.000000
L 2.3590003 -1.29999902 2.37300098 -1.31250089 2 P 0 ;0,6=45,8=0.000000
L 2.37300098 -1.31250089 2.3770001 -1.32749764 2 P 0 ;0,6=45,8=0.000000
L 2.3770001 -1.32749764 2.37500059 -1.34250364 2 P 0 ;0,6=45,8=0.000000
L 2.37500059 -1.34250364 2.36699862 -1.35500098 2 P 0 ;0,6=45,8=0.000000
L 2.36699862 -1.35500098 2.3269998 -1.3800002 2 P 0 ;0,6=45,8=0.000000
L 2.3269998 -1.3800002 2.309 -1.39750108 2 P 0 ;0,6=45,8=0.000000
L 2.309 -1.39750108 2.29699892 -1.42250482 2 P 0 ;0,6=45,8=0.000000
L 2.29699892 -1.42250482 2.2929998 -1.445 2 P 0 ;0,6=45,8=0.000000
L 2.2929998 -1.445 2.3770001 -1.445 2 P 0 ;0,6=45,8=0.000000
L 2.6129998 -1.42500433 2.629 -1.43750167 2 P 0 ;0,6=45,8=0.000000
L 2.629 -1.43750167 2.6469998 -1.445 2 P 0 ;0,6=45,8=0.000000
L 2.6469998 -1.445 2.6630001 -1.445 2 P 0 ;0,6=45,8=0.000000
L 2.6630001 -1.445 2.6790003 -1.43750167 2 P 0 ;0,6=45,8=0.000000
L 2.6790003 -1.43750167 2.69100138 -1.42500433 2 P 0 ;0,6=45,8=0.000000
L 2.69100138 -1.42500433 2.6970001 -1.40749892 2 P 0 ;0,6=45,8=0.000000
L 2.6970001 -1.40749892 2.69300098 -1.39000266 2 P 0 ;0,6=45,8=0.000000
L 2.69300098 -1.39000266 2.68299951 -1.37500128 2 P 0 ;0,6=45,8=0.000000
L 2.68299951 -1.37500128 2.66499961 -1.36499882 2 P 0 ;0,6=45,8=0.000000
L 2.66499961 -1.36499882 2.64100108 -1.3599999 2 P 0 ;0,6=45,8=0.000000
L 2.64100108 -1.3599999 2.62700039 -1.35000207 2 P 0 ;0,6=45,8=0.000000
L 2.62700039 -1.35000207 2.62099803 -1.33250118 2 P 0 ;0,6=45,8=0.000000
L 2.62099803 -1.33250118 2.62500089 -1.31500039 2 P 0 ;0,6=45,8=0.000000
L 2.62500089 -1.31500039 2.63499872 -1.30250305 2 P 0 ;0,6=45,8=0.000000
L 2.63499872 -1.30250305 2.64899941 -1.295 2 P 0 ;0,6=45,8=0.000000
L 2.64899941 -1.295 2.6630001 -1.295 2 P 0 ;0,6=45,8=0.000000
L 2.6630001 -1.295 2.67700079 -1.29999902 2 P 0 ;0,6=45,8=0.000000
L 2.67700079 -1.29999902 2.68900187 -1.31250089 2 P 0 ;0,6=45,8=0.000000
L 2.7729998 -1.445 2.8570001 -1.295 2 P 0 ;0,6=45,8=0.000000
L 2.7729998 -1.295 2.8570001 -1.445 2 P 0 ;0,6=45,8=0.000000
L 2.92299823 -1.445 2.92299823 -1.295 2 P 0 ;0,6=45,8=0.000000
L 2.92299823 -1.295 2.97499813 -1.42000079 2 P 0 ;0,6=45,8=0.000000
L 2.97499813 -1.42000079 3.02700167 -1.295 2 P 0 ;0,6=45,8=0.000000
L 3.02700167 -1.295 3.02700167 -1.445 2 P 0 ;0,6=45,8=0.000000
L 3.09699892 -1.31999931 3.109 -1.30500246 2 P 0 ;0,6=45,8=0.000000
L 3.109 -1.30500246 3.12300069 -1.29749951 2 P 0 ;0,6=45,8=0.000000
L 3.12300069 -1.29749951 3.13900089 -1.295 2 P 0 ;0,6=45,8=0.000000
L 3.13900089 -1.295 3.1590003 -1.29999902 2 P 0 ;0,6=45,8=0.000000
L 3.1590003 -1.29999902 3.17300098 -1.31250089 2 P 0 ;0,6=45,8=0.000000
L 3.17300098 -1.31250089 3.1770001 -1.32749764 2 P 0 ;0,6=45,8=0.000000
L 3.1770001 -1.32749764 3.17500059 -1.34250364 2 P 0 ;0,6=45,8=0.000000
L 3.17500059 -1.34250364 3.16699862 -1.35500098 2 P 0 ;0,6=45,8=0.000000
L 3.16699862 -1.35500098 3.1269998 -1.3800002 2 P 0 ;0,6=45,8=0.000000
L 3.1269998 -1.3800002 3.109 -1.39750108 2 P 0 ;0,6=45,8=0.000000
L 3.109 -1.39750108 3.09699892 -1.42250482 2 P 0 ;0,6=45,8=0.000000
L 3.09699892 -1.42250482 3.0929998 -1.445 2 P 0 ;0,6=45,8=0.000000
L 3.0929998 -1.445 3.1770001 -1.445 2 P 0 ;0,6=45,8=0.000000
L 3.269 -1.39500157 3.3209999 -1.39500157 2 P 0 ;0,6=45,8=0.000000
L 3.41499931 -1.445 3.41499931 -1.295 2 P 0 ;0,6=45,8=0.000000
L 3.41499931 -1.295 3.46499961 -1.295 2 P 0 ;0,6=45,8=0.000000
L 3.46499961 -1.295 3.4809999 -1.30250305 2 P 0 ;0,6=45,8=0.000000
L 3.4809999 -1.30250305 3.49100138 -1.31250089 2 P 0 ;0,6=45,8=0.000000
L 3.49100138 -1.31250089 3.49500059 -1.33250118 2 P 0 ;0,6=45,8=0.000000
L 3.49500059 -1.33250118 3.49100138 -1.35250148 2 P 0 ;0,6=45,8=0.000000
L 3.49100138 -1.35250148 3.4790003 -1.36499882 2 P 0 ;0,6=45,8=0.000000
L 3.4790003 -1.36499882 3.46499961 -1.37250177 2 P 0 ;0,6=45,8=0.000000
L 3.46499961 -1.37250177 3.41499931 -1.37250177 2 P 0 ;0,6=45,8=0.000000
L 3.46499961 -1.37250177 3.49500059 -1.445 2 P 0 ;0,6=45,8=0.000000
L 3.61499813 -1.34500315 3.61499813 -1.445 2 P 0 ;0,6=45,8=0.000000
L 3.61499813 -1.30500246 3.61099902 -1.30250305 2 P 0 ;0,6=45,8=0.000000
L 3.61099902 -1.30250305 3.61099902 -1.29749951 2 P 0 ;0,6=45,8=0.000000
L 3.61099902 -1.29749951 3.61499813 -1.295 2 P 0 ;0,6=45,8=0.000000
L 3.61499813 -1.295 3.61900089 -1.29749951 2 P 0 ;0,6=45,8=0.000000
L 3.61900089 -1.29749951 3.61900089 -1.30250305 2 P 0 ;0,6=45,8=0.000000
L 3.61900089 -1.30250305 3.61499813 -1.30500246 2 P 0 ;0,6=45,8=0.000000
L 3.74500089 -1.42750374 3.75499872 -1.43750167 2 P 0 ;0,6=45,8=0.000000
L 3.75499872 -1.43750167 3.76899941 -1.445 2 P 0 ;0,6=45,8=0.000000
L 3.76899941 -1.445 3.78100049 -1.445 2 P 0 ;0,6=45,8=0.000000
L 3.78100049 -1.445 3.79300157 -1.44000108 2 P 0 ;0,6=45,8=0.000000
L 3.79300157 -1.44000108 3.8009999 -1.43250276 2 P 0 ;0,6=45,8=0.000000
L 3.8009999 -1.43250276 3.80499902 -1.42250482 2 P 0 ;0,6=45,8=0.000000
L 3.80499902 -1.42250482 3.80299951 -1.40749892 2 P 0 ;0,6=45,8=0.000000
L 3.80299951 -1.40749892 3.79500118 -1.40000049 2 P 0 ;0,6=45,8=0.000000
L 3.79500118 -1.40000049 3.75899783 -1.38500374 2 P 0 ;0,6=45,8=0.000000
L 3.75899783 -1.38500374 3.75099961 -1.36749833 2 P 0 ;0,6=45,8=0.000000
L 3.75099961 -1.36749833 3.75499872 -1.35500098 2 P 0 ;0,6=45,8=0.000000
L 3.75499872 -1.35500098 3.76300069 -1.34750256 2 P 0 ;0,6=45,8=0.000000
L 3.76300069 -1.34750256 3.77499813 -1.34500315 2 P 0 ;0,6=45,8=0.000000
L 3.77499813 -1.34500315 3.78699921 -1.34750256 2 P 0 ;0,6=45,8=0.000000
L 3.78699921 -1.34750256 3.7990003 -1.35500098 2 P 0 ;0,6=45,8=0.000000
L 3.90500089 -1.37750069 3.96900187 -1.37750069 2 P 0 ;0,6=45,8=0.000000
L 3.96900187 -1.37750069 3.96299951 -1.3599999 2 P 0 ;0,6=45,8=0.000000
L 3.96299951 -1.3599999 3.95300157 -1.35000207 2 P 0 ;0,6=45,8=0.000000
L 3.95300157 -1.35000207 3.93900089 -1.34500315 2 P 0 ;0,6=45,8=0.000000
L 3.93900089 -1.34500315 3.9250003 -1.34750256 2 P 0 ;0,6=45,8=0.000000
L 3.9250003 -1.34750256 3.91299911 -1.35500098 2 P 0 ;0,6=45,8=0.000000
L 3.91299911 -1.35500098 3.90500089 -1.37250177 2 P 0 ;0,6=45,8=0.000000
L 3.90500089 -1.37250177 3.90099803 -1.38750315 2 P 0 ;0,6=45,8=0.000000
L 3.90099803 -1.38750315 3.90099803 -1.4025 2 P 0 ;0,6=45,8=0.000000
L 3.90099803 -1.4025 3.90500089 -1.41750138 2 P 0 ;0,6=45,8=0.000000
L 3.90500089 -1.41750138 3.91499872 -1.43250276 2 P 0 ;0,6=45,8=0.000000
L 3.91499872 -1.43250276 3.9269998 -1.44250059 2 P 0 ;0,6=45,8=0.000000
L 3.9269998 -1.44250059 3.94100049 -1.445 2 P 0 ;0,6=45,8=0.000000
L 3.94100049 -1.445 3.95500118 -1.44000108 2 P 0 ;0,6=45,8=0.000000
L 3.95500118 -1.44000108 3.96900187 -1.42500433 2 P 0 ;0,6=45,8=0.000000
L 4.06700039 -1.445 4.06700039 -1.34500315 2 P 0 ;0,6=45,8=0.000000
L 4.06700039 -1.36499882 4.07699833 -1.35500098 2 P 0 ;0,6=45,8=0.000000
L 4.07699833 -1.35500098 4.0869998 -1.34750256 2 P 0 ;0,6=45,8=0.000000
L 4.0869998 -1.34750256 4.10100049 -1.34500315 2 P 0 ;0,6=45,8=0.000000
L 4.10100049 -1.34500315 4.11099833 -1.34750256 2 P 0 ;0,6=45,8=0.000000
L 4.11099833 -1.34750256 4.12299951 -1.35500098 2 P 0 ;0,6=45,8=0.000000
L 4.16964783 -2.2038 4.21839813 -2.0478 2 P 0 ;0,6=46,8=0.000000
L 4.21839813 -2.0478 4.26715207 -2.2038 2 P 0 ;0,6=46,8=0.000000
L 4.24959862 -2.14920217 4.18719774 -2.14920217 2 P 0 ;0,6=46,8=0.000000
L 4.37939813 -2.2038 4.37939813 -2.0478 2 P 0 ;0,6=46,8=0.000000
L 4.37939813 -2.0478 4.35599961 -2.07899813 2 P 0 ;0,6=46,8=0.000000
L 4.35599961 -2.2038 4.40279675 -2.2038 2 P 0 ;0,6=46,8=0.000000
L 2.0009002 -0.9538 2.0009002 -0.8038 2 P 0 ;0,6=47,8=0.000000
L 2.0009002 -0.8038 2.04089902 -0.8038 2 P 0 ;0,6=47,8=0.000000
L 2.04089902 -0.8038 2.05689921 -0.81130305 2 P 0 ;0,6=47,8=0.000000
L 2.05689921 -0.81130305 2.0689003 -0.82130089 2 P 0 ;0,6=47,8=0.000000
L 2.0689003 -0.82130089 2.07890187 -0.83629764 2 P 0 ;0,6=47,8=0.000000
L 2.07890187 -0.83629764 2.0869001 -0.85380315 2 P 0 ;0,6=47,8=0.000000
L 2.0869001 -0.85380315 2.0888997 -0.87880236 2 P 0 ;0,6=47,8=0.000000
L 2.0888997 -0.87880236 2.0869001 -0.90380157 2 P 0 ;0,6=47,8=0.000000
L 2.0869001 -0.90380157 2.07890187 -0.92130246 2 P 0 ;0,6=47,8=0.000000
L 2.07890187 -0.92130246 2.0689003 -0.93630374 2 P 0 ;0,6=47,8=0.000000
L 2.0689003 -0.93630374 2.05689921 -0.94630167 2 P 0 ;0,6=47,8=0.000000
L 2.05689921 -0.94630167 2.04089902 -0.9538 2 P 0 ;0,6=47,8=0.000000
L 2.04089902 -0.9538 2.0009002 -0.9538 2 P 0 ;0,6=47,8=0.000000
L 2.15489783 -0.9538 2.20489813 -0.8038 2 P 0 ;0,6=47,8=0.000000
L 2.20489813 -0.8038 2.25490207 -0.9538 2 P 0 ;0,6=47,8=0.000000
L 2.23689862 -0.90130207 2.17289764 -0.90130207 2 P 0 ;0,6=47,8=0.000000
L 2.36489813 -0.8038 2.36489813 -0.9538 2 P 0 ;0,6=47,8=0.000000
L 2.31890059 -0.8038 2.41089931 -0.8038 2 P 0 ;0,6=47,8=0.000000
L 2.56490059 -0.9538 2.48489931 -0.9538 2 P 0 ;0,6=47,8=0.000000
L 2.48489931 -0.9538 2.48489931 -0.8038 2 P 0 ;0,6=47,8=0.000000
L 2.48489931 -0.8038 2.56490059 -0.8038 2 P 0 ;0,6=47,8=0.000000
L 2.5329001 -0.87629833 2.48489931 -0.87629833 2 P 0 ;0,6=47,8=0.000000
L 2.84489813 -0.9538 2.82889783 -0.95130059 2 P 0 ;0,6=47,8=0.000000
L 2.82889783 -0.95130059 2.81490089 -0.94130276 2 P 0 ;0,6=47,8=0.000000
L 2.81490089 -0.94130276 2.8028998 -0.92630138 2 P 0 ;0,6=47,8=0.000000
L 2.8028998 -0.92630138 2.79489783 -0.90880049 2 P 0 ;0,6=47,8=0.000000
L 2.79489783 -0.90880049 2.79089862 -0.8888002 2 P 0 ;0,6=47,8=0.000000
L 2.79089862 -0.8888002 2.79089862 -0.8687999 2 P 0 ;0,6=47,8=0.000000
L 2.79089862 -0.8687999 2.79489783 -0.84879961 2 P 0 ;0,6=47,8=0.000000
L 2.79489783 -0.84879961 2.8028998 -0.83129872 2 P 0 ;0,6=47,8=0.000000
L 2.8028998 -0.83129872 2.81490089 -0.81630197 2 P 0 ;0,6=47,8=0.000000
L 2.81490089 -0.81630197 2.82889783 -0.80629951 2 P 0 ;0,6=47,8=0.000000
L 2.82889783 -0.80629951 2.84489813 -0.8038 2 P 0 ;0,6=47,8=0.000000
L 2.84489813 -0.8038 2.86089833 -0.80629951 2 P 0 ;0,6=47,8=0.000000
L 2.86089833 -0.80629951 2.87489902 -0.81630197 2 P 0 ;0,6=47,8=0.000000
L 2.87489902 -0.81630197 2.8869001 -0.83129872 2 P 0 ;0,6=47,8=0.000000
L 2.8869001 -0.83129872 2.89490207 -0.84879961 2 P 0 ;0,6=47,8=0.000000
L 2.89490207 -0.84879961 2.89890128 -0.8687999 2 P 0 ;0,6=47,8=0.000000
L 2.89890128 -0.8687999 2.89890128 -0.8888002 2 P 0 ;0,6=47,8=0.000000
L 2.89890128 -0.8888002 2.89490207 -0.90880049 2 P 0 ;0,6=47,8=0.000000
L 2.89490207 -0.90880049 2.8869001 -0.92630138 2 P 0 ;0,6=47,8=0.000000
L 2.8869001 -0.92630138 2.87489902 -0.94130276 2 P 0 ;0,6=47,8=0.000000
L 2.87489902 -0.94130276 2.86089833 -0.95130059 2 P 0 ;0,6=47,8=0.000000
L 2.86089833 -0.95130059 2.84489813 -0.9538 2 P 0 ;0,6=47,8=0.000000
L 3.0488997 -0.81630197 3.03689862 -0.80879902 2 P 0 ;0,6=47,8=0.000000
L 3.03689862 -0.80879902 3.02290157 -0.8038 2 P 0 ;0,6=47,8=0.000000
L 3.02290157 -0.8038 3.00690138 -0.8038 2 P 0 ;0,6=47,8=0.000000
L 3.00690138 -0.8038 2.98889783 -0.81130305 2 P 0 ;0,6=47,8=0.000000
L 2.98889783 -0.81130305 2.97490089 -0.82380039 2 P 0 ;0,6=47,8=0.000000
L 2.97490089 -0.82380039 2.96489931 -0.83880177 2 P 0 ;0,6=47,8=0.000000
L 2.96489931 -0.83880177 2.95689734 -0.86380098 2 P 0 ;0,6=47,8=0.000000
L 2.95689734 -0.86380098 2.95489783 -0.88630069 2 P 0 ;0,6=47,8=0.000000
L 2.95489783 -0.88630069 2.95890059 -0.90880049 2 P 0 ;0,6=47,8=0.000000
L 2.95890059 -0.90880049 2.96489931 -0.92380187 2 P 0 ;0,6=47,8=0.000000
L 2.96489931 -0.92380187 2.97690039 -0.93880325 2 P 0 ;0,6=47,8=0.000000
L 2.97690039 -0.93880325 2.99090108 -0.94880108 2 P 0 ;0,6=47,8=0.000000
L 2.99090108 -0.94880108 3.00489813 -0.9538 2 P 0 ;0,6=47,8=0.000000
L 3.00489813 -0.9538 3.01889882 -0.9538 2 P 0 ;0,6=47,8=0.000000
L 3.01889882 -0.9538 3.03289951 -0.94880108 2 P 0 ;0,6=47,8=0.000000
L 3.03289951 -0.94880108 3.04490059 -0.94130276 2 P 0 ;0,6=47,8=0.000000
L 3.04490059 -0.94130276 3.05490207 -0.93130482 2 P 0 ;0,6=47,8=0.000000
L 3.16489813 -0.8038 3.16489813 -0.9538 2 P 0 ;0,6=47,8=0.000000
L 3.11890059 -0.8038 3.21089931 -0.8038 2 P 0 ;0,6=47,8=0.000000
L 3.28889852 -0.95879892 3.36090138 -0.8038 2 P 0 ;0,6=47,8=0.000000
L 3.44689892 -0.82879931 3.4589 -0.81380246 2 P 0 ;0,6=47,8=0.000000
L 3.4589 -0.81380246 3.47290069 -0.80629951 2 P 0 ;0,6=47,8=0.000000
L 3.47290069 -0.80629951 3.48890089 -0.8038 2 P 0 ;0,6=47,8=0.000000
L 3.48890089 -0.8038 3.5089003 -0.80879902 2 P 0 ;0,6=47,8=0.000000
L 3.5089003 -0.80879902 3.52290098 -0.82130089 2 P 0 ;0,6=47,8=0.000000
L 3.52290098 -0.82130089 3.5269001 -0.83629764 2 P 0 ;0,6=47,8=0.000000
L 3.5269001 -0.83629764 3.52490059 -0.85130364 2 P 0 ;0,6=47,8=0.000000
L 3.52490059 -0.85130364 3.51689862 -0.86380098 2 P 0 ;0,6=47,8=0.000000
L 3.51689862 -0.86380098 3.4768998 -0.8888002 2 P 0 ;0,6=47,8=0.000000
L 3.4768998 -0.8888002 3.4589 -0.90630108 2 P 0 ;0,6=47,8=0.000000
L 3.4589 -0.90630108 3.44689892 -0.93130482 2 P 0 ;0,6=47,8=0.000000
L 3.44689892 -0.93130482 3.4428998 -0.9538 2 P 0 ;0,6=47,8=0.000000
L 3.4428998 -0.9538 3.5269001 -0.9538 2 P 0 ;0,6=47,8=0.000000
L 3.64089902 -0.9538 3.64489813 -0.92130246 2 P 0 ;0,6=47,8=0.000000
L 3.64489813 -0.92130246 3.65090049 -0.89380374 2 P 0 ;0,6=47,8=0.000000
L 3.65090049 -0.89380374 3.65889882 -0.8687999 2 P 0 ;0,6=47,8=0.000000
L 3.65889882 -0.8687999 3.6689003 -0.84130118 2 P 0 ;0,6=47,8=0.000000
L 3.6689003 -0.84130118 3.68490059 -0.8038 2 P 0 ;0,6=47,8=0.000000
L 3.68490059 -0.8038 3.60489931 -0.8038 2 P 0 ;0,6=47,8=0.000000
L 3.76889852 -0.95879892 3.84090138 -0.8038 2 P 0 ;0,6=47,8=0.000000
L 3.92689892 -0.82879931 3.9389 -0.81380246 2 P 0 ;0,6=47,8=0.000000
L 3.9389 -0.81380246 3.95290069 -0.80629951 2 P 0 ;0,6=47,8=0.000000
L 3.95290069 -0.80629951 3.96890089 -0.8038 2 P 0 ;0,6=47,8=0.000000
L 3.96890089 -0.8038 3.9889003 -0.80879902 2 P 0 ;0,6=47,8=0.000000
L 3.9889003 -0.80879902 4.00290098 -0.82130089 2 P 0 ;0,6=47,8=0.000000
L 4.00290098 -0.82130089 4.0069001 -0.83629764 2 P 0 ;0,6=47,8=0.000000
L 4.0069001 -0.83629764 4.00490059 -0.85130364 2 P 0 ;0,6=47,8=0.000000
L 4.00490059 -0.85130364 3.99689862 -0.86380098 2 P 0 ;0,6=47,8=0.000000
L 3.99689862 -0.86380098 3.9568998 -0.8888002 2 P 0 ;0,6=47,8=0.000000
L 3.9568998 -0.8888002 3.9389 -0.90630108 2 P 0 ;0,6=47,8=0.000000
L 3.9389 -0.90630108 3.92689892 -0.93130482 2 P 0 ;0,6=47,8=0.000000
L 3.92689892 -0.93130482 3.9228998 -0.9538 2 P 0 ;0,6=47,8=0.000000
L 3.9228998 -0.9538 4.0069001 -0.9538 2 P 0 ;0,6=47,8=0.000000
L 4.12489813 -0.8038 4.10889783 -0.80879902 2 P 0 ;0,6=47,8=0.000000
L 4.10889783 -0.80879902 4.09690039 -0.82130089 2 P 0 ;0,6=47,8=0.000000
L 4.09690039 -0.82130089 4.08889852 -0.83629764 2 P 0 ;0,6=47,8=0.000000
L 4.08889852 -0.83629764 4.0828998 -0.85630256 2 P 0 ;0,6=47,8=0.000000
L 4.0828998 -0.85630256 4.0809002 -0.87880236 2 P 0 ;0,6=47,8=0.000000
L 4.0809002 -0.87880236 4.0828998 -0.90130207 2 P 0 ;0,6=47,8=0.000000
L 4.0828998 -0.90130207 4.08889852 -0.92130246 2 P 0 ;0,6=47,8=0.000000
L 4.08889852 -0.92130246 4.09690039 -0.93630374 2 P 0 ;0,6=47,8=0.000000
L 4.09690039 -0.93630374 4.10889783 -0.94880108 2 P 0 ;0,6=47,8=0.000000
L 4.10889783 -0.94880108 4.12489813 -0.9538 2 P 0 ;0,6=47,8=0.000000
L 4.12489813 -0.9538 4.14089833 -0.94880108 2 P 0 ;0,6=47,8=0.000000
L 4.14089833 -0.94880108 4.15289951 -0.93630374 2 P 0 ;0,6=47,8=0.000000
L 4.15289951 -0.93630374 4.16090138 -0.92130246 2 P 0 ;0,6=47,8=0.000000
L 4.16090138 -0.92130246 4.1669001 -0.90130207 2 P 0 ;0,6=47,8=0.000000
L 4.1669001 -0.90130207 4.1688997 -0.87880236 2 P 0 ;0,6=47,8=0.000000
L 4.1688997 -0.87880236 4.1669001 -0.85630256 2 P 0 ;0,6=47,8=0.000000
L 4.1669001 -0.85630256 4.16090138 -0.83629764 2 P 0 ;0,6=47,8=0.000000
L 4.16090138 -0.83629764 4.15289951 -0.82130089 2 P 0 ;0,6=47,8=0.000000
L 4.15289951 -0.82130089 4.14089833 -0.80879902 2 P 0 ;0,6=47,8=0.000000
L 4.14089833 -0.80879902 4.12489813 -0.8038 2 P 0 ;0,6=47,8=0.000000
L 4.28489813 -0.9538 4.28489813 -0.8038 2 P 0 ;0,6=47,8=0.000000
L 4.28489813 -0.8038 4.26089961 -0.83379823 2 P 0 ;0,6=47,8=0.000000
L 4.26089961 -0.9538 4.30889665 -0.9538 2 P 0 ;0,6=47,8=0.000000
L 4.44089902 -0.9538 4.44489813 -0.92130246 2 P 0 ;0,6=47,8=0.000000
L 4.44489813 -0.92130246 4.45090049 -0.89380374 2 P 0 ;0,6=47,8=0.000000
L 4.45090049 -0.89380374 4.45889882 -0.8687999 2 P 0 ;0,6=47,8=0.000000
L 4.45889882 -0.8687999 4.4689003 -0.84130118 2 P 0 ;0,6=47,8=0.000000
L 4.4689003 -0.84130118 4.48490059 -0.8038 2 P 0 ;0,6=47,8=0.000000
L 4.48490059 -0.8038 4.40489931 -0.8038 2 P 0 ;0,6=47,8=0.000000
A 0.57 -0.293 0.57 -0.293 0.5 -0.293 7 P 0 N
A 12.4952 -0.293 12.4952 -0.293 12.4252 -0.293 7 P 0 N
A 0.57 6.31661998 0.57 6.31661998 0.5 6.31661998 7 P 0 N
A 12.4952 6.31661998 12.4952 6.31661998 12.4252 6.31661998 7 P 0 N
A 0.6536 5.36731998 0.6536 5.36731998 0.5836 5.36731998 7 P 0 N
A 0.9911 0.2854 0.9911 0.2854 0.9211 0.2854 7 P 0 N
A 12.06518996 0.29 12.06518996 0.29 11.99518996 0.29 7 P 0 N
L 0.0825 4.8825 0.0825 4.8825 24 P 0 ;1
L 0.1325 0.1325 0.1325 0.1325 24 P 0 ;1
L 0.1325 0.1825 0.1325 0.1825 24 P 0 ;1
L 0.1325 0.2325 0.1325 0.2325 24 P 0 ;1
L 0.1325 0.2825 0.1325 0.2825 24 P 0 ;1
L 0.1325 1.0825 0.1325 1.0825 24 P 0 ;1
L 0.1325 1.1325 0.1325 1.1325 24 P 0 ;1
L 0.1325 1.1825 0.1325 1.1825 24 P 0 ;1
L 0.1325 5.5325 0.1325 5.5325 24 P 0 ;1
L 0.1325 5.5825 0.1325 5.5825 24 P 0 ;1
L 0.1325 5.6325 0.1325 5.6325 24 P 0 ;1
L 0.1325 5.6825 0.1325 5.6825 24 P 0 ;1
L 0.1825 0.1325 0.1825 0.1325 24 P 0 ;1
L 0.1825 0.1825 0.1825 0.1825 24 P 0 ;1
L 0.1825 0.2325 0.1825 0.2325 24 P 0 ;1
L 0.1825 1.0825 0.1825 1.0825 24 P 0 ;1
L 0.1825 1.1325 0.1825 1.1325 24 P 0 ;1
L 0.1825 1.1825 0.1825 1.1825 24 P 0 ;1
L 0.1825 5.5325 0.1825 5.5325 24 P 0 ;1
L 0.1825 5.5825 0.1825 5.5825 24 P 0 ;1
L 0.1825 5.6325 0.1825 5.6325 24 P 0 ;1
L 0.2325 0.1325 0.2325 0.1325 24 P 0 ;1
L 0.2325 0.1825 0.2325 0.1825 24 P 0 ;1
L 0.2325 0.2325 0.2325 0.2325 24 P 0 ;1
L 0.2325 1.0825 0.2325 1.0825 24 P 0 ;1
L 0.2325 1.1325 0.2325 1.1325 24 P 0 ;1
L 0.2325 1.1825 0.2325 1.1825 24 P 0 ;1
L 0.2325 5.5825 0.2325 5.5825 24 P 0 ;1
L 0.2325 5.6325 0.2325 5.6325 24 P 0 ;1
L 0.2825 0.1325 0.2825 0.1325 24 P 0 ;1
L 0.2825 0.1825 0.2825 0.1825 24 P 0 ;1
L 0.2825 0.2325 0.2825 0.2325 24 P 0 ;1
L 0.2825 0.2825 0.2825 0.2825 24 P 0 ;1
L 0.2825 1.0825 0.2825 1.0825 24 P 0 ;1
L 0.2825 1.1325 0.2825 1.1325 24 P 0 ;1
L 0.2825 1.1825 0.2825 1.1825 24 P 0 ;1
L 0.2825 5.5325 0.2825 5.5325 24 P 0 ;1
L 0.2825 5.5825 0.2825 5.5825 24 P 0 ;1
L 0.2825 5.6325 0.2825 5.6325 24 P 0 ;1
L 0.2825 5.6825 0.2825 5.6825 24 P 0 ;1
L 0.3325 0.1325 0.3325 0.1325 24 P 0 ;1
L 0.3325 0.1825 0.3325 0.1825 24 P 0 ;1
L 0.3325 0.2325 0.3325 0.2325 24 P 0 ;1
L 0.3325 0.2825 0.3325 0.2825 24 P 0 ;1
L 0.3325 1.0325 0.3325 1.0325 24 P 0 ;1
L 0.3325 1.0825 0.3325 1.0825 24 P 0 ;1
L 0.3325 1.1325 0.3325 1.1325 24 P 0 ;1
L 0.3325 1.1825 0.3325 1.1825 24 P 0 ;1
L 0.3325 4.7825 0.3325 4.7825 24 P 0 ;1
L 0.3325 5.5325 0.3325 5.5325 24 P 0 ;1
L 0.3325 5.5825 0.3325 5.5825 24 P 0 ;1
L 0.3325 5.6325 0.3325 5.6325 24 P 0 ;1
L 0.3325 5.6825 0.3325 5.6825 24 P 0 ;1
L 0.3325 5.7325 0.3325 5.7325 24 P 0 ;1
L 0.3825 0.1325 0.3825 0.1325 24 P 0 ;1
L 0.3825 0.1825 0.3825 0.1825 24 P 0 ;1
L 0.3825 0.2325 0.3825 0.2325 24 P 0 ;1
L 0.3825 0.2825 0.3825 0.2825 24 P 0 ;1
L 0.3825 0.3325 0.3825 0.3325 24 P 0 ;1
L 0.3825 0.3825 0.3825 0.3825 24 P 0 ;1
L 0.3825 0.4325 0.3825 0.4325 24 P 0 ;1
L 0.3825 0.4825 0.3825 0.4825 24 P 0 ;1
L 0.3825 0.8825 0.3825 0.8825 24 P 0 ;1
L 0.3825 0.9325 0.3825 0.9325 24 P 0 ;1
L 0.3825 0.9825 0.3825 0.9825 24 P 0 ;1
L 0.3825 1.0325 0.3825 1.0325 24 P 0 ;1
L 0.3825 1.0825 0.3825 1.0825 24 P 0 ;1
L 0.3825 1.1325 0.3825 1.1325 24 P 0 ;1
L 0.3825 1.1825 0.3825 1.1825 24 P 0 ;1
L 0.3825 4.7325 0.3825 4.7325 24 P 0 ;1
L 0.3825 4.7825 0.3825 4.7825 24 P 0 ;1
L 0.3825 4.8325 0.3825 4.8325 24 P 0 ;1
L 0.3825 4.8825 0.3825 4.8825 24 P 0 ;1
L 0.3825 4.9325 0.3825 4.9325 24 P 0 ;1
L 0.3825 5.3325 0.3825 5.3325 24 P 0 ;1
L 0.3825 5.3825 0.3825 5.3825 24 P 0 ;1
L 0.3825 5.4325 0.3825 5.4325 24 P 0 ;1
L 0.3825 5.4825 0.3825 5.4825 24 P 0 ;1
L 0.3825 5.5325 0.3825 5.5325 24 P 0 ;1
L 0.3825 5.5825 0.3825 5.5825 24 P 0 ;1
L 0.3825 5.6325 0.3825 5.6325 24 P 0 ;1
L 0.3825 5.6825 0.3825 5.6825 24 P 0 ;1
L 0.3825 5.7325 0.3825 5.7325 24 P 0 ;1
L 0.3825 5.7825 0.3825 5.7825 24 P 0 ;1
L 0.3825 5.8325 0.3825 5.8325 24 P 0 ;1
L 0.3825 5.8825 0.3825 5.8825 24 P 0 ;1
L 0.4325 0.1325 0.4325 0.1325 24 P 0 ;1
L 0.4325 0.1825 0.4325 0.1825 24 P 0 ;1
L 0.4325 0.2325 0.4325 0.2325 24 P 0 ;1
L 0.4325 0.2825 0.4325 0.2825 24 P 0 ;1
L 0.4325 0.3325 0.4325 0.3325 24 P 0 ;1
L 0.4325 0.3825 0.4325 0.3825 24 P 0 ;1
L 0.4325 0.4325 0.4325 0.4325 24 P 0 ;1
L 0.4325 0.4825 0.4325 0.4825 24 P 0 ;1
L 0.4325 0.5325 0.4325 0.5325 24 P 0 ;1
L 0.4325 0.8325 0.4325 0.8325 24 P 0 ;1
L 0.4325 0.8825 0.4325 0.8825 24 P 0 ;1
L 0.4325 0.9325 0.4325 0.9325 24 P 0 ;1
L 0.4325 0.9825 0.4325 0.9825 24 P 0 ;1
L 0.4325 1.0325 0.4325 1.0325 24 P 0 ;1
L 0.4325 1.0825 0.4325 1.0825 24 P 0 ;1
L 0.4325 1.1325 0.4325 1.1325 24 P 0 ;1
L 0.4325 1.1825 0.4325 1.1825 24 P 0 ;1
L 0.4325 4.6825 0.4325 4.6825 24 P 0 ;1
L 0.4325 4.7325 0.4325 4.7325 24 P 0 ;1
L 0.4325 4.7825 0.4325 4.7825 24 P 0 ;1
L 0.4325 4.8325 0.4325 4.8325 24 P 0 ;1
L 0.4325 4.8825 0.4325 4.8825 24 P 0 ;1
L 0.4325 4.9325 0.4325 4.9325 24 P 0 ;1
L 0.4325 4.9825 0.4325 4.9825 24 P 0 ;1
L 0.4325 5.2825 0.4325 5.2825 24 P 0 ;1
L 0.4325 5.4825 0.4325 5.4825 24 P 0 ;1
L 0.4325 5.5325 0.4325 5.5325 24 P 0 ;1
L 0.4325 5.5825 0.4325 5.5825 24 P 0 ;1
L 0.4325 5.6325 0.4325 5.6325 24 P 0 ;1
L 0.4325 5.6825 0.4325 5.6825 24 P 0 ;1
L 0.4325 5.7325 0.4325 5.7325 24 P 0 ;1
L 0.4325 5.7825 0.4325 5.7825 24 P 0 ;1
L 0.4825 0.1325 0.4825 0.1325 24 P 0 ;1
L 0.4825 0.1825 0.4825 0.1825 24 P 0 ;1
L 0.4825 0.2325 0.4825 0.2325 24 P 0 ;1
L 0.4825 0.2825 0.4825 0.2825 24 P 0 ;1
L 0.4825 0.3325 0.4825 0.3325 24 P 0 ;1
L 0.4825 0.3825 0.4825 0.3825 24 P 0 ;1
L 0.4825 0.4325 0.4825 0.4325 24 P 0 ;1
L 0.4825 0.4825 0.4825 0.4825 24 P 0 ;1
L 0.4825 0.5325 0.4825 0.5325 24 P 0 ;1
L 0.4825 0.5825 0.4825 0.5825 24 P 0 ;1
L 0.4825 0.6325 0.4825 0.6325 24 P 0 ;1
L 0.4825 0.6825 0.4825 0.6825 24 P 0 ;1
L 0.4825 0.7325 0.4825 0.7325 24 P 0 ;1
L 0.4825 0.7825 0.4825 0.7825 24 P 0 ;1
L 0.4825 0.8325 0.4825 0.8325 24 P 0 ;1
L 0.4825 0.8825 0.4825 0.8825 24 P 0 ;1
L 0.4825 0.9325 0.4825 0.9325 24 P 0 ;1
L 0.4825 0.9825 0.4825 0.9825 24 P 0 ;1
L 0.4825 1.0325 0.4825 1.0325 24 P 0 ;1
L 0.4825 1.0825 0.4825 1.0825 24 P 0 ;1
L 0.4825 1.1325 0.4825 1.1325 24 P 0 ;1
L 0.4825 1.1825 0.4825 1.1825 24 P 0 ;1
L 0.4825 1.3825 0.4825 1.3825 24 P 0 ;1
L 0.4825 1.4325 0.4825 1.4325 24 P 0 ;1
L 0.4825 1.4825 0.4825 1.4825 24 P 0 ;1
L 0.4825 1.5325 0.4825 1.5325 24 P 0 ;1
L 0.4825 1.7825 0.4825 1.7825 24 P 0 ;1
L 0.4825 2.1325 0.4825 2.1325 24 P 0 ;1
L 0.4825 2.1825 0.4825 2.1825 24 P 0 ;1
L 0.4825 2.2325 0.4825 2.2325 24 P 0 ;1
L 0.4825 2.2825 0.4825 2.2825 24 P 0 ;1
L 0.4825 2.3325 0.4825 2.3325 24 P 0 ;1
L 0.4825 2.3825 0.4825 2.3825 24 P 0 ;1
L 0.4825 2.4325 0.4825 2.4325 24 P 0 ;1
L 0.4825 2.4825 0.4825 2.4825 24 P 0 ;1
L 0.4825 4.6325 0.4825 4.6325 24 P 0 ;1
L 0.4825 4.6825 0.4825 4.6825 24 P 0 ;1
L 0.4825 4.7325 0.4825 4.7325 24 P 0 ;1
L 0.4825 4.7825 0.4825 4.7825 24 P 0 ;1
L 0.4825 4.8325 0.4825 4.8325 24 P 0 ;1
L 0.4825 4.8825 0.4825 4.8825 24 P 0 ;1
L 0.4825 4.9325 0.4825 4.9325 24 P 0 ;1
L 0.4825 4.9825 0.4825 4.9825 24 P 0 ;1
L 0.4825 5.0325 0.4825 5.0325 24 P 0 ;1
L 0.4825 5.0825 0.4825 5.0825 24 P 0 ;1
L 0.4825 5.1325 0.4825 5.1325 24 P 0 ;1
L 0.4825 5.1825 0.4825 5.1825 24 P 0 ;1
L 0.4825 5.2325 0.4825 5.2325 24 P 0 ;1
L 0.4825 5.5325 0.4825 5.5325 24 P 0 ;1
L 0.4825 5.5825 0.4825 5.5825 24 P 0 ;1
L 0.4825 5.6325 0.4825 5.6325 24 P 0 ;1
L 0.4825 5.6825 0.4825 5.6825 24 P 0 ;1
L 0.4825 5.7325 0.4825 5.7325 24 P 0 ;1
L 0.4825 5.7825 0.4825 5.7825 24 P 0 ;1
L 0.5325 0.1325 0.5325 0.1325 24 P 0 ;1
L 0.5325 0.1825 0.5325 0.1825 24 P 0 ;1
L 0.5325 0.3825 0.5325 0.3825 24 P 0 ;1
L 0.5325 0.4325 0.5325 0.4325 24 P 0 ;1
L 0.5325 0.4825 0.5325 0.4825 24 P 0 ;1
L 0.5325 0.5325 0.5325 0.5325 24 P 0 ;1
L 0.5325 0.5825 0.5325 0.5825 24 P 0 ;1
L 0.5325 0.6325 0.5325 0.6325 24 P 0 ;1
L 0.5325 0.6825 0.5325 0.6825 24 P 0 ;1
L 0.5325 0.7325 0.5325 0.7325 24 P 0 ;1
L 0.5325 0.7825 0.5325 0.7825 24 P 0 ;1
L 0.5325 0.8325 0.5325 0.8325 24 P 0 ;1
L 0.5325 0.8825 0.5325 0.8825 24 P 0 ;1
L 0.5325 0.9325 0.5325 0.9325 24 P 0 ;1
L 0.5325 0.9825 0.5325 0.9825 24 P 0 ;1
L 0.5325 1.0325 0.5325 1.0325 24 P 0 ;1
L 0.5325 1.0825 0.5325 1.0825 24 P 0 ;1
L 0.5325 1.1325 0.5325 1.1325 24 P 0 ;1
L 0.5325 1.1825 0.5325 1.1825 24 P 0 ;1
L 0.5325 1.4325 0.5325 1.4325 24 P 0 ;1
L 0.5325 1.4825 0.5325 1.4825 24 P 0 ;1
L 0.5325 1.5325 0.5325 1.5325 24 P 0 ;1
L 0.5325 2.1325 0.5325 2.1325 24 P 0 ;1
L 0.5325 2.1825 0.5325 2.1825 24 P 0 ;1
L 0.5325 2.2325 0.5325 2.2325 24 P 0 ;1
L 0.5325 2.2825 0.5325 2.2825 24 P 0 ;1
L 0.5325 2.3325 0.5325 2.3325 24 P 0 ;1
L 0.5325 2.3825 0.5325 2.3825 24 P 0 ;1
L 0.5325 2.4325 0.5325 2.4325 24 P 0 ;1
L 0.5325 2.4825 0.5325 2.4825 24 P 0 ;1
L 0.5325 2.5325 0.5325 2.5325 24 P 0 ;1
L 0.5325 2.5825 0.5325 2.5825 24 P 0 ;1
L 0.5325 2.6325 0.5325 2.6325 24 P 0 ;1
L 0.5325 2.6825 0.5325 2.6825 24 P 0 ;1
L 0.5325 2.7325 0.5325 2.7325 24 P 0 ;1
L 0.5325 2.7825 0.5325 2.7825 24 P 0 ;1
L 0.5325 2.8325 0.5325 2.8325 24 P 0 ;1
L 0.5325 2.8825 0.5325 2.8825 24 P 0 ;1
L 0.5325 2.9325 0.5325 2.9325 24 P 0 ;1
L 0.5325 2.9825 0.5325 2.9825 24 P 0 ;1
L 0.5325 3.0325 0.5325 3.0325 24 P 0 ;1
L 0.5325 3.0825 0.5325 3.0825 24 P 0 ;1
L 0.5325 3.1325 0.5325 3.1325 24 P 0 ;1
L 0.5325 3.1825 0.5325 3.1825 24 P 0 ;1
L 0.5325 3.2325 0.5325 3.2325 24 P 0 ;1
L 0.5325 3.2825 0.5325 3.2825 24 P 0 ;1
L 0.5325 3.3325 0.5325 3.3325 24 P 0 ;1
L 0.5325 3.3825 0.5325 3.3825 24 P 0 ;1
L 0.5325 3.4325 0.5325 3.4325 24 P 0 ;1
L 0.5325 3.4825 0.5325 3.4825 24 P 0 ;1
L 0.5325 3.5325 0.5325 3.5325 24 P 0 ;1
L 0.5325 3.5825 0.5325 3.5825 24 P 0 ;1
L 0.5325 3.6325 0.5325 3.6325 24 P 0 ;1
L 0.5325 3.6825 0.5325 3.6825 24 P 0 ;1
L 0.5325 3.7325 0.5325 3.7325 24 P 0 ;1
L 0.5325 3.7825 0.5325 3.7825 24 P 0 ;1
L 0.5325 3.8325 0.5325 3.8325 24 P 0 ;1
L 0.5325 3.8825 0.5325 3.8825 24 P 0 ;1
L 0.5325 3.9325 0.5325 3.9325 24 P 0 ;1
L 0.5325 3.9825 0.5325 3.9825 24 P 0 ;1
L 0.5325 4.0325 0.5325 4.0325 24 P 0 ;1
L 0.5325 4.0825 0.5325 4.0825 24 P 0 ;1
L 0.5325 4.1325 0.5325 4.1325 24 P 0 ;1
L 0.5325 4.1825 0.5325 4.1825 24 P 0 ;1
L 0.5325 4.2325 0.5325 4.2325 24 P 0 ;1
L 0.5325 4.2825 0.5325 4.2825 24 P 0 ;1
L 0.5325 4.3325 0.5325 4.3325 24 P 0 ;1
L 0.5325 4.3825 0.5325 4.3825 24 P 0 ;1
L 0.5325 4.4325 0.5325 4.4325 24 P 0 ;1
L 0.5325 4.4825 0.5325 4.4825 24 P 0 ;1
L 0.5325 4.5325 0.5325 4.5325 24 P 0 ;1
L 0.5325 4.5825 0.5325 4.5825 24 P 0 ;1
L 0.5325 4.6325 0.5325 4.6325 24 P 0 ;1
L 0.5325 4.6825 0.5325 4.6825 24 P 0 ;1
L 0.5325 4.7325 0.5325 4.7325 24 P 0 ;1
L 0.5325 4.7825 0.5325 4.7825 24 P 0 ;1
L 0.5325 4.8325 0.5325 4.8325 24 P 0 ;1
L 0.5325 4.8825 0.5325 4.8825 24 P 0 ;1
L 0.5325 4.9325 0.5325 4.9325 24 P 0 ;1
L 0.5325 4.9825 0.5325 4.9825 24 P 0 ;1
L 0.5325 5.0325 0.5325 5.0325 24 P 0 ;1
L 0.5325 5.0825 0.5325 5.0825 24 P 0 ;1
L 0.5325 5.1325 0.5325 5.1325 24 P 0 ;1
L 0.5325 5.1825 0.5325 5.1825 24 P 0 ;1
L 0.5325 5.6825 0.5325 5.6825 24 P 0 ;1
L 0.5325 5.7325 0.5325 5.7325 24 P 0 ;1
L 0.5325 5.7825 0.5325 5.7825 24 P 0 ;1
L 0.5825 0.1325 0.5825 0.1325 24 P 0 ;1
L 0.5825 0.4325 0.5825 0.4325 24 P 0 ;1
L 0.5825 0.4825 0.5825 0.4825 24 P 0 ;1
L 0.5825 0.5325 0.5825 0.5325 24 P 0 ;1
L 0.5825 0.5825 0.5825 0.5825 24 P 0 ;1
L 0.5825 0.6325 0.5825 0.6325 24 P 0 ;1
L 0.5825 0.6825 0.5825 0.6825 24 P 0 ;1
L 0.5825 0.7325 0.5825 0.7325 24 P 0 ;1
L 0.5825 0.7825 0.5825 0.7825 24 P 0 ;1
L 0.5825 0.8325 0.5825 0.8325 24 P 0 ;1
L 0.5825 0.8825 0.5825 0.8825 24 P 0 ;1
L 0.5825 0.9325 0.5825 0.9325 24 P 0 ;1
L 0.5825 0.9825 0.5825 0.9825 24 P 0 ;1
L 0.5825 1.0325 0.5825 1.0325 24 P 0 ;1
L 0.5825 1.0825 0.5825 1.0825 24 P 0 ;1
L 0.5825 1.1325 0.5825 1.1325 24 P 0 ;1
L 0.5825 1.1825 0.5825 1.1825 24 P 0 ;1
L 0.5825 1.4325 0.5825 1.4325 24 P 0 ;1
L 0.5825 1.4825 0.5825 1.4825 24 P 0 ;1
L 0.5825 1.5325 0.5825 1.5325 24 P 0 ;1
L 0.5825 2.1825 0.5825 2.1825 24 P 0 ;1
L 0.5825 2.2325 0.5825 2.2325 24 P 0 ;1
L 0.5825 2.2825 0.5825 2.2825 24 P 0 ;1
L 0.5825 2.3325 0.5825 2.3325 24 P 0 ;1
L 0.5825 2.3825 0.5825 2.3825 24 P 0 ;1
L 0.5825 2.4325 0.5825 2.4325 24 P 0 ;1
L 0.5825 2.4825 0.5825 2.4825 24 P 0 ;1
L 0.5825 2.5325 0.5825 2.5325 24 P 0 ;1
L 0.5825 2.5825 0.5825 2.5825 24 P 0 ;1
L 0.5825 2.6325 0.5825 2.6325 24 P 0 ;1
L 0.5825 2.6825 0.5825 2.6825 24 P 0 ;1
L 0.5825 2.7325 0.5825 2.7325 24 P 0 ;1
L 0.5825 2.7825 0.5825 2.7825 24 P 0 ;1
L 0.5825 2.8325 0.5825 2.8325 24 P 0 ;1
L 0.5825 2.8825 0.5825 2.8825 24 P 0 ;1
L 0.5825 2.9325 0.5825 2.9325 24 P 0 ;1
L 0.5825 2.9825 0.5825 2.9825 24 P 0 ;1
L 0.5825 3.0325 0.5825 3.0325 24 P 0 ;1
L 0.5825 3.0825 0.5825 3.0825 24 P 0 ;1
L 0.5825 3.1325 0.5825 3.1325 24 P 0 ;1
L 0.5825 3.1825 0.5825 3.1825 24 P 0 ;1
L 0.5825 3.2325 0.5825 3.2325 24 P 0 ;1
L 0.5825 3.2825 0.5825 3.2825 24 P 0 ;1
L 0.5825 3.3325 0.5825 3.3325 24 P 0 ;1
L 0.5825 3.3825 0.5825 3.3825 24 P 0 ;1
L 0.5825 3.4325 0.5825 3.4325 24 P 0 ;1
L 0.5825 3.4825 0.5825 3.4825 24 P 0 ;1
L 0.5825 3.5325 0.5825 3.5325 24 P 0 ;1
L 0.5825 3.5825 0.5825 3.5825 24 P 0 ;1
L 0.5825 3.6325 0.5825 3.6325 24 P 0 ;1
L 0.5825 3.6825 0.5825 3.6825 24 P 0 ;1
L 0.5825 3.7325 0.5825 3.7325 24 P 0 ;1
L 0.5825 3.7825 0.5825 3.7825 24 P 0 ;1
L 0.5825 3.8325 0.5825 3.8325 24 P 0 ;1
L 0.5825 3.8825 0.5825 3.8825 24 P 0 ;1
L 0.5825 3.9325 0.5825 3.9325 24 P 0 ;1
L 0.5825 3.9825 0.5825 3.9825 24 P 0 ;1
L 0.5825 4.0325 0.5825 4.0325 24 P 0 ;1
L 0.5825 4.0825 0.5825 4.0825 24 P 0 ;1
L 0.5825 4.1325 0.5825 4.1325 24 P 0 ;1
L 0.5825 4.1825 0.5825 4.1825 24 P 0 ;1
L 0.5825 4.2325 0.5825 4.2325 24 P 0 ;1
L 0.5825 4.2825 0.5825 4.2825 24 P 0 ;1
L 0.5825 4.3325 0.5825 4.3325 24 P 0 ;1
L 0.5825 4.3825 0.5825 4.3825 24 P 0 ;1
L 0.5825 4.4325 0.5825 4.4325 24 P 0 ;1
L 0.5825 4.4825 0.5825 4.4825 24 P 0 ;1
L 0.5825 4.5325 0.5825 4.5325 24 P 0 ;1
L 0.5825 4.5825 0.5825 4.5825 24 P 0 ;1
L 0.5825 4.6325 0.5825 4.6325 24 P 0 ;1
L 0.5825 4.6825 0.5825 4.6825 24 P 0 ;1
L 0.5825 4.7325 0.5825 4.7325 24 P 0 ;1
L 0.5825 4.7825 0.5825 4.7825 24 P 0 ;1
L 0.5825 4.8325 0.5825 4.8325 24 P 0 ;1
L 0.5825 4.8825 0.5825 4.8825 24 P 0 ;1
L 0.5825 4.9325 0.5825 4.9325 24 P 0 ;1
L 0.5825 4.9825 0.5825 4.9825 24 P 0 ;1
L 0.5825 5.0325 0.5825 5.0325 24 P 0 ;1
L 0.5825 5.0825 0.5825 5.0825 24 P 0 ;1
L 0.5825 5.1325 0.5825 5.1325 24 P 0 ;1
L 0.5825 5.1825 0.5825 5.1825 24 P 0 ;1
L 0.5825 5.7325 0.5825 5.7325 24 P 0 ;1
L 0.5825 5.7825 0.5825 5.7825 24 P 0 ;1
L 0.5825 5.8325 0.5825 5.8325 24 P 0 ;1
L 0.5825 5.8825 0.5825 5.8825 24 P 0 ;1
L 0.6325 0.1325 0.6325 0.1325 24 P 0 ;1
L 0.6325 0.4825 0.6325 0.4825 24 P 0 ;1
L 0.6325 0.5325 0.6325 0.5325 24 P 0 ;1
L 0.6325 0.5825 0.6325 0.5825 24 P 0 ;1
L 0.6325 0.6325 0.6325 0.6325 24 P 0 ;1
L 0.6325 0.6825 0.6325 0.6825 24 P 0 ;1
L 0.6325 0.7325 0.6325 0.7325 24 P 0 ;1
L 0.6325 0.7825 0.6325 0.7825 24 P 0 ;1
L 0.6325 0.8325 0.6325 0.8325 24 P 0 ;1
L 0.6325 0.8825 0.6325 0.8825 24 P 0 ;1
L 0.6325 0.9325 0.6325 0.9325 24 P 0 ;1
L 0.6325 0.9825 0.6325 0.9825 24 P 0 ;1
L 0.6325 1.0325 0.6325 1.0325 24 P 0 ;1
L 0.6325 1.0825 0.6325 1.0825 24 P 0 ;1
L 0.6325 1.1325 0.6325 1.1325 24 P 0 ;1
L 0.6325 1.1825 0.6325 1.1825 24 P 0 ;1
L 0.6325 1.2325 0.6325 1.2325 24 P 0 ;1
L 0.6325 1.4325 0.6325 1.4325 24 P 0 ;1
L 0.6325 1.4825 0.6325 1.4825 24 P 0 ;1
L 0.6325 1.5325 0.6325 1.5325 24 P 0 ;1
L 0.6325 4.8325 0.6325 4.8325 24 P 0 ;1
L 0.6325 4.8825 0.6325 4.8825 24 P 0 ;1
L 0.6325 4.9325 0.6325 4.9325 24 P 0 ;1
L 0.6325 4.9825 0.6325 4.9825 24 P 0 ;1
L 0.6325 5.0325 0.6325 5.0325 24 P 0 ;1
L 0.6325 5.0825 0.6325 5.0825 24 P 0 ;1
L 0.6325 5.1325 0.6325 5.1325 24 P 0 ;1
L 0.6325 5.1825 0.6325 5.1825 24 P 0 ;1
L 0.6325 5.6825 0.6325 5.6825 24 P 0 ;1
L 0.6325 5.7325 0.6325 5.7325 24 P 0 ;1
L 0.6325 5.7825 0.6325 5.7825 24 P 0 ;1
L 0.6325 5.8325 0.6325 5.8325 24 P 0 ;1
L 0.6325 5.8825 0.6325 5.8825 24 P 0 ;1
L 0.6825 0.1325 0.6825 0.1325 24 P 0 ;1
L 0.6825 0.4825 0.6825 0.4825 24 P 0 ;1
L 0.6825 0.5325 0.6825 0.5325 24 P 0 ;1
L 0.6825 0.5825 0.6825 0.5825 24 P 0 ;1
L 0.6825 0.6325 0.6825 0.6325 24 P 0 ;1
L 0.6825 0.6825 0.6825 0.6825 24 P 0 ;1
L 0.6825 0.7325 0.6825 0.7325 24 P 0 ;1
L 0.6825 0.7825 0.6825 0.7825 24 P 0 ;1
L 0.6825 0.8325 0.6825 0.8325 24 P 0 ;1
L 0.6825 0.8825 0.6825 0.8825 24 P 0 ;1
L 0.6825 0.9325 0.6825 0.9325 24 P 0 ;1
L 0.6825 0.9825 0.6825 0.9825 24 P 0 ;1
L 0.6825 1.0325 0.6825 1.0325 24 P 0 ;1
L 0.6825 1.0825 0.6825 1.0825 24 P 0 ;1
L 0.6825 1.1325 0.6825 1.1325 24 P 0 ;1
L 0.6825 1.1825 0.6825 1.1825 24 P 0 ;1
L 0.6825 1.2325 0.6825 1.2325 24 P 0 ;1
L 0.6825 5.0825 0.6825 5.0825 24 P 0 ;1
L 0.6825 5.6825 0.6825 5.6825 24 P 0 ;1
L 0.7325 0.1325 0.7325 0.1325 24 P 0 ;1
L 0.7325 0.4325 0.7325 0.4325 24 P 0 ;1
L 0.7325 0.4825 0.7325 0.4825 24 P 0 ;1
L 0.7325 0.5325 0.7325 0.5325 24 P 0 ;1
L 0.7325 0.5825 0.7325 0.5825 24 P 0 ;1
L 0.7325 0.6325 0.7325 0.6325 24 P 0 ;1
L 0.7325 0.6825 0.7325 0.6825 24 P 0 ;1
L 0.7325 0.7325 0.7325 0.7325 24 P 0 ;1
L 0.7325 0.7825 0.7325 0.7825 24 P 0 ;1
L 0.7325 0.8325 0.7325 0.8325 24 P 0 ;1
L 0.7325 0.8825 0.7325 0.8825 24 P 0 ;1
L 0.7325 0.9325 0.7325 0.9325 24 P 0 ;1
L 0.7325 0.9825 0.7325 0.9825 24 P 0 ;1
L 0.7325 1.0325 0.7325 1.0325 24 P 0 ;1
L 0.7325 1.0825 0.7325 1.0825 24 P 0 ;1
L 0.7325 1.1325 0.7325 1.1325 24 P 0 ;1
L 0.7325 1.1825 0.7325 1.1825 24 P 0 ;1
L 0.7325 1.2325 0.7325 1.2325 24 P 0 ;1
L 0.7825 0.1325 0.7825 0.1325 24 P 0 ;1
L 0.7825 0.1825 0.7825 0.1825 24 P 0 ;1
L 0.7825 0.3825 0.7825 0.3825 24 P 0 ;1
L 0.7825 0.4325 0.7825 0.4325 24 P 0 ;1
L 0.7825 0.4825 0.7825 0.4825 24 P 0 ;1
L 0.7825 0.5325 0.7825 0.5325 24 P 0 ;1
L 0.7825 0.5825 0.7825 0.5825 24 P 0 ;1
L 0.7825 0.6325 0.7825 0.6325 24 P 0 ;1
L 0.7825 0.6825 0.7825 0.6825 24 P 0 ;1
L 0.7825 0.7325 0.7825 0.7325 24 P 0 ;1
L 0.7825 0.7825 0.7825 0.7825 24 P 0 ;1
L 0.7825 0.8325 0.7825 0.8325 24 P 0 ;1
L 0.7825 0.8825 0.7825 0.8825 24 P 0 ;1
L 0.7825 0.9325 0.7825 0.9325 24 P 0 ;1
L 0.7825 0.9825 0.7825 0.9825 24 P 0 ;1
L 0.7825 1.0325 0.7825 1.0325 24 P 0 ;1
L 0.7825 1.0825 0.7825 1.0825 24 P 0 ;1
L 0.7825 1.1325 0.7825 1.1325 24 P 0 ;1
L 0.7825 1.1825 0.7825 1.1825 24 P 0 ;1
L 0.7825 1.2325 0.7825 1.2325 24 P 0 ;1
L 0.8325 0.1325 0.8325 0.1325 24 P 0 ;1
L 0.8325 0.4325 0.8325 0.4325 24 P 0 ;1
L 0.8325 0.4825 0.8325 0.4825 24 P 0 ;1
L 0.8325 0.5325 0.8325 0.5325 24 P 0 ;1
L 0.8325 0.5825 0.8325 0.5825 24 P 0 ;1
L 0.8325 0.6325 0.8325 0.6325 24 P 0 ;1
L 0.8325 0.6825 0.8325 0.6825 24 P 0 ;1
L 0.8325 0.7325 0.8325 0.7325 24 P 0 ;1
L 0.8325 0.7825 0.8325 0.7825 24 P 0 ;1
L 0.8325 0.8325 0.8325 0.8325 24 P 0 ;1
L 0.8325 0.8825 0.8325 0.8825 24 P 0 ;1
L 0.8325 0.9325 0.8325 0.9325 24 P 0 ;1
L 0.8325 0.9825 0.8325 0.9825 24 P 0 ;1
L 0.8325 1.0325 0.8325 1.0325 24 P 0 ;1
L 0.8325 1.0825 0.8325 1.0825 24 P 0 ;1
L 0.8325 1.1325 0.8325 1.1325 24 P 0 ;1
L 0.8325 1.1825 0.8325 1.1825 24 P 0 ;1
L 0.8325 1.2325 0.8325 1.2325 24 P 0 ;1
L 0.8325 1.2825 0.8325 1.2825 24 P 0 ;1
L 0.8325 2.1825 0.8325 2.1825 24 P 0 ;1
L 0.8325 2.2325 0.8325 2.2325 24 P 0 ;1
L 0.8325 2.2825 0.8325 2.2825 24 P 0 ;1
L 0.8325 2.3325 0.8325 2.3325 24 P 0 ;1
L 0.8325 2.3825 0.8325 2.3825 24 P 0 ;1
L 0.8325 2.4325 0.8325 2.4325 24 P 0 ;1
L 0.8325 2.4825 0.8325 2.4825 24 P 0 ;1
L 0.8325 2.5325 0.8325 2.5325 24 P 0 ;1
L 0.8325 2.5825 0.8325 2.5825 24 P 0 ;1
L 0.8325 2.6325 0.8325 2.6325 24 P 0 ;1
L 0.8325 2.6825 0.8325 2.6825 24 P 0 ;1
L 0.8325 2.7325 0.8325 2.7325 24 P 0 ;1
L 0.8325 2.7825 0.8325 2.7825 24 P 0 ;1
L 0.8325 2.8325 0.8325 2.8325 24 P 0 ;1
L 0.8325 2.8825 0.8325 2.8825 24 P 0 ;1
L 0.8325 2.9325 0.8325 2.9325 24 P 0 ;1
L 0.8325 2.9825 0.8325 2.9825 24 P 0 ;1
L 0.8325 3.0325 0.8325 3.0325 24 P 0 ;1
L 0.8325 3.0825 0.8325 3.0825 24 P 0 ;1
L 0.8325 3.1325 0.8325 3.1325 24 P 0 ;1
L 0.8325 3.1825 0.8325 3.1825 24 P 0 ;1
L 0.8325 3.2325 0.8325 3.2325 24 P 0 ;1
L 0.8325 3.2825 0.8325 3.2825 24 P 0 ;1
L 0.8325 3.3325 0.8325 3.3325 24 P 0 ;1
L 0.8325 3.3825 0.8325 3.3825 24 P 0 ;1
L 0.8325 3.4325 0.8325 3.4325 24 P 0 ;1
L 0.8325 3.4825 0.8325 3.4825 24 P 0 ;1
L 0.8325 3.5325 0.8325 3.5325 24 P 0 ;1
L 0.8325 3.5825 0.8325 3.5825 24 P 0 ;1
L 0.8325 3.6325 0.8325 3.6325 24 P 0 ;1
L 0.8325 3.6825 0.8325 3.6825 24 P 0 ;1
L 0.8325 3.7325 0.8325 3.7325 24 P 0 ;1
L 0.8325 3.7825 0.8325 3.7825 24 P 0 ;1
L 0.8325 3.8325 0.8325 3.8325 24 P 0 ;1
L 0.8325 3.8825 0.8325 3.8825 24 P 0 ;1
L 0.8325 3.9325 0.8325 3.9325 24 P 0 ;1
L 0.8325 3.9825 0.8325 3.9825 24 P 0 ;1
L 0.8325 4.4325 0.8325 4.4325 24 P 0 ;1
L 0.8325 4.4825 0.8325 4.4825 24 P 0 ;1
L 0.8325 4.5325 0.8325 4.5325 24 P 0 ;1
L 0.8325 4.5825 0.8325 4.5825 24 P 0 ;1
L 0.8325 4.6325 0.8325 4.6325 24 P 0 ;1
L 0.8325 4.6825 0.8325 4.6825 24 P 0 ;1
L 0.8325 4.7325 0.8325 4.7325 24 P 0 ;1
L 0.8825 0.4825 0.8825 0.4825 24 P 0 ;1
L 0.8825 0.5325 0.8825 0.5325 24 P 0 ;1
L 0.8825 0.5825 0.8825 0.5825 24 P 0 ;1
L 0.8825 0.6325 0.8825 0.6325 24 P 0 ;1
L 0.8825 0.6825 0.8825 0.6825 24 P 0 ;1
L 0.8825 0.7325 0.8825 0.7325 24 P 0 ;1
L 0.8825 0.7825 0.8825 0.7825 24 P 0 ;1
L 0.8825 0.8325 0.8825 0.8325 24 P 0 ;1
L 0.8825 0.8825 0.8825 0.8825 24 P 0 ;1
L 0.8825 0.9325 0.8825 0.9325 24 P 0 ;1
L 0.8825 0.9825 0.8825 0.9825 24 P 0 ;1
L 0.8825 1.0325 0.8825 1.0325 24 P 0 ;1
L 0.8825 1.0825 0.8825 1.0825 24 P 0 ;1
L 0.8825 1.1325 0.8825 1.1325 24 P 0 ;1
L 0.8825 1.1825 0.8825 1.1825 24 P 0 ;1
L 0.8825 1.2325 0.8825 1.2325 24 P 0 ;1
L 0.8825 1.2825 0.8825 1.2825 24 P 0 ;1
L 0.8825 1.7825 0.8825 1.7825 24 P 0 ;1
L 0.8825 1.8325 0.8825 1.8325 24 P 0 ;1
L 0.8825 2.1325 0.8825 2.1325 24 P 0 ;1
L 0.8825 2.1825 0.8825 2.1825 24 P 0 ;1
L 0.8825 2.2325 0.8825 2.2325 24 P 0 ;1
L 0.8825 2.2825 0.8825 2.2825 24 P 0 ;1
L 0.8825 2.3325 0.8825 2.3325 24 P 0 ;1
L 0.8825 2.3825 0.8825 2.3825 24 P 0 ;1
L 0.8825 2.4325 0.8825 2.4325 24 P 0 ;1
L 0.8825 2.4825 0.8825 2.4825 24 P 0 ;1
L 0.8825 2.5325 0.8825 2.5325 24 P 0 ;1
L 0.8825 2.6325 0.8825 2.6325 24 P 0 ;1
L 0.8825 2.6825 0.8825 2.6825 24 P 0 ;1
L 0.8825 2.7325 0.8825 2.7325 24 P 0 ;1
L 0.8825 2.7825 0.8825 2.7825 24 P 0 ;1
L 0.8825 2.8325 0.8825 2.8325 24 P 0 ;1
L 0.8825 2.8825 0.8825 2.8825 24 P 0 ;1
L 0.8825 2.9325 0.8825 2.9325 24 P 0 ;1
L 0.8825 2.9825 0.8825 2.9825 24 P 0 ;1
L 0.8825 3.0325 0.8825 3.0325 24 P 0 ;1
L 0.8825 3.0825 0.8825 3.0825 24 P 0 ;1
L 0.8825 3.1325 0.8825 3.1325 24 P 0 ;1
L 0.8825 3.1825 0.8825 3.1825 24 P 0 ;1
L 0.8825 3.2325 0.8825 3.2325 24 P 0 ;1
L 0.8825 3.2825 0.8825 3.2825 24 P 0 ;1
L 0.8825 3.3325 0.8825 3.3325 24 P 0 ;1
L 0.8825 3.3825 0.8825 3.3825 24 P 0 ;1
L 0.8825 3.4325 0.8825 3.4325 24 P 0 ;1
L 0.8825 3.4825 0.8825 3.4825 24 P 0 ;1
L 0.8825 3.5325 0.8825 3.5325 24 P 0 ;1
L 0.8825 3.5825 0.8825 3.5825 24 P 0 ;1
L 0.8825 3.6325 0.8825 3.6325 24 P 0 ;1
L 0.8825 3.6825 0.8825 3.6825 24 P 0 ;1
L 0.8825 3.7325 0.8825 3.7325 24 P 0 ;1
L 0.8825 3.7825 0.8825 3.7825 24 P 0 ;1
L 0.8825 3.8325 0.8825 3.8325 24 P 0 ;1
L 0.8825 3.8825 0.8825 3.8825 24 P 0 ;1
L 0.8825 3.9325 0.8825 3.9325 24 P 0 ;1
L 0.8825 4.4825 0.8825 4.4825 24 P 0 ;1
L 0.8825 4.5325 0.8825 4.5325 24 P 0 ;1
L 0.8825 4.5825 0.8825 4.5825 24 P 0 ;1
L 0.8825 4.6325 0.8825 4.6325 24 P 0 ;1
L 0.8825 4.6825 0.8825 4.6825 24 P 0 ;1
L 0.8825 4.7325 0.8825 4.7325 24 P 0 ;1
L 0.8825 4.7825 0.8825 4.7825 24 P 0 ;1
L 0.9325 0.4825 0.9325 0.4825 24 P 0 ;1
L 0.9325 0.5325 0.9325 0.5325 24 P 0 ;1
L 0.9325 0.5825 0.9325 0.5825 24 P 0 ;1
L 0.9325 0.6325 0.9325 0.6325 24 P 0 ;1
L 0.9325 0.6825 0.9325 0.6825 24 P 0 ;1
L 0.9325 0.7325 0.9325 0.7325 24 P 0 ;1
L 0.9325 0.7825 0.9325 0.7825 24 P 0 ;1
L 0.9325 0.8325 0.9325 0.8325 24 P 0 ;1
L 0.9325 0.8825 0.9325 0.8825 24 P 0 ;1
L 0.9325 0.9325 0.9325 0.9325 24 P 0 ;1
L 0.9325 0.9825 0.9325 0.9825 24 P 0 ;1
L 0.9325 1.0325 0.9325 1.0325 24 P 0 ;1
L 0.9325 1.0825 0.9325 1.0825 24 P 0 ;1
L 0.9325 1.1325 0.9325 1.1325 24 P 0 ;1
L 0.9325 1.1825 0.9325 1.1825 24 P 0 ;1
L 0.9325 1.2325 0.9325 1.2325 24 P 0 ;1
L 0.9325 1.2825 0.9325 1.2825 24 P 0 ;1
L 0.9325 1.7825 0.9325 1.7825 24 P 0 ;1
L 0.9325 2.0825 0.9325 2.0825 24 P 0 ;1
L 0.9325 2.1325 0.9325 2.1325 24 P 0 ;1
L 0.9325 2.1825 0.9325 2.1825 24 P 0 ;1
L 0.9325 2.2325 0.9325 2.2325 24 P 0 ;1
L 0.9325 2.2825 0.9325 2.2825 24 P 0 ;1
L 0.9325 2.3325 0.9325 2.3325 24 P 0 ;1
L 0.9325 2.3825 0.9325 2.3825 24 P 0 ;1
L 0.9325 2.4325 0.9325 2.4325 24 P 0 ;1
L 0.9325 2.7325 0.9325 2.7325 24 P 0 ;1
L 0.9325 2.7825 0.9325 2.7825 24 P 0 ;1
L 0.9325 2.8325 0.9325 2.8325 24 P 0 ;1
L 0.9325 2.8825 0.9325 2.8825 24 P 0 ;1
L 0.9325 2.9325 0.9325 2.9325 24 P 0 ;1
L 0.9325 2.9825 0.9325 2.9825 24 P 0 ;1
L 0.9325 3.0325 0.9325 3.0325 24 P 0 ;1
L 0.9325 3.0825 0.9325 3.0825 24 P 0 ;1
L 0.9325 3.1325 0.9325 3.1325 24 P 0 ;1
L 0.9325 3.1825 0.9325 3.1825 24 P 0 ;1
L 0.9325 3.2325 0.9325 3.2325 24 P 0 ;1
L 0.9325 3.2825 0.9325 3.2825 24 P 0 ;1
L 0.9325 3.3325 0.9325 3.3325 24 P 0 ;1
L 0.9325 3.3825 0.9325 3.3825 24 P 0 ;1
L 0.9325 3.4325 0.9325 3.4325 24 P 0 ;1
L 0.9325 3.4825 0.9325 3.4825 24 P 0 ;1
L 0.9325 3.5325 0.9325 3.5325 24 P 0 ;1
L 0.9325 3.5825 0.9325 3.5825 24 P 0 ;1
L 0.9325 3.6325 0.9325 3.6325 24 P 0 ;1
L 0.9325 3.6825 0.9325 3.6825 24 P 0 ;1
L 0.9325 3.7325 0.9325 3.7325 24 P 0 ;1
L 0.9325 3.7825 0.9325 3.7825 24 P 0 ;1
L 0.9325 3.8325 0.9325 3.8325 24 P 0 ;1
L 0.9325 3.8825 0.9325 3.8825 24 P 0 ;1
L 0.9325 3.9325 0.9325 3.9325 24 P 0 ;1
L 0.9325 4.4825 0.9325 4.4825 24 P 0 ;1
L 0.9325 4.5325 0.9325 4.5325 24 P 0 ;1
L 0.9325 4.5825 0.9325 4.5825 24 P 0 ;1
L 0.9325 4.6325 0.9325 4.6325 24 P 0 ;1
L 0.9325 4.6825 0.9325 4.6825 24 P 0 ;1
L 0.9325 4.7325 0.9325 4.7325 24 P 0 ;1
L 0.9325 4.7825 0.9325 4.7825 24 P 0 ;1
L 0.9325 4.8325 0.9325 4.8325 24 P 0 ;1
L 0.9325 5.2325 0.9325 5.2325 24 P 0 ;1
L 0.9825 0.1325 0.9825 0.1325 24 P 0 ;1
L 0.9825 0.4825 0.9825 0.4825 24 P 0 ;1
L 0.9825 0.5325 0.9825 0.5325 24 P 0 ;1
L 0.9825 0.5825 0.9825 0.5825 24 P 0 ;1
L 0.9825 0.6325 0.9825 0.6325 24 P 0 ;1
L 0.9825 0.6825 0.9825 0.6825 24 P 0 ;1
L 0.9825 0.7325 0.9825 0.7325 24 P 0 ;1
L 0.9825 0.7825 0.9825 0.7825 24 P 0 ;1
L 0.9825 0.8325 0.9825 0.8325 24 P 0 ;1
L 0.9825 0.8825 0.9825 0.8825 24 P 0 ;1
L 0.9825 0.9325 0.9825 0.9325 24 P 0 ;1
L 0.9825 0.9825 0.9825 0.9825 24 P 0 ;1
L 0.9825 1.0325 0.9825 1.0325 24 P 0 ;1
L 0.9825 1.0825 0.9825 1.0825 24 P 0 ;1
L 0.9825 1.1325 0.9825 1.1325 24 P 0 ;1
L 0.9825 1.1825 0.9825 1.1825 24 P 0 ;1
L 0.9825 1.2325 0.9825 1.2325 24 P 0 ;1
L 0.9825 1.2825 0.9825 1.2825 24 P 0 ;1
L 0.9825 2.0325 0.9825 2.0325 24 P 0 ;1
L 0.9825 2.0825 0.9825 2.0825 24 P 0 ;1
L 0.9825 2.1325 0.9825 2.1325 24 P 0 ;1
L 0.9825 2.1825 0.9825 2.1825 24 P 0 ;1
L 0.9825 2.2325 0.9825 2.2325 24 P 0 ;1
L 0.9825 2.2825 0.9825 2.2825 24 P 0 ;1
L 0.9825 2.3325 0.9825 2.3325 24 P 0 ;1
L 0.9825 2.3825 0.9825 2.3825 24 P 0 ;1
L 0.9825 2.4325 0.9825 2.4325 24 P 0 ;1
L 0.9825 2.7325 0.9825 2.7325 24 P 0 ;1
L 0.9825 2.7825 0.9825 2.7825 24 P 0 ;1
L 0.9825 2.8325 0.9825 2.8325 24 P 0 ;1
L 0.9825 2.8825 0.9825 2.8825 24 P 0 ;1
L 0.9825 2.9325 0.9825 2.9325 24 P 0 ;1
L 0.9825 2.9825 0.9825 2.9825 24 P 0 ;1
L 0.9825 3.0325 0.9825 3.0325 24 P 0 ;1
L 0.9825 3.0825 0.9825 3.0825 24 P 0 ;1
L 0.9825 3.1325 0.9825 3.1325 24 P 0 ;1
L 0.9825 3.1825 0.9825 3.1825 24 P 0 ;1
L 0.9825 3.2325 0.9825 3.2325 24 P 0 ;1
L 0.9825 3.2825 0.9825 3.2825 24 P 0 ;1
L 0.9825 3.3325 0.9825 3.3325 24 P 0 ;1
L 0.9825 3.3825 0.9825 3.3825 24 P 0 ;1
L 0.9825 3.4325 0.9825 3.4325 24 P 0 ;1
L 0.9825 3.4825 0.9825 3.4825 24 P 0 ;1
L 0.9825 3.5325 0.9825 3.5325 24 P 0 ;1
L 0.9825 3.5825 0.9825 3.5825 24 P 0 ;1
L 0.9825 3.6325 0.9825 3.6325 24 P 0 ;1
L 0.9825 3.6825 0.9825 3.6825 24 P 0 ;1
L 0.9825 3.7325 0.9825 3.7325 24 P 0 ;1
L 0.9825 3.7825 0.9825 3.7825 24 P 0 ;1
L 0.9825 3.8325 0.9825 3.8325 24 P 0 ;1
L 0.9825 3.8825 0.9825 3.8825 24 P 0 ;1
L 0.9825 3.9325 0.9825 3.9325 24 P 0 ;1
L 0.9825 4.4825 0.9825 4.4825 24 P 0 ;1
L 0.9825 4.5325 0.9825 4.5325 24 P 0 ;1
L 0.9825 4.5825 0.9825 4.5825 24 P 0 ;1
L 0.9825 4.6325 0.9825 4.6325 24 P 0 ;1
L 0.9825 4.6825 0.9825 4.6825 24 P 0 ;1
L 0.9825 4.7325 0.9825 4.7325 24 P 0 ;1
L 0.9825 4.7825 0.9825 4.7825 24 P 0 ;1
L 0.9825 4.8325 0.9825 4.8325 24 P 0 ;1
L 1.0325 0.1325 1.0325 0.1325 24 P 0 ;1
L 1.0325 0.4325 1.0325 0.4325 24 P 0 ;1
L 1.0325 0.4825 1.0325 0.4825 24 P 0 ;1
L 1.0325 0.5325 1.0325 0.5325 24 P 0 ;1
L 1.0325 0.5825 1.0325 0.5825 24 P 0 ;1
L 1.0325 0.6325 1.0325 0.6325 24 P 0 ;1
L 1.0325 0.6825 1.0325 0.6825 24 P 0 ;1
L 1.0325 0.7325 1.0325 0.7325 24 P 0 ;1
L 1.0325 0.7825 1.0325 0.7825 24 P 0 ;1
L 1.0325 0.8325 1.0325 0.8325 24 P 0 ;1
L 1.0325 0.8825 1.0325 0.8825 24 P 0 ;1
L 1.0325 0.9325 1.0325 0.9325 24 P 0 ;1
L 1.0325 0.9825 1.0325 0.9825 24 P 0 ;1
L 1.0325 1.0325 1.0325 1.0325 24 P 0 ;1
L 1.0325 1.0825 1.0325 1.0825 24 P 0 ;1
L 1.0325 1.1325 1.0325 1.1325 24 P 0 ;1
L 1.0325 1.1825 1.0325 1.1825 24 P 0 ;1
L 1.0325 1.2325 1.0325 1.2325 24 P 0 ;1
L 1.0325 1.2825 1.0325 1.2825 24 P 0 ;1
L 1.0325 1.9825 1.0325 1.9825 24 P 0 ;1
L 1.0325 2.0325 1.0325 2.0325 24 P 0 ;1
L 1.0325 2.0825 1.0325 2.0825 24 P 0 ;1
L 1.0325 2.1325 1.0325 2.1325 24 P 0 ;1
L 1.0325 2.1825 1.0325 2.1825 24 P 0 ;1
L 1.0325 2.2325 1.0325 2.2325 24 P 0 ;1
L 1.0325 2.2825 1.0325 2.2825 24 P 0 ;1
L 1.0325 2.3325 1.0325 2.3325 24 P 0 ;1
L 1.0325 2.3825 1.0325 2.3825 24 P 0 ;1
L 1.0325 2.7825 1.0325 2.7825 24 P 0 ;1
L 1.0325 2.8325 1.0325 2.8325 24 P 0 ;1
L 1.0325 2.8825 1.0325 2.8825 24 P 0 ;1
L 1.0325 2.9325 1.0325 2.9325 24 P 0 ;1
L 1.0325 2.9825 1.0325 2.9825 24 P 0 ;1
L 1.0325 3.0325 1.0325 3.0325 24 P 0 ;1
L 1.0325 3.0825 1.0325 3.0825 24 P 0 ;1
L 1.0325 3.1325 1.0325 3.1325 24 P 0 ;1
L 1.0325 3.1825 1.0325 3.1825 24 P 0 ;1
L 1.0325 3.2325 1.0325 3.2325 24 P 0 ;1
L 1.0325 3.2825 1.0325 3.2825 24 P 0 ;1
L 1.0325 3.3325 1.0325 3.3325 24 P 0 ;1
L 1.0325 3.3825 1.0325 3.3825 24 P 0 ;1
L 1.0325 3.4325 1.0325 3.4325 24 P 0 ;1
L 1.0325 3.4825 1.0325 3.4825 24 P 0 ;1
L 1.0325 3.5325 1.0325 3.5325 24 P 0 ;1
L 1.0325 3.5825 1.0325 3.5825 24 P 0 ;1
L 1.0325 3.6325 1.0325 3.6325 24 P 0 ;1
L 1.0325 3.6825 1.0325 3.6825 24 P 0 ;1
L 1.0325 3.7325 1.0325 3.7325 24 P 0 ;1
L 1.0325 3.7825 1.0325 3.7825 24 P 0 ;1
L 1.0325 3.8325 1.0325 3.8325 24 P 0 ;1
L 1.0325 3.8825 1.0325 3.8825 24 P 0 ;1
L 1.0325 3.9325 1.0325 3.9325 24 P 0 ;1
L 1.0325 4.4825 1.0325 4.4825 24 P 0 ;1
L 1.0325 4.5325 1.0325 4.5325 24 P 0 ;1
L 1.0325 4.5825 1.0325 4.5825 24 P 0 ;1
L 1.0325 4.6325 1.0325 4.6325 24 P 0 ;1
L 1.0325 4.6825 1.0325 4.6825 24 P 0 ;1
L 1.0325 4.7325 1.0325 4.7325 24 P 0 ;1
L 1.0325 4.7825 1.0325 4.7825 24 P 0 ;1
L 1.0325 4.8325 1.0325 4.8325 24 P 0 ;1
L 1.0825 0.1325 1.0825 0.1325 24 P 0 ;1
L 1.0825 0.1825 1.0825 0.1825 24 P 0 ;1
L 1.0825 0.2325 1.0825 0.2325 24 P 0 ;1
L 1.0825 0.3325 1.0825 0.3325 24 P 0 ;1
L 1.0825 0.3825 1.0825 0.3825 24 P 0 ;1
L 1.0825 0.4325 1.0825 0.4325 24 P 0 ;1
L 1.0825 0.4825 1.0825 0.4825 24 P 0 ;1
L 1.0825 0.5325 1.0825 0.5325 24 P 0 ;1
L 1.0825 0.5825 1.0825 0.5825 24 P 0 ;1
L 1.0825 0.6325 1.0825 0.6325 24 P 0 ;1
L 1.0825 0.6825 1.0825 0.6825 24 P 0 ;1
L 1.0825 0.7325 1.0825 0.7325 24 P 0 ;1
L 1.0825 0.7825 1.0825 0.7825 24 P 0 ;1
L 1.0825 0.8325 1.0825 0.8325 24 P 0 ;1
L 1.0825 0.8825 1.0825 0.8825 24 P 0 ;1
L 1.0825 0.9325 1.0825 0.9325 24 P 0 ;1
L 1.0825 0.9825 1.0825 0.9825 24 P 0 ;1
L 1.0825 1.0325 1.0825 1.0325 24 P 0 ;1
L 1.0825 1.0825 1.0825 1.0825 24 P 0 ;1
L 1.0825 1.1325 1.0825 1.1325 24 P 0 ;1
L 1.0825 1.1825 1.0825 1.1825 24 P 0 ;1
L 1.0825 1.2325 1.0825 1.2325 24 P 0 ;1
L 1.0825 1.2825 1.0825 1.2825 24 P 0 ;1
L 1.0825 1.9325 1.0825 1.9325 24 P 0 ;1
L 1.0825 1.9825 1.0825 1.9825 24 P 0 ;1
L 1.0825 2.0325 1.0825 2.0325 24 P 0 ;1
L 1.0825 2.0825 1.0825 2.0825 24 P 0 ;1
L 1.0825 2.1325 1.0825 2.1325 24 P 0 ;1
L 1.0825 2.1825 1.0825 2.1825 24 P 0 ;1
L 1.0825 2.2325 1.0825 2.2325 24 P 0 ;1
L 1.0825 2.2825 1.0825 2.2825 24 P 0 ;1
L 1.0825 2.3325 1.0825 2.3325 24 P 0 ;1
L 1.0825 2.3825 1.0825 2.3825 24 P 0 ;1
L 1.0825 2.7825 1.0825 2.7825 24 P 0 ;1
L 1.0825 2.8325 1.0825 2.8325 24 P 0 ;1
L 1.0825 2.8825 1.0825 2.8825 24 P 0 ;1
L 1.0825 2.9325 1.0825 2.9325 24 P 0 ;1
L 1.0825 2.9825 1.0825 2.9825 24 P 0 ;1
L 1.0825 3.0325 1.0825 3.0325 24 P 0 ;1
L 1.0825 3.0825 1.0825 3.0825 24 P 0 ;1
L 1.0825 3.1325 1.0825 3.1325 24 P 0 ;1
L 1.0825 3.1825 1.0825 3.1825 24 P 0 ;1
L 1.0825 3.2325 1.0825 3.2325 24 P 0 ;1
L 1.0825 3.2825 1.0825 3.2825 24 P 0 ;1
L 1.0825 3.3325 1.0825 3.3325 24 P 0 ;1
L 1.0825 3.3825 1.0825 3.3825 24 P 0 ;1
L 1.0825 3.4325 1.0825 3.4325 24 P 0 ;1
L 1.0825 3.4825 1.0825 3.4825 24 P 0 ;1
L 1.0825 3.5325 1.0825 3.5325 24 P 0 ;1
L 1.0825 3.5825 1.0825 3.5825 24 P 0 ;1
L 1.0825 3.6325 1.0825 3.6325 24 P 0 ;1
L 1.0825 3.6825 1.0825 3.6825 24 P 0 ;1
L 1.0825 3.7325 1.0825 3.7325 24 P 0 ;1
L 1.0825 3.7825 1.0825 3.7825 24 P 0 ;1
L 1.0825 3.8325 1.0825 3.8325 24 P 0 ;1
L 1.0825 3.8825 1.0825 3.8825 24 P 0 ;1
L 1.0825 3.9325 1.0825 3.9325 24 P 0 ;1
L 1.0825 3.9825 1.0825 3.9825 24 P 0 ;1
L 1.0825 4.4325 1.0825 4.4325 24 P 0 ;1
L 1.0825 4.4825 1.0825 4.4825 24 P 0 ;1
L 1.0825 4.5325 1.0825 4.5325 24 P 0 ;1
L 1.0825 4.5825 1.0825 4.5825 24 P 0 ;1
L 1.0825 4.6325 1.0825 4.6325 24 P 0 ;1
L 1.0825 4.6825 1.0825 4.6825 24 P 0 ;1
L 1.0825 4.7325 1.0825 4.7325 24 P 0 ;1
L 1.0825 4.7825 1.0825 4.7825 24 P 0 ;1
L 1.0825 4.8325 1.0825 4.8325 24 P 0 ;1
L 1.1325 0.1325 1.1325 0.1325 24 P 0 ;1
L 1.1325 0.1825 1.1325 0.1825 24 P 0 ;1
L 1.1325 0.2325 1.1325 0.2325 24 P 0 ;1
L 1.1325 0.2825 1.1325 0.2825 24 P 0 ;1
L 1.1325 0.3325 1.1325 0.3325 24 P 0 ;1
L 1.1325 0.3825 1.1325 0.3825 24 P 0 ;1
L 1.1325 0.4325 1.1325 0.4325 24 P 0 ;1
L 1.1325 0.4825 1.1325 0.4825 24 P 0 ;1
L 1.1325 0.5325 1.1325 0.5325 24 P 0 ;1
L 1.1325 0.5825 1.1325 0.5825 24 P 0 ;1
L 1.1325 0.6325 1.1325 0.6325 24 P 0 ;1
L 1.1325 0.6825 1.1325 0.6825 24 P 0 ;1
L 1.1325 0.7325 1.1325 0.7325 24 P 0 ;1
L 1.1325 0.7825 1.1325 0.7825 24 P 0 ;1
L 1.1325 0.8325 1.1325 0.8325 24 P 0 ;1
L 1.1325 0.8825 1.1325 0.8825 24 P 0 ;1
L 1.1325 0.9325 1.1325 0.9325 24 P 0 ;1
L 1.1325 0.9825 1.1325 0.9825 24 P 0 ;1
L 1.1325 1.0325 1.1325 1.0325 24 P 0 ;1
L 1.1325 1.0825 1.1325 1.0825 24 P 0 ;1
L 1.1325 1.1325 1.1325 1.1325 24 P 0 ;1
L 1.1325 1.1825 1.1325 1.1825 24 P 0 ;1
L 1.1325 1.2325 1.1325 1.2325 24 P 0 ;1
L 1.1325 1.2825 1.1325 1.2825 24 P 0 ;1
L 1.1325 1.3325 1.1325 1.3325 24 P 0 ;1
L 1.1325 1.8825 1.1325 1.8825 24 P 0 ;1
L 1.1325 1.9325 1.1325 1.9325 24 P 0 ;1
L 1.1325 1.9825 1.1325 1.9825 24 P 0 ;1
L 1.1325 2.0325 1.1325 2.0325 24 P 0 ;1
L 1.1325 2.0825 1.1325 2.0825 24 P 0 ;1
L 1.1325 2.1325 1.1325 2.1325 24 P 0 ;1
L 1.1325 2.1825 1.1325 2.1825 24 P 0 ;1
L 1.1325 2.2325 1.1325 2.2325 24 P 0 ;1
L 1.1325 2.2825 1.1325 2.2825 24 P 0 ;1
L 1.1325 2.3325 1.1325 2.3325 24 P 0 ;1
L 1.1325 2.3825 1.1325 2.3825 24 P 0 ;1
L 1.1325 2.4325 1.1325 2.4325 24 P 0 ;1
L 1.1325 2.7325 1.1325 2.7325 24 P 0 ;1
L 1.1325 2.7825 1.1325 2.7825 24 P 0 ;1
L 1.1325 2.8325 1.1325 2.8325 24 P 0 ;1
L 1.1325 2.8825 1.1325 2.8825 24 P 0 ;1
L 1.1325 2.9325 1.1325 2.9325 24 P 0 ;1
L 1.1325 2.9825 1.1325 2.9825 24 P 0 ;1
L 1.1325 3.0325 1.1325 3.0325 24 P 0 ;1
L 1.1325 3.0825 1.1325 3.0825 24 P 0 ;1
L 1.1325 3.1325 1.1325 3.1325 24 P 0 ;1
L 1.1325 3.1825 1.1325 3.1825 24 P 0 ;1
L 1.1325 3.2325 1.1325 3.2325 24 P 0 ;1
L 1.1325 3.2825 1.1325 3.2825 24 P 0 ;1
L 1.1325 3.3325 1.1325 3.3325 24 P 0 ;1
L 1.1325 3.3825 1.1325 3.3825 24 P 0 ;1
L 1.1325 3.4325 1.1325 3.4325 24 P 0 ;1
L 1.1325 3.4825 1.1325 3.4825 24 P 0 ;1
L 1.1325 3.5325 1.1325 3.5325 24 P 0 ;1
L 1.1325 3.5825 1.1325 3.5825 24 P 0 ;1
L 1.1325 3.6325 1.1325 3.6325 24 P 0 ;1
L 1.1325 3.6825 1.1325 3.6825 24 P 0 ;1
L 1.1325 3.7325 1.1325 3.7325 24 P 0 ;1
L 1.1325 3.7825 1.1325 3.7825 24 P 0 ;1
L 1.1325 3.8325 1.1325 3.8325 24 P 0 ;1
L 1.1325 3.8825 1.1325 3.8825 24 P 0 ;1
L 1.1325 3.9325 1.1325 3.9325 24 P 0 ;1
L 1.1325 3.9825 1.1325 3.9825 24 P 0 ;1
L 1.1325 4.0325 1.1325 4.0325 24 P 0 ;1
L 1.1325 4.3825 1.1325 4.3825 24 P 0 ;1
L 1.1325 4.4325 1.1325 4.4325 24 P 0 ;1
L 1.1325 4.4825 1.1325 4.4825 24 P 0 ;1
L 1.1325 4.5325 1.1325 4.5325 24 P 0 ;1
L 1.1325 4.5825 1.1325 4.5825 24 P 0 ;1
L 1.1325 4.6325 1.1325 4.6325 24 P 0 ;1
L 1.1325 4.6825 1.1325 4.6825 24 P 0 ;1
L 1.1325 4.7325 1.1325 4.7325 24 P 0 ;1
L 1.1325 4.7825 1.1325 4.7825 24 P 0 ;1
L 1.1325 4.8325 1.1325 4.8325 24 P 0 ;1
L 1.1825 0.1325 1.1825 0.1325 24 P 0 ;1
L 1.1825 0.1825 1.1825 0.1825 24 P 0 ;1
L 1.1825 0.2325 1.1825 0.2325 24 P 0 ;1
L 1.1825 0.2825 1.1825 0.2825 24 P 0 ;1
L 1.1825 0.3325 1.1825 0.3325 24 P 0 ;1
L 1.1825 0.3825 1.1825 0.3825 24 P 0 ;1
L 1.1825 0.4325 1.1825 0.4325 24 P 0 ;1
L 1.1825 0.4825 1.1825 0.4825 24 P 0 ;1
L 1.1825 0.5325 1.1825 0.5325 24 P 0 ;1
L 1.1825 0.5825 1.1825 0.5825 24 P 0 ;1
L 1.1825 0.6325 1.1825 0.6325 24 P 0 ;1
L 1.1825 0.6825 1.1825 0.6825 24 P 0 ;1
L 1.1825 0.7325 1.1825 0.7325 24 P 0 ;1
L 1.1825 0.7825 1.1825 0.7825 24 P 0 ;1
L 1.1825 0.8325 1.1825 0.8325 24 P 0 ;1
L 1.1825 0.8825 1.1825 0.8825 24 P 0 ;1
L 1.1825 0.9325 1.1825 0.9325 24 P 0 ;1
L 1.1825 0.9825 1.1825 0.9825 24 P 0 ;1
L 1.1825 1.0325 1.1825 1.0325 24 P 0 ;1
L 1.1825 1.0825 1.1825 1.0825 24 P 0 ;1
L 1.1825 1.1325 1.1825 1.1325 24 P 0 ;1
L 1.1825 1.1825 1.1825 1.1825 24 P 0 ;1
L 1.1825 1.2325 1.1825 1.2325 24 P 0 ;1
L 1.1825 1.2825 1.1825 1.2825 24 P 0 ;1
L 1.1825 1.3325 1.1825 1.3325 24 P 0 ;1
L 1.1825 1.3825 1.1825 1.3825 24 P 0 ;1
L 1.1825 1.8325 1.1825 1.8325 24 P 0 ;1
L 1.1825 1.8825 1.1825 1.8825 24 P 0 ;1
L 1.1825 1.9325 1.1825 1.9325 24 P 0 ;1
L 1.1825 1.9825 1.1825 1.9825 24 P 0 ;1
L 1.1825 2.0325 1.1825 2.0325 24 P 0 ;1
L 1.1825 2.0825 1.1825 2.0825 24 P 0 ;1
L 1.1825 2.1325 1.1825 2.1325 24 P 0 ;1
L 1.1825 2.1825 1.1825 2.1825 24 P 0 ;1
L 1.1825 2.2325 1.1825 2.2325 24 P 0 ;1
L 1.1825 2.2825 1.1825 2.2825 24 P 0 ;1
L 1.1825 2.3325 1.1825 2.3325 24 P 0 ;1
L 1.1825 2.3825 1.1825 2.3825 24 P 0 ;1
L 1.1825 2.4325 1.1825 2.4325 24 P 0 ;1
L 1.1825 2.7325 1.1825 2.7325 24 P 0 ;1
L 1.1825 2.7825 1.1825 2.7825 24 P 0 ;1
L 1.1825 2.8325 1.1825 2.8325 24 P 0 ;1
L 1.1825 2.8825 1.1825 2.8825 24 P 0 ;1
L 1.1825 2.9325 1.1825 2.9325 24 P 0 ;1
L 1.1825 2.9825 1.1825 2.9825 24 P 0 ;1
L 1.1825 3.0325 1.1825 3.0325 24 P 0 ;1
L 1.1825 3.0825 1.1825 3.0825 24 P 0 ;1
L 1.1825 3.1325 1.1825 3.1325 24 P 0 ;1
L 1.1825 3.1825 1.1825 3.1825 24 P 0 ;1
L 1.1825 3.2325 1.1825 3.2325 24 P 0 ;1
L 1.1825 3.2825 1.1825 3.2825 24 P 0 ;1
L 1.1825 3.3325 1.1825 3.3325 24 P 0 ;1
L 1.1825 3.3825 1.1825 3.3825 24 P 0 ;1
L 1.1825 3.4325 1.1825 3.4325 24 P 0 ;1
L 1.1825 3.4825 1.1825 3.4825 24 P 0 ;1
L 1.1825 3.5325 1.1825 3.5325 24 P 0 ;1
L 1.1825 3.5825 1.1825 3.5825 24 P 0 ;1
L 1.1825 3.6325 1.1825 3.6325 24 P 0 ;1
L 1.1825 3.6825 1.1825 3.6825 24 P 0 ;1
L 1.1825 3.7325 1.1825 3.7325 24 P 0 ;1
L 1.1825 3.7825 1.1825 3.7825 24 P 0 ;1
L 1.1825 3.8325 1.1825 3.8325 24 P 0 ;1
L 1.1825 3.8825 1.1825 3.8825 24 P 0 ;1
L 1.1825 3.9325 1.1825 3.9325 24 P 0 ;1
L 1.1825 3.9825 1.1825 3.9825 24 P 0 ;1
L 1.1825 4.0325 1.1825 4.0325 24 P 0 ;1
L 1.1825 4.0825 1.1825 4.0825 24 P 0 ;1
L 1.1825 4.3325 1.1825 4.3325 24 P 0 ;1
L 1.1825 4.3825 1.1825 4.3825 24 P 0 ;1
L 1.1825 4.4325 1.1825 4.4325 24 P 0 ;1
L 1.1825 4.4825 1.1825 4.4825 24 P 0 ;1
L 1.1825 5.2825 1.1825 5.2825 24 P 0 ;1
L 1.2325 0.1325 1.2325 0.1325 24 P 0 ;1
L 1.2325 0.1825 1.2325 0.1825 24 P 0 ;1
L 1.2325 0.2325 1.2325 0.2325 24 P 0 ;1
L 1.2325 0.2825 1.2325 0.2825 24 P 0 ;1
L 1.2325 0.3325 1.2325 0.3325 24 P 0 ;1
L 1.2325 0.3825 1.2325 0.3825 24 P 0 ;1
L 1.2325 0.4325 1.2325 0.4325 24 P 0 ;1
L 1.2325 0.4825 1.2325 0.4825 24 P 0 ;1
L 1.2325 0.5325 1.2325 0.5325 24 P 0 ;1
L 1.2325 0.5825 1.2325 0.5825 24 P 0 ;1
L 1.2325 0.6325 1.2325 0.6325 24 P 0 ;1
L 1.2325 0.6825 1.2325 0.6825 24 P 0 ;1
L 1.2325 0.7325 1.2325 0.7325 24 P 0 ;1
L 1.2325 0.7825 1.2325 0.7825 24 P 0 ;1
L 1.2325 0.8325 1.2325 0.8325 24 P 0 ;1
L 1.2325 0.8825 1.2325 0.8825 24 P 0 ;1
L 1.2325 0.9325 1.2325 0.9325 24 P 0 ;1
L 1.2325 0.9825 1.2325 0.9825 24 P 0 ;1
L 1.2325 1.0325 1.2325 1.0325 24 P 0 ;1
L 1.2325 1.0825 1.2325 1.0825 24 P 0 ;1
L 1.2325 1.1325 1.2325 1.1325 24 P 0 ;1
L 1.2325 1.1825 1.2325 1.1825 24 P 0 ;1
L 1.2325 1.2325 1.2325 1.2325 24 P 0 ;1
L 1.2325 1.2825 1.2325 1.2825 24 P 0 ;1
L 1.2325 1.3325 1.2325 1.3325 24 P 0 ;1
L 1.2325 1.3825 1.2325 1.3825 24 P 0 ;1
L 1.2325 1.4325 1.2325 1.4325 24 P 0 ;1
L 1.2325 1.4825 1.2325 1.4825 24 P 0 ;1
L 1.2325 1.7825 1.2325 1.7825 24 P 0 ;1
L 1.2325 1.8325 1.2325 1.8325 24 P 0 ;1
L 1.2325 1.8825 1.2325 1.8825 24 P 0 ;1
L 1.2325 1.9325 1.2325 1.9325 24 P 0 ;1
L 1.2325 1.9825 1.2325 1.9825 24 P 0 ;1
L 1.2325 2.0325 1.2325 2.0325 24 P 0 ;1
L 1.2325 2.0825 1.2325 2.0825 24 P 0 ;1
L 1.2325 2.1325 1.2325 2.1325 24 P 0 ;1
L 1.2325 2.1825 1.2325 2.1825 24 P 0 ;1
L 1.2325 2.2325 1.2325 2.2325 24 P 0 ;1
L 1.2325 2.2825 1.2325 2.2825 24 P 0 ;1
L 1.2325 2.3325 1.2325 2.3325 24 P 0 ;1
L 1.2325 2.3825 1.2325 2.3825 24 P 0 ;1
L 1.2325 2.4325 1.2325 2.4325 24 P 0 ;1
L 1.2325 2.4825 1.2325 2.4825 24 P 0 ;1
L 1.2325 2.6825 1.2325 2.6825 24 P 0 ;1
L 1.2325 2.7325 1.2325 2.7325 24 P 0 ;1
L 1.2325 2.7825 1.2325 2.7825 24 P 0 ;1
L 1.2325 2.8325 1.2325 2.8325 24 P 0 ;1
L 1.2325 2.8825 1.2325 2.8825 24 P 0 ;1
L 1.2325 2.9325 1.2325 2.9325 24 P 0 ;1
L 1.2325 2.9825 1.2325 2.9825 24 P 0 ;1
L 1.2325 3.0325 1.2325 3.0325 24 P 0 ;1
L 1.2325 3.0825 1.2325 3.0825 24 P 0 ;1
L 1.2325 3.1325 1.2325 3.1325 24 P 0 ;1
L 1.2325 3.1825 1.2325 3.1825 24 P 0 ;1
L 1.2325 3.2325 1.2325 3.2325 24 P 0 ;1
L 1.2325 3.2825 1.2325 3.2825 24 P 0 ;1
L 1.2325 3.3325 1.2325 3.3325 24 P 0 ;1
L 1.2325 3.3825 1.2325 3.3825 24 P 0 ;1
L 1.2325 3.4325 1.2325 3.4325 24 P 0 ;1
L 1.2325 3.4825 1.2325 3.4825 24 P 0 ;1
L 1.2325 3.5325 1.2325 3.5325 24 P 0 ;1
L 1.2325 3.5825 1.2325 3.5825 24 P 0 ;1
L 1.2325 3.6325 1.2325 3.6325 24 P 0 ;1
L 1.2325 3.6825 1.2325 3.6825 24 P 0 ;1
L 1.2325 3.7325 1.2325 3.7325 24 P 0 ;1
L 1.2325 3.7825 1.2325 3.7825 24 P 0 ;1
L 1.2325 3.8325 1.2325 3.8325 24 P 0 ;1
L 1.2325 3.8825 1.2325 3.8825 24 P 0 ;1
L 1.2325 5.2825 1.2325 5.2825 24 P 0 ;1
L 1.2825 0.1325 1.2825 0.1325 24 P 0 ;1
L 1.2825 0.1825 1.2825 0.1825 24 P 0 ;1
L 1.2825 0.2325 1.2825 0.2325 24 P 0 ;1
L 1.2825 0.2825 1.2825 0.2825 24 P 0 ;1
L 1.2825 0.3325 1.2825 0.3325 24 P 0 ;1
L 1.2825 0.3825 1.2825 0.3825 24 P 0 ;1
L 1.2825 0.4325 1.2825 0.4325 24 P 0 ;1
L 1.2825 0.4825 1.2825 0.4825 24 P 0 ;1
L 1.2825 0.5325 1.2825 0.5325 24 P 0 ;1
L 1.2825 0.5825 1.2825 0.5825 24 P 0 ;1
L 1.2825 0.6325 1.2825 0.6325 24 P 0 ;1
L 1.2825 0.6825 1.2825 0.6825 24 P 0 ;1
L 1.2825 0.7325 1.2825 0.7325 24 P 0 ;1
L 1.2825 0.7825 1.2825 0.7825 24 P 0 ;1
L 1.2825 0.8325 1.2825 0.8325 24 P 0 ;1
L 1.2825 0.8825 1.2825 0.8825 24 P 0 ;1
L 1.2825 0.9325 1.2825 0.9325 24 P 0 ;1
L 1.2825 0.9825 1.2825 0.9825 24 P 0 ;1
L 1.2825 1.0325 1.2825 1.0325 24 P 0 ;1
L 1.2825 1.0825 1.2825 1.0825 24 P 0 ;1
L 1.2825 1.1325 1.2825 1.1325 24 P 0 ;1
L 1.2825 1.1825 1.2825 1.1825 24 P 0 ;1
L 1.2825 1.2325 1.2825 1.2325 24 P 0 ;1
L 1.2825 1.2825 1.2825 1.2825 24 P 0 ;1
L 1.2825 1.3325 1.2825 1.3325 24 P 0 ;1
L 1.2825 1.3825 1.2825 1.3825 24 P 0 ;1
L 1.2825 1.4325 1.2825 1.4325 24 P 0 ;1
L 1.2825 1.7325 1.2825 1.7325 24 P 0 ;1
L 1.2825 1.7825 1.2825 1.7825 24 P 0 ;1
L 1.2825 1.8325 1.2825 1.8325 24 P 0 ;1
L 1.2825 1.8825 1.2825 1.8825 24 P 0 ;1
L 1.2825 1.9325 1.2825 1.9325 24 P 0 ;1
L 1.2825 1.9825 1.2825 1.9825 24 P 0 ;1
L 1.2825 2.0325 1.2825 2.0325 24 P 0 ;1
L 1.2825 2.0825 1.2825 2.0825 24 P 0 ;1
L 1.2825 2.1325 1.2825 2.1325 24 P 0 ;1
L 1.2825 2.1825 1.2825 2.1825 24 P 0 ;1
L 1.2825 2.2325 1.2825 2.2325 24 P 0 ;1
L 1.2825 2.2825 1.2825 2.2825 24 P 0 ;1
L 1.2825 2.3325 1.2825 2.3325 24 P 0 ;1
L 1.2825 2.3825 1.2825 2.3825 24 P 0 ;1
L 1.2825 2.4325 1.2825 2.4325 24 P 0 ;1
L 1.2825 2.4825 1.2825 2.4825 24 P 0 ;1
L 1.2825 2.5325 1.2825 2.5325 24 P 0 ;1
L 1.2825 2.5825 1.2825 2.5825 24 P 0 ;1
L 1.2825 2.6325 1.2825 2.6325 24 P 0 ;1
L 1.2825 2.6825 1.2825 2.6825 24 P 0 ;1
L 1.2825 2.7325 1.2825 2.7325 24 P 0 ;1
L 1.2825 2.7825 1.2825 2.7825 24 P 0 ;1
L 1.2825 2.8325 1.2825 2.8325 24 P 0 ;1
L 1.2825 2.8825 1.2825 2.8825 24 P 0 ;1
L 1.2825 2.9325 1.2825 2.9325 24 P 0 ;1
L 1.2825 2.9825 1.2825 2.9825 24 P 0 ;1
L 1.2825 3.0325 1.2825 3.0325 24 P 0 ;1
L 1.2825 3.0825 1.2825 3.0825 24 P 0 ;1
L 1.2825 3.1325 1.2825 3.1325 24 P 0 ;1
L 1.2825 3.1825 1.2825 3.1825 24 P 0 ;1
L 1.2825 3.2325 1.2825 3.2325 24 P 0 ;1
L 1.2825 3.2825 1.2825 3.2825 24 P 0 ;1
L 1.2825 3.3325 1.2825 3.3325 24 P 0 ;1
L 1.2825 3.3825 1.2825 3.3825 24 P 0 ;1
L 1.2825 3.4325 1.2825 3.4325 24 P 0 ;1
L 1.2825 3.4825 1.2825 3.4825 24 P 0 ;1
L 1.2825 3.5325 1.2825 3.5325 24 P 0 ;1
L 1.2825 3.5825 1.2825 3.5825 24 P 0 ;1
L 1.2825 3.6325 1.2825 3.6325 24 P 0 ;1
L 1.2825 3.6825 1.2825 3.6825 24 P 0 ;1
L 1.2825 3.7325 1.2825 3.7325 24 P 0 ;1
L 1.2825 3.7825 1.2825 3.7825 24 P 0 ;1
L 1.2825 3.8325 1.2825 3.8325 24 P 0 ;1
L 1.3325 0.1325 1.3325 0.1325 24 P 0 ;1
L 1.3325 0.1825 1.3325 0.1825 24 P 0 ;1
L 1.3325 0.2325 1.3325 0.2325 24 P 0 ;1
L 1.3325 0.2825 1.3325 0.2825 24 P 0 ;1
L 1.3325 0.3325 1.3325 0.3325 24 P 0 ;1
L 1.3325 0.3825 1.3325 0.3825 24 P 0 ;1
L 1.3325 0.4325 1.3325 0.4325 24 P 0 ;1
L 1.3325 0.4825 1.3325 0.4825 24 P 0 ;1
L 1.3325 0.5325 1.3325 0.5325 24 P 0 ;1
L 1.3325 0.5825 1.3325 0.5825 24 P 0 ;1
L 1.3325 0.6325 1.3325 0.6325 24 P 0 ;1
L 1.3325 0.6825 1.3325 0.6825 24 P 0 ;1
L 1.3325 0.7325 1.3325 0.7325 24 P 0 ;1
L 1.3325 0.7825 1.3325 0.7825 24 P 0 ;1
L 1.3325 0.8325 1.3325 0.8325 24 P 0 ;1
L 1.3325 0.8825 1.3325 0.8825 24 P 0 ;1
L 1.3325 0.9325 1.3325 0.9325 24 P 0 ;1
L 1.3325 0.9825 1.3325 0.9825 24 P 0 ;1
L 1.3325 1.0325 1.3325 1.0325 24 P 0 ;1
L 1.3325 1.0825 1.3325 1.0825 24 P 0 ;1
L 1.3325 1.1325 1.3325 1.1325 24 P 0 ;1
L 1.3325 1.1825 1.3325 1.1825 24 P 0 ;1
L 1.3325 1.2325 1.3325 1.2325 24 P 0 ;1
L 1.3325 1.2825 1.3325 1.2825 24 P 0 ;1
L 1.3325 1.3325 1.3325 1.3325 24 P 0 ;1
L 1.3325 1.3825 1.3325 1.3825 24 P 0 ;1
L 1.3325 1.6825 1.3325 1.6825 24 P 0 ;1
L 1.3325 1.7325 1.3325 1.7325 24 P 0 ;1
L 1.3325 1.7825 1.3325 1.7825 24 P 0 ;1
L 1.3325 1.8325 1.3325 1.8325 24 P 0 ;1
L 1.3325 1.8825 1.3325 1.8825 24 P 0 ;1
L 1.3325 1.9325 1.3325 1.9325 24 P 0 ;1
L 1.3325 1.9825 1.3325 1.9825 24 P 0 ;1
L 1.3325 2.0325 1.3325 2.0325 24 P 0 ;1
L 1.3325 2.0825 1.3325 2.0825 24 P 0 ;1
L 1.3325 2.1325 1.3325 2.1325 24 P 0 ;1
L 1.3325 2.1825 1.3325 2.1825 24 P 0 ;1
L 1.3325 2.2325 1.3325 2.2325 24 P 0 ;1
L 1.3325 2.2825 1.3325 2.2825 24 P 0 ;1
L 1.3325 2.3325 1.3325 2.3325 24 P 0 ;1
L 1.3325 2.3825 1.3325 2.3825 24 P 0 ;1
L 1.3325 2.4325 1.3325 2.4325 24 P 0 ;1
L 1.3325 2.4825 1.3325 2.4825 24 P 0 ;1
L 1.3325 2.5325 1.3325 2.5325 24 P 0 ;1
L 1.3325 2.5825 1.3325 2.5825 24 P 0 ;1
L 1.3325 2.6325 1.3325 2.6325 24 P 0 ;1
L 1.3325 2.6825 1.3325 2.6825 24 P 0 ;1
L 1.3325 2.7325 1.3325 2.7325 24 P 0 ;1
L 1.3325 2.7825 1.3325 2.7825 24 P 0 ;1
L 1.3325 2.8325 1.3325 2.8325 24 P 0 ;1
L 1.3325 2.8825 1.3325 2.8825 24 P 0 ;1
L 1.3325 2.9325 1.3325 2.9325 24 P 0 ;1
L 1.3325 2.9825 1.3325 2.9825 24 P 0 ;1
L 1.3325 3.0325 1.3325 3.0325 24 P 0 ;1
L 1.3325 3.0825 1.3325 3.0825 24 P 0 ;1
L 1.3325 3.1325 1.3325 3.1325 24 P 0 ;1
L 1.3325 3.1825 1.3325 3.1825 24 P 0 ;1
L 1.3325 3.2325 1.3325 3.2325 24 P 0 ;1
L 1.3325 3.2825 1.3325 3.2825 24 P 0 ;1
L 1.3325 3.3325 1.3325 3.3325 24 P 0 ;1
L 1.3325 3.3825 1.3325 3.3825 24 P 0 ;1
L 1.3325 3.4325 1.3325 3.4325 24 P 0 ;1
L 1.3325 3.4825 1.3325 3.4825 24 P 0 ;1
L 1.3325 3.5325 1.3325 3.5325 24 P 0 ;1
L 1.3325 3.5825 1.3325 3.5825 24 P 0 ;1
L 1.3325 3.6325 1.3325 3.6325 24 P 0 ;1
L 1.3325 3.6825 1.3325 3.6825 24 P 0 ;1
L 1.3325 3.7325 1.3325 3.7325 24 P 0 ;1
L 1.3325 3.7825 1.3325 3.7825 24 P 0 ;1
L 1.3825 0.1325 1.3825 0.1325 24 P 0 ;1
L 1.3825 0.1825 1.3825 0.1825 24 P 0 ;1
L 1.3825 0.2325 1.3825 0.2325 24 P 0 ;1
L 1.3825 0.2825 1.3825 0.2825 24 P 0 ;1
L 1.3825 0.3325 1.3825 0.3325 24 P 0 ;1
L 1.3825 0.3825 1.3825 0.3825 24 P 0 ;1
L 1.3825 0.4325 1.3825 0.4325 24 P 0 ;1
L 1.3825 0.4825 1.3825 0.4825 24 P 0 ;1
L 1.3825 0.5325 1.3825 0.5325 24 P 0 ;1
L 1.3825 0.5825 1.3825 0.5825 24 P 0 ;1
L 1.3825 0.6325 1.3825 0.6325 24 P 0 ;1
L 1.3825 0.6825 1.3825 0.6825 24 P 0 ;1
L 1.3825 0.7325 1.3825 0.7325 24 P 0 ;1
L 1.3825 0.7825 1.3825 0.7825 24 P 0 ;1
L 1.3825 0.8325 1.3825 0.8325 24 P 0 ;1
L 1.3825 0.8825 1.3825 0.8825 24 P 0 ;1
L 1.3825 0.9325 1.3825 0.9325 24 P 0 ;1
L 1.3825 0.9825 1.3825 0.9825 24 P 0 ;1
L 1.3825 1.0325 1.3825 1.0325 24 P 0 ;1
L 1.3825 1.0825 1.3825 1.0825 24 P 0 ;1
L 1.3825 1.1325 1.3825 1.1325 24 P 0 ;1
L 1.3825 1.1825 1.3825 1.1825 24 P 0 ;1
L 1.3825 1.2325 1.3825 1.2325 24 P 0 ;1
L 1.3825 1.2825 1.3825 1.2825 24 P 0 ;1
L 1.3825 1.3325 1.3825 1.3325 24 P 0 ;1
L 1.3825 1.6325 1.3825 1.6325 24 P 0 ;1
L 1.3825 1.6825 1.3825 1.6825 24 P 0 ;1
L 1.3825 1.7325 1.3825 1.7325 24 P 0 ;1
L 1.3825 1.7825 1.3825 1.7825 24 P 0 ;1
L 1.3825 1.8325 1.3825 1.8325 24 P 0 ;1
L 1.3825 1.8825 1.3825 1.8825 24 P 0 ;1
L 1.3825 1.9325 1.3825 1.9325 24 P 0 ;1
L 1.3825 1.9825 1.3825 1.9825 24 P 0 ;1
L 1.3825 2.0325 1.3825 2.0325 24 P 0 ;1
L 1.3825 2.0825 1.3825 2.0825 24 P 0 ;1
L 1.3825 2.1325 1.3825 2.1325 24 P 0 ;1
L 1.3825 2.1825 1.3825 2.1825 24 P 0 ;1
L 1.3825 2.2325 1.3825 2.2325 24 P 0 ;1
L 1.3825 2.2825 1.3825 2.2825 24 P 0 ;1
L 1.3825 2.3325 1.3825 2.3325 24 P 0 ;1
L 1.3825 2.3825 1.3825 2.3825 24 P 0 ;1
L 1.3825 2.4325 1.3825 2.4325 24 P 0 ;1
L 1.3825 2.4825 1.3825 2.4825 24 P 0 ;1
L 1.3825 2.5325 1.3825 2.5325 24 P 0 ;1
L 1.3825 2.5825 1.3825 2.5825 24 P 0 ;1
L 1.3825 2.6325 1.3825 2.6325 24 P 0 ;1
L 1.3825 2.6825 1.3825 2.6825 24 P 0 ;1
L 1.3825 2.7325 1.3825 2.7325 24 P 0 ;1
L 1.3825 2.7825 1.3825 2.7825 24 P 0 ;1
L 1.3825 2.8325 1.3825 2.8325 24 P 0 ;1
L 1.3825 2.8825 1.3825 2.8825 24 P 0 ;1
L 1.3825 2.9325 1.3825 2.9325 24 P 0 ;1
L 1.3825 2.9825 1.3825 2.9825 24 P 0 ;1
L 1.3825 3.0325 1.3825 3.0325 24 P 0 ;1
L 1.3825 3.0825 1.3825 3.0825 24 P 0 ;1
L 1.3825 3.1325 1.3825 3.1325 24 P 0 ;1
L 1.3825 3.1825 1.3825 3.1825 24 P 0 ;1
L 1.3825 3.2325 1.3825 3.2325 24 P 0 ;1
L 1.3825 3.2825 1.3825 3.2825 24 P 0 ;1
L 1.3825 3.3325 1.3825 3.3325 24 P 0 ;1
L 1.3825 3.3825 1.3825 3.3825 24 P 0 ;1
L 1.3825 3.4325 1.3825 3.4325 24 P 0 ;1
L 1.3825 3.4825 1.3825 3.4825 24 P 0 ;1
L 1.3825 3.5325 1.3825 3.5325 24 P 0 ;1
L 1.3825 3.5825 1.3825 3.5825 24 P 0 ;1
L 1.3825 3.6325 1.3825 3.6325 24 P 0 ;1
L 1.3825 3.6825 1.3825 3.6825 24 P 0 ;1
L 1.3825 3.7325 1.3825 3.7325 24 P 0 ;1
L 1.4325 0.1325 1.4325 0.1325 24 P 0 ;1
L 1.4325 0.1825 1.4325 0.1825 24 P 0 ;1
L 1.4325 0.2325 1.4325 0.2325 24 P 0 ;1
L 1.4325 0.2825 1.4325 0.2825 24 P 0 ;1
L 1.4325 0.3325 1.4325 0.3325 24 P 0 ;1
L 1.4325 0.3825 1.4325 0.3825 24 P 0 ;1
L 1.4325 0.4325 1.4325 0.4325 24 P 0 ;1
L 1.4325 0.4825 1.4325 0.4825 24 P 0 ;1
L 1.4325 0.5325 1.4325 0.5325 24 P 0 ;1
L 1.4325 0.5825 1.4325 0.5825 24 P 0 ;1
L 1.4325 0.6325 1.4325 0.6325 24 P 0 ;1
L 1.4325 0.6825 1.4325 0.6825 24 P 0 ;1
L 1.4325 0.7325 1.4325 0.7325 24 P 0 ;1
L 1.4325 0.7825 1.4325 0.7825 24 P 0 ;1
L 1.4325 0.8325 1.4325 0.8325 24 P 0 ;1
L 1.4325 0.8825 1.4325 0.8825 24 P 0 ;1
L 1.4325 0.9325 1.4325 0.9325 24 P 0 ;1
L 1.4325 0.9825 1.4325 0.9825 24 P 0 ;1
L 1.4325 1.0325 1.4325 1.0325 24 P 0 ;1
L 1.4325 1.0825 1.4325 1.0825 24 P 0 ;1
L 1.4325 1.1325 1.4325 1.1325 24 P 0 ;1
L 1.4325 1.1825 1.4325 1.1825 24 P 0 ;1
L 1.4325 1.2325 1.4325 1.2325 24 P 0 ;1
L 1.4325 1.2825 1.4325 1.2825 24 P 0 ;1
L 1.4325 1.5825 1.4325 1.5825 24 P 0 ;1
L 1.4325 1.6325 1.4325 1.6325 24 P 0 ;1
L 1.4325 1.6825 1.4325 1.6825 24 P 0 ;1
L 1.4325 1.7325 1.4325 1.7325 24 P 0 ;1
L 1.4325 1.7825 1.4325 1.7825 24 P 0 ;1
L 1.4325 1.8325 1.4325 1.8325 24 P 0 ;1
L 1.4325 1.8825 1.4325 1.8825 24 P 0 ;1
L 1.4325 1.9325 1.4325 1.9325 24 P 0 ;1
L 1.4325 1.9825 1.4325 1.9825 24 P 0 ;1
L 1.4325 2.0325 1.4325 2.0325 24 P 0 ;1
L 1.4325 2.0825 1.4325 2.0825 24 P 0 ;1
L 1.4325 2.1325 1.4325 2.1325 24 P 0 ;1
L 1.4325 2.1825 1.4325 2.1825 24 P 0 ;1
L 1.4325 2.2325 1.4325 2.2325 24 P 0 ;1
L 1.4325 2.2825 1.4325 2.2825 24 P 0 ;1
L 1.4325 2.3325 1.4325 2.3325 24 P 0 ;1
L 1.4325 2.3825 1.4325 2.3825 24 P 0 ;1
L 1.4325 2.4325 1.4325 2.4325 24 P 0 ;1
L 1.4325 2.4825 1.4325 2.4825 24 P 0 ;1
L 1.4325 2.5325 1.4325 2.5325 24 P 0 ;1
L 1.4325 2.5825 1.4325 2.5825 24 P 0 ;1
L 1.4325 2.6325 1.4325 2.6325 24 P 0 ;1
L 1.4325 2.6825 1.4325 2.6825 24 P 0 ;1
L 1.4325 2.7325 1.4325 2.7325 24 P 0 ;1
L 1.4325 2.7825 1.4325 2.7825 24 P 0 ;1
L 1.4325 2.8325 1.4325 2.8325 24 P 0 ;1
L 1.4325 2.8825 1.4325 2.8825 24 P 0 ;1
L 1.4325 2.9325 1.4325 2.9325 24 P 0 ;1
L 1.4325 2.9825 1.4325 2.9825 24 P 0 ;1
L 1.4325 3.0325 1.4325 3.0325 24 P 0 ;1
L 1.4325 3.0825 1.4325 3.0825 24 P 0 ;1
L 1.4325 3.1325 1.4325 3.1325 24 P 0 ;1
L 1.4325 3.1825 1.4325 3.1825 24 P 0 ;1
L 1.4325 3.2325 1.4325 3.2325 24 P 0 ;1
L 1.4325 3.2825 1.4325 3.2825 24 P 0 ;1
L 1.4325 3.3325 1.4325 3.3325 24 P 0 ;1
L 1.4325 3.3825 1.4325 3.3825 24 P 0 ;1
L 1.4325 3.4325 1.4325 3.4325 24 P 0 ;1
L 1.4325 3.4825 1.4325 3.4825 24 P 0 ;1
L 1.4325 3.5325 1.4325 3.5325 24 P 0 ;1
L 1.4325 3.5825 1.4325 3.5825 24 P 0 ;1
L 1.4325 3.6325 1.4325 3.6325 24 P 0 ;1
L 1.4325 3.6825 1.4325 3.6825 24 P 0 ;1
L 1.4325 4.0325 1.4325 4.0325 24 P 0 ;1
L 1.4325 4.0825 1.4325 4.0825 24 P 0 ;1
L 1.4325 4.1325 1.4325 4.1325 24 P 0 ;1
L 1.4325 4.1825 1.4325 4.1825 24 P 0 ;1
L 1.4325 4.2325 1.4325 4.2325 24 P 0 ;1
L 1.4325 4.2825 1.4325 4.2825 24 P 0 ;1
L 1.4325 4.3325 1.4325 4.3325 24 P 0 ;1
L 1.4825 0.1325 1.4825 0.1325 24 P 0 ;1
L 1.4825 0.1825 1.4825 0.1825 24 P 0 ;1
L 1.4825 0.2325 1.4825 0.2325 24 P 0 ;1
L 1.4825 0.2825 1.4825 0.2825 24 P 0 ;1
L 1.4825 0.3325 1.4825 0.3325 24 P 0 ;1
L 1.4825 0.3825 1.4825 0.3825 24 P 0 ;1
L 1.4825 0.4325 1.4825 0.4325 24 P 0 ;1
L 1.4825 0.4825 1.4825 0.4825 24 P 0 ;1
L 1.4825 0.5325 1.4825 0.5325 24 P 0 ;1
L 1.4825 0.5825 1.4825 0.5825 24 P 0 ;1
L 1.4825 0.6325 1.4825 0.6325 24 P 0 ;1
L 1.4825 0.6825 1.4825 0.6825 24 P 0 ;1
L 1.4825 0.7325 1.4825 0.7325 24 P 0 ;1
L 1.4825 0.7825 1.4825 0.7825 24 P 0 ;1
L 1.4825 0.8325 1.4825 0.8325 24 P 0 ;1
L 1.4825 0.8825 1.4825 0.8825 24 P 0 ;1
L 1.4825 0.9325 1.4825 0.9325 24 P 0 ;1
L 1.4825 0.9825 1.4825 0.9825 24 P 0 ;1
L 1.4825 1.0325 1.4825 1.0325 24 P 0 ;1
L 1.4825 1.0825 1.4825 1.0825 24 P 0 ;1
L 1.4825 1.1325 1.4825 1.1325 24 P 0 ;1
L 1.4825 1.1825 1.4825 1.1825 24 P 0 ;1
L 1.4825 1.2325 1.4825 1.2325 24 P 0 ;1
L 1.4825 1.5325 1.4825 1.5325 24 P 0 ;1
L 1.4825 1.5825 1.4825 1.5825 24 P 0 ;1
L 1.4825 1.6325 1.4825 1.6325 24 P 0 ;1
L 1.4825 1.6825 1.4825 1.6825 24 P 0 ;1
L 1.4825 1.7325 1.4825 1.7325 24 P 0 ;1
L 1.4825 1.7825 1.4825 1.7825 24 P 0 ;1
L 1.4825 1.8325 1.4825 1.8325 24 P 0 ;1
L 1.4825 1.8825 1.4825 1.8825 24 P 0 ;1
L 1.4825 1.9325 1.4825 1.9325 24 P 0 ;1
L 1.4825 1.9825 1.4825 1.9825 24 P 0 ;1
L 1.4825 2.0325 1.4825 2.0325 24 P 0 ;1
L 1.4825 2.0825 1.4825 2.0825 24 P 0 ;1
L 1.4825 2.1325 1.4825 2.1325 24 P 0 ;1
L 1.4825 2.1825 1.4825 2.1825 24 P 0 ;1
L 1.4825 2.2325 1.4825 2.2325 24 P 0 ;1
L 1.4825 2.2825 1.4825 2.2825 24 P 0 ;1
L 1.4825 2.3325 1.4825 2.3325 24 P 0 ;1
L 1.4825 2.3825 1.4825 2.3825 24 P 0 ;1
L 1.4825 2.4325 1.4825 2.4325 24 P 0 ;1
L 1.4825 2.4825 1.4825 2.4825 24 P 0 ;1
L 1.4825 2.5325 1.4825 2.5325 24 P 0 ;1
L 1.4825 2.5825 1.4825 2.5825 24 P 0 ;1
L 1.4825 2.6325 1.4825 2.6325 24 P 0 ;1
L 1.4825 2.6825 1.4825 2.6825 24 P 0 ;1
L 1.4825 2.7325 1.4825 2.7325 24 P 0 ;1
L 1.4825 2.7825 1.4825 2.7825 24 P 0 ;1
L 1.4825 2.8325 1.4825 2.8325 24 P 0 ;1
L 1.4825 2.8825 1.4825 2.8825 24 P 0 ;1
L 1.4825 2.9325 1.4825 2.9325 24 P 0 ;1
L 1.4825 2.9825 1.4825 2.9825 24 P 0 ;1
L 1.4825 3.0325 1.4825 3.0325 24 P 0 ;1
L 1.4825 3.0825 1.4825 3.0825 24 P 0 ;1
L 1.4825 3.1325 1.4825 3.1325 24 P 0 ;1
L 1.4825 3.1825 1.4825 3.1825 24 P 0 ;1
L 1.4825 3.2325 1.4825 3.2325 24 P 0 ;1
L 1.4825 3.2825 1.4825 3.2825 24 P 0 ;1
L 1.4825 3.3325 1.4825 3.3325 24 P 0 ;1
L 1.4825 3.3825 1.4825 3.3825 24 P 0 ;1
L 1.4825 3.4325 1.4825 3.4325 24 P 0 ;1
L 1.4825 3.4825 1.4825 3.4825 24 P 0 ;1
L 1.4825 3.5325 1.4825 3.5325 24 P 0 ;1
L 1.4825 3.5825 1.4825 3.5825 24 P 0 ;1
L 1.4825 3.6325 1.4825 3.6325 24 P 0 ;1
L 1.4825 3.9825 1.4825 3.9825 24 P 0 ;1
L 1.4825 4.0325 1.4825 4.0325 24 P 0 ;1
L 1.4825 4.0825 1.4825 4.0825 24 P 0 ;1
L 1.4825 4.1325 1.4825 4.1325 24 P 0 ;1
L 1.4825 4.1825 1.4825 4.1825 24 P 0 ;1
L 1.4825 4.2325 1.4825 4.2325 24 P 0 ;1
L 1.4825 4.2825 1.4825 4.2825 24 P 0 ;1
L 1.5325 0.1325 1.5325 0.1325 24 P 0 ;1
L 1.5325 0.1825 1.5325 0.1825 24 P 0 ;1
L 1.5325 0.2325 1.5325 0.2325 24 P 0 ;1
L 1.5325 0.2825 1.5325 0.2825 24 P 0 ;1
L 1.5325 0.3325 1.5325 0.3325 24 P 0 ;1
L 1.5325 0.3825 1.5325 0.3825 24 P 0 ;1
L 1.5325 0.4325 1.5325 0.4325 24 P 0 ;1
L 1.5325 0.4825 1.5325 0.4825 24 P 0 ;1
L 1.5325 0.5325 1.5325 0.5325 24 P 0 ;1
L 1.5325 0.5825 1.5325 0.5825 24 P 0 ;1
L 1.5325 0.6325 1.5325 0.6325 24 P 0 ;1
L 1.5325 0.6825 1.5325 0.6825 24 P 0 ;1
L 1.5325 0.7325 1.5325 0.7325 24 P 0 ;1
L 1.5325 0.7825 1.5325 0.7825 24 P 0 ;1
L 1.5325 0.8325 1.5325 0.8325 24 P 0 ;1
L 1.5325 0.8825 1.5325 0.8825 24 P 0 ;1
L 1.5325 0.9325 1.5325 0.9325 24 P 0 ;1
L 1.5325 0.9825 1.5325 0.9825 24 P 0 ;1
L 1.5325 1.0325 1.5325 1.0325 24 P 0 ;1
L 1.5325 1.0825 1.5325 1.0825 24 P 0 ;1
L 1.5325 1.1325 1.5325 1.1325 24 P 0 ;1
L 1.5325 1.1825 1.5325 1.1825 24 P 0 ;1
L 1.5325 1.4825 1.5325 1.4825 24 P 0 ;1
L 1.5325 1.5325 1.5325 1.5325 24 P 0 ;1
L 1.5325 1.5825 1.5325 1.5825 24 P 0 ;1
L 1.5325 1.6325 1.5325 1.6325 24 P 0 ;1
L 1.5325 1.6825 1.5325 1.6825 24 P 0 ;1
L 1.5325 1.7325 1.5325 1.7325 24 P 0 ;1
L 1.5325 1.7825 1.5325 1.7825 24 P 0 ;1
L 1.5325 1.8325 1.5325 1.8325 24 P 0 ;1
L 1.5325 1.8825 1.5325 1.8825 24 P 0 ;1
L 1.5325 1.9325 1.5325 1.9325 24 P 0 ;1
L 1.5325 1.9825 1.5325 1.9825 24 P 0 ;1
L 1.5325 2.0325 1.5325 2.0325 24 P 0 ;1
L 1.5325 2.0825 1.5325 2.0825 24 P 0 ;1
L 1.5325 2.1325 1.5325 2.1325 24 P 0 ;1
L 1.5325 2.1825 1.5325 2.1825 24 P 0 ;1
L 1.5325 2.2325 1.5325 2.2325 24 P 0 ;1
L 1.5325 2.2825 1.5325 2.2825 24 P 0 ;1
L 1.5325 2.3325 1.5325 2.3325 24 P 0 ;1
L 1.5325 2.3825 1.5325 2.3825 24 P 0 ;1
L 1.5325 2.4325 1.5325 2.4325 24 P 0 ;1
L 1.5325 2.4825 1.5325 2.4825 24 P 0 ;1
L 1.5325 2.5325 1.5325 2.5325 24 P 0 ;1
L 1.5325 2.5825 1.5325 2.5825 24 P 0 ;1
L 1.5325 2.6325 1.5325 2.6325 24 P 0 ;1
L 1.5325 2.6825 1.5325 2.6825 24 P 0 ;1
L 1.5325 2.7325 1.5325 2.7325 24 P 0 ;1
L 1.5325 2.7825 1.5325 2.7825 24 P 0 ;1
L 1.5325 2.8325 1.5325 2.8325 24 P 0 ;1
L 1.5325 2.8825 1.5325 2.8825 24 P 0 ;1
L 1.5325 2.9325 1.5325 2.9325 24 P 0 ;1
L 1.5325 2.9825 1.5325 2.9825 24 P 0 ;1
L 1.5325 3.0325 1.5325 3.0325 24 P 0 ;1
L 1.5325 3.0825 1.5325 3.0825 24 P 0 ;1
L 1.5325 3.1325 1.5325 3.1325 24 P 0 ;1
L 1.5325 3.1825 1.5325 3.1825 24 P 0 ;1
L 1.5325 3.2325 1.5325 3.2325 24 P 0 ;1
L 1.5325 3.2825 1.5325 3.2825 24 P 0 ;1
L 1.5325 3.3325 1.5325 3.3325 24 P 0 ;1
L 1.5325 3.3825 1.5325 3.3825 24 P 0 ;1
L 1.5325 3.4325 1.5325 3.4325 24 P 0 ;1
L 1.5325 3.4825 1.5325 3.4825 24 P 0 ;1
L 1.5325 3.5325 1.5325 3.5325 24 P 0 ;1
L 1.5325 3.5825 1.5325 3.5825 24 P 0 ;1
L 1.5325 3.9325 1.5325 3.9325 24 P 0 ;1
L 1.5325 3.9825 1.5325 3.9825 24 P 0 ;1
L 1.5325 4.0325 1.5325 4.0325 24 P 0 ;1
L 1.5325 4.0825 1.5325 4.0825 24 P 0 ;1
L 1.5325 4.1325 1.5325 4.1325 24 P 0 ;1
L 1.5325 4.1825 1.5325 4.1825 24 P 0 ;1
L 1.5325 4.2325 1.5325 4.2325 24 P 0 ;1
L 1.5325 4.2825 1.5325 4.2825 24 P 0 ;1
L 1.5825 0.1325 1.5825 0.1325 24 P 0 ;1
L 1.5825 0.1825 1.5825 0.1825 24 P 0 ;1
L 1.5825 0.2325 1.5825 0.2325 24 P 0 ;1
L 1.5825 0.2825 1.5825 0.2825 24 P 0 ;1
L 1.5825 0.3325 1.5825 0.3325 24 P 0 ;1
L 1.5825 0.3825 1.5825 0.3825 24 P 0 ;1
L 1.5825 0.4325 1.5825 0.4325 24 P 0 ;1
L 1.5825 0.4825 1.5825 0.4825 24 P 0 ;1
L 1.5825 0.5325 1.5825 0.5325 24 P 0 ;1
L 1.5825 0.5825 1.5825 0.5825 24 P 0 ;1
L 1.5825 0.6325 1.5825 0.6325 24 P 0 ;1
L 1.5825 0.6825 1.5825 0.6825 24 P 0 ;1
L 1.5825 0.7325 1.5825 0.7325 24 P 0 ;1
L 1.5825 0.7825 1.5825 0.7825 24 P 0 ;1
L 1.5825 0.8325 1.5825 0.8325 24 P 0 ;1
L 1.5825 0.8825 1.5825 0.8825 24 P 0 ;1
L 1.5825 0.9325 1.5825 0.9325 24 P 0 ;1
L 1.5825 0.9825 1.5825 0.9825 24 P 0 ;1
L 1.5825 1.0325 1.5825 1.0325 24 P 0 ;1
L 1.5825 1.0825 1.5825 1.0825 24 P 0 ;1
L 1.5825 1.1325 1.5825 1.1325 24 P 0 ;1
L 1.5825 1.4325 1.5825 1.4325 24 P 0 ;1
L 1.5825 1.4825 1.5825 1.4825 24 P 0 ;1
L 1.5825 1.5325 1.5825 1.5325 24 P 0 ;1
L 1.5825 1.5825 1.5825 1.5825 24 P 0 ;1
L 1.5825 1.6325 1.5825 1.6325 24 P 0 ;1
L 1.5825 1.6825 1.5825 1.6825 24 P 0 ;1
L 1.5825 1.7325 1.5825 1.7325 24 P 0 ;1
L 1.5825 1.7825 1.5825 1.7825 24 P 0 ;1
L 1.5825 1.8325 1.5825 1.8325 24 P 0 ;1
L 1.5825 1.8825 1.5825 1.8825 24 P 0 ;1
L 1.5825 1.9325 1.5825 1.9325 24 P 0 ;1
L 1.5825 1.9825 1.5825 1.9825 24 P 0 ;1
L 1.5825 2.0325 1.5825 2.0325 24 P 0 ;1
L 1.5825 2.0825 1.5825 2.0825 24 P 0 ;1
L 1.5825 2.1325 1.5825 2.1325 24 P 0 ;1
L 1.5825 2.1825 1.5825 2.1825 24 P 0 ;1
L 1.5825 2.2325 1.5825 2.2325 24 P 0 ;1
L 1.5825 2.2825 1.5825 2.2825 24 P 0 ;1
L 1.5825 2.3325 1.5825 2.3325 24 P 0 ;1
L 1.5825 2.3825 1.5825 2.3825 24 P 0 ;1
L 1.5825 2.4325 1.5825 2.4325 24 P 0 ;1
L 1.5825 2.4825 1.5825 2.4825 24 P 0 ;1
L 1.5825 2.5325 1.5825 2.5325 24 P 0 ;1
L 1.5825 2.5825 1.5825 2.5825 24 P 0 ;1
L 1.5825 2.6325 1.5825 2.6325 24 P 0 ;1
L 1.5825 2.6825 1.5825 2.6825 24 P 0 ;1
L 1.5825 2.7325 1.5825 2.7325 24 P 0 ;1
L 1.5825 2.7825 1.5825 2.7825 24 P 0 ;1
L 1.5825 2.8325 1.5825 2.8325 24 P 0 ;1
L 1.5825 2.8825 1.5825 2.8825 24 P 0 ;1
L 1.5825 2.9325 1.5825 2.9325 24 P 0 ;1
L 1.5825 2.9825 1.5825 2.9825 24 P 0 ;1
L 1.5825 3.0325 1.5825 3.0325 24 P 0 ;1
L 1.5825 3.0825 1.5825 3.0825 24 P 0 ;1
L 1.5825 3.1325 1.5825 3.1325 24 P 0 ;1
L 1.5825 3.1825 1.5825 3.1825 24 P 0 ;1
L 1.5825 3.2325 1.5825 3.2325 24 P 0 ;1
L 1.5825 3.2825 1.5825 3.2825 24 P 0 ;1
L 1.5825 3.3325 1.5825 3.3325 24 P 0 ;1
L 1.5825 3.3825 1.5825 3.3825 24 P 0 ;1
L 1.5825 3.4325 1.5825 3.4325 24 P 0 ;1
L 1.5825 3.4825 1.5825 3.4825 24 P 0 ;1
L 1.5825 3.5325 1.5825 3.5325 24 P 0 ;1
L 1.5825 3.8825 1.5825 3.8825 24 P 0 ;1
L 1.5825 3.9325 1.5825 3.9325 24 P 0 ;1
L 1.5825 3.9825 1.5825 3.9825 24 P 0 ;1
L 1.5825 4.0325 1.5825 4.0325 24 P 0 ;1
L 1.5825 4.0825 1.5825 4.0825 24 P 0 ;1
L 1.5825 4.1325 1.5825 4.1325 24 P 0 ;1
L 1.5825 4.1825 1.5825 4.1825 24 P 0 ;1
L 1.5825 4.2325 1.5825 4.2325 24 P 0 ;1
L 1.5825 4.2825 1.5825 4.2825 24 P 0 ;1
L 1.6325 0.1325 1.6325 0.1325 24 P 0 ;1
L 1.6325 0.1825 1.6325 0.1825 24 P 0 ;1
L 1.6325 0.2325 1.6325 0.2325 24 P 0 ;1
L 1.6325 0.2825 1.6325 0.2825 24 P 0 ;1
L 1.6325 0.3325 1.6325 0.3325 24 P 0 ;1
L 1.6325 0.3825 1.6325 0.3825 24 P 0 ;1
L 1.6325 0.4325 1.6325 0.4325 24 P 0 ;1
L 1.6325 0.4825 1.6325 0.4825 24 P 0 ;1
L 1.6325 0.5325 1.6325 0.5325 24 P 0 ;1
L 1.6325 0.5825 1.6325 0.5825 24 P 0 ;1
L 1.6325 0.6325 1.6325 0.6325 24 P 0 ;1
L 1.6325 0.6825 1.6325 0.6825 24 P 0 ;1
L 1.6325 0.7325 1.6325 0.7325 24 P 0 ;1
L 1.6325 0.7825 1.6325 0.7825 24 P 0 ;1
L 1.6325 0.8325 1.6325 0.8325 24 P 0 ;1
L 1.6325 0.8825 1.6325 0.8825 24 P 0 ;1
L 1.6325 0.9325 1.6325 0.9325 24 P 0 ;1
L 1.6325 0.9825 1.6325 0.9825 24 P 0 ;1
L 1.6325 1.0325 1.6325 1.0325 24 P 0 ;1
L 1.6325 1.0825 1.6325 1.0825 24 P 0 ;1
L 1.6325 1.3825 1.6325 1.3825 24 P 0 ;1
L 1.6325 1.4325 1.6325 1.4325 24 P 0 ;1
L 1.6325 1.4825 1.6325 1.4825 24 P 0 ;1
L 1.6325 1.5325 1.6325 1.5325 24 P 0 ;1
L 1.6325 1.5825 1.6325 1.5825 24 P 0 ;1
L 1.6325 1.6325 1.6325 1.6325 24 P 0 ;1
L 1.6325 1.6825 1.6325 1.6825 24 P 0 ;1
L 1.6325 1.7325 1.6325 1.7325 24 P 0 ;1
L 1.6325 1.7825 1.6325 1.7825 24 P 0 ;1
L 1.6325 1.8325 1.6325 1.8325 24 P 0 ;1
L 1.6325 1.8825 1.6325 1.8825 24 P 0 ;1
L 1.6325 1.9325 1.6325 1.9325 24 P 0 ;1
L 1.6325 1.9825 1.6325 1.9825 24 P 0 ;1
L 1.6325 2.0325 1.6325 2.0325 24 P 0 ;1
L 1.6325 2.0825 1.6325 2.0825 24 P 0 ;1
L 1.6325 2.1325 1.6325 2.1325 24 P 0 ;1
L 1.6325 2.1825 1.6325 2.1825 24 P 0 ;1
L 1.6325 2.2325 1.6325 2.2325 24 P 0 ;1
L 1.6325 2.2825 1.6325 2.2825 24 P 0 ;1
L 1.6325 2.3325 1.6325 2.3325 24 P 0 ;1
L 1.6325 2.3825 1.6325 2.3825 24 P 0 ;1
L 1.6325 2.4325 1.6325 2.4325 24 P 0 ;1
L 1.6325 2.4825 1.6325 2.4825 24 P 0 ;1
L 1.6325 2.5325 1.6325 2.5325 24 P 0 ;1
L 1.6325 2.5825 1.6325 2.5825 24 P 0 ;1
L 1.6325 2.6325 1.6325 2.6325 24 P 0 ;1
L 1.6325 2.6825 1.6325 2.6825 24 P 0 ;1
L 1.6325 2.7325 1.6325 2.7325 24 P 0 ;1
L 1.6325 2.7825 1.6325 2.7825 24 P 0 ;1
L 1.6325 2.8325 1.6325 2.8325 24 P 0 ;1
L 1.6325 2.8825 1.6325 2.8825 24 P 0 ;1
L 1.6325 2.9325 1.6325 2.9325 24 P 0 ;1
L 1.6325 2.9825 1.6325 2.9825 24 P 0 ;1
L 1.6325 3.0325 1.6325 3.0325 24 P 0 ;1
L 1.6325 3.0825 1.6325 3.0825 24 P 0 ;1
L 1.6325 3.1325 1.6325 3.1325 24 P 0 ;1
L 1.6325 3.1825 1.6325 3.1825 24 P 0 ;1
L 1.6325 3.2325 1.6325 3.2325 24 P 0 ;1
L 1.6325 3.2825 1.6325 3.2825 24 P 0 ;1
L 1.6325 3.3325 1.6325 3.3325 24 P 0 ;1
L 1.6325 3.3825 1.6325 3.3825 24 P 0 ;1
L 1.6325 3.4325 1.6325 3.4325 24 P 0 ;1
L 1.6325 3.4825 1.6325 3.4825 24 P 0 ;1
L 1.6325 3.8325 1.6325 3.8325 24 P 0 ;1
L 1.6325 3.8825 1.6325 3.8825 24 P 0 ;1
L 1.6325 3.9325 1.6325 3.9325 24 P 0 ;1
L 1.6325 3.9825 1.6325 3.9825 24 P 0 ;1
L 1.6325 4.0325 1.6325 4.0325 24 P 0 ;1
L 1.6325 4.0825 1.6325 4.0825 24 P 0 ;1
L 1.6325 4.1325 1.6325 4.1325 24 P 0 ;1
L 1.6325 4.1825 1.6325 4.1825 24 P 0 ;1
L 1.6325 4.2325 1.6325 4.2325 24 P 0 ;1
L 1.6325 4.2825 1.6325 4.2825 24 P 0 ;1
L 1.6325 5.2825 1.6325 5.2825 24 P 0 ;1
L 1.6825 0.1325 1.6825 0.1325 24 P 0 ;1
L 1.6825 0.1825 1.6825 0.1825 24 P 0 ;1
L 1.6825 0.2325 1.6825 0.2325 24 P 0 ;1
L 1.6825 0.2825 1.6825 0.2825 24 P 0 ;1
L 1.6825 0.3325 1.6825 0.3325 24 P 0 ;1
L 1.6825 0.3825 1.6825 0.3825 24 P 0 ;1
L 1.6825 0.4325 1.6825 0.4325 24 P 0 ;1
L 1.6825 0.4825 1.6825 0.4825 24 P 0 ;1
L 1.6825 0.5325 1.6825 0.5325 24 P 0 ;1
L 1.6825 0.5825 1.6825 0.5825 24 P 0 ;1
L 1.6825 0.6325 1.6825 0.6325 24 P 0 ;1
L 1.6825 0.6825 1.6825 0.6825 24 P 0 ;1
L 1.6825 0.7325 1.6825 0.7325 24 P 0 ;1
L 1.6825 0.7825 1.6825 0.7825 24 P 0 ;1
L 1.6825 0.8325 1.6825 0.8325 24 P 0 ;1
L 1.6825 0.8825 1.6825 0.8825 24 P 0 ;1
L 1.6825 0.9325 1.6825 0.9325 24 P 0 ;1
L 1.6825 0.9825 1.6825 0.9825 24 P 0 ;1
L 1.6825 1.0325 1.6825 1.0325 24 P 0 ;1
L 1.6825 1.3325 1.6825 1.3325 24 P 0 ;1
L 1.6825 1.3825 1.6825 1.3825 24 P 0 ;1
L 1.6825 1.4325 1.6825 1.4325 24 P 0 ;1
L 1.6825 1.4825 1.6825 1.4825 24 P 0 ;1
L 1.6825 1.5325 1.6825 1.5325 24 P 0 ;1
L 1.6825 1.5825 1.6825 1.5825 24 P 0 ;1
L 1.6825 1.6325 1.6825 1.6325 24 P 0 ;1
L 1.6825 1.6825 1.6825 1.6825 24 P 0 ;1
L 1.6825 1.7325 1.6825 1.7325 24 P 0 ;1
L 1.6825 1.7825 1.6825 1.7825 24 P 0 ;1
L 1.6825 1.8325 1.6825 1.8325 24 P 0 ;1
L 1.6825 1.8825 1.6825 1.8825 24 P 0 ;1
L 1.6825 1.9325 1.6825 1.9325 24 P 0 ;1
L 1.6825 1.9825 1.6825 1.9825 24 P 0 ;1
L 1.6825 2.0325 1.6825 2.0325 24 P 0 ;1
L 1.6825 2.0825 1.6825 2.0825 24 P 0 ;1
L 1.6825 2.1325 1.6825 2.1325 24 P 0 ;1
L 1.6825 2.1825 1.6825 2.1825 24 P 0 ;1
L 1.6825 2.2325 1.6825 2.2325 24 P 0 ;1
L 1.6825 2.2825 1.6825 2.2825 24 P 0 ;1
L 1.6825 2.3325 1.6825 2.3325 24 P 0 ;1
L 1.6825 2.3825 1.6825 2.3825 24 P 0 ;1
L 1.6825 2.4325 1.6825 2.4325 24 P 0 ;1
L 1.6825 2.4825 1.6825 2.4825 24 P 0 ;1
L 1.6825 2.5325 1.6825 2.5325 24 P 0 ;1
L 1.6825 2.5825 1.6825 2.5825 24 P 0 ;1
L 1.6825 2.6325 1.6825 2.6325 24 P 0 ;1
L 1.6825 2.6825 1.6825 2.6825 24 P 0 ;1
L 1.6825 2.7325 1.6825 2.7325 24 P 0 ;1
L 1.6825 2.7825 1.6825 2.7825 24 P 0 ;1
L 1.6825 2.8325 1.6825 2.8325 24 P 0 ;1
L 1.6825 2.8825 1.6825 2.8825 24 P 0 ;1
L 1.6825 2.9325 1.6825 2.9325 24 P 0 ;1
L 1.6825 2.9825 1.6825 2.9825 24 P 0 ;1
L 1.6825 3.0325 1.6825 3.0325 24 P 0 ;1
L 1.6825 3.0825 1.6825 3.0825 24 P 0 ;1
L 1.6825 3.1325 1.6825 3.1325 24 P 0 ;1
L 1.6825 3.1825 1.6825 3.1825 24 P 0 ;1
L 1.6825 3.2325 1.6825 3.2325 24 P 0 ;1
L 1.6825 3.2825 1.6825 3.2825 24 P 0 ;1
L 1.6825 3.3325 1.6825 3.3325 24 P 0 ;1
L 1.6825 3.3825 1.6825 3.3825 24 P 0 ;1
L 1.6825 3.4325 1.6825 3.4325 24 P 0 ;1
L 1.6825 3.7825 1.6825 3.7825 24 P 0 ;1
L 1.6825 3.8325 1.6825 3.8325 24 P 0 ;1
L 1.6825 3.8825 1.6825 3.8825 24 P 0 ;1
L 1.6825 3.9325 1.6825 3.9325 24 P 0 ;1
L 1.6825 3.9825 1.6825 3.9825 24 P 0 ;1
L 1.6825 4.0325 1.6825 4.0325 24 P 0 ;1
L 1.6825 4.0825 1.6825 4.0825 24 P 0 ;1
L 1.6825 4.1325 1.6825 4.1325 24 P 0 ;1
L 1.6825 4.1825 1.6825 4.1825 24 P 0 ;1
L 1.6825 4.2325 1.6825 4.2325 24 P 0 ;1
L 1.6825 4.2825 1.6825 4.2825 24 P 0 ;1
L 1.6825 5.2825 1.6825 5.2825 24 P 0 ;1
L 1.7325 0.1325 1.7325 0.1325 24 P 0 ;1
L 1.7325 0.1825 1.7325 0.1825 24 P 0 ;1
L 1.7325 0.2325 1.7325 0.2325 24 P 0 ;1
L 1.7325 0.2825 1.7325 0.2825 24 P 0 ;1
L 1.7325 0.3325 1.7325 0.3325 24 P 0 ;1
L 1.7325 0.3825 1.7325 0.3825 24 P 0 ;1
L 1.7325 0.4325 1.7325 0.4325 24 P 0 ;1
L 1.7325 0.4825 1.7325 0.4825 24 P 0 ;1
L 1.7325 0.5325 1.7325 0.5325 24 P 0 ;1
L 1.7325 0.5825 1.7325 0.5825 24 P 0 ;1
L 1.7325 0.6325 1.7325 0.6325 24 P 0 ;1
L 1.7325 0.6825 1.7325 0.6825 24 P 0 ;1
L 1.7325 0.7325 1.7325 0.7325 24 P 0 ;1
L 1.7325 0.7825 1.7325 0.7825 24 P 0 ;1
L 1.7325 0.8325 1.7325 0.8325 24 P 0 ;1
L 1.7325 0.8825 1.7325 0.8825 24 P 0 ;1
L 1.7325 0.9325 1.7325 0.9325 24 P 0 ;1
L 1.7325 0.9825 1.7325 0.9825 24 P 0 ;1
L 1.7325 1.2825 1.7325 1.2825 24 P 0 ;1
L 1.7325 1.3325 1.7325 1.3325 24 P 0 ;1
L 1.7325 1.3825 1.7325 1.3825 24 P 0 ;1
L 1.7325 1.4325 1.7325 1.4325 24 P 0 ;1
L 1.7325 1.4825 1.7325 1.4825 24 P 0 ;1
L 1.7325 1.5325 1.7325 1.5325 24 P 0 ;1
L 1.7325 1.5825 1.7325 1.5825 24 P 0 ;1
L 1.7325 1.6325 1.7325 1.6325 24 P 0 ;1
L 1.7325 1.6825 1.7325 1.6825 24 P 0 ;1
L 1.7325 1.7325 1.7325 1.7325 24 P 0 ;1
L 1.7325 1.7825 1.7325 1.7825 24 P 0 ;1
L 1.7325 1.8325 1.7325 1.8325 24 P 0 ;1
L 1.7325 1.8825 1.7325 1.8825 24 P 0 ;1
L 1.7325 1.9325 1.7325 1.9325 24 P 0 ;1
L 1.7325 1.9825 1.7325 1.9825 24 P 0 ;1
L 1.7325 2.0325 1.7325 2.0325 24 P 0 ;1
L 1.7325 2.0825 1.7325 2.0825 24 P 0 ;1
L 1.7325 2.1325 1.7325 2.1325 24 P 0 ;1
L 1.7325 2.1825 1.7325 2.1825 24 P 0 ;1
L 1.7325 2.2325 1.7325 2.2325 24 P 0 ;1
L 1.7325 2.2825 1.7325 2.2825 24 P 0 ;1
L 1.7325 2.3325 1.7325 2.3325 24 P 0 ;1
L 1.7325 2.3825 1.7325 2.3825 24 P 0 ;1
L 1.7325 2.5825 1.7325 2.5825 24 P 0 ;1
L 1.7325 2.6325 1.7325 2.6325 24 P 0 ;1
L 1.7325 2.6825 1.7325 2.6825 24 P 0 ;1
L 1.7325 2.7325 1.7325 2.7325 24 P 0 ;1
L 1.7325 2.7825 1.7325 2.7825 24 P 0 ;1
L 1.7325 2.8325 1.7325 2.8325 24 P 0 ;1
L 1.7325 2.8825 1.7325 2.8825 24 P 0 ;1
L 1.7325 2.9325 1.7325 2.9325 24 P 0 ;1
L 1.7325 2.9825 1.7325 2.9825 24 P 0 ;1
L 1.7325 3.0325 1.7325 3.0325 24 P 0 ;1
L 1.7325 3.0825 1.7325 3.0825 24 P 0 ;1
L 1.7325 3.1325 1.7325 3.1325 24 P 0 ;1
L 1.7325 3.1825 1.7325 3.1825 24 P 0 ;1
L 1.7325 3.2325 1.7325 3.2325 24 P 0 ;1
L 1.7325 3.2825 1.7325 3.2825 24 P 0 ;1
L 1.7325 3.3325 1.7325 3.3325 24 P 0 ;1
L 1.7325 3.3825 1.7325 3.3825 24 P 0 ;1
L 1.7325 3.4325 1.7325 3.4325 24 P 0 ;1
L 1.7325 3.7325 1.7325 3.7325 24 P 0 ;1
L 1.7325 3.7825 1.7325 3.7825 24 P 0 ;1
L 1.7325 3.8325 1.7325 3.8325 24 P 0 ;1
L 1.7325 3.8825 1.7325 3.8825 24 P 0 ;1
L 1.7325 3.9325 1.7325 3.9325 24 P 0 ;1
L 1.7325 3.9825 1.7325 3.9825 24 P 0 ;1
L 1.7325 4.0325 1.7325 4.0325 24 P 0 ;1
L 1.7325 4.0825 1.7325 4.0825 24 P 0 ;1
L 1.7325 4.1325 1.7325 4.1325 24 P 0 ;1
L 1.7325 4.1825 1.7325 4.1825 24 P 0 ;1
L 1.7325 4.2325 1.7325 4.2325 24 P 0 ;1
L 1.7325 4.2825 1.7325 4.2825 24 P 0 ;1
L 1.7325 5.1825 1.7325 5.1825 24 P 0 ;1
L 1.7325 5.2325 1.7325 5.2325 24 P 0 ;1
L 1.7325 5.2825 1.7325 5.2825 24 P 0 ;1
L 1.7825 0.1325 1.7825 0.1325 24 P 0 ;1
L 1.7825 0.1825 1.7825 0.1825 24 P 0 ;1
L 1.7825 0.2325 1.7825 0.2325 24 P 0 ;1
L 1.7825 0.2825 1.7825 0.2825 24 P 0 ;1
L 1.7825 0.3325 1.7825 0.3325 24 P 0 ;1
L 1.7825 0.3825 1.7825 0.3825 24 P 0 ;1
L 1.7825 0.4325 1.7825 0.4325 24 P 0 ;1
L 1.7825 0.4825 1.7825 0.4825 24 P 0 ;1
L 1.7825 0.5325 1.7825 0.5325 24 P 0 ;1
L 1.7825 0.5825 1.7825 0.5825 24 P 0 ;1
L 1.7825 0.6325 1.7825 0.6325 24 P 0 ;1
L 1.7825 0.6825 1.7825 0.6825 24 P 0 ;1
L 1.7825 0.7325 1.7825 0.7325 24 P 0 ;1
L 1.7825 0.7825 1.7825 0.7825 24 P 0 ;1
L 1.7825 0.8325 1.7825 0.8325 24 P 0 ;1
L 1.7825 0.8825 1.7825 0.8825 24 P 0 ;1
L 1.7825 0.9325 1.7825 0.9325 24 P 0 ;1
L 1.7825 1.2325 1.7825 1.2325 24 P 0 ;1
L 1.7825 1.2825 1.7825 1.2825 24 P 0 ;1
L 1.7825 1.3325 1.7825 1.3325 24 P 0 ;1
L 1.7825 1.3825 1.7825 1.3825 24 P 0 ;1
L 1.7825 1.4325 1.7825 1.4325 24 P 0 ;1
L 1.7825 1.4825 1.7825 1.4825 24 P 0 ;1
L 1.7825 1.5325 1.7825 1.5325 24 P 0 ;1
L 1.7825 1.5825 1.7825 1.5825 24 P 0 ;1
L 1.7825 1.6325 1.7825 1.6325 24 P 0 ;1
L 1.7825 1.6825 1.7825 1.6825 24 P 0 ;1
L 1.7825 1.7325 1.7825 1.7325 24 P 0 ;1
L 1.7825 1.7825 1.7825 1.7825 24 P 0 ;1
L 1.7825 1.8325 1.7825 1.8325 24 P 0 ;1
L 1.7825 1.8825 1.7825 1.8825 24 P 0 ;1
L 1.7825 1.9325 1.7825 1.9325 24 P 0 ;1
L 1.7825 1.9825 1.7825 1.9825 24 P 0 ;1
L 1.7825 2.0325 1.7825 2.0325 24 P 0 ;1
L 1.7825 2.0825 1.7825 2.0825 24 P 0 ;1
L 1.7825 2.1325 1.7825 2.1325 24 P 0 ;1
L 1.7825 2.1825 1.7825 2.1825 24 P 0 ;1
L 1.7825 2.2325 1.7825 2.2325 24 P 0 ;1
L 1.7825 2.2825 1.7825 2.2825 24 P 0 ;1
L 1.7825 2.3325 1.7825 2.3325 24 P 0 ;1
L 1.7825 2.3825 1.7825 2.3825 24 P 0 ;1
L 1.7825 2.5825 1.7825 2.5825 24 P 0 ;1
L 1.7825 2.6325 1.7825 2.6325 24 P 0 ;1
L 1.7825 2.6825 1.7825 2.6825 24 P 0 ;1
L 1.7825 2.7325 1.7825 2.7325 24 P 0 ;1
L 1.7825 2.7825 1.7825 2.7825 24 P 0 ;1
L 1.7825 2.8325 1.7825 2.8325 24 P 0 ;1
L 1.7825 2.8825 1.7825 2.8825 24 P 0 ;1
L 1.7825 2.9325 1.7825 2.9325 24 P 0 ;1
L 1.7825 2.9825 1.7825 2.9825 24 P 0 ;1
L 1.7825 3.0325 1.7825 3.0325 24 P 0 ;1
L 1.7825 3.0825 1.7825 3.0825 24 P 0 ;1
L 1.7825 3.1325 1.7825 3.1325 24 P 0 ;1
L 1.7825 3.1825 1.7825 3.1825 24 P 0 ;1
L 1.7825 3.2325 1.7825 3.2325 24 P 0 ;1
L 1.7825 3.2825 1.7825 3.2825 24 P 0 ;1
L 1.7825 3.3325 1.7825 3.3325 24 P 0 ;1
L 1.7825 3.3825 1.7825 3.3825 24 P 0 ;1
L 1.7825 4.2325 1.7825 4.2325 24 P 0 ;1
L 1.7825 4.2825 1.7825 4.2825 24 P 0 ;1
L 1.7825 5.2325 1.7825 5.2325 24 P 0 ;1
L 1.7825 5.2825 1.7825 5.2825 24 P 0 ;1
L 1.8325 0.1325 1.8325 0.1325 24 P 0 ;1
L 1.8325 0.1825 1.8325 0.1825 24 P 0 ;1
L 1.8325 0.2325 1.8325 0.2325 24 P 0 ;1
L 1.8325 0.2825 1.8325 0.2825 24 P 0 ;1
L 1.8325 0.3325 1.8325 0.3325 24 P 0 ;1
L 1.8325 0.3825 1.8325 0.3825 24 P 0 ;1
L 1.8325 0.4325 1.8325 0.4325 24 P 0 ;1
L 1.8325 0.4825 1.8325 0.4825 24 P 0 ;1
L 1.8325 0.5325 1.8325 0.5325 24 P 0 ;1
L 1.8325 0.5825 1.8325 0.5825 24 P 0 ;1
L 1.8325 0.6325 1.8325 0.6325 24 P 0 ;1
L 1.8325 0.6825 1.8325 0.6825 24 P 0 ;1
L 1.8325 0.7325 1.8325 0.7325 24 P 0 ;1
L 1.8325 0.7825 1.8325 0.7825 24 P 0 ;1
L 1.8325 0.8325 1.8325 0.8325 24 P 0 ;1
L 1.8325 0.8825 1.8325 0.8825 24 P 0 ;1
L 1.8325 1.1825 1.8325 1.1825 24 P 0 ;1
L 1.8325 1.2325 1.8325 1.2325 24 P 0 ;1
L 1.8325 1.2825 1.8325 1.2825 24 P 0 ;1
L 1.8325 1.3325 1.8325 1.3325 24 P 0 ;1
L 1.8325 1.3825 1.8325 1.3825 24 P 0 ;1
L 1.8325 1.4325 1.8325 1.4325 24 P 0 ;1
L 1.8325 1.4825 1.8325 1.4825 24 P 0 ;1
L 1.8325 1.5325 1.8325 1.5325 24 P 0 ;1
L 1.8325 1.5825 1.8325 1.5825 24 P 0 ;1
L 1.8325 1.6325 1.8325 1.6325 24 P 0 ;1
L 1.8325 1.6825 1.8325 1.6825 24 P 0 ;1
L 1.8325 1.7325 1.8325 1.7325 24 P 0 ;1
L 1.8325 1.7825 1.8325 1.7825 24 P 0 ;1
L 1.8325 1.8325 1.8325 1.8325 24 P 0 ;1
L 1.8325 1.8825 1.8325 1.8825 24 P 0 ;1
L 1.8325 1.9325 1.8325 1.9325 24 P 0 ;1
L 1.8325 1.9825 1.8325 1.9825 24 P 0 ;1
L 1.8325 2.0325 1.8325 2.0325 24 P 0 ;1
L 1.8325 2.0825 1.8325 2.0825 24 P 0 ;1
L 1.8325 2.1325 1.8325 2.1325 24 P 0 ;1
L 1.8325 2.1825 1.8325 2.1825 24 P 0 ;1
L 1.8325 2.2325 1.8325 2.2325 24 P 0 ;1
L 1.8325 2.2825 1.8325 2.2825 24 P 0 ;1
L 1.8325 2.3325 1.8325 2.3325 24 P 0 ;1
L 1.8325 2.3825 1.8325 2.3825 24 P 0 ;1
L 1.8325 2.5825 1.8325 2.5825 24 P 0 ;1
L 1.8325 2.6325 1.8325 2.6325 24 P 0 ;1
L 1.8325 2.6825 1.8325 2.6825 24 P 0 ;1
L 1.8325 2.7325 1.8325 2.7325 24 P 0 ;1
L 1.8325 2.7825 1.8325 2.7825 24 P 0 ;1
L 1.8325 2.8325 1.8325 2.8325 24 P 0 ;1
L 1.8325 2.8825 1.8325 2.8825 24 P 0 ;1
L 1.8325 2.9325 1.8325 2.9325 24 P 0 ;1
L 1.8325 2.9825 1.8325 2.9825 24 P 0 ;1
L 1.8325 3.0325 1.8325 3.0325 24 P 0 ;1
L 1.8325 3.0825 1.8325 3.0825 24 P 0 ;1
L 1.8325 3.1325 1.8325 3.1325 24 P 0 ;1
L 1.8325 3.1825 1.8325 3.1825 24 P 0 ;1
L 1.8325 3.2325 1.8325 3.2325 24 P 0 ;1
L 1.8325 3.2825 1.8325 3.2825 24 P 0 ;1
L 1.8325 3.3325 1.8325 3.3325 24 P 0 ;1
L 1.8325 3.3825 1.8325 3.3825 24 P 0 ;1
L 1.8325 4.2825 1.8325 4.2825 24 P 0 ;1
L 1.8325 5.2825 1.8325 5.2825 24 P 0 ;1
L 1.8825 0.1325 1.8825 0.1325 24 P 0 ;1
L 1.8825 0.1825 1.8825 0.1825 24 P 0 ;1
L 1.8825 0.2325 1.8825 0.2325 24 P 0 ;1
L 1.8825 0.2825 1.8825 0.2825 24 P 0 ;1
L 1.8825 0.3325 1.8825 0.3325 24 P 0 ;1
L 1.8825 0.3825 1.8825 0.3825 24 P 0 ;1
L 1.8825 0.4325 1.8825 0.4325 24 P 0 ;1
L 1.8825 0.4825 1.8825 0.4825 24 P 0 ;1
L 1.8825 0.5325 1.8825 0.5325 24 P 0 ;1
L 1.8825 0.5825 1.8825 0.5825 24 P 0 ;1
L 1.8825 0.6325 1.8825 0.6325 24 P 0 ;1
L 1.8825 0.6825 1.8825 0.6825 24 P 0 ;1
L 1.8825 0.7325 1.8825 0.7325 24 P 0 ;1
L 1.8825 0.7825 1.8825 0.7825 24 P 0 ;1
L 1.8825 0.8325 1.8825 0.8325 24 P 0 ;1
L 1.8825 1.1325 1.8825 1.1325 24 P 0 ;1
L 1.8825 1.1825 1.8825 1.1825 24 P 0 ;1
L 1.8825 1.2325 1.8825 1.2325 24 P 0 ;1
L 1.8825 1.2825 1.8825 1.2825 24 P 0 ;1
L 1.8825 1.3325 1.8825 1.3325 24 P 0 ;1
L 1.8825 1.3825 1.8825 1.3825 24 P 0 ;1
L 1.8825 1.4325 1.8825 1.4325 24 P 0 ;1
L 1.8825 1.4825 1.8825 1.4825 24 P 0 ;1
L 1.8825 1.5325 1.8825 1.5325 24 P 0 ;1
L 1.8825 1.5825 1.8825 1.5825 24 P 0 ;1
L 1.8825 1.6325 1.8825 1.6325 24 P 0 ;1
L 1.8825 1.6825 1.8825 1.6825 24 P 0 ;1
L 1.8825 1.7325 1.8825 1.7325 24 P 0 ;1
L 1.8825 1.7825 1.8825 1.7825 24 P 0 ;1
L 1.8825 1.8325 1.8825 1.8325 24 P 0 ;1
L 1.8825 1.8825 1.8825 1.8825 24 P 0 ;1
L 1.8825 1.9325 1.8825 1.9325 24 P 0 ;1
L 1.8825 1.9825 1.8825 1.9825 24 P 0 ;1
L 1.8825 2.0325 1.8825 2.0325 24 P 0 ;1
L 1.8825 2.0825 1.8825 2.0825 24 P 0 ;1
L 1.8825 2.1325 1.8825 2.1325 24 P 0 ;1
L 1.8825 2.1825 1.8825 2.1825 24 P 0 ;1
L 1.8825 2.2325 1.8825 2.2325 24 P 0 ;1
L 1.8825 2.2825 1.8825 2.2825 24 P 0 ;1
L 1.8825 2.3325 1.8825 2.3325 24 P 0 ;1
L 1.8825 2.3825 1.8825 2.3825 24 P 0 ;1
L 1.8825 2.5825 1.8825 2.5825 24 P 0 ;1
L 1.8825 2.6325 1.8825 2.6325 24 P 0 ;1
L 1.8825 2.6825 1.8825 2.6825 24 P 0 ;1
L 1.8825 2.7325 1.8825 2.7325 24 P 0 ;1
L 1.8825 2.7825 1.8825 2.7825 24 P 0 ;1
L 1.8825 2.8325 1.8825 2.8325 24 P 0 ;1
L 1.8825 2.8825 1.8825 2.8825 24 P 0 ;1
L 1.8825 2.9325 1.8825 2.9325 24 P 0 ;1
L 1.8825 2.9825 1.8825 2.9825 24 P 0 ;1
L 1.8825 3.0325 1.8825 3.0325 24 P 0 ;1
L 1.8825 3.0825 1.8825 3.0825 24 P 0 ;1
L 1.8825 3.1325 1.8825 3.1325 24 P 0 ;1
L 1.8825 3.1825 1.8825 3.1825 24 P 0 ;1
L 1.8825 3.2325 1.8825 3.2325 24 P 0 ;1
L 1.8825 3.2825 1.8825 3.2825 24 P 0 ;1
L 1.8825 3.3325 1.8825 3.3325 24 P 0 ;1
L 1.9325 0.1325 1.9325 0.1325 24 P 0 ;1
L 1.9325 0.1825 1.9325 0.1825 24 P 0 ;1
L 1.9325 0.2325 1.9325 0.2325 24 P 0 ;1
L 1.9325 0.2825 1.9325 0.2825 24 P 0 ;1
L 1.9325 0.3325 1.9325 0.3325 24 P 0 ;1
L 1.9325 0.3825 1.9325 0.3825 24 P 0 ;1
L 1.9325 0.4325 1.9325 0.4325 24 P 0 ;1
L 1.9325 0.4825 1.9325 0.4825 24 P 0 ;1
L 1.9325 0.5325 1.9325 0.5325 24 P 0 ;1
L 1.9325 0.5825 1.9325 0.5825 24 P 0 ;1
L 1.9325 0.6325 1.9325 0.6325 24 P 0 ;1
L 1.9325 0.6825 1.9325 0.6825 24 P 0 ;1
L 1.9325 0.7325 1.9325 0.7325 24 P 0 ;1
L 1.9325 0.7825 1.9325 0.7825 24 P 0 ;1
L 1.9325 1.0825 1.9325 1.0825 24 P 0 ;1
L 1.9325 1.1325 1.9325 1.1325 24 P 0 ;1
L 1.9325 1.1825 1.9325 1.1825 24 P 0 ;1
L 1.9325 1.2325 1.9325 1.2325 24 P 0 ;1
L 1.9325 1.2825 1.9325 1.2825 24 P 0 ;1
L 1.9325 1.3325 1.9325 1.3325 24 P 0 ;1
L 1.9325 1.3825 1.9325 1.3825 24 P 0 ;1
L 1.9325 1.4325 1.9325 1.4325 24 P 0 ;1
L 1.9325 1.4825 1.9325 1.4825 24 P 0 ;1
L 1.9325 1.5325 1.9325 1.5325 24 P 0 ;1
L 1.9325 1.5825 1.9325 1.5825 24 P 0 ;1
L 1.9325 1.6325 1.9325 1.6325 24 P 0 ;1
L 1.9325 1.6825 1.9325 1.6825 24 P 0 ;1
L 1.9325 1.7325 1.9325 1.7325 24 P 0 ;1
L 1.9325 1.7825 1.9325 1.7825 24 P 0 ;1
L 1.9325 1.8325 1.9325 1.8325 24 P 0 ;1
L 1.9325 1.8825 1.9325 1.8825 24 P 0 ;1
L 1.9325 1.9325 1.9325 1.9325 24 P 0 ;1
L 1.9325 1.9825 1.9325 1.9825 24 P 0 ;1
L 1.9325 2.0325 1.9325 2.0325 24 P 0 ;1
L 1.9325 2.0825 1.9325 2.0825 24 P 0 ;1
L 1.9325 2.1325 1.9325 2.1325 24 P 0 ;1
L 1.9325 2.1825 1.9325 2.1825 24 P 0 ;1
L 1.9325 2.2325 1.9325 2.2325 24 P 0 ;1
L 1.9325 2.2825 1.9325 2.2825 24 P 0 ;1
L 1.9325 2.3325 1.9325 2.3325 24 P 0 ;1
L 1.9325 2.3825 1.9325 2.3825 24 P 0 ;1
L 1.9325 2.5825 1.9325 2.5825 24 P 0 ;1
L 1.9325 2.6325 1.9325 2.6325 24 P 0 ;1
L 1.9325 2.9825 1.9325 2.9825 24 P 0 ;1
L 1.9325 3.0325 1.9325 3.0325 24 P 0 ;1
L 1.9325 3.0825 1.9325 3.0825 24 P 0 ;1
L 1.9325 3.1325 1.9325 3.1325 24 P 0 ;1
L 1.9325 3.1825 1.9325 3.1825 24 P 0 ;1
L 1.9325 3.2325 1.9325 3.2325 24 P 0 ;1
L 1.9325 3.2825 1.9325 3.2825 24 P 0 ;1
L 1.9325 3.7325 1.9325 3.7325 24 P 0 ;1
L 1.9325 3.7825 1.9325 3.7825 24 P 0 ;1
L 1.9325 3.8325 1.9325 3.8325 24 P 0 ;1
L 1.9325 3.8825 1.9325 3.8825 24 P 0 ;1
L 1.9325 3.9325 1.9325 3.9325 24 P 0 ;1
L 1.9325 3.9825 1.9325 3.9825 24 P 0 ;1
L 1.9325 4.0325 1.9325 4.0325 24 P 0 ;1
L 1.9325 4.0825 1.9325 4.0825 24 P 0 ;1
L 1.9825 0.1325 1.9825 0.1325 24 P 0 ;1
L 1.9825 0.1825 1.9825 0.1825 24 P 0 ;1
L 1.9825 0.2325 1.9825 0.2325 24 P 0 ;1
L 1.9825 0.2825 1.9825 0.2825 24 P 0 ;1
L 1.9825 0.3325 1.9825 0.3325 24 P 0 ;1
L 1.9825 0.3825 1.9825 0.3825 24 P 0 ;1
L 1.9825 0.4325 1.9825 0.4325 24 P 0 ;1
L 1.9825 0.4825 1.9825 0.4825 24 P 0 ;1
L 1.9825 0.5325 1.9825 0.5325 24 P 0 ;1
L 1.9825 0.5825 1.9825 0.5825 24 P 0 ;1
L 1.9825 0.6325 1.9825 0.6325 24 P 0 ;1
L 1.9825 0.6825 1.9825 0.6825 24 P 0 ;1
L 1.9825 0.7325 1.9825 0.7325 24 P 0 ;1
L 1.9825 1.0325 1.9825 1.0325 24 P 0 ;1
L 1.9825 1.0825 1.9825 1.0825 24 P 0 ;1
L 1.9825 1.1325 1.9825 1.1325 24 P 0 ;1
L 1.9825 1.1825 1.9825 1.1825 24 P 0 ;1
L 1.9825 1.2325 1.9825 1.2325 24 P 0 ;1
L 1.9825 1.2825 1.9825 1.2825 24 P 0 ;1
L 1.9825 1.3325 1.9825 1.3325 24 P 0 ;1
L 1.9825 1.3825 1.9825 1.3825 24 P 0 ;1
L 1.9825 1.4325 1.9825 1.4325 24 P 0 ;1
L 1.9825 1.4825 1.9825 1.4825 24 P 0 ;1
L 1.9825 1.5325 1.9825 1.5325 24 P 0 ;1
L 1.9825 1.5825 1.9825 1.5825 24 P 0 ;1
L 1.9825 1.6325 1.9825 1.6325 24 P 0 ;1
L 1.9825 1.6825 1.9825 1.6825 24 P 0 ;1
L 1.9825 1.7325 1.9825 1.7325 24 P 0 ;1
L 1.9825 1.7825 1.9825 1.7825 24 P 0 ;1
L 1.9825 3.9825 1.9825 3.9825 24 P 0 ;1
L 1.9825 4.0325 1.9825 4.0325 24 P 0 ;1
L 1.9825 4.0825 1.9825 4.0825 24 P 0 ;1
L 1.9825 4.1325 1.9825 4.1325 24 P 0 ;1
L 2.0325 0.1325 2.0325 0.1325 24 P 0 ;1
L 2.0325 0.1825 2.0325 0.1825 24 P 0 ;1
L 2.0325 0.2325 2.0325 0.2325 24 P 0 ;1
L 2.0325 0.2825 2.0325 0.2825 24 P 0 ;1
L 2.0325 0.3325 2.0325 0.3325 24 P 0 ;1
L 2.0325 0.3825 2.0325 0.3825 24 P 0 ;1
L 2.0325 0.4325 2.0325 0.4325 24 P 0 ;1
L 2.0325 0.4825 2.0325 0.4825 24 P 0 ;1
L 2.0325 0.5325 2.0325 0.5325 24 P 0 ;1
L 2.0325 0.5825 2.0325 0.5825 24 P 0 ;1
L 2.0325 0.6325 2.0325 0.6325 24 P 0 ;1
L 2.0325 0.6825 2.0325 0.6825 24 P 0 ;1
L 2.0325 0.9825 2.0325 0.9825 24 P 0 ;1
L 2.0325 1.0325 2.0325 1.0325 24 P 0 ;1
L 2.0325 1.0825 2.0325 1.0825 24 P 0 ;1
L 2.0325 1.1325 2.0325 1.1325 24 P 0 ;1
L 2.0325 1.1825 2.0325 1.1825 24 P 0 ;1
L 2.0325 1.2325 2.0325 1.2325 24 P 0 ;1
L 2.0325 1.2825 2.0325 1.2825 24 P 0 ;1
L 2.0325 1.3325 2.0325 1.3325 24 P 0 ;1
L 2.0325 1.3825 2.0325 1.3825 24 P 0 ;1
L 2.0325 1.6325 2.0325 1.6325 24 P 0 ;1
L 2.0325 1.6825 2.0325 1.6825 24 P 0 ;1
L 2.0325 1.7325 2.0325 1.7325 24 P 0 ;1
L 2.0325 3.9825 2.0325 3.9825 24 P 0 ;1
L 2.0325 4.0325 2.0325 4.0325 24 P 0 ;1
L 2.0325 4.0825 2.0325 4.0825 24 P 0 ;1
L 2.0825 0.1325 2.0825 0.1325 24 P 0 ;1
L 2.0825 0.1825 2.0825 0.1825 24 P 0 ;1
L 2.0825 0.2325 2.0825 0.2325 24 P 0 ;1
L 2.0825 0.2825 2.0825 0.2825 24 P 0 ;1
L 2.0825 0.3325 2.0825 0.3325 24 P 0 ;1
L 2.0825 0.3825 2.0825 0.3825 24 P 0 ;1
L 2.0825 0.4325 2.0825 0.4325 24 P 0 ;1
L 2.0825 0.4825 2.0825 0.4825 24 P 0 ;1
L 2.0825 0.5325 2.0825 0.5325 24 P 0 ;1
L 2.0825 0.5825 2.0825 0.5825 24 P 0 ;1
L 2.0825 0.6325 2.0825 0.6325 24 P 0 ;1
L 2.0825 0.9325 2.0825 0.9325 24 P 0 ;1
L 2.0825 0.9825 2.0825 0.9825 24 P 0 ;1
L 2.0825 1.0325 2.0825 1.0325 24 P 0 ;1
L 2.0825 1.0825 2.0825 1.0825 24 P 0 ;1
L 2.0825 1.1325 2.0825 1.1325 24 P 0 ;1
L 2.0825 1.1825 2.0825 1.1825 24 P 0 ;1
L 2.0825 1.2325 2.0825 1.2325 24 P 0 ;1
L 2.0825 1.2825 2.0825 1.2825 24 P 0 ;1
L 2.0825 1.7325 2.0825 1.7325 24 P 0 ;1
L 2.0825 3.9825 2.0825 3.9825 24 P 0 ;1
L 2.0825 4.0325 2.0825 4.0325 24 P 0 ;1
L 2.1325 0.1325 2.1325 0.1325 24 P 0 ;1
L 2.1325 0.1825 2.1325 0.1825 24 P 0 ;1
L 2.1325 0.2325 2.1325 0.2325 24 P 0 ;1
L 2.1325 0.2825 2.1325 0.2825 24 P 0 ;1
L 2.1325 0.3325 2.1325 0.3325 24 P 0 ;1
L 2.1325 0.3825 2.1325 0.3825 24 P 0 ;1
L 2.1325 0.4325 2.1325 0.4325 24 P 0 ;1
L 2.1325 0.4825 2.1325 0.4825 24 P 0 ;1
L 2.1325 0.5325 2.1325 0.5325 24 P 0 ;1
L 2.1325 0.5825 2.1325 0.5825 24 P 0 ;1
L 2.1325 0.8825 2.1325 0.8825 24 P 0 ;1
L 2.1325 0.9325 2.1325 0.9325 24 P 0 ;1
L 2.1325 0.9825 2.1325 0.9825 24 P 0 ;1
L 2.1325 1.0325 2.1325 1.0325 24 P 0 ;1
L 2.1325 1.0825 2.1325 1.0825 24 P 0 ;1
L 2.1325 1.1325 2.1325 1.1325 24 P 0 ;1
L 2.1325 1.1825 2.1325 1.1825 24 P 0 ;1
L 2.1325 1.2325 2.1325 1.2325 24 P 0 ;1
L 2.1325 1.2825 2.1325 1.2825 24 P 0 ;1
L 2.1325 1.7325 2.1325 1.7325 24 P 0 ;1
L 2.1325 3.9825 2.1325 3.9825 24 P 0 ;1
L 2.1825 0.1325 2.1825 0.1325 24 P 0 ;1
L 2.1825 0.1825 2.1825 0.1825 24 P 0 ;1
L 2.1825 0.2325 2.1825 0.2325 24 P 0 ;1
L 2.1825 0.2825 2.1825 0.2825 24 P 0 ;1
L 2.1825 0.3325 2.1825 0.3325 24 P 0 ;1
L 2.1825 0.3825 2.1825 0.3825 24 P 0 ;1
L 2.1825 0.4325 2.1825 0.4325 24 P 0 ;1
L 2.1825 0.4825 2.1825 0.4825 24 P 0 ;1
L 2.1825 0.5325 2.1825 0.5325 24 P 0 ;1
L 2.1825 0.8325 2.1825 0.8325 24 P 0 ;1
L 2.1825 0.8825 2.1825 0.8825 24 P 0 ;1
L 2.1825 0.9325 2.1825 0.9325 24 P 0 ;1
L 2.1825 0.9825 2.1825 0.9825 24 P 0 ;1
L 2.1825 1.0325 2.1825 1.0325 24 P 0 ;1
L 2.1825 1.0825 2.1825 1.0825 24 P 0 ;1
L 2.1825 1.1325 2.1825 1.1325 24 P 0 ;1
L 2.1825 1.1825 2.1825 1.1825 24 P 0 ;1
L 2.1825 1.2325 2.1825 1.2325 24 P 0 ;1
L 2.1825 3.9825 2.1825 3.9825 24 P 0 ;1
L 2.2325 0.1325 2.2325 0.1325 24 P 0 ;1
L 2.2325 0.1825 2.2325 0.1825 24 P 0 ;1
L 2.2325 0.2325 2.2325 0.2325 24 P 0 ;1
L 2.2325 0.2825 2.2325 0.2825 24 P 0 ;1
L 2.2325 0.3325 2.2325 0.3325 24 P 0 ;1
L 2.2325 0.3825 2.2325 0.3825 24 P 0 ;1
L 2.2325 0.4325 2.2325 0.4325 24 P 0 ;1
L 2.2325 0.4825 2.2325 0.4825 24 P 0 ;1
L 2.2325 0.7825 2.2325 0.7825 24 P 0 ;1
L 2.2325 0.8325 2.2325 0.8325 24 P 0 ;1
L 2.2325 0.8825 2.2325 0.8825 24 P 0 ;1
L 2.2325 0.9325 2.2325 0.9325 24 P 0 ;1
L 2.2325 0.9825 2.2325 0.9825 24 P 0 ;1
L 2.2325 1.0325 2.2325 1.0325 24 P 0 ;1
L 2.2325 1.0825 2.2325 1.0825 24 P 0 ;1
L 2.2325 1.1325 2.2325 1.1325 24 P 0 ;1
L 2.2325 1.1825 2.2325 1.1825 24 P 0 ;1
L 2.2325 1.2325 2.2325 1.2325 24 P 0 ;1
L 2.2325 3.9825 2.2325 3.9825 24 P 0 ;1
L 2.2325 5.1825 2.2325 5.1825 24 P 0 ;1
L 2.2325 5.2325 2.2325 5.2325 24 P 0 ;1
L 2.2325 5.2825 2.2325 5.2825 24 P 0 ;1
L 2.2825 0.1325 2.2825 0.1325 24 P 0 ;1
L 2.2825 0.1825 2.2825 0.1825 24 P 0 ;1
L 2.2825 0.2325 2.2825 0.2325 24 P 0 ;1
L 2.2825 0.2825 2.2825 0.2825 24 P 0 ;1
L 2.2825 0.3325 2.2825 0.3325 24 P 0 ;1
L 2.2825 0.3825 2.2825 0.3825 24 P 0 ;1
L 2.2825 0.4325 2.2825 0.4325 24 P 0 ;1
L 2.2825 0.7325 2.2825 0.7325 24 P 0 ;1
L 2.2825 0.7825 2.2825 0.7825 24 P 0 ;1
L 2.2825 0.8325 2.2825 0.8325 24 P 0 ;1
L 2.2825 0.8825 2.2825 0.8825 24 P 0 ;1
L 2.2825 0.9325 2.2825 0.9325 24 P 0 ;1
L 2.2825 0.9825 2.2825 0.9825 24 P 0 ;1
L 2.2825 1.0325 2.2825 1.0325 24 P 0 ;1
L 2.2825 1.0825 2.2825 1.0825 24 P 0 ;1
L 2.2825 1.1325 2.2825 1.1325 24 P 0 ;1
L 2.2825 1.1825 2.2825 1.1825 24 P 0 ;1
L 2.2825 1.2325 2.2825 1.2325 24 P 0 ;1
L 2.2825 3.9825 2.2825 3.9825 24 P 0 ;1
L 2.2825 5.2325 2.2825 5.2325 24 P 0 ;1
L 2.2825 5.2825 2.2825 5.2825 24 P 0 ;1
L 2.3325 0.1325 2.3325 0.1325 24 P 0 ;1
L 2.3325 0.1825 2.3325 0.1825 24 P 0 ;1
L 2.3325 0.2325 2.3325 0.2325 24 P 0 ;1
L 2.3325 0.2825 2.3325 0.2825 24 P 0 ;1
L 2.3325 0.3325 2.3325 0.3325 24 P 0 ;1
L 2.3325 0.3825 2.3325 0.3825 24 P 0 ;1
L 2.3325 0.6825 2.3325 0.6825 24 P 0 ;1
L 2.3325 0.7325 2.3325 0.7325 24 P 0 ;1
L 2.3325 0.7825 2.3325 0.7825 24 P 0 ;1
L 2.3325 0.8325 2.3325 0.8325 24 P 0 ;1
L 2.3325 0.8825 2.3325 0.8825 24 P 0 ;1
L 2.3325 0.9325 2.3325 0.9325 24 P 0 ;1
L 2.3325 0.9825 2.3325 0.9825 24 P 0 ;1
L 2.3325 1.0325 2.3325 1.0325 24 P 0 ;1
L 2.3325 1.0825 2.3325 1.0825 24 P 0 ;1
L 2.3325 1.1325 2.3325 1.1325 24 P 0 ;1
L 2.3325 1.1825 2.3325 1.1825 24 P 0 ;1
L 2.3325 1.2325 2.3325 1.2325 24 P 0 ;1
L 2.3325 3.9825 2.3325 3.9825 24 P 0 ;1
L 2.3325 5.2825 2.3325 5.2825 24 P 0 ;1
L 2.3825 0.1325 2.3825 0.1325 24 P 0 ;1
L 2.3825 0.1825 2.3825 0.1825 24 P 0 ;1
L 2.3825 0.2325 2.3825 0.2325 24 P 0 ;1
L 2.3825 0.2825 2.3825 0.2825 24 P 0 ;1
L 2.3825 0.3325 2.3825 0.3325 24 P 0 ;1
L 2.3825 0.6325 2.3825 0.6325 24 P 0 ;1
L 2.3825 0.6825 2.3825 0.6825 24 P 0 ;1
L 2.3825 0.7325 2.3825 0.7325 24 P 0 ;1
L 2.3825 0.7825 2.3825 0.7825 24 P 0 ;1
L 2.3825 0.8325 2.3825 0.8325 24 P 0 ;1
L 2.3825 0.8825 2.3825 0.8825 24 P 0 ;1
L 2.3825 0.9325 2.3825 0.9325 24 P 0 ;1
L 2.3825 0.9825 2.3825 0.9825 24 P 0 ;1
L 2.3825 1.0325 2.3825 1.0325 24 P 0 ;1
L 2.3825 1.0825 2.3825 1.0825 24 P 0 ;1
L 2.3825 1.1325 2.3825 1.1325 24 P 0 ;1
L 2.3825 1.1825 2.3825 1.1825 24 P 0 ;1
L 2.3825 1.2325 2.3825 1.2325 24 P 0 ;1
L 2.3825 1.2825 2.3825 1.2825 24 P 0 ;1
L 2.3825 1.7325 2.3825 1.7325 24 P 0 ;1
L 2.3825 3.9825 2.3825 3.9825 24 P 0 ;1
L 2.3825 5.2825 2.3825 5.2825 24 P 0 ;1
L 2.4325 0.1325 2.4325 0.1325 24 P 0 ;1
L 2.4325 0.1825 2.4325 0.1825 24 P 0 ;1
L 2.4325 0.2325 2.4325 0.2325 24 P 0 ;1
L 2.4325 0.2825 2.4325 0.2825 24 P 0 ;1
L 2.4325 0.5825 2.4325 0.5825 24 P 0 ;1
L 2.4325 0.6325 2.4325 0.6325 24 P 0 ;1
L 2.4325 0.6825 2.4325 0.6825 24 P 0 ;1
L 2.4325 0.7325 2.4325 0.7325 24 P 0 ;1
L 2.4325 0.7825 2.4325 0.7825 24 P 0 ;1
L 2.4325 0.8325 2.4325 0.8325 24 P 0 ;1
L 2.4325 0.8825 2.4325 0.8825 24 P 0 ;1
L 2.4325 0.9325 2.4325 0.9325 24 P 0 ;1
L 2.4325 0.9825 2.4325 0.9825 24 P 0 ;1
L 2.4325 1.0325 2.4325 1.0325 24 P 0 ;1
L 2.4325 1.0825 2.4325 1.0825 24 P 0 ;1
L 2.4325 1.1325 2.4325 1.1325 24 P 0 ;1
L 2.4325 1.1825 2.4325 1.1825 24 P 0 ;1
L 2.4325 1.2325 2.4325 1.2325 24 P 0 ;1
L 2.4325 1.2825 2.4325 1.2825 24 P 0 ;1
L 2.4325 1.3325 2.4325 1.3325 24 P 0 ;1
L 2.4325 1.6825 2.4325 1.6825 24 P 0 ;1
L 2.4325 1.7325 2.4325 1.7325 24 P 0 ;1
L 2.4325 3.9825 2.4325 3.9825 24 P 0 ;1
L 2.4325 4.0325 2.4325 4.0325 24 P 0 ;1
L 2.4325 5.2825 2.4325 5.2825 24 P 0 ;1
L 2.4825 0.1325 2.4825 0.1325 24 P 0 ;1
L 2.4825 0.1825 2.4825 0.1825 24 P 0 ;1
L 2.4825 0.2325 2.4825 0.2325 24 P 0 ;1
L 2.4825 0.5325 2.4825 0.5325 24 P 0 ;1
L 2.4825 0.5825 2.4825 0.5825 24 P 0 ;1
L 2.4825 0.6325 2.4825 0.6325 24 P 0 ;1
L 2.4825 0.6825 2.4825 0.6825 24 P 0 ;1
L 2.4825 0.7325 2.4825 0.7325 24 P 0 ;1
L 2.4825 0.7825 2.4825 0.7825 24 P 0 ;1
L 2.4825 0.8325 2.4825 0.8325 24 P 0 ;1
L 2.4825 0.8825 2.4825 0.8825 24 P 0 ;1
L 2.4825 0.9325 2.4825 0.9325 24 P 0 ;1
L 2.4825 0.9825 2.4825 0.9825 24 P 0 ;1
L 2.4825 1.0325 2.4825 1.0325 24 P 0 ;1
L 2.4825 1.0825 2.4825 1.0825 24 P 0 ;1
L 2.4825 1.1325 2.4825 1.1325 24 P 0 ;1
L 2.4825 1.1825 2.4825 1.1825 24 P 0 ;1
L 2.4825 1.2325 2.4825 1.2325 24 P 0 ;1
L 2.4825 1.2825 2.4825 1.2825 24 P 0 ;1
L 2.4825 1.3325 2.4825 1.3325 24 P 0 ;1
L 2.4825 1.3825 2.4825 1.3825 24 P 0 ;1
L 2.4825 1.4325 2.4825 1.4325 24 P 0 ;1
L 2.4825 1.5825 2.4825 1.5825 24 P 0 ;1
L 2.4825 1.6325 2.4825 1.6325 24 P 0 ;1
L 2.4825 1.6825 2.4825 1.6825 24 P 0 ;1
L 2.4825 1.7325 2.4825 1.7325 24 P 0 ;1
L 2.4825 3.9825 2.4825 3.9825 24 P 0 ;1
L 2.4825 4.0325 2.4825 4.0325 24 P 0 ;1
L 2.4825 4.0825 2.4825 4.0825 24 P 0 ;1
L 2.4825 4.1325 2.4825 4.1325 24 P 0 ;1
L 2.4825 4.2825 2.4825 4.2825 24 P 0 ;1
L 2.4825 4.3325 2.4825 4.3325 24 P 0 ;1
L 2.4825 5.2325 2.4825 5.2325 24 P 0 ;1
L 2.4825 5.2825 2.4825 5.2825 24 P 0 ;1
L 2.5325 0.1325 2.5325 0.1325 24 P 0 ;1
L 2.5325 0.1825 2.5325 0.1825 24 P 0 ;1
L 2.5325 0.4825 2.5325 0.4825 24 P 0 ;1
L 2.5325 0.5325 2.5325 0.5325 24 P 0 ;1
L 2.5325 0.5825 2.5325 0.5825 24 P 0 ;1
L 2.5325 0.6325 2.5325 0.6325 24 P 0 ;1
L 2.5325 0.6825 2.5325 0.6825 24 P 0 ;1
L 2.5325 0.7325 2.5325 0.7325 24 P 0 ;1
L 2.5325 0.7825 2.5325 0.7825 24 P 0 ;1
L 2.5325 0.8325 2.5325 0.8325 24 P 0 ;1
L 2.5325 0.8825 2.5325 0.8825 24 P 0 ;1
L 2.5325 0.9325 2.5325 0.9325 24 P 0 ;1
L 2.5325 0.9825 2.5325 0.9825 24 P 0 ;1
L 2.5325 1.0325 2.5325 1.0325 24 P 0 ;1
L 2.5325 1.0825 2.5325 1.0825 24 P 0 ;1
L 2.5325 1.1325 2.5325 1.1325 24 P 0 ;1
L 2.5325 1.1825 2.5325 1.1825 24 P 0 ;1
L 2.5325 1.2325 2.5325 1.2325 24 P 0 ;1
L 2.5325 1.2825 2.5325 1.2825 24 P 0 ;1
L 2.5325 1.3325 2.5325 1.3325 24 P 0 ;1
L 2.5325 1.3825 2.5325 1.3825 24 P 0 ;1
L 2.5325 1.4325 2.5325 1.4325 24 P 0 ;1
L 2.5325 1.4825 2.5325 1.4825 24 P 0 ;1
L 2.5325 1.5325 2.5325 1.5325 24 P 0 ;1
L 2.5325 1.5825 2.5325 1.5825 24 P 0 ;1
L 2.5325 1.6325 2.5325 1.6325 24 P 0 ;1
L 2.5325 1.6825 2.5325 1.6825 24 P 0 ;1
L 2.5325 1.7325 2.5325 1.7325 24 P 0 ;1
L 2.5325 3.9825 2.5325 3.9825 24 P 0 ;1
L 2.5325 4.0325 2.5325 4.0325 24 P 0 ;1
L 2.5325 4.0825 2.5325 4.0825 24 P 0 ;1
L 2.5325 4.1325 2.5325 4.1325 24 P 0 ;1
L 2.5325 4.1825 2.5325 4.1825 24 P 0 ;1
L 2.5325 4.2325 2.5325 4.2325 24 P 0 ;1
L 2.5325 4.2825 2.5325 4.2825 24 P 0 ;1
L 2.5325 4.3325 2.5325 4.3325 24 P 0 ;1
L 2.5325 4.6825 2.5325 4.6825 24 P 0 ;1
L 2.5325 4.8825 2.5325 4.8825 24 P 0 ;1
L 2.5325 4.9325 2.5325 4.9325 24 P 0 ;1
L 2.5325 4.9825 2.5325 4.9825 24 P 0 ;1
L 2.5325 5.1325 2.5325 5.1325 24 P 0 ;1
L 2.5325 5.1825 2.5325 5.1825 24 P 0 ;1
L 2.5325 5.2325 2.5325 5.2325 24 P 0 ;1
L 2.5325 5.2825 2.5325 5.2825 24 P 0 ;1
L 2.5825 0.1325 2.5825 0.1325 24 P 0 ;1
L 2.5825 0.1825 2.5825 0.1825 24 P 0 ;1
L 2.5825 0.4325 2.5825 0.4325 24 P 0 ;1
L 2.5825 0.4825 2.5825 0.4825 24 P 0 ;1
L 2.5825 0.5325 2.5825 0.5325 24 P 0 ;1
L 2.5825 0.5825 2.5825 0.5825 24 P 0 ;1
L 2.5825 0.6325 2.5825 0.6325 24 P 0 ;1
L 2.5825 0.6825 2.5825 0.6825 24 P 0 ;1
L 2.5825 0.7325 2.5825 0.7325 24 P 0 ;1
L 2.5825 0.7825 2.5825 0.7825 24 P 0 ;1
L 2.5825 0.8325 2.5825 0.8325 24 P 0 ;1
L 2.5825 0.8825 2.5825 0.8825 24 P 0 ;1
L 2.5825 0.9325 2.5825 0.9325 24 P 0 ;1
L 2.5825 0.9825 2.5825 0.9825 24 P 0 ;1
L 2.5825 1.0325 2.5825 1.0325 24 P 0 ;1
L 2.5825 1.0825 2.5825 1.0825 24 P 0 ;1
L 2.5825 1.1325 2.5825 1.1325 24 P 0 ;1
L 2.5825 1.1825 2.5825 1.1825 24 P 0 ;1
L 2.5825 1.2325 2.5825 1.2325 24 P 0 ;1
L 2.5825 1.2825 2.5825 1.2825 24 P 0 ;1
L 2.5825 1.3325 2.5825 1.3325 24 P 0 ;1
L 2.5825 1.3825 2.5825 1.3825 24 P 0 ;1
L 2.5825 1.4325 2.5825 1.4325 24 P 0 ;1
L 2.5825 1.4825 2.5825 1.4825 24 P 0 ;1
L 2.5825 1.5325 2.5825 1.5325 24 P 0 ;1
L 2.5825 1.5825 2.5825 1.5825 24 P 0 ;1
L 2.5825 1.6325 2.5825 1.6325 24 P 0 ;1
L 2.5825 1.6825 2.5825 1.6825 24 P 0 ;1
L 2.5825 1.7325 2.5825 1.7325 24 P 0 ;1
L 2.5825 1.7825 2.5825 1.7825 24 P 0 ;1
L 2.5825 3.9325 2.5825 3.9325 24 P 0 ;1
L 2.5825 3.9825 2.5825 3.9825 24 P 0 ;1
L 2.5825 4.0325 2.5825 4.0325 24 P 0 ;1
L 2.5825 4.0825 2.5825 4.0825 24 P 0 ;1
L 2.5825 4.1325 2.5825 4.1325 24 P 0 ;1
L 2.5825 4.1825 2.5825 4.1825 24 P 0 ;1
L 2.5825 4.2325 2.5825 4.2325 24 P 0 ;1
L 2.5825 4.2825 2.5825 4.2825 24 P 0 ;1
L 2.5825 4.3325 2.5825 4.3325 24 P 0 ;1
L 2.5825 4.6825 2.5825 4.6825 24 P 0 ;1
L 2.5825 4.8325 2.5825 4.8325 24 P 0 ;1
L 2.5825 4.8825 2.5825 4.8825 24 P 0 ;1
L 2.5825 4.9325 2.5825 4.9325 24 P 0 ;1
L 2.5825 4.9825 2.5825 4.9825 24 P 0 ;1
L 2.5825 5.0325 2.5825 5.0325 24 P 0 ;1
L 2.5825 5.0825 2.5825 5.0825 24 P 0 ;1
L 2.5825 5.1325 2.5825 5.1325 24 P 0 ;1
L 2.5825 5.1825 2.5825 5.1825 24 P 0 ;1
L 2.5825 5.2325 2.5825 5.2325 24 P 0 ;1
L 2.5825 5.2825 2.5825 5.2825 24 P 0 ;1
L 2.6325 0.1325 2.6325 0.1325 24 P 0 ;1
L 2.6325 0.1825 2.6325 0.1825 24 P 0 ;1
L 2.6325 0.4325 2.6325 0.4325 24 P 0 ;1
L 2.6325 0.4825 2.6325 0.4825 24 P 0 ;1
L 2.6325 0.5325 2.6325 0.5325 24 P 0 ;1
L 2.6325 0.5825 2.6325 0.5825 24 P 0 ;1
L 2.6325 0.6325 2.6325 0.6325 24 P 0 ;1
L 2.6325 0.6825 2.6325 0.6825 24 P 0 ;1
L 2.6325 0.7325 2.6325 0.7325 24 P 0 ;1
L 2.6325 0.7825 2.6325 0.7825 24 P 0 ;1
L 2.6325 0.8325 2.6325 0.8325 24 P 0 ;1
L 2.6325 0.8825 2.6325 0.8825 24 P 0 ;1
L 2.6325 0.9325 2.6325 0.9325 24 P 0 ;1
L 2.6325 0.9825 2.6325 0.9825 24 P 0 ;1
L 2.6325 1.0325 2.6325 1.0325 24 P 0 ;1
L 2.6325 1.0825 2.6325 1.0825 24 P 0 ;1
L 2.6325 1.1325 2.6325 1.1325 24 P 0 ;1
L 2.6325 1.1825 2.6325 1.1825 24 P 0 ;1
L 2.6325 1.2325 2.6325 1.2325 24 P 0 ;1
L 2.6325 1.2825 2.6325 1.2825 24 P 0 ;1
L 2.6325 1.3325 2.6325 1.3325 24 P 0 ;1
L 2.6325 1.3825 2.6325 1.3825 24 P 0 ;1
L 2.6325 1.4325 2.6325 1.4325 24 P 0 ;1
L 2.6325 1.4825 2.6325 1.4825 24 P 0 ;1
L 2.6325 1.5325 2.6325 1.5325 24 P 0 ;1
L 2.6325 1.5825 2.6325 1.5825 24 P 0 ;1
L 2.6325 1.6325 2.6325 1.6325 24 P 0 ;1
L 2.6325 1.6825 2.6325 1.6825 24 P 0 ;1
L 2.6325 1.7325 2.6325 1.7325 24 P 0 ;1
L 2.6325 1.7825 2.6325 1.7825 24 P 0 ;1
L 2.6325 1.8325 2.6325 1.8325 24 P 0 ;1
L 2.6325 1.8825 2.6325 1.8825 24 P 0 ;1
L 2.6325 1.9325 2.6325 1.9325 24 P 0 ;1
L 2.6325 1.9825 2.6325 1.9825 24 P 0 ;1
L 2.6325 2.0325 2.6325 2.0325 24 P 0 ;1
L 2.6325 2.0825 2.6325 2.0825 24 P 0 ;1
L 2.6325 2.1325 2.6325 2.1325 24 P 0 ;1
L 2.6325 2.1825 2.6325 2.1825 24 P 0 ;1
L 2.6325 2.2325 2.6325 2.2325 24 P 0 ;1
L 2.6325 2.2825 2.6325 2.2825 24 P 0 ;1
L 2.6325 2.3325 2.6325 2.3325 24 P 0 ;1
L 2.6325 2.3825 2.6325 2.3825 24 P 0 ;1
L 2.6325 2.4325 2.6325 2.4325 24 P 0 ;1
L 2.6325 2.4825 2.6325 2.4825 24 P 0 ;1
L 2.6325 2.5325 2.6325 2.5325 24 P 0 ;1
L 2.6325 2.5825 2.6325 2.5825 24 P 0 ;1
L 2.6325 2.6325 2.6325 2.6325 24 P 0 ;1
L 2.6325 2.6825 2.6325 2.6825 24 P 0 ;1
L 2.6325 2.9825 2.6325 2.9825 24 P 0 ;1
L 2.6325 3.0325 2.6325 3.0325 24 P 0 ;1
L 2.6325 3.0825 2.6325 3.0825 24 P 0 ;1
L 2.6325 3.1325 2.6325 3.1325 24 P 0 ;1
L 2.6325 3.1825 2.6325 3.1825 24 P 0 ;1
L 2.6325 3.2325 2.6325 3.2325 24 P 0 ;1
L 2.6325 3.2825 2.6325 3.2825 24 P 0 ;1
L 2.6325 3.3325 2.6325 3.3325 24 P 0 ;1
L 2.6325 3.3825 2.6325 3.3825 24 P 0 ;1
L 2.6325 3.4325 2.6325 3.4325 24 P 0 ;1
L 2.6325 3.4825 2.6325 3.4825 24 P 0 ;1
L 2.6325 3.5325 2.6325 3.5325 24 P 0 ;1
L 2.6325 3.5825 2.6325 3.5825 24 P 0 ;1
L 2.6325 3.6325 2.6325 3.6325 24 P 0 ;1
L 2.6325 3.6825 2.6325 3.6825 24 P 0 ;1
L 2.6325 3.7325 2.6325 3.7325 24 P 0 ;1
L 2.6325 3.7825 2.6325 3.7825 24 P 0 ;1
L 2.6325 3.8325 2.6325 3.8325 24 P 0 ;1
L 2.6325 3.8825 2.6325 3.8825 24 P 0 ;1
L 2.6325 3.9325 2.6325 3.9325 24 P 0 ;1
L 2.6325 3.9825 2.6325 3.9825 24 P 0 ;1
L 2.6325 4.0325 2.6325 4.0325 24 P 0 ;1
L 2.6325 4.0825 2.6325 4.0825 24 P 0 ;1
L 2.6325 4.1325 2.6325 4.1325 24 P 0 ;1
L 2.6325 4.1825 2.6325 4.1825 24 P 0 ;1
L 2.6325 4.2325 2.6325 4.2325 24 P 0 ;1
L 2.6325 4.2825 2.6325 4.2825 24 P 0 ;1
L 2.6325 4.3325 2.6325 4.3325 24 P 0 ;1
L 2.6325 5.1825 2.6325 5.1825 24 P 0 ;1
L 2.6325 5.2325 2.6325 5.2325 24 P 0 ;1
L 2.6325 5.2825 2.6325 5.2825 24 P 0 ;1
L 2.6825 0.1325 2.6825 0.1325 24 P 0 ;1
L 2.6825 0.1825 2.6825 0.1825 24 P 0 ;1
L 2.6825 0.4325 2.6825 0.4325 24 P 0 ;1
L 2.6825 0.4825 2.6825 0.4825 24 P 0 ;1
L 2.6825 0.5325 2.6825 0.5325 24 P 0 ;1
L 2.6825 0.5825 2.6825 0.5825 24 P 0 ;1
L 2.6825 0.6325 2.6825 0.6325 24 P 0 ;1
L 2.6825 0.6825 2.6825 0.6825 24 P 0 ;1
L 2.6825 0.7325 2.6825 0.7325 24 P 0 ;1
L 2.6825 0.7825 2.6825 0.7825 24 P 0 ;1
L 2.6825 0.8325 2.6825 0.8325 24 P 0 ;1
L 2.6825 0.8825 2.6825 0.8825 24 P 0 ;1
L 2.6825 0.9325 2.6825 0.9325 24 P 0 ;1
L 2.6825 0.9825 2.6825 0.9825 24 P 0 ;1
L 2.6825 1.0325 2.6825 1.0325 24 P 0 ;1
L 2.6825 1.0825 2.6825 1.0825 24 P 0 ;1
L 2.6825 1.1325 2.6825 1.1325 24 P 0 ;1
L 2.6825 1.1825 2.6825 1.1825 24 P 0 ;1
L 2.6825 1.2325 2.6825 1.2325 24 P 0 ;1
L 2.6825 1.2825 2.6825 1.2825 24 P 0 ;1
L 2.6825 1.3325 2.6825 1.3325 24 P 0 ;1
L 2.6825 1.3825 2.6825 1.3825 24 P 0 ;1
L 2.6825 1.4325 2.6825 1.4325 24 P 0 ;1
L 2.6825 1.4825 2.6825 1.4825 24 P 0 ;1
L 2.6825 1.5325 2.6825 1.5325 24 P 0 ;1
L 2.6825 1.5825 2.6825 1.5825 24 P 0 ;1
L 2.6825 1.6325 2.6825 1.6325 24 P 0 ;1
L 2.6825 1.6825 2.6825 1.6825 24 P 0 ;1
L 2.6825 1.7325 2.6825 1.7325 24 P 0 ;1
L 2.6825 1.7825 2.6825 1.7825 24 P 0 ;1
L 2.6825 1.8325 2.6825 1.8325 24 P 0 ;1
L 2.6825 1.8825 2.6825 1.8825 24 P 0 ;1
L 2.6825 1.9325 2.6825 1.9325 24 P 0 ;1
L 2.6825 1.9825 2.6825 1.9825 24 P 0 ;1
L 2.6825 2.0325 2.6825 2.0325 24 P 0 ;1
L 2.6825 2.0825 2.6825 2.0825 24 P 0 ;1
L 2.6825 2.1325 2.6825 2.1325 24 P 0 ;1
L 2.6825 2.1825 2.6825 2.1825 24 P 0 ;1
L 2.6825 2.2325 2.6825 2.2325 24 P 0 ;1
L 2.6825 2.2825 2.6825 2.2825 24 P 0 ;1
L 2.6825 2.3325 2.6825 2.3325 24 P 0 ;1
L 2.6825 2.3825 2.6825 2.3825 24 P 0 ;1
L 2.6825 2.4325 2.6825 2.4325 24 P 0 ;1
L 2.6825 2.4825 2.6825 2.4825 24 P 0 ;1
L 2.6825 2.5325 2.6825 2.5325 24 P 0 ;1
L 2.6825 2.5825 2.6825 2.5825 24 P 0 ;1
L 2.6825 2.6325 2.6825 2.6325 24 P 0 ;1
L 2.6825 2.6825 2.6825 2.6825 24 P 0 ;1
L 2.6825 2.9825 2.6825 2.9825 24 P 0 ;1
L 2.6825 3.0325 2.6825 3.0325 24 P 0 ;1
L 2.6825 3.0825 2.6825 3.0825 24 P 0 ;1
L 2.6825 3.1325 2.6825 3.1325 24 P 0 ;1
L 2.6825 3.1825 2.6825 3.1825 24 P 0 ;1
L 2.6825 3.2325 2.6825 3.2325 24 P 0 ;1
L 2.6825 3.2825 2.6825 3.2825 24 P 0 ;1
L 2.6825 3.3325 2.6825 3.3325 24 P 0 ;1
L 2.6825 3.3825 2.6825 3.3825 24 P 0 ;1
L 2.6825 3.4325 2.6825 3.4325 24 P 0 ;1
L 2.6825 3.4825 2.6825 3.4825 24 P 0 ;1
L 2.6825 3.5325 2.6825 3.5325 24 P 0 ;1
L 2.6825 3.5825 2.6825 3.5825 24 P 0 ;1
L 2.6825 3.6325 2.6825 3.6325 24 P 0 ;1
L 2.6825 3.6825 2.6825 3.6825 24 P 0 ;1
L 2.6825 3.7325 2.6825 3.7325 24 P 0 ;1
L 2.6825 3.7825 2.6825 3.7825 24 P 0 ;1
L 2.6825 3.8325 2.6825 3.8325 24 P 0 ;1
L 2.6825 3.8825 2.6825 3.8825 24 P 0 ;1
L 2.6825 3.9325 2.6825 3.9325 24 P 0 ;1
L 2.6825 3.9825 2.6825 3.9825 24 P 0 ;1
L 2.6825 4.0325 2.6825 4.0325 24 P 0 ;1
L 2.6825 4.0825 2.6825 4.0825 24 P 0 ;1
L 2.6825 4.1325 2.6825 4.1325 24 P 0 ;1
L 2.6825 4.1825 2.6825 4.1825 24 P 0 ;1
L 2.6825 4.2325 2.6825 4.2325 24 P 0 ;1
L 2.6825 4.2825 2.6825 4.2825 24 P 0 ;1
L 2.6825 4.3325 2.6825 4.3325 24 P 0 ;1
L 2.6825 5.2825 2.6825 5.2825 24 P 0 ;1
L 2.7325 0.1325 2.7325 0.1325 24 P 0 ;1
L 2.7325 0.1825 2.7325 0.1825 24 P 0 ;1
L 2.7325 0.4325 2.7325 0.4325 24 P 0 ;1
L 2.7325 0.4825 2.7325 0.4825 24 P 0 ;1
L 2.7325 0.5325 2.7325 0.5325 24 P 0 ;1
L 2.7325 0.5825 2.7325 0.5825 24 P 0 ;1
L 2.7325 0.6325 2.7325 0.6325 24 P 0 ;1
L 2.7325 0.6825 2.7325 0.6825 24 P 0 ;1
L 2.7325 0.7325 2.7325 0.7325 24 P 0 ;1
L 2.7325 0.7825 2.7325 0.7825 24 P 0 ;1
L 2.7325 0.8325 2.7325 0.8325 24 P 0 ;1
L 2.7325 0.8825 2.7325 0.8825 24 P 0 ;1
L 2.7325 0.9325 2.7325 0.9325 24 P 0 ;1
L 2.7325 0.9825 2.7325 0.9825 24 P 0 ;1
L 2.7325 1.0325 2.7325 1.0325 24 P 0 ;1
L 2.7325 1.0825 2.7325 1.0825 24 P 0 ;1
L 2.7325 1.1325 2.7325 1.1325 24 P 0 ;1
L 2.7325 1.1825 2.7325 1.1825 24 P 0 ;1
L 2.7325 1.2325 2.7325 1.2325 24 P 0 ;1
L 2.7325 1.2825 2.7325 1.2825 24 P 0 ;1
L 2.7325 1.3325 2.7325 1.3325 24 P 0 ;1
L 2.7325 1.3825 2.7325 1.3825 24 P 0 ;1
L 2.7325 1.4325 2.7325 1.4325 24 P 0 ;1
L 2.7325 1.4825 2.7325 1.4825 24 P 0 ;1
L 2.7325 1.5325 2.7325 1.5325 24 P 0 ;1
L 2.7325 1.5825 2.7325 1.5825 24 P 0 ;1
L 2.7325 1.6325 2.7325 1.6325 24 P 0 ;1
L 2.7325 1.6825 2.7325 1.6825 24 P 0 ;1
L 2.7325 1.7325 2.7325 1.7325 24 P 0 ;1
L 2.7325 1.7825 2.7325 1.7825 24 P 0 ;1
L 2.7325 1.8325 2.7325 1.8325 24 P 0 ;1
L 2.7325 1.8825 2.7325 1.8825 24 P 0 ;1
L 2.7325 1.9325 2.7325 1.9325 24 P 0 ;1
L 2.7325 1.9825 2.7325 1.9825 24 P 0 ;1
L 2.7325 2.0325 2.7325 2.0325 24 P 0 ;1
L 2.7325 2.0825 2.7325 2.0825 24 P 0 ;1
L 2.7325 2.1325 2.7325 2.1325 24 P 0 ;1
L 2.7325 2.1825 2.7325 2.1825 24 P 0 ;1
L 2.7325 2.2325 2.7325 2.2325 24 P 0 ;1
L 2.7325 2.2825 2.7325 2.2825 24 P 0 ;1
L 2.7325 2.3325 2.7325 2.3325 24 P 0 ;1
L 2.7325 2.3825 2.7325 2.3825 24 P 0 ;1
L 2.7325 2.4325 2.7325 2.4325 24 P 0 ;1
L 2.7325 2.4825 2.7325 2.4825 24 P 0 ;1
L 2.7325 2.5325 2.7325 2.5325 24 P 0 ;1
L 2.7325 2.5825 2.7325 2.5825 24 P 0 ;1
L 2.7325 2.6325 2.7325 2.6325 24 P 0 ;1
L 2.7325 2.6825 2.7325 2.6825 24 P 0 ;1
L 2.7325 2.7325 2.7325 2.7325 24 P 0 ;1
L 2.7325 2.9825 2.7325 2.9825 24 P 0 ;1
L 2.7325 3.0325 2.7325 3.0325 24 P 0 ;1
L 2.7325 3.0825 2.7325 3.0825 24 P 0 ;1
L 2.7325 3.1325 2.7325 3.1325 24 P 0 ;1
L 2.7325 3.1825 2.7325 3.1825 24 P 0 ;1
L 2.7325 3.2325 2.7325 3.2325 24 P 0 ;1
L 2.7325 3.2825 2.7325 3.2825 24 P 0 ;1
L 2.7325 3.3325 2.7325 3.3325 24 P 0 ;1
L 2.7325 3.3825 2.7325 3.3825 24 P 0 ;1
L 2.7325 3.4325 2.7325 3.4325 24 P 0 ;1
L 2.7325 3.4825 2.7325 3.4825 24 P 0 ;1
L 2.7325 3.5325 2.7325 3.5325 24 P 0 ;1
L 2.7325 3.5825 2.7325 3.5825 24 P 0 ;1
L 2.7325 3.6325 2.7325 3.6325 24 P 0 ;1
L 2.7325 3.6825 2.7325 3.6825 24 P 0 ;1
L 2.7325 3.7325 2.7325 3.7325 24 P 0 ;1
L 2.7325 3.7825 2.7325 3.7825 24 P 0 ;1
L 2.7325 3.8325 2.7325 3.8325 24 P 0 ;1
L 2.7325 3.8825 2.7325 3.8825 24 P 0 ;1
L 2.7325 3.9325 2.7325 3.9325 24 P 0 ;1
L 2.7325 3.9825 2.7325 3.9825 24 P 0 ;1
L 2.7325 4.0325 2.7325 4.0325 24 P 0 ;1
L 2.7325 4.0825 2.7325 4.0825 24 P 0 ;1
L 2.7325 4.1325 2.7325 4.1325 24 P 0 ;1
L 2.7325 4.1825 2.7325 4.1825 24 P 0 ;1
L 2.7325 4.2325 2.7325 4.2325 24 P 0 ;1
L 2.7325 4.2825 2.7325 4.2825 24 P 0 ;1
L 2.7325 4.3325 2.7325 4.3325 24 P 0 ;1
L 2.7325 5.2825 2.7325 5.2825 24 P 0 ;1
L 2.7825 0.1325 2.7825 0.1325 24 P 0 ;1
L 2.7825 0.1825 2.7825 0.1825 24 P 0 ;1
L 2.7825 0.4325 2.7825 0.4325 24 P 0 ;1
L 2.7825 0.4825 2.7825 0.4825 24 P 0 ;1
L 2.7825 0.5325 2.7825 0.5325 24 P 0 ;1
L 2.7825 0.5825 2.7825 0.5825 24 P 0 ;1
L 2.7825 0.6325 2.7825 0.6325 24 P 0 ;1
L 2.7825 0.6825 2.7825 0.6825 24 P 0 ;1
L 2.7825 0.7325 2.7825 0.7325 24 P 0 ;1
L 2.7825 0.7825 2.7825 0.7825 24 P 0 ;1
L 2.7825 0.8325 2.7825 0.8325 24 P 0 ;1
L 2.7825 0.8825 2.7825 0.8825 24 P 0 ;1
L 2.7825 0.9325 2.7825 0.9325 24 P 0 ;1
L 2.7825 0.9825 2.7825 0.9825 24 P 0 ;1
L 2.7825 1.0325 2.7825 1.0325 24 P 0 ;1
L 2.7825 1.0825 2.7825 1.0825 24 P 0 ;1
L 2.7825 1.1325 2.7825 1.1325 24 P 0 ;1
L 2.7825 1.1825 2.7825 1.1825 24 P 0 ;1
L 2.7825 1.2325 2.7825 1.2325 24 P 0 ;1
L 2.7825 1.2825 2.7825 1.2825 24 P 0 ;1
L 2.7825 1.3325 2.7825 1.3325 24 P 0 ;1
L 2.7825 1.3825 2.7825 1.3825 24 P 0 ;1
L 2.7825 1.4325 2.7825 1.4325 24 P 0 ;1
L 2.7825 1.4825 2.7825 1.4825 24 P 0 ;1
L 2.7825 1.5325 2.7825 1.5325 24 P 0 ;1
L 2.7825 1.5825 2.7825 1.5825 24 P 0 ;1
L 2.7825 1.6325 2.7825 1.6325 24 P 0 ;1
L 2.7825 1.6825 2.7825 1.6825 24 P 0 ;1
L 2.7825 1.7325 2.7825 1.7325 24 P 0 ;1
L 2.7825 1.7825 2.7825 1.7825 24 P 0 ;1
L 2.7825 1.8325 2.7825 1.8325 24 P 0 ;1
L 2.7825 1.8825 2.7825 1.8825 24 P 0 ;1
L 2.7825 1.9325 2.7825 1.9325 24 P 0 ;1
L 2.7825 1.9825 2.7825 1.9825 24 P 0 ;1
L 2.7825 2.0325 2.7825 2.0325 24 P 0 ;1
L 2.7825 2.0825 2.7825 2.0825 24 P 0 ;1
L 2.7825 2.1325 2.7825 2.1325 24 P 0 ;1
L 2.7825 2.1825 2.7825 2.1825 24 P 0 ;1
L 2.7825 2.2325 2.7825 2.2325 24 P 0 ;1
L 2.7825 2.2825 2.7825 2.2825 24 P 0 ;1
L 2.7825 2.3325 2.7825 2.3325 24 P 0 ;1
L 2.7825 2.3825 2.7825 2.3825 24 P 0 ;1
L 2.7825 2.4325 2.7825 2.4325 24 P 0 ;1
L 2.7825 2.4825 2.7825 2.4825 24 P 0 ;1
L 2.7825 2.5325 2.7825 2.5325 24 P 0 ;1
L 2.7825 2.5825 2.7825 2.5825 24 P 0 ;1
L 2.7825 2.6325 2.7825 2.6325 24 P 0 ;1
L 2.7825 2.6825 2.7825 2.6825 24 P 0 ;1
L 2.7825 2.7325 2.7825 2.7325 24 P 0 ;1
L 2.7825 2.9825 2.7825 2.9825 24 P 0 ;1
L 2.7825 3.0325 2.7825 3.0325 24 P 0 ;1
L 2.7825 3.0825 2.7825 3.0825 24 P 0 ;1
L 2.7825 3.1325 2.7825 3.1325 24 P 0 ;1
L 2.7825 3.1825 2.7825 3.1825 24 P 0 ;1
L 2.7825 3.2325 2.7825 3.2325 24 P 0 ;1
L 2.7825 3.2825 2.7825 3.2825 24 P 0 ;1
L 2.7825 3.3325 2.7825 3.3325 24 P 0 ;1
L 2.7825 3.3825 2.7825 3.3825 24 P 0 ;1
L 2.7825 3.4325 2.7825 3.4325 24 P 0 ;1
L 2.7825 3.4825 2.7825 3.4825 24 P 0 ;1
L 2.7825 3.5325 2.7825 3.5325 24 P 0 ;1
L 2.7825 3.5825 2.7825 3.5825 24 P 0 ;1
L 2.7825 3.6325 2.7825 3.6325 24 P 0 ;1
L 2.7825 3.6825 2.7825 3.6825 24 P 0 ;1
L 2.7825 3.7325 2.7825 3.7325 24 P 0 ;1
L 2.7825 3.7825 2.7825 3.7825 24 P 0 ;1
L 2.7825 3.8325 2.7825 3.8325 24 P 0 ;1
L 2.7825 3.8825 2.7825 3.8825 24 P 0 ;1
L 2.7825 3.9325 2.7825 3.9325 24 P 0 ;1
L 2.7825 3.9825 2.7825 3.9825 24 P 0 ;1
L 2.7825 4.0325 2.7825 4.0325 24 P 0 ;1
L 2.7825 4.0825 2.7825 4.0825 24 P 0 ;1
L 2.7825 4.1325 2.7825 4.1325 24 P 0 ;1
L 2.7825 4.1825 2.7825 4.1825 24 P 0 ;1
L 2.7825 4.2325 2.7825 4.2325 24 P 0 ;1
L 2.7825 4.2825 2.7825 4.2825 24 P 0 ;1
L 2.7825 4.3325 2.7825 4.3325 24 P 0 ;1
L 2.7825 5.2825 2.7825 5.2825 24 P 0 ;1
L 2.8325 0.1325 2.8325 0.1325 24 P 0 ;1
L 2.8325 0.1825 2.8325 0.1825 24 P 0 ;1
L 2.8325 0.4325 2.8325 0.4325 24 P 0 ;1
L 2.8325 0.4825 2.8325 0.4825 24 P 0 ;1
L 2.8325 0.5325 2.8325 0.5325 24 P 0 ;1
L 2.8325 0.5825 2.8325 0.5825 24 P 0 ;1
L 2.8325 0.6325 2.8325 0.6325 24 P 0 ;1
L 2.8325 0.6825 2.8325 0.6825 24 P 0 ;1
L 2.8325 0.7325 2.8325 0.7325 24 P 0 ;1
L 2.8325 0.7825 2.8325 0.7825 24 P 0 ;1
L 2.8325 0.8325 2.8325 0.8325 24 P 0 ;1
L 2.8325 0.8825 2.8325 0.8825 24 P 0 ;1
L 2.8325 0.9325 2.8325 0.9325 24 P 0 ;1
L 2.8325 0.9825 2.8325 0.9825 24 P 0 ;1
L 2.8325 1.0325 2.8325 1.0325 24 P 0 ;1
L 2.8325 1.0825 2.8325 1.0825 24 P 0 ;1
L 2.8325 1.1325 2.8325 1.1325 24 P 0 ;1
L 2.8325 1.1825 2.8325 1.1825 24 P 0 ;1
L 2.8325 1.2325 2.8325 1.2325 24 P 0 ;1
L 2.8325 1.2825 2.8325 1.2825 24 P 0 ;1
L 2.8325 1.3325 2.8325 1.3325 24 P 0 ;1
L 2.8325 1.3825 2.8325 1.3825 24 P 0 ;1
L 2.8325 1.4325 2.8325 1.4325 24 P 0 ;1
L 2.8325 1.4825 2.8325 1.4825 24 P 0 ;1
L 2.8325 1.5325 2.8325 1.5325 24 P 0 ;1
L 2.8325 1.5825 2.8325 1.5825 24 P 0 ;1
L 2.8325 1.6325 2.8325 1.6325 24 P 0 ;1
L 2.8325 1.6825 2.8325 1.6825 24 P 0 ;1
L 2.8325 1.7325 2.8325 1.7325 24 P 0 ;1
L 2.8325 1.7825 2.8325 1.7825 24 P 0 ;1
L 2.8325 1.8325 2.8325 1.8325 24 P 0 ;1
L 2.8325 1.8825 2.8325 1.8825 24 P 0 ;1
L 2.8325 1.9325 2.8325 1.9325 24 P 0 ;1
L 2.8325 1.9825 2.8325 1.9825 24 P 0 ;1
L 2.8325 2.0325 2.8325 2.0325 24 P 0 ;1
L 2.8325 2.0825 2.8325 2.0825 24 P 0 ;1
L 2.8325 2.1325 2.8325 2.1325 24 P 0 ;1
L 2.8325 2.1825 2.8325 2.1825 24 P 0 ;1
L 2.8325 2.2325 2.8325 2.2325 24 P 0 ;1
L 2.8325 2.2825 2.8325 2.2825 24 P 0 ;1
L 2.8325 2.3325 2.8325 2.3325 24 P 0 ;1
L 2.8325 2.3825 2.8325 2.3825 24 P 0 ;1
L 2.8325 2.4325 2.8325 2.4325 24 P 0 ;1
L 2.8325 2.4825 2.8325 2.4825 24 P 0 ;1
L 2.8325 2.5325 2.8325 2.5325 24 P 0 ;1
L 2.8325 2.5825 2.8325 2.5825 24 P 0 ;1
L 2.8325 2.6325 2.8325 2.6325 24 P 0 ;1
L 2.8325 2.6825 2.8325 2.6825 24 P 0 ;1
L 2.8325 2.7325 2.8325 2.7325 24 P 0 ;1
L 2.8325 2.9825 2.8325 2.9825 24 P 0 ;1
L 2.8325 3.0325 2.8325 3.0325 24 P 0 ;1
L 2.8325 3.0825 2.8325 3.0825 24 P 0 ;1
L 2.8325 3.1325 2.8325 3.1325 24 P 0 ;1
L 2.8325 3.1825 2.8325 3.1825 24 P 0 ;1
L 2.8325 3.2325 2.8325 3.2325 24 P 0 ;1
L 2.8325 3.2825 2.8325 3.2825 24 P 0 ;1
L 2.8325 3.3325 2.8325 3.3325 24 P 0 ;1
L 2.8325 3.3825 2.8325 3.3825 24 P 0 ;1
L 2.8325 3.4325 2.8325 3.4325 24 P 0 ;1
L 2.8325 3.4825 2.8325 3.4825 24 P 0 ;1
L 2.8325 3.5325 2.8325 3.5325 24 P 0 ;1
L 2.8325 3.5825 2.8325 3.5825 24 P 0 ;1
L 2.8325 3.6325 2.8325 3.6325 24 P 0 ;1
L 2.8325 3.6825 2.8325 3.6825 24 P 0 ;1
L 2.8325 3.7325 2.8325 3.7325 24 P 0 ;1
L 2.8325 3.7825 2.8325 3.7825 24 P 0 ;1
L 2.8325 3.8325 2.8325 3.8325 24 P 0 ;1
L 2.8325 3.8825 2.8325 3.8825 24 P 0 ;1
L 2.8325 3.9325 2.8325 3.9325 24 P 0 ;1
L 2.8325 3.9825 2.8325 3.9825 24 P 0 ;1
L 2.8325 4.0325 2.8325 4.0325 24 P 0 ;1
L 2.8325 4.0825 2.8325 4.0825 24 P 0 ;1
L 2.8325 4.1325 2.8325 4.1325 24 P 0 ;1
L 2.8325 4.1825 2.8325 4.1825 24 P 0 ;1
L 2.8325 4.2325 2.8325 4.2325 24 P 0 ;1
L 2.8325 4.2825 2.8325 4.2825 24 P 0 ;1
L 2.8325 4.3325 2.8325 4.3325 24 P 0 ;1
L 2.8825 0.1325 2.8825 0.1325 24 P 0 ;1
L 2.8825 0.1825 2.8825 0.1825 24 P 0 ;1
L 2.8825 0.4325 2.8825 0.4325 24 P 0 ;1
L 2.8825 0.4825 2.8825 0.4825 24 P 0 ;1
L 2.8825 0.5325 2.8825 0.5325 24 P 0 ;1
L 2.8825 0.5825 2.8825 0.5825 24 P 0 ;1
L 2.8825 0.6325 2.8825 0.6325 24 P 0 ;1
L 2.8825 0.6825 2.8825 0.6825 24 P 0 ;1
L 2.8825 0.7325 2.8825 0.7325 24 P 0 ;1
L 2.8825 0.7825 2.8825 0.7825 24 P 0 ;1
L 2.8825 0.8325 2.8825 0.8325 24 P 0 ;1
L 2.8825 0.8825 2.8825 0.8825 24 P 0 ;1
L 2.8825 0.9325 2.8825 0.9325 24 P 0 ;1
L 2.8825 0.9825 2.8825 0.9825 24 P 0 ;1
L 2.8825 1.0325 2.8825 1.0325 24 P 0 ;1
L 2.8825 1.0825 2.8825 1.0825 24 P 0 ;1
L 2.8825 1.1325 2.8825 1.1325 24 P 0 ;1
L 2.8825 1.1825 2.8825 1.1825 24 P 0 ;1
L 2.8825 1.2325 2.8825 1.2325 24 P 0 ;1
L 2.8825 1.2825 2.8825 1.2825 24 P 0 ;1
L 2.8825 1.3325 2.8825 1.3325 24 P 0 ;1
L 2.8825 1.3825 2.8825 1.3825 24 P 0 ;1
L 2.8825 1.4325 2.8825 1.4325 24 P 0 ;1
L 2.8825 1.4825 2.8825 1.4825 24 P 0 ;1
L 2.8825 1.5325 2.8825 1.5325 24 P 0 ;1
L 2.8825 1.5825 2.8825 1.5825 24 P 0 ;1
L 2.8825 1.6325 2.8825 1.6325 24 P 0 ;1
L 2.8825 1.6825 2.8825 1.6825 24 P 0 ;1
L 2.8825 1.7325 2.8825 1.7325 24 P 0 ;1
L 2.8825 1.7825 2.8825 1.7825 24 P 0 ;1
L 2.8825 1.8325 2.8825 1.8325 24 P 0 ;1
L 2.8825 1.8825 2.8825 1.8825 24 P 0 ;1
L 2.8825 1.9325 2.8825 1.9325 24 P 0 ;1
L 2.8825 1.9825 2.8825 1.9825 24 P 0 ;1
L 2.8825 2.0325 2.8825 2.0325 24 P 0 ;1
L 2.8825 2.0825 2.8825 2.0825 24 P 0 ;1
L 2.8825 2.1325 2.8825 2.1325 24 P 0 ;1
L 2.8825 2.1825 2.8825 2.1825 24 P 0 ;1
L 2.8825 2.2325 2.8825 2.2325 24 P 0 ;1
L 2.8825 2.2825 2.8825 2.2825 24 P 0 ;1
L 2.8825 2.3325 2.8825 2.3325 24 P 0 ;1
L 2.8825 2.3825 2.8825 2.3825 24 P 0 ;1
L 2.8825 2.4325 2.8825 2.4325 24 P 0 ;1
L 2.8825 2.4825 2.8825 2.4825 24 P 0 ;1
L 2.8825 2.5325 2.8825 2.5325 24 P 0 ;1
L 2.8825 2.5825 2.8825 2.5825 24 P 0 ;1
L 2.8825 2.6325 2.8825 2.6325 24 P 0 ;1
L 2.8825 2.6825 2.8825 2.6825 24 P 0 ;1
L 2.8825 2.7325 2.8825 2.7325 24 P 0 ;1
L 2.8825 3.0325 2.8825 3.0325 24 P 0 ;1
L 2.8825 3.0825 2.8825 3.0825 24 P 0 ;1
L 2.8825 3.1325 2.8825 3.1325 24 P 0 ;1
L 2.8825 3.1825 2.8825 3.1825 24 P 0 ;1
L 2.8825 3.2325 2.8825 3.2325 24 P 0 ;1
L 2.8825 3.2825 2.8825 3.2825 24 P 0 ;1
L 2.8825 3.3325 2.8825 3.3325 24 P 0 ;1
L 2.8825 3.3825 2.8825 3.3825 24 P 0 ;1
L 2.8825 3.4325 2.8825 3.4325 24 P 0 ;1
L 2.8825 3.4825 2.8825 3.4825 24 P 0 ;1
L 2.8825 3.5325 2.8825 3.5325 24 P 0 ;1
L 2.8825 3.5825 2.8825 3.5825 24 P 0 ;1
L 2.8825 3.6325 2.8825 3.6325 24 P 0 ;1
L 2.8825 3.6825 2.8825 3.6825 24 P 0 ;1
L 2.8825 3.7325 2.8825 3.7325 24 P 0 ;1
L 2.8825 3.7825 2.8825 3.7825 24 P 0 ;1
L 2.8825 3.8325 2.8825 3.8325 24 P 0 ;1
L 2.8825 3.8825 2.8825 3.8825 24 P 0 ;1
L 2.8825 3.9325 2.8825 3.9325 24 P 0 ;1
L 2.8825 3.9825 2.8825 3.9825 24 P 0 ;1
L 2.8825 4.0325 2.8825 4.0325 24 P 0 ;1
L 2.8825 4.0825 2.8825 4.0825 24 P 0 ;1
L 2.8825 4.1325 2.8825 4.1325 24 P 0 ;1
L 2.8825 4.1825 2.8825 4.1825 24 P 0 ;1
L 2.8825 4.2325 2.8825 4.2325 24 P 0 ;1
L 2.8825 4.2825 2.8825 4.2825 24 P 0 ;1
L 2.8825 4.3325 2.8825 4.3325 24 P 0 ;1
L 2.9325 0.1325 2.9325 0.1325 24 P 0 ;1
L 2.9325 0.1825 2.9325 0.1825 24 P 0 ;1
L 2.9325 0.4325 2.9325 0.4325 24 P 0 ;1
L 2.9325 0.4825 2.9325 0.4825 24 P 0 ;1
L 2.9325 0.5325 2.9325 0.5325 24 P 0 ;1
L 2.9325 0.5825 2.9325 0.5825 24 P 0 ;1
L 2.9325 0.6325 2.9325 0.6325 24 P 0 ;1
L 2.9325 0.6825 2.9325 0.6825 24 P 0 ;1
L 2.9325 0.7325 2.9325 0.7325 24 P 0 ;1
L 2.9325 0.7825 2.9325 0.7825 24 P 0 ;1
L 2.9325 0.8325 2.9325 0.8325 24 P 0 ;1
L 2.9325 0.8825 2.9325 0.8825 24 P 0 ;1
L 2.9325 0.9325 2.9325 0.9325 24 P 0 ;1
L 2.9325 0.9825 2.9325 0.9825 24 P 0 ;1
L 2.9325 1.0325 2.9325 1.0325 24 P 0 ;1
L 2.9325 1.0825 2.9325 1.0825 24 P 0 ;1
L 2.9325 1.1325 2.9325 1.1325 24 P 0 ;1
L 2.9325 1.1825 2.9325 1.1825 24 P 0 ;1
L 2.9325 1.2325 2.9325 1.2325 24 P 0 ;1
L 2.9325 1.2825 2.9325 1.2825 24 P 0 ;1
L 2.9325 1.3325 2.9325 1.3325 24 P 0 ;1
L 2.9325 1.3825 2.9325 1.3825 24 P 0 ;1
L 2.9325 1.4325 2.9325 1.4325 24 P 0 ;1
L 2.9325 1.4825 2.9325 1.4825 24 P 0 ;1
L 2.9325 1.5325 2.9325 1.5325 24 P 0 ;1
L 2.9325 1.5825 2.9325 1.5825 24 P 0 ;1
L 2.9325 1.6325 2.9325 1.6325 24 P 0 ;1
L 2.9325 1.6825 2.9325 1.6825 24 P 0 ;1
L 2.9325 1.7325 2.9325 1.7325 24 P 0 ;1
L 2.9325 1.7825 2.9325 1.7825 24 P 0 ;1
L 2.9325 1.8325 2.9325 1.8325 24 P 0 ;1
L 2.9325 1.8825 2.9325 1.8825 24 P 0 ;1
L 2.9325 1.9325 2.9325 1.9325 24 P 0 ;1
L 2.9325 1.9825 2.9325 1.9825 24 P 0 ;1
L 2.9325 2.0325 2.9325 2.0325 24 P 0 ;1
L 2.9325 2.0825 2.9325 2.0825 24 P 0 ;1
L 2.9325 2.1325 2.9325 2.1325 24 P 0 ;1
L 2.9325 2.1825 2.9325 2.1825 24 P 0 ;1
L 2.9325 2.2325 2.9325 2.2325 24 P 0 ;1
L 2.9325 2.2825 2.9325 2.2825 24 P 0 ;1
L 2.9325 2.3325 2.9325 2.3325 24 P 0 ;1
L 2.9325 2.3825 2.9325 2.3825 24 P 0 ;1
L 2.9325 2.4325 2.9325 2.4325 24 P 0 ;1
L 2.9325 2.4825 2.9325 2.4825 24 P 0 ;1
L 2.9325 2.5325 2.9325 2.5325 24 P 0 ;1
L 2.9325 2.5825 2.9325 2.5825 24 P 0 ;1
L 2.9325 2.6325 2.9325 2.6325 24 P 0 ;1
L 2.9325 2.6825 2.9325 2.6825 24 P 0 ;1
L 2.9325 3.0325 2.9325 3.0325 24 P 0 ;1
L 2.9325 3.0825 2.9325 3.0825 24 P 0 ;1
L 2.9325 3.1325 2.9325 3.1325 24 P 0 ;1
L 2.9325 3.1825 2.9325 3.1825 24 P 0 ;1
L 2.9325 3.2325 2.9325 3.2325 24 P 0 ;1
L 2.9325 3.2825 2.9325 3.2825 24 P 0 ;1
L 2.9325 3.3325 2.9325 3.3325 24 P 0 ;1
L 2.9325 3.3825 2.9325 3.3825 24 P 0 ;1
L 2.9325 3.4325 2.9325 3.4325 24 P 0 ;1
L 2.9325 3.4825 2.9325 3.4825 24 P 0 ;1
L 2.9325 3.5325 2.9325 3.5325 24 P 0 ;1
L 2.9325 3.5825 2.9325 3.5825 24 P 0 ;1
L 2.9325 3.6325 2.9325 3.6325 24 P 0 ;1
L 2.9325 3.6825 2.9325 3.6825 24 P 0 ;1
L 2.9325 3.7325 2.9325 3.7325 24 P 0 ;1
L 2.9325 3.7825 2.9325 3.7825 24 P 0 ;1
L 2.9325 3.8325 2.9325 3.8325 24 P 0 ;1
L 2.9325 3.8825 2.9325 3.8825 24 P 0 ;1
L 2.9325 3.9325 2.9325 3.9325 24 P 0 ;1
L 2.9325 3.9825 2.9325 3.9825 24 P 0 ;1
L 2.9325 4.0325 2.9325 4.0325 24 P 0 ;1
L 2.9325 4.0825 2.9325 4.0825 24 P 0 ;1
L 2.9325 4.1325 2.9325 4.1325 24 P 0 ;1
L 2.9325 4.1825 2.9325 4.1825 24 P 0 ;1
L 2.9325 4.2325 2.9325 4.2325 24 P 0 ;1
L 2.9325 4.2825 2.9325 4.2825 24 P 0 ;1
L 2.9825 0.1325 2.9825 0.1325 24 P 0 ;1
L 2.9825 0.1825 2.9825 0.1825 24 P 0 ;1
L 2.9825 0.4325 2.9825 0.4325 24 P 0 ;1
L 2.9825 0.4825 2.9825 0.4825 24 P 0 ;1
L 2.9825 0.5325 2.9825 0.5325 24 P 0 ;1
L 2.9825 0.5825 2.9825 0.5825 24 P 0 ;1
L 2.9825 0.6325 2.9825 0.6325 24 P 0 ;1
L 2.9825 0.6825 2.9825 0.6825 24 P 0 ;1
L 2.9825 0.7325 2.9825 0.7325 24 P 0 ;1
L 2.9825 0.7825 2.9825 0.7825 24 P 0 ;1
L 2.9825 0.8325 2.9825 0.8325 24 P 0 ;1
L 2.9825 0.8825 2.9825 0.8825 24 P 0 ;1
L 2.9825 0.9325 2.9825 0.9325 24 P 0 ;1
L 2.9825 0.9825 2.9825 0.9825 24 P 0 ;1
L 2.9825 1.0325 2.9825 1.0325 24 P 0 ;1
L 2.9825 1.0825 2.9825 1.0825 24 P 0 ;1
L 2.9825 1.1325 2.9825 1.1325 24 P 0 ;1
L 2.9825 1.1825 2.9825 1.1825 24 P 0 ;1
L 2.9825 1.2325 2.9825 1.2325 24 P 0 ;1
L 2.9825 1.2825 2.9825 1.2825 24 P 0 ;1
L 2.9825 1.3325 2.9825 1.3325 24 P 0 ;1
L 2.9825 1.3825 2.9825 1.3825 24 P 0 ;1
L 2.9825 1.4325 2.9825 1.4325 24 P 0 ;1
L 2.9825 1.4825 2.9825 1.4825 24 P 0 ;1
L 2.9825 1.5325 2.9825 1.5325 24 P 0 ;1
L 2.9825 1.5825 2.9825 1.5825 24 P 0 ;1
L 2.9825 1.6325 2.9825 1.6325 24 P 0 ;1
L 2.9825 1.6825 2.9825 1.6825 24 P 0 ;1
L 2.9825 1.7325 2.9825 1.7325 24 P 0 ;1
L 2.9825 1.7825 2.9825 1.7825 24 P 0 ;1
L 2.9825 1.8325 2.9825 1.8325 24 P 0 ;1
L 2.9825 1.8825 2.9825 1.8825 24 P 0 ;1
L 2.9825 1.9325 2.9825 1.9325 24 P 0 ;1
L 2.9825 1.9825 2.9825 1.9825 24 P 0 ;1
L 2.9825 2.0325 2.9825 2.0325 24 P 0 ;1
L 2.9825 2.0825 2.9825 2.0825 24 P 0 ;1
L 2.9825 2.1325 2.9825 2.1325 24 P 0 ;1
L 2.9825 2.1825 2.9825 2.1825 24 P 0 ;1
L 2.9825 2.2325 2.9825 2.2325 24 P 0 ;1
L 2.9825 2.2825 2.9825 2.2825 24 P 0 ;1
L 2.9825 2.3325 2.9825 2.3325 24 P 0 ;1
L 2.9825 2.3825 2.9825 2.3825 24 P 0 ;1
L 2.9825 2.4325 2.9825 2.4325 24 P 0 ;1
L 2.9825 2.4825 2.9825 2.4825 24 P 0 ;1
L 2.9825 2.5325 2.9825 2.5325 24 P 0 ;1
L 2.9825 2.5825 2.9825 2.5825 24 P 0 ;1
L 2.9825 2.6325 2.9825 2.6325 24 P 0 ;1
L 2.9825 2.6825 2.9825 2.6825 24 P 0 ;1
L 2.9825 3.0325 2.9825 3.0325 24 P 0 ;1
L 2.9825 3.0825 2.9825 3.0825 24 P 0 ;1
L 2.9825 3.1325 2.9825 3.1325 24 P 0 ;1
L 2.9825 3.1825 2.9825 3.1825 24 P 0 ;1
L 2.9825 3.2325 2.9825 3.2325 24 P 0 ;1
L 2.9825 3.2825 2.9825 3.2825 24 P 0 ;1
L 2.9825 3.3325 2.9825 3.3325 24 P 0 ;1
L 2.9825 3.3825 2.9825 3.3825 24 P 0 ;1
L 2.9825 3.4325 2.9825 3.4325 24 P 0 ;1
L 2.9825 3.4825 2.9825 3.4825 24 P 0 ;1
L 2.9825 3.5325 2.9825 3.5325 24 P 0 ;1
L 2.9825 3.5825 2.9825 3.5825 24 P 0 ;1
L 2.9825 3.6325 2.9825 3.6325 24 P 0 ;1
L 2.9825 3.6825 2.9825 3.6825 24 P 0 ;1
L 2.9825 3.7325 2.9825 3.7325 24 P 0 ;1
L 2.9825 3.7825 2.9825 3.7825 24 P 0 ;1
L 2.9825 3.8325 2.9825 3.8325 24 P 0 ;1
L 2.9825 3.8825 2.9825 3.8825 24 P 0 ;1
L 2.9825 3.9325 2.9825 3.9325 24 P 0 ;1
L 2.9825 3.9825 2.9825 3.9825 24 P 0 ;1
L 2.9825 4.0325 2.9825 4.0325 24 P 0 ;1
L 2.9825 4.0825 2.9825 4.0825 24 P 0 ;1
L 2.9825 4.1325 2.9825 4.1325 24 P 0 ;1
L 2.9825 4.1825 2.9825 4.1825 24 P 0 ;1
L 2.9825 4.2325 2.9825 4.2325 24 P 0 ;1
L 3.0325 0.1325 3.0325 0.1325 24 P 0 ;1
L 3.0325 0.1825 3.0325 0.1825 24 P 0 ;1
L 3.0325 0.4325 3.0325 0.4325 24 P 0 ;1
L 3.0325 0.4825 3.0325 0.4825 24 P 0 ;1
L 3.0325 0.5325 3.0325 0.5325 24 P 0 ;1
L 3.0325 0.5825 3.0325 0.5825 24 P 0 ;1
L 3.0325 0.6325 3.0325 0.6325 24 P 0 ;1
L 3.0325 0.6825 3.0325 0.6825 24 P 0 ;1
L 3.0325 0.7325 3.0325 0.7325 24 P 0 ;1
L 3.0325 0.7825 3.0325 0.7825 24 P 0 ;1
L 3.0325 0.8325 3.0325 0.8325 24 P 0 ;1
L 3.0325 0.8825 3.0325 0.8825 24 P 0 ;1
L 3.0325 0.9325 3.0325 0.9325 24 P 0 ;1
L 3.0325 0.9825 3.0325 0.9825 24 P 0 ;1
L 3.0325 1.0325 3.0325 1.0325 24 P 0 ;1
L 3.0325 1.0825 3.0325 1.0825 24 P 0 ;1
L 3.0325 1.1325 3.0325 1.1325 24 P 0 ;1
L 3.0325 1.1825 3.0325 1.1825 24 P 0 ;1
L 3.0325 1.2325 3.0325 1.2325 24 P 0 ;1
L 3.0325 1.2825 3.0325 1.2825 24 P 0 ;1
L 3.0325 1.3325 3.0325 1.3325 24 P 0 ;1
L 3.0325 1.3825 3.0325 1.3825 24 P 0 ;1
L 3.0325 1.4325 3.0325 1.4325 24 P 0 ;1
L 3.0325 1.4825 3.0325 1.4825 24 P 0 ;1
L 3.0325 1.5325 3.0325 1.5325 24 P 0 ;1
L 3.0325 1.5825 3.0325 1.5825 24 P 0 ;1
L 3.0325 1.6325 3.0325 1.6325 24 P 0 ;1
L 3.0325 1.6825 3.0325 1.6825 24 P 0 ;1
L 3.0325 1.7325 3.0325 1.7325 24 P 0 ;1
L 3.0325 1.7825 3.0325 1.7825 24 P 0 ;1
L 3.0325 1.8325 3.0325 1.8325 24 P 0 ;1
L 3.0325 1.8825 3.0325 1.8825 24 P 0 ;1
L 3.0325 1.9325 3.0325 1.9325 24 P 0 ;1
L 3.0325 1.9825 3.0325 1.9825 24 P 0 ;1
L 3.0325 2.0325 3.0325 2.0325 24 P 0 ;1
L 3.0325 2.0825 3.0325 2.0825 24 P 0 ;1
L 3.0325 2.1325 3.0325 2.1325 24 P 0 ;1
L 3.0325 2.1825 3.0325 2.1825 24 P 0 ;1
L 3.0325 2.2325 3.0325 2.2325 24 P 0 ;1
L 3.0325 2.2825 3.0325 2.2825 24 P 0 ;1
L 3.0325 2.3325 3.0325 2.3325 24 P 0 ;1
L 3.0325 2.3825 3.0325 2.3825 24 P 0 ;1
L 3.0325 2.4325 3.0325 2.4325 24 P 0 ;1
L 3.0325 2.4825 3.0325 2.4825 24 P 0 ;1
L 3.0325 2.5325 3.0325 2.5325 24 P 0 ;1
L 3.0325 2.5825 3.0325 2.5825 24 P 0 ;1
L 3.0325 2.6325 3.0325 2.6325 24 P 0 ;1
L 3.0325 2.6825 3.0325 2.6825 24 P 0 ;1
L 3.0325 2.9825 3.0325 2.9825 24 P 0 ;1
L 3.0325 3.0325 3.0325 3.0325 24 P 0 ;1
L 3.0325 3.0825 3.0325 3.0825 24 P 0 ;1
L 3.0325 3.1325 3.0325 3.1325 24 P 0 ;1
L 3.0325 3.1825 3.0325 3.1825 24 P 0 ;1
L 3.0325 3.2325 3.0325 3.2325 24 P 0 ;1
L 3.0325 3.2825 3.0325 3.2825 24 P 0 ;1
L 3.0325 3.3325 3.0325 3.3325 24 P 0 ;1
L 3.0325 3.3825 3.0325 3.3825 24 P 0 ;1
L 3.0325 3.4325 3.0325 3.4325 24 P 0 ;1
L 3.0325 3.4825 3.0325 3.4825 24 P 0 ;1
L 3.0325 3.5325 3.0325 3.5325 24 P 0 ;1
L 3.0325 3.5825 3.0325 3.5825 24 P 0 ;1
L 3.0325 3.6325 3.0325 3.6325 24 P 0 ;1
L 3.0325 3.6825 3.0325 3.6825 24 P 0 ;1
L 3.0325 3.7325 3.0325 3.7325 24 P 0 ;1
L 3.0325 3.7825 3.0325 3.7825 24 P 0 ;1
L 3.0325 3.8325 3.0325 3.8325 24 P 0 ;1
L 3.0325 3.8825 3.0325 3.8825 24 P 0 ;1
L 3.0325 3.9325 3.0325 3.9325 24 P 0 ;1
L 3.0325 3.9825 3.0325 3.9825 24 P 0 ;1
L 3.0325 4.0325 3.0325 4.0325 24 P 0 ;1
L 3.0325 4.0825 3.0325 4.0825 24 P 0 ;1
L 3.0325 4.1325 3.0325 4.1325 24 P 0 ;1
L 3.0325 4.1825 3.0325 4.1825 24 P 0 ;1
L 3.0825 0.1325 3.0825 0.1325 24 P 0 ;1
L 3.0825 0.1825 3.0825 0.1825 24 P 0 ;1
L 3.0825 0.4325 3.0825 0.4325 24 P 0 ;1
L 3.0825 0.4825 3.0825 0.4825 24 P 0 ;1
L 3.0825 0.5325 3.0825 0.5325 24 P 0 ;1
L 3.0825 0.5825 3.0825 0.5825 24 P 0 ;1
L 3.0825 0.6325 3.0825 0.6325 24 P 0 ;1
L 3.0825 0.6825 3.0825 0.6825 24 P 0 ;1
L 3.0825 0.7325 3.0825 0.7325 24 P 0 ;1
L 3.0825 0.7825 3.0825 0.7825 24 P 0 ;1
L 3.0825 0.8325 3.0825 0.8325 24 P 0 ;1
L 3.0825 0.8825 3.0825 0.8825 24 P 0 ;1
L 3.0825 0.9325 3.0825 0.9325 24 P 0 ;1
L 3.0825 0.9825 3.0825 0.9825 24 P 0 ;1
L 3.0825 1.0325 3.0825 1.0325 24 P 0 ;1
L 3.0825 1.0825 3.0825 1.0825 24 P 0 ;1
L 3.0825 1.1325 3.0825 1.1325 24 P 0 ;1
L 3.0825 1.1825 3.0825 1.1825 24 P 0 ;1
L 3.0825 1.2325 3.0825 1.2325 24 P 0 ;1
L 3.0825 1.2825 3.0825 1.2825 24 P 0 ;1
L 3.0825 1.3325 3.0825 1.3325 24 P 0 ;1
L 3.0825 1.3825 3.0825 1.3825 24 P 0 ;1
L 3.0825 1.4325 3.0825 1.4325 24 P 0 ;1
L 3.0825 1.4825 3.0825 1.4825 24 P 0 ;1
L 3.0825 1.5325 3.0825 1.5325 24 P 0 ;1
L 3.0825 1.5825 3.0825 1.5825 24 P 0 ;1
L 3.0825 1.6325 3.0825 1.6325 24 P 0 ;1
L 3.0825 1.6825 3.0825 1.6825 24 P 0 ;1
L 3.0825 1.7325 3.0825 1.7325 24 P 0 ;1
L 3.0825 1.7825 3.0825 1.7825 24 P 0 ;1
L 3.0825 1.8325 3.0825 1.8325 24 P 0 ;1
L 3.0825 1.8825 3.0825 1.8825 24 P 0 ;1
L 3.0825 1.9325 3.0825 1.9325 24 P 0 ;1
L 3.0825 1.9825 3.0825 1.9825 24 P 0 ;1
L 3.0825 2.0325 3.0825 2.0325 24 P 0 ;1
L 3.0825 2.0825 3.0825 2.0825 24 P 0 ;1
L 3.0825 2.1325 3.0825 2.1325 24 P 0 ;1
L 3.0825 2.1825 3.0825 2.1825 24 P 0 ;1
L 3.0825 2.2325 3.0825 2.2325 24 P 0 ;1
L 3.0825 2.2825 3.0825 2.2825 24 P 0 ;1
L 3.0825 2.3325 3.0825 2.3325 24 P 0 ;1
L 3.0825 2.3825 3.0825 2.3825 24 P 0 ;1
L 3.0825 2.4325 3.0825 2.4325 24 P 0 ;1
L 3.0825 2.4825 3.0825 2.4825 24 P 0 ;1
L 3.0825 2.5325 3.0825 2.5325 24 P 0 ;1
L 3.0825 2.5825 3.0825 2.5825 24 P 0 ;1
L 3.0825 2.6325 3.0825 2.6325 24 P 0 ;1
L 3.0825 2.6825 3.0825 2.6825 24 P 0 ;1
L 3.0825 2.7325 3.0825 2.7325 24 P 0 ;1
L 3.0825 2.7825 3.0825 2.7825 24 P 0 ;1
L 3.0825 2.8325 3.0825 2.8325 24 P 0 ;1
L 3.0825 2.8825 3.0825 2.8825 24 P 0 ;1
L 3.0825 2.9325 3.0825 2.9325 24 P 0 ;1
L 3.0825 2.9825 3.0825 2.9825 24 P 0 ;1
L 3.0825 3.0325 3.0825 3.0325 24 P 0 ;1
L 3.0825 3.0825 3.0825 3.0825 24 P 0 ;1
L 3.0825 3.1325 3.0825 3.1325 24 P 0 ;1
L 3.0825 3.1825 3.0825 3.1825 24 P 0 ;1
L 3.0825 3.2325 3.0825 3.2325 24 P 0 ;1
L 3.0825 3.2825 3.0825 3.2825 24 P 0 ;1
L 3.0825 3.3325 3.0825 3.3325 24 P 0 ;1
L 3.0825 3.3825 3.0825 3.3825 24 P 0 ;1
L 3.0825 3.4325 3.0825 3.4325 24 P 0 ;1
L 3.0825 3.4825 3.0825 3.4825 24 P 0 ;1
L 3.0825 3.5325 3.0825 3.5325 24 P 0 ;1
L 3.0825 3.5825 3.0825 3.5825 24 P 0 ;1
L 3.0825 3.6325 3.0825 3.6325 24 P 0 ;1
L 3.0825 3.6825 3.0825 3.6825 24 P 0 ;1
L 3.0825 3.7325 3.0825 3.7325 24 P 0 ;1
L 3.0825 3.7825 3.0825 3.7825 24 P 0 ;1
L 3.0825 3.8325 3.0825 3.8325 24 P 0 ;1
L 3.0825 3.8825 3.0825 3.8825 24 P 0 ;1
L 3.0825 3.9325 3.0825 3.9325 24 P 0 ;1
L 3.0825 3.9825 3.0825 3.9825 24 P 0 ;1
L 3.0825 4.0325 3.0825 4.0325 24 P 0 ;1
L 3.0825 4.0825 3.0825 4.0825 24 P 0 ;1
L 3.0825 4.1325 3.0825 4.1325 24 P 0 ;1
L 3.0825 4.1825 3.0825 4.1825 24 P 0 ;1
L 3.1325 0.1325 3.1325 0.1325 24 P 0 ;1
L 3.1325 0.1825 3.1325 0.1825 24 P 0 ;1
L 3.1325 0.4325 3.1325 0.4325 24 P 0 ;1
L 3.1325 0.4825 3.1325 0.4825 24 P 0 ;1
L 3.1325 0.5325 3.1325 0.5325 24 P 0 ;1
L 3.1325 0.5825 3.1325 0.5825 24 P 0 ;1
L 3.1325 0.6325 3.1325 0.6325 24 P 0 ;1
L 3.1325 0.6825 3.1325 0.6825 24 P 0 ;1
L 3.1325 0.7325 3.1325 0.7325 24 P 0 ;1
L 3.1325 0.7825 3.1325 0.7825 24 P 0 ;1
L 3.1325 0.8325 3.1325 0.8325 24 P 0 ;1
L 3.1325 0.8825 3.1325 0.8825 24 P 0 ;1
L 3.1325 0.9325 3.1325 0.9325 24 P 0 ;1
L 3.1325 0.9825 3.1325 0.9825 24 P 0 ;1
L 3.1325 1.0325 3.1325 1.0325 24 P 0 ;1
L 3.1325 1.0825 3.1325 1.0825 24 P 0 ;1
L 3.1325 1.1325 3.1325 1.1325 24 P 0 ;1
L 3.1325 1.1825 3.1325 1.1825 24 P 0 ;1
L 3.1325 1.2325 3.1325 1.2325 24 P 0 ;1
L 3.1325 1.2825 3.1325 1.2825 24 P 0 ;1
L 3.1325 1.3325 3.1325 1.3325 24 P 0 ;1
L 3.1325 1.3825 3.1325 1.3825 24 P 0 ;1
L 3.1325 1.4325 3.1325 1.4325 24 P 0 ;1
L 3.1325 1.4825 3.1325 1.4825 24 P 0 ;1
L 3.1325 1.5325 3.1325 1.5325 24 P 0 ;1
L 3.1325 1.5825 3.1325 1.5825 24 P 0 ;1
L 3.1325 1.6325 3.1325 1.6325 24 P 0 ;1
L 3.1325 1.6825 3.1325 1.6825 24 P 0 ;1
L 3.1325 1.7325 3.1325 1.7325 24 P 0 ;1
L 3.1325 1.7825 3.1325 1.7825 24 P 0 ;1
L 3.1325 1.8325 3.1325 1.8325 24 P 0 ;1
L 3.1325 1.8825 3.1325 1.8825 24 P 0 ;1
L 3.1325 1.9325 3.1325 1.9325 24 P 0 ;1
L 3.1325 1.9825 3.1325 1.9825 24 P 0 ;1
L 3.1325 2.0325 3.1325 2.0325 24 P 0 ;1
L 3.1325 2.0825 3.1325 2.0825 24 P 0 ;1
L 3.1325 2.1325 3.1325 2.1325 24 P 0 ;1
L 3.1325 2.1825 3.1325 2.1825 24 P 0 ;1
L 3.1325 2.2325 3.1325 2.2325 24 P 0 ;1
L 3.1325 2.2825 3.1325 2.2825 24 P 0 ;1
L 3.1325 2.3325 3.1325 2.3325 24 P 0 ;1
L 3.1325 2.3825 3.1325 2.3825 24 P 0 ;1
L 3.1325 2.4325 3.1325 2.4325 24 P 0 ;1
L 3.1325 2.4825 3.1325 2.4825 24 P 0 ;1
L 3.1325 2.5325 3.1325 2.5325 24 P 0 ;1
L 3.1325 2.5825 3.1325 2.5825 24 P 0 ;1
L 3.1325 2.6325 3.1325 2.6325 24 P 0 ;1
L 3.1325 2.6825 3.1325 2.6825 24 P 0 ;1
L 3.1325 2.7325 3.1325 2.7325 24 P 0 ;1
L 3.1325 2.7825 3.1325 2.7825 24 P 0 ;1
L 3.1325 2.8325 3.1325 2.8325 24 P 0 ;1
L 3.1325 2.8825 3.1325 2.8825 24 P 0 ;1
L 3.1325 2.9325 3.1325 2.9325 24 P 0 ;1
L 3.1325 2.9825 3.1325 2.9825 24 P 0 ;1
L 3.1325 3.0325 3.1325 3.0325 24 P 0 ;1
L 3.1325 3.0825 3.1325 3.0825 24 P 0 ;1
L 3.1325 3.1325 3.1325 3.1325 24 P 0 ;1
L 3.1325 3.1825 3.1325 3.1825 24 P 0 ;1
L 3.1325 3.2325 3.1325 3.2325 24 P 0 ;1
L 3.1325 3.2825 3.1325 3.2825 24 P 0 ;1
L 3.1325 3.3325 3.1325 3.3325 24 P 0 ;1
L 3.1325 3.3825 3.1325 3.3825 24 P 0 ;1
L 3.1325 3.4325 3.1325 3.4325 24 P 0 ;1
L 3.1325 3.4825 3.1325 3.4825 24 P 0 ;1
L 3.1325 3.5325 3.1325 3.5325 24 P 0 ;1
L 3.1325 3.5825 3.1325 3.5825 24 P 0 ;1
L 3.1325 3.6325 3.1325 3.6325 24 P 0 ;1
L 3.1325 3.6825 3.1325 3.6825 24 P 0 ;1
L 3.1325 3.7325 3.1325 3.7325 24 P 0 ;1
L 3.1325 3.7825 3.1325 3.7825 24 P 0 ;1
L 3.1325 3.8325 3.1325 3.8325 24 P 0 ;1
L 3.1325 3.8825 3.1325 3.8825 24 P 0 ;1
L 3.1325 3.9325 3.1325 3.9325 24 P 0 ;1
L 3.1325 3.9825 3.1325 3.9825 24 P 0 ;1
L 3.1325 4.0325 3.1325 4.0325 24 P 0 ;1
L 3.1325 4.0825 3.1325 4.0825 24 P 0 ;1
L 3.1325 4.1325 3.1325 4.1325 24 P 0 ;1
L 3.1325 4.1825 3.1325 4.1825 24 P 0 ;1
L 3.1825 0.1325 3.1825 0.1325 24 P 0 ;1
L 3.1825 0.1825 3.1825 0.1825 24 P 0 ;1
L 3.1825 0.4325 3.1825 0.4325 24 P 0 ;1
L 3.1825 0.4825 3.1825 0.4825 24 P 0 ;1
L 3.1825 0.5325 3.1825 0.5325 24 P 0 ;1
L 3.1825 0.5825 3.1825 0.5825 24 P 0 ;1
L 3.1825 0.6325 3.1825 0.6325 24 P 0 ;1
L 3.1825 0.6825 3.1825 0.6825 24 P 0 ;1
L 3.1825 0.7325 3.1825 0.7325 24 P 0 ;1
L 3.1825 0.7825 3.1825 0.7825 24 P 0 ;1
L 3.1825 0.8325 3.1825 0.8325 24 P 0 ;1
L 3.1825 0.8825 3.1825 0.8825 24 P 0 ;1
L 3.1825 0.9325 3.1825 0.9325 24 P 0 ;1
L 3.1825 0.9825 3.1825 0.9825 24 P 0 ;1
L 3.1825 1.0325 3.1825 1.0325 24 P 0 ;1
L 3.1825 1.0825 3.1825 1.0825 24 P 0 ;1
L 3.1825 1.1325 3.1825 1.1325 24 P 0 ;1
L 3.1825 1.1825 3.1825 1.1825 24 P 0 ;1
L 3.1825 1.2325 3.1825 1.2325 24 P 0 ;1
L 3.1825 1.2825 3.1825 1.2825 24 P 0 ;1
L 3.1825 1.3325 3.1825 1.3325 24 P 0 ;1
L 3.1825 1.3825 3.1825 1.3825 24 P 0 ;1
L 3.1825 1.4325 3.1825 1.4325 24 P 0 ;1
L 3.1825 1.4825 3.1825 1.4825 24 P 0 ;1
L 3.1825 1.5325 3.1825 1.5325 24 P 0 ;1
L 3.1825 1.5825 3.1825 1.5825 24 P 0 ;1
L 3.1825 1.6325 3.1825 1.6325 24 P 0 ;1
L 3.1825 1.6825 3.1825 1.6825 24 P 0 ;1
L 3.1825 1.7325 3.1825 1.7325 24 P 0 ;1
L 3.1825 1.7825 3.1825 1.7825 24 P 0 ;1
L 3.1825 1.8325 3.1825 1.8325 24 P 0 ;1
L 3.1825 1.8825 3.1825 1.8825 24 P 0 ;1
L 3.1825 1.9325 3.1825 1.9325 24 P 0 ;1
L 3.1825 1.9825 3.1825 1.9825 24 P 0 ;1
L 3.1825 2.0325 3.1825 2.0325 24 P 0 ;1
L 3.1825 2.0825 3.1825 2.0825 24 P 0 ;1
L 3.1825 2.1325 3.1825 2.1325 24 P 0 ;1
L 3.1825 2.1825 3.1825 2.1825 24 P 0 ;1
L 3.1825 2.2325 3.1825 2.2325 24 P 0 ;1
L 3.1825 2.2825 3.1825 2.2825 24 P 0 ;1
L 3.1825 2.3325 3.1825 2.3325 24 P 0 ;1
L 3.1825 2.3825 3.1825 2.3825 24 P 0 ;1
L 3.1825 2.4325 3.1825 2.4325 24 P 0 ;1
L 3.1825 2.4825 3.1825 2.4825 24 P 0 ;1
L 3.1825 2.5325 3.1825 2.5325 24 P 0 ;1
L 3.1825 2.5825 3.1825 2.5825 24 P 0 ;1
L 3.1825 2.6325 3.1825 2.6325 24 P 0 ;1
L 3.1825 2.6825 3.1825 2.6825 24 P 0 ;1
L 3.1825 2.7325 3.1825 2.7325 24 P 0 ;1
L 3.1825 2.7825 3.1825 2.7825 24 P 0 ;1
L 3.1825 2.8325 3.1825 2.8325 24 P 0 ;1
L 3.1825 2.8825 3.1825 2.8825 24 P 0 ;1
L 3.1825 2.9325 3.1825 2.9325 24 P 0 ;1
L 3.1825 2.9825 3.1825 2.9825 24 P 0 ;1
L 3.1825 3.0325 3.1825 3.0325 24 P 0 ;1
L 3.1825 3.0825 3.1825 3.0825 24 P 0 ;1
L 3.1825 3.1325 3.1825 3.1325 24 P 0 ;1
L 3.1825 3.1825 3.1825 3.1825 24 P 0 ;1
L 3.1825 3.2325 3.1825 3.2325 24 P 0 ;1
L 3.1825 3.2825 3.1825 3.2825 24 P 0 ;1
L 3.1825 3.3325 3.1825 3.3325 24 P 0 ;1
L 3.1825 3.3825 3.1825 3.3825 24 P 0 ;1
L 3.1825 3.4325 3.1825 3.4325 24 P 0 ;1
L 3.1825 3.4825 3.1825 3.4825 24 P 0 ;1
L 3.1825 3.5325 3.1825 3.5325 24 P 0 ;1
L 3.1825 3.5825 3.1825 3.5825 24 P 0 ;1
L 3.1825 3.6325 3.1825 3.6325 24 P 0 ;1
L 3.1825 3.6825 3.1825 3.6825 24 P 0 ;1
L 3.1825 3.7325 3.1825 3.7325 24 P 0 ;1
L 3.1825 3.7825 3.1825 3.7825 24 P 0 ;1
L 3.1825 3.8325 3.1825 3.8325 24 P 0 ;1
L 3.1825 3.8825 3.1825 3.8825 24 P 0 ;1
L 3.1825 3.9325 3.1825 3.9325 24 P 0 ;1
L 3.1825 3.9825 3.1825 3.9825 24 P 0 ;1
L 3.1825 4.0325 3.1825 4.0325 24 P 0 ;1
L 3.1825 4.0825 3.1825 4.0825 24 P 0 ;1
L 3.1825 4.1325 3.1825 4.1325 24 P 0 ;1
L 3.1825 4.1825 3.1825 4.1825 24 P 0 ;1
L 3.2325 0.1325 3.2325 0.1325 24 P 0 ;1
L 3.2325 0.1825 3.2325 0.1825 24 P 0 ;1
L 3.2325 0.4325 3.2325 0.4325 24 P 0 ;1
L 3.2325 0.4825 3.2325 0.4825 24 P 0 ;1
L 3.2325 0.5325 3.2325 0.5325 24 P 0 ;1
L 3.2325 0.5825 3.2325 0.5825 24 P 0 ;1
L 3.2325 0.6325 3.2325 0.6325 24 P 0 ;1
L 3.2325 0.6825 3.2325 0.6825 24 P 0 ;1
L 3.2325 0.7325 3.2325 0.7325 24 P 0 ;1
L 3.2325 0.7825 3.2325 0.7825 24 P 0 ;1
L 3.2325 0.8325 3.2325 0.8325 24 P 0 ;1
L 3.2325 0.8825 3.2325 0.8825 24 P 0 ;1
L 3.2325 0.9325 3.2325 0.9325 24 P 0 ;1
L 3.2325 0.9825 3.2325 0.9825 24 P 0 ;1
L 3.2325 1.0325 3.2325 1.0325 24 P 0 ;1
L 3.2325 1.0825 3.2325 1.0825 24 P 0 ;1
L 3.2325 1.1325 3.2325 1.1325 24 P 0 ;1
L 3.2325 1.1825 3.2325 1.1825 24 P 0 ;1
L 3.2325 1.2325 3.2325 1.2325 24 P 0 ;1
L 3.2325 1.2825 3.2325 1.2825 24 P 0 ;1
L 3.2325 1.3325 3.2325 1.3325 24 P 0 ;1
L 3.2325 1.3825 3.2325 1.3825 24 P 0 ;1
L 3.2325 1.4325 3.2325 1.4325 24 P 0 ;1
L 3.2325 1.4825 3.2325 1.4825 24 P 0 ;1
L 3.2325 1.5325 3.2325 1.5325 24 P 0 ;1
L 3.2325 1.5825 3.2325 1.5825 24 P 0 ;1
L 3.2325 1.6325 3.2325 1.6325 24 P 0 ;1
L 3.2325 1.6825 3.2325 1.6825 24 P 0 ;1
L 3.2325 1.7325 3.2325 1.7325 24 P 0 ;1
L 3.2325 1.7825 3.2325 1.7825 24 P 0 ;1
L 3.2325 1.8325 3.2325 1.8325 24 P 0 ;1
L 3.2325 1.8825 3.2325 1.8825 24 P 0 ;1
L 3.2325 1.9325 3.2325 1.9325 24 P 0 ;1
L 3.2325 1.9825 3.2325 1.9825 24 P 0 ;1
L 3.2325 2.0325 3.2325 2.0325 24 P 0 ;1
L 3.2325 2.0825 3.2325 2.0825 24 P 0 ;1
L 3.2325 2.1325 3.2325 2.1325 24 P 0 ;1
L 3.2325 2.1825 3.2325 2.1825 24 P 0 ;1
L 3.2325 2.2325 3.2325 2.2325 24 P 0 ;1
L 3.2325 2.2825 3.2325 2.2825 24 P 0 ;1
L 3.2325 2.3325 3.2325 2.3325 24 P 0 ;1
L 3.2325 2.3825 3.2325 2.3825 24 P 0 ;1
L 3.2325 2.4325 3.2325 2.4325 24 P 0 ;1
L 3.2325 2.4825 3.2325 2.4825 24 P 0 ;1
L 3.2325 2.5325 3.2325 2.5325 24 P 0 ;1
L 3.2325 2.5825 3.2325 2.5825 24 P 0 ;1
L 3.2325 2.6325 3.2325 2.6325 24 P 0 ;1
L 3.2325 2.6825 3.2325 2.6825 24 P 0 ;1
L 3.2325 2.7325 3.2325 2.7325 24 P 0 ;1
L 3.2325 2.7825 3.2325 2.7825 24 P 0 ;1
L 3.2325 2.8325 3.2325 2.8325 24 P 0 ;1
L 3.2325 2.8825 3.2325 2.8825 24 P 0 ;1
L 3.2325 2.9325 3.2325 2.9325 24 P 0 ;1
L 3.2325 2.9825 3.2325 2.9825 24 P 0 ;1
L 3.2325 3.0325 3.2325 3.0325 24 P 0 ;1
L 3.2325 3.0825 3.2325 3.0825 24 P 0 ;1
L 3.2325 3.1325 3.2325 3.1325 24 P 0 ;1
L 3.2325 3.1825 3.2325 3.1825 24 P 0 ;1
L 3.2325 3.2325 3.2325 3.2325 24 P 0 ;1
L 3.2325 3.2825 3.2325 3.2825 24 P 0 ;1
L 3.2325 3.3325 3.2325 3.3325 24 P 0 ;1
L 3.2325 3.3825 3.2325 3.3825 24 P 0 ;1
L 3.2325 3.4325 3.2325 3.4325 24 P 0 ;1
L 3.2325 3.4825 3.2325 3.4825 24 P 0 ;1
L 3.2325 3.5325 3.2325 3.5325 24 P 0 ;1
L 3.2325 3.5825 3.2325 3.5825 24 P 0 ;1
L 3.2325 3.6325 3.2325 3.6325 24 P 0 ;1
L 3.2325 3.6825 3.2325 3.6825 24 P 0 ;1
L 3.2325 3.7325 3.2325 3.7325 24 P 0 ;1
L 3.2325 3.7825 3.2325 3.7825 24 P 0 ;1
L 3.2325 3.8325 3.2325 3.8325 24 P 0 ;1
L 3.2325 3.8825 3.2325 3.8825 24 P 0 ;1
L 3.2325 3.9325 3.2325 3.9325 24 P 0 ;1
L 3.2325 3.9825 3.2325 3.9825 24 P 0 ;1
L 3.2325 4.0325 3.2325 4.0325 24 P 0 ;1
L 3.2325 4.0825 3.2325 4.0825 24 P 0 ;1
L 3.2325 4.1325 3.2325 4.1325 24 P 0 ;1
L 3.2325 4.1825 3.2325 4.1825 24 P 0 ;1
L 3.2825 0.1325 3.2825 0.1325 24 P 0 ;1
L 3.2825 0.1825 3.2825 0.1825 24 P 0 ;1
L 3.2825 0.4325 3.2825 0.4325 24 P 0 ;1
L 3.2825 0.4825 3.2825 0.4825 24 P 0 ;1
L 3.2825 0.5325 3.2825 0.5325 24 P 0 ;1
L 3.2825 0.5825 3.2825 0.5825 24 P 0 ;1
L 3.2825 0.6325 3.2825 0.6325 24 P 0 ;1
L 3.2825 0.6825 3.2825 0.6825 24 P 0 ;1
L 3.2825 0.7325 3.2825 0.7325 24 P 0 ;1
L 3.2825 0.7825 3.2825 0.7825 24 P 0 ;1
L 3.2825 0.8325 3.2825 0.8325 24 P 0 ;1
L 3.2825 0.8825 3.2825 0.8825 24 P 0 ;1
L 3.2825 0.9325 3.2825 0.9325 24 P 0 ;1
L 3.2825 0.9825 3.2825 0.9825 24 P 0 ;1
L 3.2825 1.0325 3.2825 1.0325 24 P 0 ;1
L 3.2825 1.0825 3.2825 1.0825 24 P 0 ;1
L 3.2825 1.1325 3.2825 1.1325 24 P 0 ;1
L 3.2825 1.1825 3.2825 1.1825 24 P 0 ;1
L 3.2825 1.2325 3.2825 1.2325 24 P 0 ;1
L 3.2825 1.2825 3.2825 1.2825 24 P 0 ;1
L 3.2825 1.3325 3.2825 1.3325 24 P 0 ;1
L 3.2825 1.3825 3.2825 1.3825 24 P 0 ;1
L 3.2825 1.4325 3.2825 1.4325 24 P 0 ;1
L 3.2825 1.4825 3.2825 1.4825 24 P 0 ;1
L 3.2825 1.5325 3.2825 1.5325 24 P 0 ;1
L 3.2825 1.5825 3.2825 1.5825 24 P 0 ;1
L 3.2825 1.6325 3.2825 1.6325 24 P 0 ;1
L 3.2825 1.6825 3.2825 1.6825 24 P 0 ;1
L 3.2825 1.7325 3.2825 1.7325 24 P 0 ;1
L 3.2825 1.7825 3.2825 1.7825 24 P 0 ;1
L 3.2825 1.8325 3.2825 1.8325 24 P 0 ;1
L 3.2825 1.8825 3.2825 1.8825 24 P 0 ;1
L 3.2825 1.9325 3.2825 1.9325 24 P 0 ;1
L 3.2825 1.9825 3.2825 1.9825 24 P 0 ;1
L 3.2825 2.0325 3.2825 2.0325 24 P 0 ;1
L 3.2825 2.0825 3.2825 2.0825 24 P 0 ;1
L 3.2825 2.1325 3.2825 2.1325 24 P 0 ;1
L 3.2825 2.1825 3.2825 2.1825 24 P 0 ;1
L 3.2825 2.2325 3.2825 2.2325 24 P 0 ;1
L 3.2825 2.2825 3.2825 2.2825 24 P 0 ;1
L 3.2825 2.3325 3.2825 2.3325 24 P 0 ;1
L 3.2825 2.3825 3.2825 2.3825 24 P 0 ;1
L 3.2825 2.4325 3.2825 2.4325 24 P 0 ;1
L 3.2825 2.4825 3.2825 2.4825 24 P 0 ;1
L 3.2825 2.5325 3.2825 2.5325 24 P 0 ;1
L 3.2825 2.5825 3.2825 2.5825 24 P 0 ;1
L 3.2825 2.6325 3.2825 2.6325 24 P 0 ;1
L 3.2825 2.6825 3.2825 2.6825 24 P 0 ;1
L 3.2825 2.7325 3.2825 2.7325 24 P 0 ;1
L 3.2825 2.7825 3.2825 2.7825 24 P 0 ;1
L 3.2825 2.8325 3.2825 2.8325 24 P 0 ;1
L 3.2825 2.8825 3.2825 2.8825 24 P 0 ;1
L 3.2825 2.9325 3.2825 2.9325 24 P 0 ;1
L 3.2825 2.9825 3.2825 2.9825 24 P 0 ;1
L 3.2825 3.0325 3.2825 3.0325 24 P 0 ;1
L 3.2825 3.0825 3.2825 3.0825 24 P 0 ;1
L 3.2825 3.1325 3.2825 3.1325 24 P 0 ;1
L 3.2825 3.1825 3.2825 3.1825 24 P 0 ;1
L 3.2825 3.2325 3.2825 3.2325 24 P 0 ;1
L 3.2825 3.2825 3.2825 3.2825 24 P 0 ;1
L 3.2825 3.3325 3.2825 3.3325 24 P 0 ;1
L 3.2825 3.3825 3.2825 3.3825 24 P 0 ;1
L 3.2825 3.4325 3.2825 3.4325 24 P 0 ;1
L 3.2825 3.4825 3.2825 3.4825 24 P 0 ;1
L 3.2825 3.5325 3.2825 3.5325 24 P 0 ;1
L 3.2825 3.5825 3.2825 3.5825 24 P 0 ;1
L 3.2825 3.6325 3.2825 3.6325 24 P 0 ;1
L 3.2825 3.6825 3.2825 3.6825 24 P 0 ;1
L 3.2825 3.7325 3.2825 3.7325 24 P 0 ;1
L 3.2825 3.7825 3.2825 3.7825 24 P 0 ;1
L 3.2825 3.8325 3.2825 3.8325 24 P 0 ;1
L 3.2825 3.8825 3.2825 3.8825 24 P 0 ;1
L 3.2825 3.9325 3.2825 3.9325 24 P 0 ;1
L 3.2825 3.9825 3.2825 3.9825 24 P 0 ;1
L 3.2825 4.0325 3.2825 4.0325 24 P 0 ;1
L 3.2825 4.0825 3.2825 4.0825 24 P 0 ;1
L 3.2825 4.1325 3.2825 4.1325 24 P 0 ;1
L 3.2825 4.1825 3.2825 4.1825 24 P 0 ;1
L 3.2825 4.4325 3.2825 4.4325 24 P 0 ;1
L 3.2825 4.4825 3.2825 4.4825 24 P 0 ;1
L 3.2825 4.5325 3.2825 4.5325 24 P 0 ;1
L 3.3325 0.1325 3.3325 0.1325 24 P 0 ;1
L 3.3325 0.1825 3.3325 0.1825 24 P 0 ;1
L 3.3325 0.4325 3.3325 0.4325 24 P 0 ;1
L 3.3325 0.4825 3.3325 0.4825 24 P 0 ;1
L 3.3325 0.5325 3.3325 0.5325 24 P 0 ;1
L 3.3325 0.5825 3.3325 0.5825 24 P 0 ;1
L 3.3325 0.6325 3.3325 0.6325 24 P 0 ;1
L 3.3325 0.6825 3.3325 0.6825 24 P 0 ;1
L 3.3325 0.7325 3.3325 0.7325 24 P 0 ;1
L 3.3325 0.7825 3.3325 0.7825 24 P 0 ;1
L 3.3325 0.8325 3.3325 0.8325 24 P 0 ;1
L 3.3325 0.8825 3.3325 0.8825 24 P 0 ;1
L 3.3325 0.9325 3.3325 0.9325 24 P 0 ;1
L 3.3325 0.9825 3.3325 0.9825 24 P 0 ;1
L 3.3325 1.0325 3.3325 1.0325 24 P 0 ;1
L 3.3325 1.0825 3.3325 1.0825 24 P 0 ;1
L 3.3325 1.1325 3.3325 1.1325 24 P 0 ;1
L 3.3325 1.1825 3.3325 1.1825 24 P 0 ;1
L 3.3325 1.2325 3.3325 1.2325 24 P 0 ;1
L 3.3325 1.2825 3.3325 1.2825 24 P 0 ;1
L 3.3325 1.3325 3.3325 1.3325 24 P 0 ;1
L 3.3325 1.3825 3.3325 1.3825 24 P 0 ;1
L 3.3325 1.4325 3.3325 1.4325 24 P 0 ;1
L 3.3325 1.4825 3.3325 1.4825 24 P 0 ;1
L 3.3325 1.5325 3.3325 1.5325 24 P 0 ;1
L 3.3325 1.5825 3.3325 1.5825 24 P 0 ;1
L 3.3325 1.6325 3.3325 1.6325 24 P 0 ;1
L 3.3325 1.6825 3.3325 1.6825 24 P 0 ;1
L 3.3325 1.7325 3.3325 1.7325 24 P 0 ;1
L 3.3325 1.7825 3.3325 1.7825 24 P 0 ;1
L 3.3325 1.8325 3.3325 1.8325 24 P 0 ;1
L 3.3325 1.8825 3.3325 1.8825 24 P 0 ;1
L 3.3325 1.9325 3.3325 1.9325 24 P 0 ;1
L 3.3325 1.9825 3.3325 1.9825 24 P 0 ;1
L 3.3325 2.0325 3.3325 2.0325 24 P 0 ;1
L 3.3325 2.0825 3.3325 2.0825 24 P 0 ;1
L 3.3325 2.1325 3.3325 2.1325 24 P 0 ;1
L 3.3325 2.1825 3.3325 2.1825 24 P 0 ;1
L 3.3325 2.2325 3.3325 2.2325 24 P 0 ;1
L 3.3325 2.2825 3.3325 2.2825 24 P 0 ;1
L 3.3325 2.3325 3.3325 2.3325 24 P 0 ;1
L 3.3325 2.3825 3.3325 2.3825 24 P 0 ;1
L 3.3325 2.4325 3.3325 2.4325 24 P 0 ;1
L 3.3325 2.4825 3.3325 2.4825 24 P 0 ;1
L 3.3325 2.5325 3.3325 2.5325 24 P 0 ;1
L 3.3325 2.5825 3.3325 2.5825 24 P 0 ;1
L 3.3325 2.6325 3.3325 2.6325 24 P 0 ;1
L 3.3325 2.6825 3.3325 2.6825 24 P 0 ;1
L 3.3325 2.7325 3.3325 2.7325 24 P 0 ;1
L 3.3325 2.7825 3.3325 2.7825 24 P 0 ;1
L 3.3325 2.8325 3.3325 2.8325 24 P 0 ;1
L 3.3325 2.8825 3.3325 2.8825 24 P 0 ;1
L 3.3325 2.9325 3.3325 2.9325 24 P 0 ;1
L 3.3325 2.9825 3.3325 2.9825 24 P 0 ;1
L 3.3325 3.0325 3.3325 3.0325 24 P 0 ;1
L 3.3325 3.0825 3.3325 3.0825 24 P 0 ;1
L 3.3325 3.1325 3.3325 3.1325 24 P 0 ;1
L 3.3325 3.1825 3.3325 3.1825 24 P 0 ;1
L 3.3325 3.2325 3.3325 3.2325 24 P 0 ;1
L 3.3325 3.2825 3.3325 3.2825 24 P 0 ;1
L 3.3325 3.3325 3.3325 3.3325 24 P 0 ;1
L 3.3325 3.3825 3.3325 3.3825 24 P 0 ;1
L 3.3325 3.4325 3.3325 3.4325 24 P 0 ;1
L 3.3325 3.4825 3.3325 3.4825 24 P 0 ;1
L 3.3325 3.5325 3.3325 3.5325 24 P 0 ;1
L 3.3325 3.5825 3.3325 3.5825 24 P 0 ;1
L 3.3325 3.6325 3.3325 3.6325 24 P 0 ;1
L 3.3325 3.6825 3.3325 3.6825 24 P 0 ;1
L 3.3325 3.7325 3.3325 3.7325 24 P 0 ;1
L 3.3325 3.7825 3.3325 3.7825 24 P 0 ;1
L 3.3325 3.8325 3.3325 3.8325 24 P 0 ;1
L 3.3325 3.8825 3.3325 3.8825 24 P 0 ;1
L 3.3325 3.9325 3.3325 3.9325 24 P 0 ;1
L 3.3325 3.9825 3.3325 3.9825 24 P 0 ;1
L 3.3325 4.0325 3.3325 4.0325 24 P 0 ;1
L 3.3325 4.0825 3.3325 4.0825 24 P 0 ;1
L 3.3325 4.1325 3.3325 4.1325 24 P 0 ;1
L 3.3325 4.1825 3.3325 4.1825 24 P 0 ;1
L 3.3325 4.4325 3.3325 4.4325 24 P 0 ;1
L 3.3325 4.4825 3.3325 4.4825 24 P 0 ;1
L 3.3325 4.5325 3.3325 4.5325 24 P 0 ;1
L 3.3825 0.1325 3.3825 0.1325 24 P 0 ;1
L 3.3825 0.1825 3.3825 0.1825 24 P 0 ;1
L 3.3825 0.4325 3.3825 0.4325 24 P 0 ;1
L 3.3825 0.4825 3.3825 0.4825 24 P 0 ;1
L 3.3825 0.5325 3.3825 0.5325 24 P 0 ;1
L 3.3825 0.5825 3.3825 0.5825 24 P 0 ;1
L 3.3825 0.6325 3.3825 0.6325 24 P 0 ;1
L 3.3825 0.6825 3.3825 0.6825 24 P 0 ;1
L 3.3825 0.7325 3.3825 0.7325 24 P 0 ;1
L 3.3825 0.7825 3.3825 0.7825 24 P 0 ;1
L 3.3825 0.8325 3.3825 0.8325 24 P 0 ;1
L 3.3825 0.8825 3.3825 0.8825 24 P 0 ;1
L 3.3825 0.9325 3.3825 0.9325 24 P 0 ;1
L 3.3825 0.9825 3.3825 0.9825 24 P 0 ;1
L 3.3825 1.0325 3.3825 1.0325 24 P 0 ;1
L 3.3825 1.0825 3.3825 1.0825 24 P 0 ;1
L 3.3825 1.1325 3.3825 1.1325 24 P 0 ;1
L 3.3825 1.1825 3.3825 1.1825 24 P 0 ;1
L 3.3825 1.2325 3.3825 1.2325 24 P 0 ;1
L 3.3825 1.2825 3.3825 1.2825 24 P 0 ;1
L 3.3825 1.3325 3.3825 1.3325 24 P 0 ;1
L 3.3825 1.3825 3.3825 1.3825 24 P 0 ;1
L 3.3825 1.4325 3.3825 1.4325 24 P 0 ;1
L 3.3825 1.4825 3.3825 1.4825 24 P 0 ;1
L 3.3825 1.5325 3.3825 1.5325 24 P 0 ;1
L 3.3825 1.5825 3.3825 1.5825 24 P 0 ;1
L 3.3825 1.6325 3.3825 1.6325 24 P 0 ;1
L 3.3825 1.6825 3.3825 1.6825 24 P 0 ;1
L 3.3825 1.7325 3.3825 1.7325 24 P 0 ;1
L 3.3825 1.7825 3.3825 1.7825 24 P 0 ;1
L 3.3825 1.8325 3.3825 1.8325 24 P 0 ;1
L 3.3825 1.8825 3.3825 1.8825 24 P 0 ;1
L 3.3825 1.9325 3.3825 1.9325 24 P 0 ;1
L 3.3825 1.9825 3.3825 1.9825 24 P 0 ;1
L 3.3825 2.0325 3.3825 2.0325 24 P 0 ;1
L 3.3825 2.0825 3.3825 2.0825 24 P 0 ;1
L 3.3825 2.1325 3.3825 2.1325 24 P 0 ;1
L 3.3825 2.1825 3.3825 2.1825 24 P 0 ;1
L 3.3825 2.2325 3.3825 2.2325 24 P 0 ;1
L 3.3825 2.2825 3.3825 2.2825 24 P 0 ;1
L 3.3825 2.3325 3.3825 2.3325 24 P 0 ;1
L 3.3825 2.3825 3.3825 2.3825 24 P 0 ;1
L 3.3825 2.4325 3.3825 2.4325 24 P 0 ;1
L 3.3825 2.4825 3.3825 2.4825 24 P 0 ;1
L 3.3825 2.5325 3.3825 2.5325 24 P 0 ;1
L 3.3825 2.5825 3.3825 2.5825 24 P 0 ;1
L 3.3825 2.6325 3.3825 2.6325 24 P 0 ;1
L 3.3825 2.6825 3.3825 2.6825 24 P 0 ;1
L 3.3825 2.7325 3.3825 2.7325 24 P 0 ;1
L 3.3825 2.7825 3.3825 2.7825 24 P 0 ;1
L 3.3825 2.8325 3.3825 2.8325 24 P 0 ;1
L 3.3825 2.8825 3.3825 2.8825 24 P 0 ;1
L 3.3825 2.9325 3.3825 2.9325 24 P 0 ;1
L 3.3825 2.9825 3.3825 2.9825 24 P 0 ;1
L 3.3825 3.0325 3.3825 3.0325 24 P 0 ;1
L 3.3825 3.0825 3.3825 3.0825 24 P 0 ;1
L 3.3825 3.1325 3.3825 3.1325 24 P 0 ;1
L 3.3825 3.1825 3.3825 3.1825 24 P 0 ;1
L 3.3825 3.2325 3.3825 3.2325 24 P 0 ;1
L 3.3825 3.2825 3.3825 3.2825 24 P 0 ;1
L 3.3825 3.3325 3.3825 3.3325 24 P 0 ;1
L 3.3825 3.3825 3.3825 3.3825 24 P 0 ;1
L 3.3825 3.4325 3.3825 3.4325 24 P 0 ;1
L 3.3825 3.4825 3.3825 3.4825 24 P 0 ;1
L 3.3825 3.5325 3.3825 3.5325 24 P 0 ;1
L 3.3825 3.5825 3.3825 3.5825 24 P 0 ;1
L 3.3825 3.6325 3.3825 3.6325 24 P 0 ;1
L 3.3825 3.6825 3.3825 3.6825 24 P 0 ;1
L 3.3825 3.7325 3.3825 3.7325 24 P 0 ;1
L 3.3825 3.7825 3.3825 3.7825 24 P 0 ;1
L 3.3825 3.8325 3.3825 3.8325 24 P 0 ;1
L 3.3825 3.8825 3.3825 3.8825 24 P 0 ;1
L 3.3825 3.9325 3.3825 3.9325 24 P 0 ;1
L 3.3825 3.9825 3.3825 3.9825 24 P 0 ;1
L 3.3825 4.0325 3.3825 4.0325 24 P 0 ;1
L 3.3825 4.0825 3.3825 4.0825 24 P 0 ;1
L 3.3825 4.1325 3.3825 4.1325 24 P 0 ;1
L 3.3825 4.1825 3.3825 4.1825 24 P 0 ;1
L 3.3825 4.4325 3.3825 4.4325 24 P 0 ;1
L 3.3825 4.4825 3.3825 4.4825 24 P 0 ;1
L 3.4325 0.1325 3.4325 0.1325 24 P 0 ;1
L 3.4325 0.1825 3.4325 0.1825 24 P 0 ;1
L 3.4325 0.4325 3.4325 0.4325 24 P 0 ;1
L 3.4325 0.4825 3.4325 0.4825 24 P 0 ;1
L 3.4325 0.5325 3.4325 0.5325 24 P 0 ;1
L 3.4325 0.5825 3.4325 0.5825 24 P 0 ;1
L 3.4325 0.6325 3.4325 0.6325 24 P 0 ;1
L 3.4325 0.6825 3.4325 0.6825 24 P 0 ;1
L 3.4325 0.7325 3.4325 0.7325 24 P 0 ;1
L 3.4325 0.7825 3.4325 0.7825 24 P 0 ;1
L 3.4325 0.8325 3.4325 0.8325 24 P 0 ;1
L 3.4325 0.8825 3.4325 0.8825 24 P 0 ;1
L 3.4325 0.9325 3.4325 0.9325 24 P 0 ;1
L 3.4325 0.9825 3.4325 0.9825 24 P 0 ;1
L 3.4325 1.0325 3.4325 1.0325 24 P 0 ;1
L 3.4325 1.0825 3.4325 1.0825 24 P 0 ;1
L 3.4325 1.1325 3.4325 1.1325 24 P 0 ;1
L 3.4325 1.1825 3.4325 1.1825 24 P 0 ;1
L 3.4325 1.2325 3.4325 1.2325 24 P 0 ;1
L 3.4325 1.2825 3.4325 1.2825 24 P 0 ;1
L 3.4325 1.3325 3.4325 1.3325 24 P 0 ;1
L 3.4325 1.3825 3.4325 1.3825 24 P 0 ;1
L 3.4325 1.4325 3.4325 1.4325 24 P 0 ;1
L 3.4325 1.4825 3.4325 1.4825 24 P 0 ;1
L 3.4325 1.5325 3.4325 1.5325 24 P 0 ;1
L 3.4325 1.5825 3.4325 1.5825 24 P 0 ;1
L 3.4325 1.6325 3.4325 1.6325 24 P 0 ;1
L 3.4325 1.6825 3.4325 1.6825 24 P 0 ;1
L 3.4325 1.7325 3.4325 1.7325 24 P 0 ;1
L 3.4325 1.7825 3.4325 1.7825 24 P 0 ;1
L 3.4325 1.8325 3.4325 1.8325 24 P 0 ;1
L 3.4325 1.8825 3.4325 1.8825 24 P 0 ;1
L 3.4325 1.9325 3.4325 1.9325 24 P 0 ;1
L 3.4325 1.9825 3.4325 1.9825 24 P 0 ;1
L 3.4325 2.0325 3.4325 2.0325 24 P 0 ;1
L 3.4325 2.0825 3.4325 2.0825 24 P 0 ;1
L 3.4325 2.1325 3.4325 2.1325 24 P 0 ;1
L 3.4325 2.1825 3.4325 2.1825 24 P 0 ;1
L 3.4325 2.2325 3.4325 2.2325 24 P 0 ;1
L 3.4325 2.2825 3.4325 2.2825 24 P 0 ;1
L 3.4325 2.3325 3.4325 2.3325 24 P 0 ;1
L 3.4325 2.3825 3.4325 2.3825 24 P 0 ;1
L 3.4325 2.4325 3.4325 2.4325 24 P 0 ;1
L 3.4325 2.4825 3.4325 2.4825 24 P 0 ;1
L 3.4325 2.5325 3.4325 2.5325 24 P 0 ;1
L 3.4325 2.5825 3.4325 2.5825 24 P 0 ;1
L 3.4325 2.6325 3.4325 2.6325 24 P 0 ;1
L 3.4325 2.6825 3.4325 2.6825 24 P 0 ;1
L 3.4325 2.7325 3.4325 2.7325 24 P 0 ;1
L 3.4325 2.7825 3.4325 2.7825 24 P 0 ;1
L 3.4325 2.8325 3.4325 2.8325 24 P 0 ;1
L 3.4325 2.8825 3.4325 2.8825 24 P 0 ;1
L 3.4325 2.9325 3.4325 2.9325 24 P 0 ;1
L 3.4325 2.9825 3.4325 2.9825 24 P 0 ;1
L 3.4325 3.0325 3.4325 3.0325 24 P 0 ;1
L 3.4325 3.0825 3.4325 3.0825 24 P 0 ;1
L 3.4325 3.1325 3.4325 3.1325 24 P 0 ;1
L 3.4325 3.1825 3.4325 3.1825 24 P 0 ;1
L 3.4325 3.2325 3.4325 3.2325 24 P 0 ;1
L 3.4325 3.2825 3.4325 3.2825 24 P 0 ;1
L 3.4325 3.3325 3.4325 3.3325 24 P 0 ;1
L 3.4325 3.3825 3.4325 3.3825 24 P 0 ;1
L 3.4325 3.4325 3.4325 3.4325 24 P 0 ;1
L 3.4325 3.4825 3.4325 3.4825 24 P 0 ;1
L 3.4325 3.5325 3.4325 3.5325 24 P 0 ;1
L 3.4325 3.5825 3.4325 3.5825 24 P 0 ;1
L 3.4325 3.6325 3.4325 3.6325 24 P 0 ;1
L 3.4325 3.6825 3.4325 3.6825 24 P 0 ;1
L 3.4325 3.7325 3.4325 3.7325 24 P 0 ;1
L 3.4325 3.7825 3.4325 3.7825 24 P 0 ;1
L 3.4325 3.8325 3.4325 3.8325 24 P 0 ;1
L 3.4325 3.8825 3.4325 3.8825 24 P 0 ;1
L 3.4325 3.9325 3.4325 3.9325 24 P 0 ;1
L 3.4325 3.9825 3.4325 3.9825 24 P 0 ;1
L 3.4325 4.0325 3.4325 4.0325 24 P 0 ;1
L 3.4325 4.0825 3.4325 4.0825 24 P 0 ;1
L 3.4325 4.1325 3.4325 4.1325 24 P 0 ;1
L 3.4325 4.1825 3.4325 4.1825 24 P 0 ;1
L 3.4325 4.4325 3.4325 4.4325 24 P 0 ;1
L 3.4325 4.4825 3.4325 4.4825 24 P 0 ;1
L 3.4825 0.1325 3.4825 0.1325 24 P 0 ;1
L 3.4825 0.1825 3.4825 0.1825 24 P 0 ;1
L 3.4825 2.7325 3.4825 2.7325 24 P 0 ;1
L 3.4825 2.7825 3.4825 2.7825 24 P 0 ;1
L 3.4825 2.8325 3.4825 2.8325 24 P 0 ;1
L 3.4825 2.8825 3.4825 2.8825 24 P 0 ;1
L 3.4825 2.9325 3.4825 2.9325 24 P 0 ;1
L 3.4825 2.9825 3.4825 2.9825 24 P 0 ;1
L 3.4825 3.0325 3.4825 3.0325 24 P 0 ;1
L 3.4825 3.0825 3.4825 3.0825 24 P 0 ;1
L 3.4825 3.1325 3.4825 3.1325 24 P 0 ;1
L 3.4825 3.1825 3.4825 3.1825 24 P 0 ;1
L 3.4825 3.2325 3.4825 3.2325 24 P 0 ;1
L 3.4825 3.2825 3.4825 3.2825 24 P 0 ;1
L 3.4825 3.3325 3.4825 3.3325 24 P 0 ;1
L 3.4825 3.3825 3.4825 3.3825 24 P 0 ;1
L 3.4825 3.4325 3.4825 3.4325 24 P 0 ;1
L 3.4825 3.4825 3.4825 3.4825 24 P 0 ;1
L 3.4825 3.5325 3.4825 3.5325 24 P 0 ;1
L 3.4825 3.5825 3.4825 3.5825 24 P 0 ;1
L 3.4825 3.6325 3.4825 3.6325 24 P 0 ;1
L 3.4825 3.6825 3.4825 3.6825 24 P 0 ;1
L 3.4825 3.7325 3.4825 3.7325 24 P 0 ;1
L 3.4825 3.7825 3.4825 3.7825 24 P 0 ;1
L 3.4825 3.8325 3.4825 3.8325 24 P 0 ;1
L 3.4825 3.8825 3.4825 3.8825 24 P 0 ;1
L 3.4825 3.9325 3.4825 3.9325 24 P 0 ;1
L 3.4825 3.9825 3.4825 3.9825 24 P 0 ;1
L 3.4825 4.0325 3.4825 4.0325 24 P 0 ;1
L 3.4825 4.0825 3.4825 4.0825 24 P 0 ;1
L 3.4825 4.1325 3.4825 4.1325 24 P 0 ;1
L 3.4825 4.1825 3.4825 4.1825 24 P 0 ;1
L 3.5325 0.1325 3.5325 0.1325 24 P 0 ;1
L 3.5325 0.1825 3.5325 0.1825 24 P 0 ;1
L 3.5325 2.7825 3.5325 2.7825 24 P 0 ;1
L 3.5325 2.8325 3.5325 2.8325 24 P 0 ;1
L 3.5325 2.8825 3.5325 2.8825 24 P 0 ;1
L 3.5325 2.9325 3.5325 2.9325 24 P 0 ;1
L 3.5325 2.9825 3.5325 2.9825 24 P 0 ;1
L 3.5325 3.0325 3.5325 3.0325 24 P 0 ;1
L 3.5325 3.0825 3.5325 3.0825 24 P 0 ;1
L 3.5325 3.1325 3.5325 3.1325 24 P 0 ;1
L 3.5325 3.1825 3.5325 3.1825 24 P 0 ;1
L 3.5325 3.2325 3.5325 3.2325 24 P 0 ;1
L 3.5325 3.2825 3.5325 3.2825 24 P 0 ;1
L 3.5325 3.3325 3.5325 3.3325 24 P 0 ;1
L 3.5325 3.3825 3.5325 3.3825 24 P 0 ;1
L 3.5325 3.4325 3.5325 3.4325 24 P 0 ;1
L 3.5325 3.4825 3.5325 3.4825 24 P 0 ;1
L 3.5325 3.5325 3.5325 3.5325 24 P 0 ;1
L 3.5325 3.5825 3.5325 3.5825 24 P 0 ;1
L 3.5325 3.6325 3.5325 3.6325 24 P 0 ;1
L 3.5325 3.6825 3.5325 3.6825 24 P 0 ;1
L 3.5325 3.7325 3.5325 3.7325 24 P 0 ;1
L 3.5325 3.7825 3.5325 3.7825 24 P 0 ;1
L 3.5325 3.8325 3.5325 3.8325 24 P 0 ;1
L 3.5325 3.8825 3.5325 3.8825 24 P 0 ;1
L 3.5325 3.9325 3.5325 3.9325 24 P 0 ;1
L 3.5325 3.9825 3.5325 3.9825 24 P 0 ;1
L 3.5325 4.0325 3.5325 4.0325 24 P 0 ;1
L 3.5325 4.0825 3.5325 4.0825 24 P 0 ;1
L 3.5325 4.1325 3.5325 4.1325 24 P 0 ;1
L 3.5325 4.1825 3.5325 4.1825 24 P 0 ;1
L 3.5825 0.1325 3.5825 0.1325 24 P 0 ;1
L 3.5825 2.8325 3.5825 2.8325 24 P 0 ;1
L 3.5825 2.8825 3.5825 2.8825 24 P 0 ;1
L 3.5825 2.9325 3.5825 2.9325 24 P 0 ;1
L 3.5825 2.9825 3.5825 2.9825 24 P 0 ;1
L 3.5825 3.0325 3.5825 3.0325 24 P 0 ;1
L 3.5825 3.0825 3.5825 3.0825 24 P 0 ;1
L 3.5825 3.1325 3.5825 3.1325 24 P 0 ;1
L 3.5825 3.1825 3.5825 3.1825 24 P 0 ;1
L 3.5825 3.2325 3.5825 3.2325 24 P 0 ;1
L 3.5825 3.2825 3.5825 3.2825 24 P 0 ;1
L 3.5825 3.3325 3.5825 3.3325 24 P 0 ;1
L 3.5825 3.3825 3.5825 3.3825 24 P 0 ;1
L 3.5825 3.4325 3.5825 3.4325 24 P 0 ;1
L 3.5825 3.4825 3.5825 3.4825 24 P 0 ;1
L 3.5825 3.5325 3.5825 3.5325 24 P 0 ;1
L 3.5825 3.5825 3.5825 3.5825 24 P 0 ;1
L 3.5825 3.6325 3.5825 3.6325 24 P 0 ;1
L 3.5825 3.6825 3.5825 3.6825 24 P 0 ;1
L 3.5825 3.7325 3.5825 3.7325 24 P 0 ;1
L 3.5825 3.7825 3.5825 3.7825 24 P 0 ;1
L 3.5825 3.8325 3.5825 3.8325 24 P 0 ;1
L 3.5825 3.8825 3.5825 3.8825 24 P 0 ;1
L 3.5825 3.9325 3.5825 3.9325 24 P 0 ;1
L 3.5825 3.9825 3.5825 3.9825 24 P 0 ;1
L 3.5825 4.0325 3.5825 4.0325 24 P 0 ;1
L 3.5825 4.0825 3.5825 4.0825 24 P 0 ;1
L 3.5825 4.1325 3.5825 4.1325 24 P 0 ;1
L 3.5825 4.1825 3.5825 4.1825 24 P 0 ;1
L 3.6325 0.1325 3.6325 0.1325 24 P 0 ;1
L 3.6325 2.8825 3.6325 2.8825 24 P 0 ;1
L 3.6325 2.9325 3.6325 2.9325 24 P 0 ;1
L 3.6325 2.9825 3.6325 2.9825 24 P 0 ;1
L 3.6325 3.0325 3.6325 3.0325 24 P 0 ;1
L 3.6325 3.0825 3.6325 3.0825 24 P 0 ;1
L 3.6325 3.1325 3.6325 3.1325 24 P 0 ;1
L 3.6325 3.1825 3.6325 3.1825 24 P 0 ;1
L 3.6325 3.2325 3.6325 3.2325 24 P 0 ;1
L 3.6325 3.2825 3.6325 3.2825 24 P 0 ;1
L 3.6325 3.3325 3.6325 3.3325 24 P 0 ;1
L 3.6325 3.3825 3.6325 3.3825 24 P 0 ;1
L 3.6325 3.4325 3.6325 3.4325 24 P 0 ;1
L 3.6325 3.4825 3.6325 3.4825 24 P 0 ;1
L 3.6325 3.5325 3.6325 3.5325 24 P 0 ;1
L 3.6325 3.5825 3.6325 3.5825 24 P 0 ;1
L 3.6325 3.6325 3.6325 3.6325 24 P 0 ;1
L 3.6325 3.6825 3.6325 3.6825 24 P 0 ;1
L 3.6325 3.7325 3.6325 3.7325 24 P 0 ;1
L 3.6325 3.7825 3.6325 3.7825 24 P 0 ;1
L 3.6325 3.8325 3.6325 3.8325 24 P 0 ;1
L 3.6325 3.8825 3.6325 3.8825 24 P 0 ;1
L 3.6325 3.9325 3.6325 3.9325 24 P 0 ;1
L 3.6325 3.9825 3.6325 3.9825 24 P 0 ;1
L 3.6325 4.0325 3.6325 4.0325 24 P 0 ;1
L 3.6325 4.0825 3.6325 4.0825 24 P 0 ;1
L 3.6325 4.1325 3.6325 4.1325 24 P 0 ;1
L 3.6325 4.1825 3.6325 4.1825 24 P 0 ;1
L 3.6825 0.1325 3.6825 0.1325 24 P 0 ;1
L 3.6825 2.9325 3.6825 2.9325 24 P 0 ;1
L 3.6825 2.9825 3.6825 2.9825 24 P 0 ;1
L 3.6825 3.0325 3.6825 3.0325 24 P 0 ;1
L 3.6825 3.0825 3.6825 3.0825 24 P 0 ;1
L 3.6825 3.1325 3.6825 3.1325 24 P 0 ;1
L 3.6825 3.1825 3.6825 3.1825 24 P 0 ;1
L 3.6825 3.2325 3.6825 3.2325 24 P 0 ;1
L 3.6825 3.2825 3.6825 3.2825 24 P 0 ;1
L 3.6825 3.3325 3.6825 3.3325 24 P 0 ;1
L 3.6825 3.3825 3.6825 3.3825 24 P 0 ;1
L 3.6825 3.4325 3.6825 3.4325 24 P 0 ;1
L 3.6825 3.4825 3.6825 3.4825 24 P 0 ;1
L 3.6825 3.5325 3.6825 3.5325 24 P 0 ;1
L 3.6825 3.5825 3.6825 3.5825 24 P 0 ;1
L 3.6825 3.6325 3.6825 3.6325 24 P 0 ;1
L 3.6825 3.6825 3.6825 3.6825 24 P 0 ;1
L 3.6825 3.7325 3.6825 3.7325 24 P 0 ;1
L 3.6825 3.7825 3.6825 3.7825 24 P 0 ;1
L 3.6825 3.8325 3.6825 3.8325 24 P 0 ;1
L 3.6825 3.8825 3.6825 3.8825 24 P 0 ;1
L 3.6825 3.9325 3.6825 3.9325 24 P 0 ;1
L 3.6825 3.9825 3.6825 3.9825 24 P 0 ;1
L 3.6825 4.0325 3.6825 4.0325 24 P 0 ;1
L 3.6825 4.0825 3.6825 4.0825 24 P 0 ;1
L 3.6825 4.1325 3.6825 4.1325 24 P 0 ;1
L 3.6825 4.1825 3.6825 4.1825 24 P 0 ;1
L 3.6825 5.8825 3.6825 5.8825 24 P 0 ;1
L 3.7325 0.1325 3.7325 0.1325 24 P 0 ;1
L 3.7325 2.9825 3.7325 2.9825 24 P 0 ;1
L 3.7325 3.0325 3.7325 3.0325 24 P 0 ;1
L 3.7325 3.0825 3.7325 3.0825 24 P 0 ;1
L 3.7325 3.1325 3.7325 3.1325 24 P 0 ;1
L 3.7325 3.1825 3.7325 3.1825 24 P 0 ;1
L 3.7325 3.2325 3.7325 3.2325 24 P 0 ;1
L 3.7325 3.2825 3.7325 3.2825 24 P 0 ;1
L 3.7325 3.3325 3.7325 3.3325 24 P 0 ;1
L 3.7325 3.3825 3.7325 3.3825 24 P 0 ;1
L 3.7325 3.4325 3.7325 3.4325 24 P 0 ;1
L 3.7325 3.4825 3.7325 3.4825 24 P 0 ;1
L 3.7325 3.5325 3.7325 3.5325 24 P 0 ;1
L 3.7325 3.5825 3.7325 3.5825 24 P 0 ;1
L 3.7325 3.6325 3.7325 3.6325 24 P 0 ;1
L 3.7325 3.6825 3.7325 3.6825 24 P 0 ;1
L 3.7325 3.7325 3.7325 3.7325 24 P 0 ;1
L 3.7325 3.7825 3.7325 3.7825 24 P 0 ;1
L 3.7325 3.8325 3.7325 3.8325 24 P 0 ;1
L 3.7325 3.8825 3.7325 3.8825 24 P 0 ;1
L 3.7325 3.9325 3.7325 3.9325 24 P 0 ;1
L 3.7325 3.9825 3.7325 3.9825 24 P 0 ;1
L 3.7325 4.0325 3.7325 4.0325 24 P 0 ;1
L 3.7325 4.0825 3.7325 4.0825 24 P 0 ;1
L 3.7325 4.1325 3.7325 4.1325 24 P 0 ;1
L 3.7325 4.1825 3.7325 4.1825 24 P 0 ;1
L 3.7325 5.8825 3.7325 5.8825 24 P 0 ;1
L 3.7825 0.1325 3.7825 0.1325 24 P 0 ;1
L 3.7825 0.4825 3.7825 0.4825 24 P 0 ;1
L 3.7825 3.0325 3.7825 3.0325 24 P 0 ;1
L 3.7825 3.0825 3.7825 3.0825 24 P 0 ;1
L 3.7825 3.1325 3.7825 3.1325 24 P 0 ;1
L 3.7825 3.1825 3.7825 3.1825 24 P 0 ;1
L 3.7825 3.2325 3.7825 3.2325 24 P 0 ;1
L 3.7825 3.2825 3.7825 3.2825 24 P 0 ;1
L 3.7825 3.3325 3.7825 3.3325 24 P 0 ;1
L 3.7825 3.3825 3.7825 3.3825 24 P 0 ;1
L 3.7825 3.4325 3.7825 3.4325 24 P 0 ;1
L 3.7825 3.4825 3.7825 3.4825 24 P 0 ;1
L 3.7825 3.5325 3.7825 3.5325 24 P 0 ;1
L 3.7825 3.5825 3.7825 3.5825 24 P 0 ;1
L 3.7825 3.6325 3.7825 3.6325 24 P 0 ;1
L 3.7825 3.6825 3.7825 3.6825 24 P 0 ;1
L 3.7825 3.7325 3.7825 3.7325 24 P 0 ;1
L 3.7825 3.7825 3.7825 3.7825 24 P 0 ;1
L 3.7825 3.8325 3.7825 3.8325 24 P 0 ;1
L 3.7825 3.8825 3.7825 3.8825 24 P 0 ;1
L 3.7825 3.9325 3.7825 3.9325 24 P 0 ;1
L 3.7825 3.9825 3.7825 3.9825 24 P 0 ;1
L 3.7825 4.0325 3.7825 4.0325 24 P 0 ;1
L 3.7825 4.0825 3.7825 4.0825 24 P 0 ;1
L 3.7825 4.1325 3.7825 4.1325 24 P 0 ;1
L 3.7825 4.1825 3.7825 4.1825 24 P 0 ;1
L 3.8325 0.1325 3.8325 0.1325 24 P 0 ;1
L 3.8325 0.4325 3.8325 0.4325 24 P 0 ;1
L 3.8325 0.4825 3.8325 0.4825 24 P 0 ;1
L 3.8325 0.5325 3.8325 0.5325 24 P 0 ;1
L 3.8325 3.0825 3.8325 3.0825 24 P 0 ;1
L 3.8325 3.1325 3.8325 3.1325 24 P 0 ;1
L 3.8325 3.1825 3.8325 3.1825 24 P 0 ;1
L 3.8325 3.2325 3.8325 3.2325 24 P 0 ;1
L 3.8325 3.2825 3.8325 3.2825 24 P 0 ;1
L 3.8325 3.3325 3.8325 3.3325 24 P 0 ;1
L 3.8325 3.3825 3.8325 3.3825 24 P 0 ;1
L 3.8325 3.4325 3.8325 3.4325 24 P 0 ;1
L 3.8325 3.4825 3.8325 3.4825 24 P 0 ;1
L 3.8325 3.5325 3.8325 3.5325 24 P 0 ;1
L 3.8325 3.5825 3.8325 3.5825 24 P 0 ;1
L 3.8325 3.6325 3.8325 3.6325 24 P 0 ;1
L 3.8325 3.6825 3.8325 3.6825 24 P 0 ;1
L 3.8325 3.7325 3.8325 3.7325 24 P 0 ;1
L 3.8325 3.7825 3.8325 3.7825 24 P 0 ;1
L 3.8325 3.8325 3.8325 3.8325 24 P 0 ;1
L 3.8325 3.8825 3.8325 3.8825 24 P 0 ;1
L 3.8325 3.9325 3.8325 3.9325 24 P 0 ;1
L 3.8325 3.9825 3.8325 3.9825 24 P 0 ;1
L 3.8325 4.0325 3.8325 4.0325 24 P 0 ;1
L 3.8325 4.0825 3.8325 4.0825 24 P 0 ;1
L 3.8325 4.1325 3.8325 4.1325 24 P 0 ;1
L 3.8325 4.4325 3.8325 4.4325 24 P 0 ;1
L 3.8325 5.6325 3.8325 5.6325 24 P 0 ;1
L 3.8325 5.6825 3.8325 5.6825 24 P 0 ;1
L 3.8825 0.1325 3.8825 0.1325 24 P 0 ;1
L 3.8825 0.1825 3.8825 0.1825 24 P 0 ;1
L 3.8825 3.0825 3.8825 3.0825 24 P 0 ;1
L 3.8825 3.1325 3.8825 3.1325 24 P 0 ;1
L 3.8825 3.1825 3.8825 3.1825 24 P 0 ;1
L 3.8825 3.2325 3.8825 3.2325 24 P 0 ;1
L 3.8825 3.2825 3.8825 3.2825 24 P 0 ;1
L 3.8825 3.3325 3.8825 3.3325 24 P 0 ;1
L 3.8825 3.3825 3.8825 3.3825 24 P 0 ;1
L 3.8825 3.4325 3.8825 3.4325 24 P 0 ;1
L 3.8825 3.4825 3.8825 3.4825 24 P 0 ;1
L 3.8825 3.5325 3.8825 3.5325 24 P 0 ;1
L 3.8825 3.5825 3.8825 3.5825 24 P 0 ;1
L 3.8825 3.6325 3.8825 3.6325 24 P 0 ;1
L 3.8825 3.6825 3.8825 3.6825 24 P 0 ;1
L 3.8825 3.7325 3.8825 3.7325 24 P 0 ;1
L 3.8825 3.7825 3.8825 3.7825 24 P 0 ;1
L 3.8825 3.8325 3.8825 3.8325 24 P 0 ;1
L 3.8825 3.8825 3.8825 3.8825 24 P 0 ;1
L 3.8825 3.9325 3.8825 3.9325 24 P 0 ;1
L 3.8825 3.9825 3.8825 3.9825 24 P 0 ;1
L 3.8825 4.0325 3.8825 4.0325 24 P 0 ;1
L 3.8825 4.0825 3.8825 4.0825 24 P 0 ;1
L 3.8825 5.6325 3.8825 5.6325 24 P 0 ;1
L 3.8825 5.6825 3.8825 5.6825 24 P 0 ;1
L 3.8825 5.7325 3.8825 5.7325 24 P 0 ;1
L 3.9325 0.1325 3.9325 0.1325 24 P 0 ;1
L 3.9325 0.1825 3.9325 0.1825 24 P 0 ;1
L 3.9325 3.0825 3.9325 3.0825 24 P 0 ;1
L 3.9325 3.1325 3.9325 3.1325 24 P 0 ;1
L 3.9325 3.1825 3.9325 3.1825 24 P 0 ;1
L 3.9325 3.2325 3.9325 3.2325 24 P 0 ;1
L 3.9325 3.2825 3.9325 3.2825 24 P 0 ;1
L 3.9325 3.3325 3.9325 3.3325 24 P 0 ;1
L 3.9325 3.3825 3.9325 3.3825 24 P 0 ;1
L 3.9325 3.4325 3.9325 3.4325 24 P 0 ;1
L 3.9325 3.4825 3.9325 3.4825 24 P 0 ;1
L 3.9325 3.5325 3.9325 3.5325 24 P 0 ;1
L 3.9325 3.5825 3.9325 3.5825 24 P 0 ;1
L 3.9325 3.6325 3.9325 3.6325 24 P 0 ;1
L 3.9325 3.6825 3.9325 3.6825 24 P 0 ;1
L 3.9325 3.7325 3.9325 3.7325 24 P 0 ;1
L 3.9325 3.7825 3.9325 3.7825 24 P 0 ;1
L 3.9325 3.8325 3.9325 3.8325 24 P 0 ;1
L 3.9325 3.8825 3.9325 3.8825 24 P 0 ;1
L 3.9325 3.9325 3.9325 3.9325 24 P 0 ;1
L 3.9325 3.9825 3.9325 3.9825 24 P 0 ;1
L 3.9325 4.0325 3.9325 4.0325 24 P 0 ;1
L 3.9325 5.6325 3.9325 5.6325 24 P 0 ;1
L 3.9325 5.6825 3.9325 5.6825 24 P 0 ;1
L 3.9325 5.7325 3.9325 5.7325 24 P 0 ;1
L 3.9325 5.7825 3.9325 5.7825 24 P 0 ;1
L 3.9325 5.8325 3.9325 5.8325 24 P 0 ;1
L 3.9325 5.8825 3.9325 5.8825 24 P 0 ;1
L 3.9825 0.1325 3.9825 0.1325 24 P 0 ;1
L 3.9825 0.1825 3.9825 0.1825 24 P 0 ;1
L 3.9825 0.2325 3.9825 0.2325 24 P 0 ;1
L 3.9825 3.0825 3.9825 3.0825 24 P 0 ;1
L 3.9825 3.1325 3.9825 3.1325 24 P 0 ;1
L 3.9825 3.1825 3.9825 3.1825 24 P 0 ;1
L 3.9825 3.2325 3.9825 3.2325 24 P 0 ;1
L 3.9825 3.2825 3.9825 3.2825 24 P 0 ;1
L 3.9825 3.3325 3.9825 3.3325 24 P 0 ;1
L 3.9825 3.3825 3.9825 3.3825 24 P 0 ;1
L 3.9825 3.4325 3.9825 3.4325 24 P 0 ;1
L 3.9825 3.4825 3.9825 3.4825 24 P 0 ;1
L 3.9825 3.5325 3.9825 3.5325 24 P 0 ;1
L 3.9825 3.5825 3.9825 3.5825 24 P 0 ;1
L 3.9825 3.6325 3.9825 3.6325 24 P 0 ;1
L 3.9825 3.6825 3.9825 3.6825 24 P 0 ;1
L 3.9825 3.7325 3.9825 3.7325 24 P 0 ;1
L 3.9825 3.7825 3.9825 3.7825 24 P 0 ;1
L 3.9825 3.8325 3.9825 3.8325 24 P 0 ;1
L 3.9825 3.8825 3.9825 3.8825 24 P 0 ;1
L 3.9825 3.9325 3.9825 3.9325 24 P 0 ;1
L 3.9825 5.5825 3.9825 5.5825 24 P 0 ;1
L 3.9825 5.6325 3.9825 5.6325 24 P 0 ;1
L 3.9825 5.6825 3.9825 5.6825 24 P 0 ;1
L 3.9825 5.7325 3.9825 5.7325 24 P 0 ;1
L 3.9825 5.7825 3.9825 5.7825 24 P 0 ;1
L 3.9825 5.8325 3.9825 5.8325 24 P 0 ;1
L 3.9825 5.8825 3.9825 5.8825 24 P 0 ;1
L 4.0325 0.1325 4.0325 0.1325 24 P 0 ;1
L 4.0325 0.1825 4.0325 0.1825 24 P 0 ;1
L 4.0325 0.2325 4.0325 0.2325 24 P 0 ;1
L 4.0325 0.2825 4.0325 0.2825 24 P 0 ;1
L 4.0325 3.0825 4.0325 3.0825 24 P 0 ;1
L 4.0325 3.1325 4.0325 3.1325 24 P 0 ;1
L 4.0325 3.1825 4.0325 3.1825 24 P 0 ;1
L 4.0325 3.2325 4.0325 3.2325 24 P 0 ;1
L 4.0325 3.2825 4.0325 3.2825 24 P 0 ;1
L 4.0325 3.3325 4.0325 3.3325 24 P 0 ;1
L 4.0325 3.3825 4.0325 3.3825 24 P 0 ;1
L 4.0325 3.4325 4.0325 3.4325 24 P 0 ;1
L 4.0325 3.4825 4.0325 3.4825 24 P 0 ;1
L 4.0325 3.5325 4.0325 3.5325 24 P 0 ;1
L 4.0325 3.5825 4.0325 3.5825 24 P 0 ;1
L 4.0325 3.6325 4.0325 3.6325 24 P 0 ;1
L 4.0325 3.6825 4.0325 3.6825 24 P 0 ;1
L 4.0325 3.7325 4.0325 3.7325 24 P 0 ;1
L 4.0325 3.7825 4.0325 3.7825 24 P 0 ;1
L 4.0325 3.8325 4.0325 3.8325 24 P 0 ;1
L 4.0325 3.8825 4.0325 3.8825 24 P 0 ;1
L 4.0325 4.2325 4.0325 4.2325 24 P 0 ;1
L 4.0325 5.5325 4.0325 5.5325 24 P 0 ;1
L 4.0325 5.5825 4.0325 5.5825 24 P 0 ;1
L 4.0325 5.6325 4.0325 5.6325 24 P 0 ;1
L 4.0325 5.6825 4.0325 5.6825 24 P 0 ;1
L 4.0325 5.7325 4.0325 5.7325 24 P 0 ;1
L 4.0325 5.7825 4.0325 5.7825 24 P 0 ;1
L 4.0325 5.8325 4.0325 5.8325 24 P 0 ;1
L 4.0325 5.8825 4.0325 5.8825 24 P 0 ;1
L 4.0825 0.1325 4.0825 0.1325 24 P 0 ;1
L 4.0825 0.1825 4.0825 0.1825 24 P 0 ;1
L 4.0825 0.2325 4.0825 0.2325 24 P 0 ;1
L 4.0825 0.2825 4.0825 0.2825 24 P 0 ;1
L 4.0825 0.3325 4.0825 0.3325 24 P 0 ;1
L 4.0825 0.3825 4.0825 0.3825 24 P 0 ;1
L 4.0825 0.4325 4.0825 0.4325 24 P 0 ;1
L 4.0825 0.6825 4.0825 0.6825 24 P 0 ;1
L 4.0825 0.7325 4.0825 0.7325 24 P 0 ;1
L 4.0825 0.7825 4.0825 0.7825 24 P 0 ;1
L 4.0825 0.8325 4.0825 0.8325 24 P 0 ;1
L 4.0825 0.8825 4.0825 0.8825 24 P 0 ;1
L 4.0825 0.9325 4.0825 0.9325 24 P 0 ;1
L 4.0825 0.9825 4.0825 0.9825 24 P 0 ;1
L 4.0825 1.0325 4.0825 1.0325 24 P 0 ;1
L 4.0825 1.0825 4.0825 1.0825 24 P 0 ;1
L 4.0825 1.1325 4.0825 1.1325 24 P 0 ;1
L 4.0825 1.1825 4.0825 1.1825 24 P 0 ;1
L 4.0825 1.2325 4.0825 1.2325 24 P 0 ;1
L 4.0825 1.2825 4.0825 1.2825 24 P 0 ;1
L 4.0825 1.3325 4.0825 1.3325 24 P 0 ;1
L 4.0825 1.3825 4.0825 1.3825 24 P 0 ;1
L 4.0825 1.4325 4.0825 1.4325 24 P 0 ;1
L 4.0825 1.4825 4.0825 1.4825 24 P 0 ;1
L 4.0825 1.5325 4.0825 1.5325 24 P 0 ;1
L 4.0825 1.5825 4.0825 1.5825 24 P 0 ;1
L 4.0825 1.6325 4.0825 1.6325 24 P 0 ;1
L 4.0825 1.6825 4.0825 1.6825 24 P 0 ;1
L 4.0825 1.7325 4.0825 1.7325 24 P 0 ;1
L 4.0825 1.7825 4.0825 1.7825 24 P 0 ;1
L 4.0825 1.8325 4.0825 1.8325 24 P 0 ;1
L 4.0825 1.8825 4.0825 1.8825 24 P 0 ;1
L 4.0825 1.9325 4.0825 1.9325 24 P 0 ;1
L 4.0825 1.9825 4.0825 1.9825 24 P 0 ;1
L 4.0825 2.0325 4.0825 2.0325 24 P 0 ;1
L 4.0825 2.0825 4.0825 2.0825 24 P 0 ;1
L 4.0825 2.1325 4.0825 2.1325 24 P 0 ;1
L 4.0825 2.1825 4.0825 2.1825 24 P 0 ;1
L 4.0825 2.2325 4.0825 2.2325 24 P 0 ;1
L 4.0825 2.2825 4.0825 2.2825 24 P 0 ;1
L 4.0825 2.3325 4.0825 2.3325 24 P 0 ;1
L 4.0825 2.3825 4.0825 2.3825 24 P 0 ;1
L 4.0825 2.4325 4.0825 2.4325 24 P 0 ;1
L 4.0825 3.0825 4.0825 3.0825 24 P 0 ;1
L 4.0825 3.1325 4.0825 3.1325 24 P 0 ;1
L 4.0825 3.1825 4.0825 3.1825 24 P 0 ;1
L 4.0825 3.2325 4.0825 3.2325 24 P 0 ;1
L 4.0825 3.2825 4.0825 3.2825 24 P 0 ;1
L 4.0825 3.3325 4.0825 3.3325 24 P 0 ;1
L 4.0825 3.3825 4.0825 3.3825 24 P 0 ;1
L 4.0825 3.4325 4.0825 3.4325 24 P 0 ;1
L 4.0825 3.4825 4.0825 3.4825 24 P 0 ;1
L 4.0825 3.5325 4.0825 3.5325 24 P 0 ;1
L 4.0825 3.5825 4.0825 3.5825 24 P 0 ;1
L 4.0825 3.6325 4.0825 3.6325 24 P 0 ;1
L 4.0825 3.6825 4.0825 3.6825 24 P 0 ;1
L 4.0825 3.7325 4.0825 3.7325 24 P 0 ;1
L 4.0825 3.7825 4.0825 3.7825 24 P 0 ;1
L 4.0825 3.8325 4.0825 3.8325 24 P 0 ;1
L 4.0825 3.8825 4.0825 3.8825 24 P 0 ;1
L 4.0825 4.1825 4.0825 4.1825 24 P 0 ;1
L 4.0825 4.2325 4.0825 4.2325 24 P 0 ;1
L 4.0825 5.5325 4.0825 5.5325 24 P 0 ;1
L 4.0825 5.5825 4.0825 5.5825 24 P 0 ;1
L 4.0825 5.6325 4.0825 5.6325 24 P 0 ;1
L 4.0825 5.6825 4.0825 5.6825 24 P 0 ;1
L 4.0825 5.7325 4.0825 5.7325 24 P 0 ;1
L 4.0825 5.7825 4.0825 5.7825 24 P 0 ;1
L 4.0825 5.8325 4.0825 5.8325 24 P 0 ;1
L 4.0825 5.8825 4.0825 5.8825 24 P 0 ;1
L 4.1325 0.1325 4.1325 0.1325 24 P 0 ;1
L 4.1325 0.1825 4.1325 0.1825 24 P 0 ;1
L 4.1325 0.2325 4.1325 0.2325 24 P 0 ;1
L 4.1325 0.2825 4.1325 0.2825 24 P 0 ;1
L 4.1325 0.3325 4.1325 0.3325 24 P 0 ;1
L 4.1325 0.3825 4.1325 0.3825 24 P 0 ;1
L 4.1325 0.4325 4.1325 0.4325 24 P 0 ;1
L 4.1325 0.6825 4.1325 0.6825 24 P 0 ;1
L 4.1325 0.7325 4.1325 0.7325 24 P 0 ;1
L 4.1325 0.7825 4.1325 0.7825 24 P 0 ;1
L 4.1325 0.8325 4.1325 0.8325 24 P 0 ;1
L 4.1325 0.8825 4.1325 0.8825 24 P 0 ;1
L 4.1325 0.9325 4.1325 0.9325 24 P 0 ;1
L 4.1325 0.9825 4.1325 0.9825 24 P 0 ;1
L 4.1325 1.0325 4.1325 1.0325 24 P 0 ;1
L 4.1325 1.0825 4.1325 1.0825 24 P 0 ;1
L 4.1325 1.1325 4.1325 1.1325 24 P 0 ;1
L 4.1325 1.1825 4.1325 1.1825 24 P 0 ;1
L 4.1325 1.2325 4.1325 1.2325 24 P 0 ;1
L 4.1325 1.2825 4.1325 1.2825 24 P 0 ;1
L 4.1325 1.3325 4.1325 1.3325 24 P 0 ;1
L 4.1325 1.3825 4.1325 1.3825 24 P 0 ;1
L 4.1325 1.4325 4.1325 1.4325 24 P 0 ;1
L 4.1325 1.4825 4.1325 1.4825 24 P 0 ;1
L 4.1325 1.5325 4.1325 1.5325 24 P 0 ;1
L 4.1325 1.5825 4.1325 1.5825 24 P 0 ;1
L 4.1325 1.6325 4.1325 1.6325 24 P 0 ;1
L 4.1325 1.6825 4.1325 1.6825 24 P 0 ;1
L 4.1325 1.7325 4.1325 1.7325 24 P 0 ;1
L 4.1325 1.7825 4.1325 1.7825 24 P 0 ;1
L 4.1325 1.8325 4.1325 1.8325 24 P 0 ;1
L 4.1325 1.8825 4.1325 1.8825 24 P 0 ;1
L 4.1325 1.9325 4.1325 1.9325 24 P 0 ;1
L 4.1325 1.9825 4.1325 1.9825 24 P 0 ;1
L 4.1325 2.0325 4.1325 2.0325 24 P 0 ;1
L 4.1325 2.0825 4.1325 2.0825 24 P 0 ;1
L 4.1325 2.1325 4.1325 2.1325 24 P 0 ;1
L 4.1325 2.1825 4.1325 2.1825 24 P 0 ;1
L 4.1325 2.2325 4.1325 2.2325 24 P 0 ;1
L 4.1325 2.2825 4.1325 2.2825 24 P 0 ;1
L 4.1325 2.3325 4.1325 2.3325 24 P 0 ;1
L 4.1325 2.3825 4.1325 2.3825 24 P 0 ;1
L 4.1325 2.4325 4.1325 2.4325 24 P 0 ;1
L 4.1325 3.0825 4.1325 3.0825 24 P 0 ;1
L 4.1325 3.1325 4.1325 3.1325 24 P 0 ;1
L 4.1325 3.1825 4.1325 3.1825 24 P 0 ;1
L 4.1325 3.2325 4.1325 3.2325 24 P 0 ;1
L 4.1325 3.2825 4.1325 3.2825 24 P 0 ;1
L 4.1325 3.3325 4.1325 3.3325 24 P 0 ;1
L 4.1325 3.3825 4.1325 3.3825 24 P 0 ;1
L 4.1325 3.4325 4.1325 3.4325 24 P 0 ;1
L 4.1325 3.4825 4.1325 3.4825 24 P 0 ;1
L 4.1325 3.5325 4.1325 3.5325 24 P 0 ;1
L 4.1325 3.5825 4.1325 3.5825 24 P 0 ;1
L 4.1325 3.6325 4.1325 3.6325 24 P 0 ;1
L 4.1325 3.6825 4.1325 3.6825 24 P 0 ;1
L 4.1325 3.7325 4.1325 3.7325 24 P 0 ;1
L 4.1325 3.7825 4.1325 3.7825 24 P 0 ;1
L 4.1325 3.8325 4.1325 3.8325 24 P 0 ;1
L 4.1325 3.8825 4.1325 3.8825 24 P 0 ;1
L 4.1325 3.9325 4.1325 3.9325 24 P 0 ;1
L 4.1325 4.1325 4.1325 4.1325 24 P 0 ;1
L 4.1325 4.1825 4.1325 4.1825 24 P 0 ;1
L 4.1325 4.2325 4.1325 4.2325 24 P 0 ;1
L 4.1325 4.2825 4.1325 4.2825 24 P 0 ;1
L 4.1325 4.3325 4.1325 4.3325 24 P 0 ;1
L 4.1325 4.3825 4.1325 4.3825 24 P 0 ;1
L 4.1325 5.4825 4.1325 5.4825 24 P 0 ;1
L 4.1325 5.5325 4.1325 5.5325 24 P 0 ;1
L 4.1325 5.5825 4.1325 5.5825 24 P 0 ;1
L 4.1325 5.6325 4.1325 5.6325 24 P 0 ;1
L 4.1325 5.6825 4.1325 5.6825 24 P 0 ;1
L 4.1325 5.7325 4.1325 5.7325 24 P 0 ;1
L 4.1325 5.7825 4.1325 5.7825 24 P 0 ;1
L 4.1325 5.8325 4.1325 5.8325 24 P 0 ;1
L 4.1325 5.8825 4.1325 5.8825 24 P 0 ;1
L 4.1825 0.1325 4.1825 0.1325 24 P 0 ;1
L 4.1825 0.1825 4.1825 0.1825 24 P 0 ;1
L 4.1825 0.2325 4.1825 0.2325 24 P 0 ;1
L 4.1825 0.2825 4.1825 0.2825 24 P 0 ;1
L 4.1825 0.3325 4.1825 0.3325 24 P 0 ;1
L 4.1825 0.3825 4.1825 0.3825 24 P 0 ;1
L 4.1825 0.4325 4.1825 0.4325 24 P 0 ;1
L 4.1825 0.6825 4.1825 0.6825 24 P 0 ;1
L 4.1825 0.7325 4.1825 0.7325 24 P 0 ;1
L 4.1825 0.7825 4.1825 0.7825 24 P 0 ;1
L 4.1825 0.8325 4.1825 0.8325 24 P 0 ;1
L 4.1825 0.8825 4.1825 0.8825 24 P 0 ;1
L 4.1825 0.9325 4.1825 0.9325 24 P 0 ;1
L 4.1825 0.9825 4.1825 0.9825 24 P 0 ;1
L 4.1825 1.0325 4.1825 1.0325 24 P 0 ;1
L 4.1825 1.0825 4.1825 1.0825 24 P 0 ;1
L 4.1825 1.1325 4.1825 1.1325 24 P 0 ;1
L 4.1825 1.1825 4.1825 1.1825 24 P 0 ;1
L 4.1825 1.2325 4.1825 1.2325 24 P 0 ;1
L 4.1825 1.2825 4.1825 1.2825 24 P 0 ;1
L 4.1825 1.3325 4.1825 1.3325 24 P 0 ;1
L 4.1825 1.3825 4.1825 1.3825 24 P 0 ;1
L 4.1825 1.4325 4.1825 1.4325 24 P 0 ;1
L 4.1825 1.4825 4.1825 1.4825 24 P 0 ;1
L 4.1825 1.5325 4.1825 1.5325 24 P 0 ;1
L 4.1825 1.5825 4.1825 1.5825 24 P 0 ;1
L 4.1825 1.6325 4.1825 1.6325 24 P 0 ;1
L 4.1825 1.6825 4.1825 1.6825 24 P 0 ;1
L 4.1825 1.7325 4.1825 1.7325 24 P 0 ;1
L 4.1825 1.7825 4.1825 1.7825 24 P 0 ;1
L 4.1825 1.8325 4.1825 1.8325 24 P 0 ;1
L 4.1825 1.8825 4.1825 1.8825 24 P 0 ;1
L 4.1825 1.9325 4.1825 1.9325 24 P 0 ;1
L 4.1825 1.9825 4.1825 1.9825 24 P 0 ;1
L 4.1825 2.0325 4.1825 2.0325 24 P 0 ;1
L 4.1825 2.0825 4.1825 2.0825 24 P 0 ;1
L 4.1825 2.1325 4.1825 2.1325 24 P 0 ;1
L 4.1825 2.1825 4.1825 2.1825 24 P 0 ;1
L 4.1825 2.2325 4.1825 2.2325 24 P 0 ;1
L 4.1825 2.2825 4.1825 2.2825 24 P 0 ;1
L 4.1825 2.3325 4.1825 2.3325 24 P 0 ;1
L 4.1825 2.3825 4.1825 2.3825 24 P 0 ;1
L 4.1825 2.4325 4.1825 2.4325 24 P 0 ;1
L 4.1825 2.4825 4.1825 2.4825 24 P 0 ;1
L 4.1825 2.5325 4.1825 2.5325 24 P 0 ;1
L 4.1825 5.4325 4.1825 5.4325 24 P 0 ;1
L 4.1825 5.4825 4.1825 5.4825 24 P 0 ;1
L 4.1825 5.5325 4.1825 5.5325 24 P 0 ;1
L 4.1825 5.5825 4.1825 5.5825 24 P 0 ;1
L 4.1825 5.6325 4.1825 5.6325 24 P 0 ;1
L 4.1825 5.6825 4.1825 5.6825 24 P 0 ;1
L 4.1825 5.7325 4.1825 5.7325 24 P 0 ;1
L 4.1825 5.7825 4.1825 5.7825 24 P 0 ;1
L 4.1825 5.8325 4.1825 5.8325 24 P 0 ;1
L 4.1825 5.8825 4.1825 5.8825 24 P 0 ;1
L 4.2325 0.1325 4.2325 0.1325 24 P 0 ;1
L 4.2325 0.1825 4.2325 0.1825 24 P 0 ;1
L 4.2325 0.2325 4.2325 0.2325 24 P 0 ;1
L 4.2325 0.2825 4.2325 0.2825 24 P 0 ;1
L 4.2325 0.3325 4.2325 0.3325 24 P 0 ;1
L 4.2325 0.3825 4.2325 0.3825 24 P 0 ;1
L 4.2325 0.4325 4.2325 0.4325 24 P 0 ;1
L 4.2325 0.6825 4.2325 0.6825 24 P 0 ;1
L 4.2325 0.7325 4.2325 0.7325 24 P 0 ;1
L 4.2325 0.7825 4.2325 0.7825 24 P 0 ;1
L 4.2325 0.8325 4.2325 0.8325 24 P 0 ;1
L 4.2325 0.8825 4.2325 0.8825 24 P 0 ;1
L 4.2325 0.9325 4.2325 0.9325 24 P 0 ;1
L 4.2325 0.9825 4.2325 0.9825 24 P 0 ;1
L 4.2325 1.0325 4.2325 1.0325 24 P 0 ;1
L 4.2325 1.0825 4.2325 1.0825 24 P 0 ;1
L 4.2325 1.1325 4.2325 1.1325 24 P 0 ;1
L 4.2325 1.1825 4.2325 1.1825 24 P 0 ;1
L 4.2325 1.2325 4.2325 1.2325 24 P 0 ;1
L 4.2325 1.2825 4.2325 1.2825 24 P 0 ;1
L 4.2325 1.3325 4.2325 1.3325 24 P 0 ;1
L 4.2325 1.3825 4.2325 1.3825 24 P 0 ;1
L 4.2325 1.4325 4.2325 1.4325 24 P 0 ;1
L 4.2325 1.4825 4.2325 1.4825 24 P 0 ;1
L 4.2325 1.5325 4.2325 1.5325 24 P 0 ;1
L 4.2325 1.5825 4.2325 1.5825 24 P 0 ;1
L 4.2325 1.6325 4.2325 1.6325 24 P 0 ;1
L 4.2325 1.6825 4.2325 1.6825 24 P 0 ;1
L 4.2325 1.7325 4.2325 1.7325 24 P 0 ;1
L 4.2325 1.7825 4.2325 1.7825 24 P 0 ;1
L 4.2325 1.8325 4.2325 1.8325 24 P 0 ;1
L 4.2325 1.8825 4.2325 1.8825 24 P 0 ;1
L 4.2325 1.9325 4.2325 1.9325 24 P 0 ;1
L 4.2325 1.9825 4.2325 1.9825 24 P 0 ;1
L 4.2325 2.0325 4.2325 2.0325 24 P 0 ;1
L 4.2325 2.0825 4.2325 2.0825 24 P 0 ;1
L 4.2325 2.1325 4.2325 2.1325 24 P 0 ;1
L 4.2325 2.1825 4.2325 2.1825 24 P 0 ;1
L 4.2325 2.2325 4.2325 2.2325 24 P 0 ;1
L 4.2325 2.2825 4.2325 2.2825 24 P 0 ;1
L 4.2325 2.3325 4.2325 2.3325 24 P 0 ;1
L 4.2325 2.3825 4.2325 2.3825 24 P 0 ;1
L 4.2325 2.4325 4.2325 2.4325 24 P 0 ;1
L 4.2325 2.4825 4.2325 2.4825 24 P 0 ;1
L 4.2325 2.5325 4.2325 2.5325 24 P 0 ;1
L 4.2325 2.5825 4.2325 2.5825 24 P 0 ;1
L 4.2325 5.4325 4.2325 5.4325 24 P 0 ;1
L 4.2325 5.4825 4.2325 5.4825 24 P 0 ;1
L 4.2325 5.5325 4.2325 5.5325 24 P 0 ;1
L 4.2325 5.5825 4.2325 5.5825 24 P 0 ;1
L 4.2325 5.6325 4.2325 5.6325 24 P 0 ;1
L 4.2325 5.6825 4.2325 5.6825 24 P 0 ;1
L 4.2325 5.7325 4.2325 5.7325 24 P 0 ;1
L 4.2325 5.7825 4.2325 5.7825 24 P 0 ;1
L 4.2325 5.8325 4.2325 5.8325 24 P 0 ;1
L 4.2325 5.8825 4.2325 5.8825 24 P 0 ;1
L 4.2825 0.1325 4.2825 0.1325 24 P 0 ;1
L 4.2825 0.1825 4.2825 0.1825 24 P 0 ;1
L 4.2825 0.2325 4.2825 0.2325 24 P 0 ;1
L 4.2825 0.2825 4.2825 0.2825 24 P 0 ;1
L 4.2825 0.3325 4.2825 0.3325 24 P 0 ;1
L 4.2825 0.3825 4.2825 0.3825 24 P 0 ;1
L 4.2825 0.4325 4.2825 0.4325 24 P 0 ;1
L 4.2825 0.6825 4.2825 0.6825 24 P 0 ;1
L 4.2825 0.7325 4.2825 0.7325 24 P 0 ;1
L 4.2825 0.7825 4.2825 0.7825 24 P 0 ;1
L 4.2825 0.8325 4.2825 0.8325 24 P 0 ;1
L 4.2825 0.8825 4.2825 0.8825 24 P 0 ;1
L 4.2825 0.9325 4.2825 0.9325 24 P 0 ;1
L 4.2825 0.9825 4.2825 0.9825 24 P 0 ;1
L 4.2825 1.0325 4.2825 1.0325 24 P 0 ;1
L 4.2825 1.0825 4.2825 1.0825 24 P 0 ;1
L 4.2825 1.1325 4.2825 1.1325 24 P 0 ;1
L 4.2825 1.1825 4.2825 1.1825 24 P 0 ;1
L 4.2825 1.2325 4.2825 1.2325 24 P 0 ;1
L 4.2825 1.2825 4.2825 1.2825 24 P 0 ;1
L 4.2825 1.3325 4.2825 1.3325 24 P 0 ;1
L 4.2825 1.3825 4.2825 1.3825 24 P 0 ;1
L 4.2825 1.4325 4.2825 1.4325 24 P 0 ;1
L 4.2825 1.4825 4.2825 1.4825 24 P 0 ;1
L 4.2825 1.5325 4.2825 1.5325 24 P 0 ;1
L 4.2825 1.5825 4.2825 1.5825 24 P 0 ;1
L 4.2825 1.6325 4.2825 1.6325 24 P 0 ;1
L 4.2825 1.6825 4.2825 1.6825 24 P 0 ;1
L 4.2825 1.7325 4.2825 1.7325 24 P 0 ;1
L 4.2825 1.7825 4.2825 1.7825 24 P 0 ;1
L 4.2825 1.8325 4.2825 1.8325 24 P 0 ;1
L 4.2825 1.8825 4.2825 1.8825 24 P 0 ;1
L 4.2825 1.9325 4.2825 1.9325 24 P 0 ;1
L 4.2825 1.9825 4.2825 1.9825 24 P 0 ;1
L 4.2825 2.0325 4.2825 2.0325 24 P 0 ;1
L 4.2825 2.0825 4.2825 2.0825 24 P 0 ;1
L 4.2825 2.1325 4.2825 2.1325 24 P 0 ;1
L 4.2825 2.1825 4.2825 2.1825 24 P 0 ;1
L 4.2825 2.2325 4.2825 2.2325 24 P 0 ;1
L 4.2825 2.2825 4.2825 2.2825 24 P 0 ;1
L 4.2825 2.3325 4.2825 2.3325 24 P 0 ;1
L 4.2825 2.3825 4.2825 2.3825 24 P 0 ;1
L 4.2825 2.4325 4.2825 2.4325 24 P 0 ;1
L 4.2825 2.4825 4.2825 2.4825 24 P 0 ;1
L 4.2825 2.5325 4.2825 2.5325 24 P 0 ;1
L 4.2825 2.5825 4.2825 2.5825 24 P 0 ;1
L 4.2825 5.4325 4.2825 5.4325 24 P 0 ;1
L 4.2825 5.4825 4.2825 5.4825 24 P 0 ;1
L 4.2825 5.5325 4.2825 5.5325 24 P 0 ;1
L 4.2825 5.5825 4.2825 5.5825 24 P 0 ;1
L 4.2825 5.6325 4.2825 5.6325 24 P 0 ;1
L 4.2825 5.6825 4.2825 5.6825 24 P 0 ;1
L 4.2825 5.7325 4.2825 5.7325 24 P 0 ;1
L 4.2825 5.7825 4.2825 5.7825 24 P 0 ;1
L 4.2825 5.8325 4.2825 5.8325 24 P 0 ;1
L 4.2825 5.8825 4.2825 5.8825 24 P 0 ;1
L 4.3325 0.1325 4.3325 0.1325 24 P 0 ;1
L 4.3325 0.1825 4.3325 0.1825 24 P 0 ;1
L 4.3325 0.2325 4.3325 0.2325 24 P 0 ;1
L 4.3325 0.2825 4.3325 0.2825 24 P 0 ;1
L 4.3325 0.3325 4.3325 0.3325 24 P 0 ;1
L 4.3325 0.3825 4.3325 0.3825 24 P 0 ;1
L 4.3325 0.4325 4.3325 0.4325 24 P 0 ;1
L 4.3325 0.6825 4.3325 0.6825 24 P 0 ;1
L 4.3325 0.7325 4.3325 0.7325 24 P 0 ;1
L 4.3325 0.7825 4.3325 0.7825 24 P 0 ;1
L 4.3325 0.8325 4.3325 0.8325 24 P 0 ;1
L 4.3325 0.8825 4.3325 0.8825 24 P 0 ;1
L 4.3325 0.9325 4.3325 0.9325 24 P 0 ;1
L 4.3325 0.9825 4.3325 0.9825 24 P 0 ;1
L 4.3325 1.0325 4.3325 1.0325 24 P 0 ;1
L 4.3325 1.0825 4.3325 1.0825 24 P 0 ;1
L 4.3325 1.1325 4.3325 1.1325 24 P 0 ;1
L 4.3325 1.1825 4.3325 1.1825 24 P 0 ;1
L 4.3325 1.2325 4.3325 1.2325 24 P 0 ;1
L 4.3325 1.2825 4.3325 1.2825 24 P 0 ;1
L 4.3325 1.3325 4.3325 1.3325 24 P 0 ;1
L 4.3325 1.3825 4.3325 1.3825 24 P 0 ;1
L 4.3325 1.4325 4.3325 1.4325 24 P 0 ;1
L 4.3325 1.4825 4.3325 1.4825 24 P 0 ;1
L 4.3325 1.5325 4.3325 1.5325 24 P 0 ;1
L 4.3325 1.5825 4.3325 1.5825 24 P 0 ;1
L 4.3325 1.6325 4.3325 1.6325 24 P 0 ;1
L 4.3325 1.6825 4.3325 1.6825 24 P 0 ;1
L 4.3325 1.7325 4.3325 1.7325 24 P 0 ;1
L 4.3325 1.7825 4.3325 1.7825 24 P 0 ;1
L 4.3325 1.8325 4.3325 1.8325 24 P 0 ;1
L 4.3325 1.8825 4.3325 1.8825 24 P 0 ;1
L 4.3325 1.9325 4.3325 1.9325 24 P 0 ;1
L 4.3325 1.9825 4.3325 1.9825 24 P 0 ;1
L 4.3325 2.0325 4.3325 2.0325 24 P 0 ;1
L 4.3325 2.0825 4.3325 2.0825 24 P 0 ;1
L 4.3325 2.1325 4.3325 2.1325 24 P 0 ;1
L 4.3325 2.1825 4.3325 2.1825 24 P 0 ;1
L 4.3325 2.2325 4.3325 2.2325 24 P 0 ;1
L 4.3325 2.2825 4.3325 2.2825 24 P 0 ;1
L 4.3325 2.3325 4.3325 2.3325 24 P 0 ;1
L 4.3325 2.3825 4.3325 2.3825 24 P 0 ;1
L 4.3325 2.4325 4.3325 2.4325 24 P 0 ;1
L 4.3325 2.4825 4.3325 2.4825 24 P 0 ;1
L 4.3325 2.5325 4.3325 2.5325 24 P 0 ;1
L 4.3325 2.5825 4.3325 2.5825 24 P 0 ;1
L 4.3325 5.4325 4.3325 5.4325 24 P 0 ;1
L 4.3325 5.4825 4.3325 5.4825 24 P 0 ;1
L 4.3325 5.5325 4.3325 5.5325 24 P 0 ;1
L 4.3325 5.5825 4.3325 5.5825 24 P 0 ;1
L 4.3325 5.6325 4.3325 5.6325 24 P 0 ;1
L 4.3325 5.6825 4.3325 5.6825 24 P 0 ;1
L 4.3325 5.7325 4.3325 5.7325 24 P 0 ;1
L 4.3325 5.7825 4.3325 5.7825 24 P 0 ;1
L 4.3325 5.8325 4.3325 5.8325 24 P 0 ;1
L 4.3325 5.8825 4.3325 5.8825 24 P 0 ;1
L 4.3825 0.1325 4.3825 0.1325 24 P 0 ;1
L 4.3825 0.1825 4.3825 0.1825 24 P 0 ;1
L 4.3825 0.2325 4.3825 0.2325 24 P 0 ;1
L 4.3825 0.2825 4.3825 0.2825 24 P 0 ;1
L 4.3825 0.3325 4.3825 0.3325 24 P 0 ;1
L 4.3825 0.3825 4.3825 0.3825 24 P 0 ;1
L 4.3825 0.4325 4.3825 0.4325 24 P 0 ;1
L 4.3825 0.6825 4.3825 0.6825 24 P 0 ;1
L 4.3825 0.7325 4.3825 0.7325 24 P 0 ;1
L 4.3825 0.7825 4.3825 0.7825 24 P 0 ;1
L 4.3825 0.8325 4.3825 0.8325 24 P 0 ;1
L 4.3825 0.8825 4.3825 0.8825 24 P 0 ;1
L 4.3825 0.9325 4.3825 0.9325 24 P 0 ;1
L 4.3825 0.9825 4.3825 0.9825 24 P 0 ;1
L 4.3825 1.0325 4.3825 1.0325 24 P 0 ;1
L 4.3825 1.0825 4.3825 1.0825 24 P 0 ;1
L 4.3825 1.1325 4.3825 1.1325 24 P 0 ;1
L 4.3825 1.1825 4.3825 1.1825 24 P 0 ;1
L 4.3825 1.2325 4.3825 1.2325 24 P 0 ;1
L 4.3825 1.2825 4.3825 1.2825 24 P 0 ;1
L 4.3825 1.3325 4.3825 1.3325 24 P 0 ;1
L 4.3825 1.3825 4.3825 1.3825 24 P 0 ;1
L 4.3825 1.4325 4.3825 1.4325 24 P 0 ;1
L 4.3825 1.4825 4.3825 1.4825 24 P 0 ;1
L 4.3825 1.5325 4.3825 1.5325 24 P 0 ;1
L 4.3825 1.5825 4.3825 1.5825 24 P 0 ;1
L 4.3825 1.6325 4.3825 1.6325 24 P 0 ;1
L 4.3825 1.6825 4.3825 1.6825 24 P 0 ;1
L 4.3825 1.7325 4.3825 1.7325 24 P 0 ;1
L 4.3825 1.7825 4.3825 1.7825 24 P 0 ;1
L 4.3825 1.8325 4.3825 1.8325 24 P 0 ;1
L 4.3825 1.8825 4.3825 1.8825 24 P 0 ;1
L 4.3825 1.9325 4.3825 1.9325 24 P 0 ;1
L 4.3825 1.9825 4.3825 1.9825 24 P 0 ;1
L 4.3825 2.0325 4.3825 2.0325 24 P 0 ;1
L 4.3825 2.0825 4.3825 2.0825 24 P 0 ;1
L 4.3825 2.1325 4.3825 2.1325 24 P 0 ;1
L 4.3825 2.1825 4.3825 2.1825 24 P 0 ;1
L 4.3825 2.2325 4.3825 2.2325 24 P 0 ;1
L 4.3825 2.2825 4.3825 2.2825 24 P 0 ;1
L 4.3825 2.3325 4.3825 2.3325 24 P 0 ;1
L 4.3825 2.3825 4.3825 2.3825 24 P 0 ;1
L 4.3825 2.4325 4.3825 2.4325 24 P 0 ;1
L 4.3825 2.4825 4.3825 2.4825 24 P 0 ;1
L 4.3825 2.5325 4.3825 2.5325 24 P 0 ;1
L 4.3825 2.5825 4.3825 2.5825 24 P 0 ;1
L 4.3825 5.4325 4.3825 5.4325 24 P 0 ;1
L 4.3825 5.4825 4.3825 5.4825 24 P 0 ;1
L 4.3825 5.5325 4.3825 5.5325 24 P 0 ;1
L 4.3825 5.5825 4.3825 5.5825 24 P 0 ;1
L 4.3825 5.6325 4.3825 5.6325 24 P 0 ;1
L 4.3825 5.6825 4.3825 5.6825 24 P 0 ;1
L 4.3825 5.7325 4.3825 5.7325 24 P 0 ;1
L 4.3825 5.7825 4.3825 5.7825 24 P 0 ;1
L 4.3825 5.8325 4.3825 5.8325 24 P 0 ;1
L 4.3825 5.8825 4.3825 5.8825 24 P 0 ;1
L 4.4325 0.1325 4.4325 0.1325 24 P 0 ;1
L 4.4325 0.1825 4.4325 0.1825 24 P 0 ;1
L 4.4325 0.2325 4.4325 0.2325 24 P 0 ;1
L 4.4325 0.2825 4.4325 0.2825 24 P 0 ;1
L 4.4325 0.3325 4.4325 0.3325 24 P 0 ;1
L 4.4325 0.3825 4.4325 0.3825 24 P 0 ;1
L 4.4325 0.4325 4.4325 0.4325 24 P 0 ;1
L 4.4325 0.6825 4.4325 0.6825 24 P 0 ;1
L 4.4325 0.7325 4.4325 0.7325 24 P 0 ;1
L 4.4325 0.7825 4.4325 0.7825 24 P 0 ;1
L 4.4325 0.8325 4.4325 0.8325 24 P 0 ;1
L 4.4325 0.8825 4.4325 0.8825 24 P 0 ;1
L 4.4325 0.9325 4.4325 0.9325 24 P 0 ;1
L 4.4325 0.9825 4.4325 0.9825 24 P 0 ;1
L 4.4325 1.0325 4.4325 1.0325 24 P 0 ;1
L 4.4325 1.0825 4.4325 1.0825 24 P 0 ;1
L 4.4325 1.1325 4.4325 1.1325 24 P 0 ;1
L 4.4325 1.1825 4.4325 1.1825 24 P 0 ;1
L 4.4325 1.2325 4.4325 1.2325 24 P 0 ;1
L 4.4325 1.2825 4.4325 1.2825 24 P 0 ;1
L 4.4325 1.3325 4.4325 1.3325 24 P 0 ;1
L 4.4325 1.3825 4.4325 1.3825 24 P 0 ;1
L 4.4325 1.4325 4.4325 1.4325 24 P 0 ;1
L 4.4325 1.4825 4.4325 1.4825 24 P 0 ;1
L 4.4325 1.5325 4.4325 1.5325 24 P 0 ;1
L 4.4325 1.5825 4.4325 1.5825 24 P 0 ;1
L 4.4325 1.6325 4.4325 1.6325 24 P 0 ;1
L 4.4325 1.6825 4.4325 1.6825 24 P 0 ;1
L 4.4325 1.7325 4.4325 1.7325 24 P 0 ;1
L 4.4325 1.7825 4.4325 1.7825 24 P 0 ;1
L 4.4325 1.8325 4.4325 1.8325 24 P 0 ;1
L 4.4325 1.8825 4.4325 1.8825 24 P 0 ;1
L 4.4325 1.9325 4.4325 1.9325 24 P 0 ;1
L 4.4325 1.9825 4.4325 1.9825 24 P 0 ;1
L 4.4325 2.0325 4.4325 2.0325 24 P 0 ;1
L 4.4325 2.0825 4.4325 2.0825 24 P 0 ;1
L 4.4325 2.1325 4.4325 2.1325 24 P 0 ;1
L 4.4325 2.1825 4.4325 2.1825 24 P 0 ;1
L 4.4325 2.2325 4.4325 2.2325 24 P 0 ;1
L 4.4325 2.2825 4.4325 2.2825 24 P 0 ;1
L 4.4325 2.3325 4.4325 2.3325 24 P 0 ;1
L 4.4325 2.3825 4.4325 2.3825 24 P 0 ;1
L 4.4325 2.4325 4.4325 2.4325 24 P 0 ;1
L 4.4325 2.4825 4.4325 2.4825 24 P 0 ;1
L 4.4325 2.5325 4.4325 2.5325 24 P 0 ;1
L 4.4325 2.5825 4.4325 2.5825 24 P 0 ;1
L 4.4325 5.4325 4.4325 5.4325 24 P 0 ;1
L 4.4325 5.4825 4.4325 5.4825 24 P 0 ;1
L 4.4325 5.5325 4.4325 5.5325 24 P 0 ;1
L 4.4325 5.5825 4.4325 5.5825 24 P 0 ;1
L 4.4325 5.6325 4.4325 5.6325 24 P 0 ;1
L 4.4325 5.6825 4.4325 5.6825 24 P 0 ;1
L 4.4325 5.7325 4.4325 5.7325 24 P 0 ;1
L 4.4325 5.7825 4.4325 5.7825 24 P 0 ;1
L 4.4325 5.8325 4.4325 5.8325 24 P 0 ;1
L 4.4325 5.8825 4.4325 5.8825 24 P 0 ;1
L 4.4825 0.1325 4.4825 0.1325 24 P 0 ;1
L 4.4825 0.1825 4.4825 0.1825 24 P 0 ;1
L 4.4825 0.2325 4.4825 0.2325 24 P 0 ;1
L 4.4825 0.2825 4.4825 0.2825 24 P 0 ;1
L 4.4825 0.3325 4.4825 0.3325 24 P 0 ;1
L 4.4825 0.3825 4.4825 0.3825 24 P 0 ;1
L 4.4825 0.4325 4.4825 0.4325 24 P 0 ;1
L 4.4825 0.6825 4.4825 0.6825 24 P 0 ;1
L 4.4825 0.7325 4.4825 0.7325 24 P 0 ;1
L 4.4825 0.7825 4.4825 0.7825 24 P 0 ;1
L 4.4825 0.8325 4.4825 0.8325 24 P 0 ;1
L 4.4825 0.8825 4.4825 0.8825 24 P 0 ;1
L 4.4825 0.9325 4.4825 0.9325 24 P 0 ;1
L 4.4825 0.9825 4.4825 0.9825 24 P 0 ;1
L 4.4825 1.0325 4.4825 1.0325 24 P 0 ;1
L 4.4825 1.0825 4.4825 1.0825 24 P 0 ;1
L 4.4825 1.1325 4.4825 1.1325 24 P 0 ;1
L 4.4825 1.1825 4.4825 1.1825 24 P 0 ;1
L 4.4825 1.2325 4.4825 1.2325 24 P 0 ;1
L 4.4825 1.2825 4.4825 1.2825 24 P 0 ;1
L 4.4825 1.3325 4.4825 1.3325 24 P 0 ;1
L 4.4825 1.3825 4.4825 1.3825 24 P 0 ;1
L 4.4825 1.4325 4.4825 1.4325 24 P 0 ;1
L 4.4825 1.4825 4.4825 1.4825 24 P 0 ;1
L 4.4825 1.5325 4.4825 1.5325 24 P 0 ;1
L 4.4825 1.5825 4.4825 1.5825 24 P 0 ;1
L 4.4825 1.6325 4.4825 1.6325 24 P 0 ;1
L 4.4825 1.6825 4.4825 1.6825 24 P 0 ;1
L 4.4825 1.7325 4.4825 1.7325 24 P 0 ;1
L 4.4825 1.7825 4.4825 1.7825 24 P 0 ;1
L 4.4825 1.8325 4.4825 1.8325 24 P 0 ;1
L 4.4825 1.8825 4.4825 1.8825 24 P 0 ;1
L 4.4825 1.9325 4.4825 1.9325 24 P 0 ;1
L 4.4825 1.9825 4.4825 1.9825 24 P 0 ;1
L 4.4825 2.0325 4.4825 2.0325 24 P 0 ;1
L 4.4825 2.0825 4.4825 2.0825 24 P 0 ;1
L 4.4825 2.1325 4.4825 2.1325 24 P 0 ;1
L 4.4825 2.1825 4.4825 2.1825 24 P 0 ;1
L 4.4825 2.2325 4.4825 2.2325 24 P 0 ;1
L 4.4825 2.2825 4.4825 2.2825 24 P 0 ;1
L 4.4825 2.3325 4.4825 2.3325 24 P 0 ;1
L 4.4825 2.3825 4.4825 2.3825 24 P 0 ;1
L 4.4825 2.4325 4.4825 2.4325 24 P 0 ;1
L 4.4825 2.4825 4.4825 2.4825 24 P 0 ;1
L 4.4825 2.5325 4.4825 2.5325 24 P 0 ;1
L 4.4825 2.5825 4.4825 2.5825 24 P 0 ;1
L 4.4825 5.4325 4.4825 5.4325 24 P 0 ;1
L 4.4825 5.4825 4.4825 5.4825 24 P 0 ;1
L 4.4825 5.5325 4.4825 5.5325 24 P 0 ;1
L 4.4825 5.5825 4.4825 5.5825 24 P 0 ;1
L 4.4825 5.6325 4.4825 5.6325 24 P 0 ;1
L 4.4825 5.6825 4.4825 5.6825 24 P 0 ;1
L 4.4825 5.7325 4.4825 5.7325 24 P 0 ;1
L 4.4825 5.7825 4.4825 5.7825 24 P 0 ;1
L 4.4825 5.8325 4.4825 5.8325 24 P 0 ;1
L 4.4825 5.8825 4.4825 5.8825 24 P 0 ;1
L 4.5325 0.1325 4.5325 0.1325 24 P 0 ;1
L 4.5325 0.1825 4.5325 0.1825 24 P 0 ;1
L 4.5325 0.2325 4.5325 0.2325 24 P 0 ;1
L 4.5325 0.2825 4.5325 0.2825 24 P 0 ;1
L 4.5325 0.3325 4.5325 0.3325 24 P 0 ;1
L 4.5325 0.3825 4.5325 0.3825 24 P 0 ;1
L 4.5325 0.4325 4.5325 0.4325 24 P 0 ;1
L 4.5325 0.6825 4.5325 0.6825 24 P 0 ;1
L 4.5325 0.7325 4.5325 0.7325 24 P 0 ;1
L 4.5325 0.7825 4.5325 0.7825 24 P 0 ;1
L 4.5325 0.8325 4.5325 0.8325 24 P 0 ;1
L 4.5325 0.8825 4.5325 0.8825 24 P 0 ;1
L 4.5325 0.9325 4.5325 0.9325 24 P 0 ;1
L 4.5325 0.9825 4.5325 0.9825 24 P 0 ;1
L 4.5325 1.0325 4.5325 1.0325 24 P 0 ;1
L 4.5325 1.0825 4.5325 1.0825 24 P 0 ;1
L 4.5325 1.1325 4.5325 1.1325 24 P 0 ;1
L 4.5325 1.1825 4.5325 1.1825 24 P 0 ;1
L 4.5325 1.2325 4.5325 1.2325 24 P 0 ;1
L 4.5325 1.2825 4.5325 1.2825 24 P 0 ;1
L 4.5325 1.3325 4.5325 1.3325 24 P 0 ;1
L 4.5325 1.3825 4.5325 1.3825 24 P 0 ;1
L 4.5325 1.4325 4.5325 1.4325 24 P 0 ;1
L 4.5325 1.4825 4.5325 1.4825 24 P 0 ;1
L 4.5325 1.5325 4.5325 1.5325 24 P 0 ;1
L 4.5325 1.5825 4.5325 1.5825 24 P 0 ;1
L 4.5325 1.6325 4.5325 1.6325 24 P 0 ;1
L 4.5325 1.6825 4.5325 1.6825 24 P 0 ;1
L 4.5325 1.7325 4.5325 1.7325 24 P 0 ;1
L 4.5325 1.7825 4.5325 1.7825 24 P 0 ;1
L 4.5325 5.4325 4.5325 5.4325 24 P 0 ;1
L 4.5325 5.4825 4.5325 5.4825 24 P 0 ;1
L 4.5325 5.5325 4.5325 5.5325 24 P 0 ;1
L 4.5325 5.5825 4.5325 5.5825 24 P 0 ;1
L 4.5325 5.6325 4.5325 5.6325 24 P 0 ;1
L 4.5325 5.6825 4.5325 5.6825 24 P 0 ;1
L 4.5325 5.7325 4.5325 5.7325 24 P 0 ;1
L 4.5325 5.7825 4.5325 5.7825 24 P 0 ;1
L 4.5325 5.8325 4.5325 5.8325 24 P 0 ;1
L 4.5325 5.8825 4.5325 5.8825 24 P 0 ;1
L 4.5825 0.1325 4.5825 0.1325 24 P 0 ;1
L 4.5825 0.1825 4.5825 0.1825 24 P 0 ;1
L 4.5825 0.2325 4.5825 0.2325 24 P 0 ;1
L 4.5825 0.2825 4.5825 0.2825 24 P 0 ;1
L 4.5825 0.3325 4.5825 0.3325 24 P 0 ;1
L 4.5825 0.3825 4.5825 0.3825 24 P 0 ;1
L 4.5825 0.4325 4.5825 0.4325 24 P 0 ;1
L 4.5825 0.6825 4.5825 0.6825 24 P 0 ;1
L 4.5825 0.7325 4.5825 0.7325 24 P 0 ;1
L 4.5825 0.7825 4.5825 0.7825 24 P 0 ;1
L 4.5825 0.8325 4.5825 0.8325 24 P 0 ;1
L 4.5825 0.8825 4.5825 0.8825 24 P 0 ;1
L 4.5825 0.9325 4.5825 0.9325 24 P 0 ;1
L 4.5825 0.9825 4.5825 0.9825 24 P 0 ;1
L 4.5825 1.0325 4.5825 1.0325 24 P 0 ;1
L 4.5825 1.0825 4.5825 1.0825 24 P 0 ;1
L 4.5825 1.1325 4.5825 1.1325 24 P 0 ;1
L 4.5825 1.1825 4.5825 1.1825 24 P 0 ;1
L 4.5825 1.2325 4.5825 1.2325 24 P 0 ;1
L 4.5825 1.2825 4.5825 1.2825 24 P 0 ;1
L 4.5825 1.3325 4.5825 1.3325 24 P 0 ;1
L 4.5825 1.3825 4.5825 1.3825 24 P 0 ;1
L 4.5825 1.4325 4.5825 1.4325 24 P 0 ;1
L 4.5825 1.4825 4.5825 1.4825 24 P 0 ;1
L 4.5825 1.5325 4.5825 1.5325 24 P 0 ;1
L 4.5825 1.5825 4.5825 1.5825 24 P 0 ;1
L 4.5825 1.6325 4.5825 1.6325 24 P 0 ;1
L 4.5825 1.6825 4.5825 1.6825 24 P 0 ;1
L 4.5825 1.7325 4.5825 1.7325 24 P 0 ;1
L 4.5825 5.4325 4.5825 5.4325 24 P 0 ;1
L 4.5825 5.4825 4.5825 5.4825 24 P 0 ;1
L 4.5825 5.5325 4.5825 5.5325 24 P 0 ;1
L 4.5825 5.5825 4.5825 5.5825 24 P 0 ;1
L 4.5825 5.6325 4.5825 5.6325 24 P 0 ;1
L 4.5825 5.6825 4.5825 5.6825 24 P 0 ;1
L 4.5825 5.7325 4.5825 5.7325 24 P 0 ;1
L 4.5825 5.7825 4.5825 5.7825 24 P 0 ;1
L 4.5825 5.8325 4.5825 5.8325 24 P 0 ;1
L 4.5825 5.8825 4.5825 5.8825 24 P 0 ;1
L 4.6325 0.1325 4.6325 0.1325 24 P 0 ;1
L 4.6325 0.1825 4.6325 0.1825 24 P 0 ;1
L 4.6325 0.2325 4.6325 0.2325 24 P 0 ;1
L 4.6325 0.2825 4.6325 0.2825 24 P 0 ;1
L 4.6325 0.3325 4.6325 0.3325 24 P 0 ;1
L 4.6325 0.3825 4.6325 0.3825 24 P 0 ;1
L 4.6325 0.4325 4.6325 0.4325 24 P 0 ;1
L 4.6325 0.6825 4.6325 0.6825 24 P 0 ;1
L 4.6325 0.7325 4.6325 0.7325 24 P 0 ;1
L 4.6325 0.7825 4.6325 0.7825 24 P 0 ;1
L 4.6325 0.8325 4.6325 0.8325 24 P 0 ;1
L 4.6325 0.8825 4.6325 0.8825 24 P 0 ;1
L 4.6325 0.9325 4.6325 0.9325 24 P 0 ;1
L 4.6325 0.9825 4.6325 0.9825 24 P 0 ;1
L 4.6325 1.0325 4.6325 1.0325 24 P 0 ;1
L 4.6325 1.0825 4.6325 1.0825 24 P 0 ;1
L 4.6325 1.1325 4.6325 1.1325 24 P 0 ;1
L 4.6325 1.1825 4.6325 1.1825 24 P 0 ;1
L 4.6325 1.2325 4.6325 1.2325 24 P 0 ;1
L 4.6325 1.2825 4.6325 1.2825 24 P 0 ;1
L 4.6325 1.3325 4.6325 1.3325 24 P 0 ;1
L 4.6325 1.6825 4.6325 1.6825 24 P 0 ;1
L 4.6325 1.7325 4.6325 1.7325 24 P 0 ;1
L 4.6325 5.4325 4.6325 5.4325 24 P 0 ;1
L 4.6325 5.6325 4.6325 5.6325 24 P 0 ;1
L 4.6325 5.6825 4.6325 5.6825 24 P 0 ;1
L 4.6325 5.7325 4.6325 5.7325 24 P 0 ;1
L 4.6325 5.7825 4.6325 5.7825 24 P 0 ;1
L 4.6325 5.8325 4.6325 5.8325 24 P 0 ;1
L 4.6325 5.8825 4.6325 5.8825 24 P 0 ;1
L 4.6825 0.1325 4.6825 0.1325 24 P 0 ;1
L 4.6825 0.1825 4.6825 0.1825 24 P 0 ;1
L 4.6825 0.2325 4.6825 0.2325 24 P 0 ;1
L 4.6825 0.2825 4.6825 0.2825 24 P 0 ;1
L 4.6825 0.3325 4.6825 0.3325 24 P 0 ;1
L 4.6825 0.3825 4.6825 0.3825 24 P 0 ;1
L 4.6825 0.4325 4.6825 0.4325 24 P 0 ;1
L 4.6825 0.6825 4.6825 0.6825 24 P 0 ;1
L 4.6825 0.7325 4.6825 0.7325 24 P 0 ;1
L 4.6825 0.7825 4.6825 0.7825 24 P 0 ;1
L 4.6825 0.8325 4.6825 0.8325 24 P 0 ;1
L 4.6825 0.8825 4.6825 0.8825 24 P 0 ;1
L 4.6825 0.9325 4.6825 0.9325 24 P 0 ;1
L 4.6825 0.9825 4.6825 0.9825 24 P 0 ;1
L 4.6825 1.0325 4.6825 1.0325 24 P 0 ;1
L 4.6825 1.0825 4.6825 1.0825 24 P 0 ;1
L 4.6825 1.1325 4.6825 1.1325 24 P 0 ;1
L 4.6825 1.1825 4.6825 1.1825 24 P 0 ;1
L 4.6825 1.2325 4.6825 1.2325 24 P 0 ;1
L 4.6825 1.2825 4.6825 1.2825 24 P 0 ;1
L 4.6825 1.7325 4.6825 1.7325 24 P 0 ;1
L 4.6825 5.4325 4.6825 5.4325 24 P 0 ;1
L 4.6825 5.6825 4.6825 5.6825 24 P 0 ;1
L 4.6825 5.7325 4.6825 5.7325 24 P 0 ;1
L 4.6825 5.7825 4.6825 5.7825 24 P 0 ;1
L 4.6825 5.8325 4.6825 5.8325 24 P 0 ;1
L 4.6825 5.8825 4.6825 5.8825 24 P 0 ;1
L 4.7325 0.4325 4.7325 0.4325 24 P 0 ;1
L 4.7325 0.6825 4.7325 0.6825 24 P 0 ;1
L 4.7325 0.7325 4.7325 0.7325 24 P 0 ;1
L 4.7325 0.7825 4.7325 0.7825 24 P 0 ;1
L 4.7325 0.8325 4.7325 0.8325 24 P 0 ;1
L 4.7325 0.8825 4.7325 0.8825 24 P 0 ;1
L 4.7325 0.9325 4.7325 0.9325 24 P 0 ;1
L 4.7325 0.9825 4.7325 0.9825 24 P 0 ;1
L 4.7325 1.0325 4.7325 1.0325 24 P 0 ;1
L 4.7325 1.0825 4.7325 1.0825 24 P 0 ;1
L 4.7325 1.1325 4.7325 1.1325 24 P 0 ;1
L 4.7325 1.1825 4.7325 1.1825 24 P 0 ;1
L 4.7325 1.2325 4.7325 1.2325 24 P 0 ;1
L 4.7325 1.2825 4.7325 1.2825 24 P 0 ;1
L 4.7325 1.7325 4.7325 1.7325 24 P 0 ;1
L 4.7325 5.6825 4.7325 5.6825 24 P 0 ;1
L 4.7325 5.7325 4.7325 5.7325 24 P 0 ;1
L 4.7325 5.7825 4.7325 5.7825 24 P 0 ;1
L 4.7325 5.8325 4.7325 5.8325 24 P 0 ;1
L 4.7325 5.8825 4.7325 5.8825 24 P 0 ;1
L 4.7825 0.6825 4.7825 0.6825 24 P 0 ;1
L 4.7825 0.7325 4.7825 0.7325 24 P 0 ;1
L 4.7825 0.7825 4.7825 0.7825 24 P 0 ;1
L 4.7825 0.8325 4.7825 0.8325 24 P 0 ;1
L 4.7825 0.8825 4.7825 0.8825 24 P 0 ;1
L 4.7825 0.9325 4.7825 0.9325 24 P 0 ;1
L 4.7825 0.9825 4.7825 0.9825 24 P 0 ;1
L 4.7825 1.0325 4.7825 1.0325 24 P 0 ;1
L 4.7825 1.0825 4.7825 1.0825 24 P 0 ;1
L 4.7825 1.1325 4.7825 1.1325 24 P 0 ;1
L 4.7825 1.1825 4.7825 1.1825 24 P 0 ;1
L 4.7825 1.2325 4.7825 1.2325 24 P 0 ;1
L 4.7825 5.6325 4.7825 5.6325 24 P 0 ;1
L 4.7825 5.6825 4.7825 5.6825 24 P 0 ;1
L 4.7825 5.7325 4.7825 5.7325 24 P 0 ;1
L 4.7825 5.7825 4.7825 5.7825 24 P 0 ;1
L 4.7825 5.8325 4.7825 5.8325 24 P 0 ;1
L 4.7825 5.8825 4.7825 5.8825 24 P 0 ;1
L 4.8325 0.6825 4.8325 0.6825 24 P 0 ;1
L 4.8325 0.7325 4.8325 0.7325 24 P 0 ;1
L 4.8325 0.7825 4.8325 0.7825 24 P 0 ;1
L 4.8325 0.8325 4.8325 0.8325 24 P 0 ;1
L 4.8325 0.8825 4.8325 0.8825 24 P 0 ;1
L 4.8325 0.9325 4.8325 0.9325 24 P 0 ;1
L 4.8325 0.9825 4.8325 0.9825 24 P 0 ;1
L 4.8325 1.0325 4.8325 1.0325 24 P 0 ;1
L 4.8325 1.0825 4.8325 1.0825 24 P 0 ;1
L 4.8325 1.1325 4.8325 1.1325 24 P 0 ;1
L 4.8325 1.1825 4.8325 1.1825 24 P 0 ;1
L 4.8325 1.2325 4.8325 1.2325 24 P 0 ;1
L 4.8325 5.8825 4.8325 5.8825 24 P 0 ;1
L 4.8825 0.6825 4.8825 0.6825 24 P 0 ;1
L 4.8825 0.7325 4.8825 0.7325 24 P 0 ;1
L 4.8825 0.7825 4.8825 0.7825 24 P 0 ;1
L 4.8825 0.8325 4.8825 0.8325 24 P 0 ;1
L 4.8825 0.8825 4.8825 0.8825 24 P 0 ;1
L 4.8825 0.9325 4.8825 0.9325 24 P 0 ;1
L 4.8825 0.9825 4.8825 0.9825 24 P 0 ;1
L 4.8825 1.0325 4.8825 1.0325 24 P 0 ;1
L 4.8825 1.0825 4.8825 1.0825 24 P 0 ;1
L 4.8825 1.1325 4.8825 1.1325 24 P 0 ;1
L 4.8825 1.1825 4.8825 1.1825 24 P 0 ;1
L 4.8825 1.2325 4.8825 1.2325 24 P 0 ;1
L 4.8825 5.8825 4.8825 5.8825 24 P 0 ;1
L 4.9325 0.6825 4.9325 0.6825 24 P 0 ;1
L 4.9325 0.7325 4.9325 0.7325 24 P 0 ;1
L 4.9325 0.7825 4.9325 0.7825 24 P 0 ;1
L 4.9325 0.8325 4.9325 0.8325 24 P 0 ;1
L 4.9325 0.8825 4.9325 0.8825 24 P 0 ;1
L 4.9325 0.9325 4.9325 0.9325 24 P 0 ;1
L 4.9325 0.9825 4.9325 0.9825 24 P 0 ;1
L 4.9325 1.0325 4.9325 1.0325 24 P 0 ;1
L 4.9325 1.0825 4.9325 1.0825 24 P 0 ;1
L 4.9325 1.1325 4.9325 1.1325 24 P 0 ;1
L 4.9325 1.1825 4.9325 1.1825 24 P 0 ;1
L 4.9325 1.2325 4.9325 1.2325 24 P 0 ;1
L 4.9325 1.2825 4.9325 1.2825 24 P 0 ;1
L 4.9325 5.8825 4.9325 5.8825 24 P 0 ;1
L 4.9825 0.6825 4.9825 0.6825 24 P 0 ;1
L 4.9825 0.7325 4.9825 0.7325 24 P 0 ;1
L 4.9825 0.7825 4.9825 0.7825 24 P 0 ;1
L 4.9825 0.8325 4.9825 0.8325 24 P 0 ;1
L 4.9825 0.8825 4.9825 0.8825 24 P 0 ;1
L 4.9825 0.9325 4.9825 0.9325 24 P 0 ;1
L 4.9825 0.9825 4.9825 0.9825 24 P 0 ;1
L 4.9825 1.0325 4.9825 1.0325 24 P 0 ;1
L 4.9825 1.0825 4.9825 1.0825 24 P 0 ;1
L 4.9825 1.1325 4.9825 1.1325 24 P 0 ;1
L 4.9825 1.1825 4.9825 1.1825 24 P 0 ;1
L 4.9825 1.2325 4.9825 1.2325 24 P 0 ;1
L 4.9825 1.2825 4.9825 1.2825 24 P 0 ;1
L 4.9825 5.8325 4.9825 5.8325 24 P 0 ;1
L 4.9825 5.8825 4.9825 5.8825 24 P 0 ;1
L 5.0325 0.6825 5.0325 0.6825 24 P 0 ;1
L 5.0325 0.7325 5.0325 0.7325 24 P 0 ;1
L 5.0325 0.7825 5.0325 0.7825 24 P 0 ;1
L 5.0325 0.8325 5.0325 0.8325 24 P 0 ;1
L 5.0325 0.8825 5.0325 0.8825 24 P 0 ;1
L 5.0325 0.9325 5.0325 0.9325 24 P 0 ;1
L 5.0325 0.9825 5.0325 0.9825 24 P 0 ;1
L 5.0325 1.0325 5.0325 1.0325 24 P 0 ;1
L 5.0325 1.0825 5.0325 1.0825 24 P 0 ;1
L 5.0325 1.1325 5.0325 1.1325 24 P 0 ;1
L 5.0325 1.1825 5.0325 1.1825 24 P 0 ;1
L 5.0325 1.2325 5.0325 1.2325 24 P 0 ;1
L 5.0325 1.2825 5.0325 1.2825 24 P 0 ;1
L 5.0325 1.3325 5.0325 1.3325 24 P 0 ;1
L 5.0325 5.8825 5.0325 5.8825 24 P 0 ;1
L 5.0825 0.6825 5.0825 0.6825 24 P 0 ;1
L 5.0825 0.7325 5.0825 0.7325 24 P 0 ;1
L 5.0825 0.7825 5.0825 0.7825 24 P 0 ;1
L 5.0825 0.8325 5.0825 0.8325 24 P 0 ;1
L 5.0825 0.8825 5.0825 0.8825 24 P 0 ;1
L 5.0825 0.9325 5.0825 0.9325 24 P 0 ;1
L 5.0825 0.9825 5.0825 0.9825 24 P 0 ;1
L 5.0825 1.0325 5.0825 1.0325 24 P 0 ;1
L 5.0825 1.0825 5.0825 1.0825 24 P 0 ;1
L 5.0825 1.1325 5.0825 1.1325 24 P 0 ;1
L 5.0825 1.1825 5.0825 1.1825 24 P 0 ;1
L 5.0825 1.2325 5.0825 1.2325 24 P 0 ;1
L 5.0825 1.2825 5.0825 1.2825 24 P 0 ;1
L 5.0825 1.3325 5.0825 1.3325 24 P 0 ;1
L 5.0825 1.3825 5.0825 1.3825 24 P 0 ;1
L 5.0825 1.4325 5.0825 1.4325 24 P 0 ;1
L 5.0825 1.4825 5.0825 1.4825 24 P 0 ;1
L 5.0825 5.8825 5.0825 5.8825 24 P 0 ;1
L 5.1325 0.6825 5.1325 0.6825 24 P 0 ;1
L 5.1325 0.7325 5.1325 0.7325 24 P 0 ;1
L 5.1325 0.7825 5.1325 0.7825 24 P 0 ;1
L 5.1325 0.8325 5.1325 0.8325 24 P 0 ;1
L 5.1325 0.8825 5.1325 0.8825 24 P 0 ;1
L 5.1325 0.9325 5.1325 0.9325 24 P 0 ;1
L 5.1325 0.9825 5.1325 0.9825 24 P 0 ;1
L 5.1325 1.0325 5.1325 1.0325 24 P 0 ;1
L 5.1325 1.0825 5.1325 1.0825 24 P 0 ;1
L 5.1325 1.1325 5.1325 1.1325 24 P 0 ;1
L 5.1325 1.1825 5.1325 1.1825 24 P 0 ;1
L 5.1325 1.2325 5.1325 1.2325 24 P 0 ;1
L 5.1325 1.2825 5.1325 1.2825 24 P 0 ;1
L 5.1325 1.3325 5.1325 1.3325 24 P 0 ;1
L 5.1325 1.3825 5.1325 1.3825 24 P 0 ;1
L 5.1325 1.4325 5.1325 1.4325 24 P 0 ;1
L 5.1325 1.4825 5.1325 1.4825 24 P 0 ;1
L 5.1325 5.8825 5.1325 5.8825 24 P 0 ;1
L 5.1825 0.6825 5.1825 0.6825 24 P 0 ;1
L 5.1825 0.7325 5.1825 0.7325 24 P 0 ;1
L 5.1825 0.7825 5.1825 0.7825 24 P 0 ;1
L 5.1825 0.8325 5.1825 0.8325 24 P 0 ;1
L 5.1825 0.8825 5.1825 0.8825 24 P 0 ;1
L 5.1825 0.9325 5.1825 0.9325 24 P 0 ;1
L 5.1825 0.9825 5.1825 0.9825 24 P 0 ;1
L 5.1825 1.0325 5.1825 1.0325 24 P 0 ;1
L 5.1825 1.0825 5.1825 1.0825 24 P 0 ;1
L 5.1825 1.1325 5.1825 1.1325 24 P 0 ;1
L 5.1825 1.1825 5.1825 1.1825 24 P 0 ;1
L 5.1825 1.2325 5.1825 1.2325 24 P 0 ;1
L 5.1825 1.2825 5.1825 1.2825 24 P 0 ;1
L 5.1825 1.3325 5.1825 1.3325 24 P 0 ;1
L 5.1825 1.3825 5.1825 1.3825 24 P 0 ;1
L 5.1825 1.4325 5.1825 1.4325 24 P 0 ;1
L 5.1825 1.4825 5.1825 1.4825 24 P 0 ;1
L 5.1825 5.8325 5.1825 5.8325 24 P 0 ;1
L 5.1825 5.8825 5.1825 5.8825 24 P 0 ;1
L 5.2325 0.6825 5.2325 0.6825 24 P 0 ;1
L 5.2325 0.7325 5.2325 0.7325 24 P 0 ;1
L 5.2325 0.7825 5.2325 0.7825 24 P 0 ;1
L 5.2325 0.8325 5.2325 0.8325 24 P 0 ;1
L 5.2325 0.8825 5.2325 0.8825 24 P 0 ;1
L 5.2325 0.9325 5.2325 0.9325 24 P 0 ;1
L 5.2325 0.9825 5.2325 0.9825 24 P 0 ;1
L 5.2325 1.0325 5.2325 1.0325 24 P 0 ;1
L 5.2325 1.0825 5.2325 1.0825 24 P 0 ;1
L 5.2325 1.1325 5.2325 1.1325 24 P 0 ;1
L 5.2325 1.1825 5.2325 1.1825 24 P 0 ;1
L 5.2325 1.2325 5.2325 1.2325 24 P 0 ;1
L 5.2325 1.2825 5.2325 1.2825 24 P 0 ;1
L 5.2325 1.3325 5.2325 1.3325 24 P 0 ;1
L 5.2325 1.3825 5.2325 1.3825 24 P 0 ;1
L 5.2325 1.4325 5.2325 1.4325 24 P 0 ;1
L 5.2325 1.4825 5.2325 1.4825 24 P 0 ;1
L 5.2325 5.3325 5.2325 5.3325 24 P 0 ;1
L 5.2325 5.3825 5.2325 5.3825 24 P 0 ;1
L 5.2325 5.4325 5.2325 5.4325 24 P 0 ;1
L 5.2325 5.4825 5.2325 5.4825 24 P 0 ;1
L 5.2325 5.8325 5.2325 5.8325 24 P 0 ;1
L 5.2325 5.8825 5.2325 5.8825 24 P 0 ;1
L 5.2825 0.6825 5.2825 0.6825 24 P 0 ;1
L 5.2825 0.7325 5.2825 0.7325 24 P 0 ;1
L 5.2825 0.7825 5.2825 0.7825 24 P 0 ;1
L 5.2825 0.8325 5.2825 0.8325 24 P 0 ;1
L 5.2825 0.8825 5.2825 0.8825 24 P 0 ;1
L 5.2825 0.9325 5.2825 0.9325 24 P 0 ;1
L 5.2825 0.9825 5.2825 0.9825 24 P 0 ;1
L 5.2825 1.0325 5.2825 1.0325 24 P 0 ;1
L 5.2825 1.0825 5.2825 1.0825 24 P 0 ;1
L 5.2825 1.1325 5.2825 1.1325 24 P 0 ;1
L 5.2825 1.1825 5.2825 1.1825 24 P 0 ;1
L 5.2825 1.2325 5.2825 1.2325 24 P 0 ;1
L 5.2825 1.2825 5.2825 1.2825 24 P 0 ;1
L 5.2825 1.3325 5.2825 1.3325 24 P 0 ;1
L 5.2825 1.3825 5.2825 1.3825 24 P 0 ;1
L 5.2825 1.4325 5.2825 1.4325 24 P 0 ;1
L 5.2825 1.4825 5.2825 1.4825 24 P 0 ;1
L 5.2825 5.3325 5.2825 5.3325 24 P 0 ;1
L 5.2825 5.3825 5.2825 5.3825 24 P 0 ;1
L 5.2825 5.4325 5.2825 5.4325 24 P 0 ;1
L 5.2825 5.4825 5.2825 5.4825 24 P 0 ;1
L 5.2825 5.5325 5.2825 5.5325 24 P 0 ;1
L 5.2825 5.5825 5.2825 5.5825 24 P 0 ;1
L 5.2825 5.8325 5.2825 5.8325 24 P 0 ;1
L 5.2825 5.8825 5.2825 5.8825 24 P 0 ;1
L 5.3325 0.6825 5.3325 0.6825 24 P 0 ;1
L 5.3325 0.7325 5.3325 0.7325 24 P 0 ;1
L 5.3325 0.7825 5.3325 0.7825 24 P 0 ;1
L 5.3325 0.8325 5.3325 0.8325 24 P 0 ;1
L 5.3325 0.8825 5.3325 0.8825 24 P 0 ;1
L 5.3325 0.9325 5.3325 0.9325 24 P 0 ;1
L 5.3325 0.9825 5.3325 0.9825 24 P 0 ;1
L 5.3325 1.0325 5.3325 1.0325 24 P 0 ;1
L 5.3325 1.0825 5.3325 1.0825 24 P 0 ;1
L 5.3325 1.1325 5.3325 1.1325 24 P 0 ;1
L 5.3325 1.1825 5.3325 1.1825 24 P 0 ;1
L 5.3325 1.2325 5.3325 1.2325 24 P 0 ;1
L 5.3325 1.2825 5.3325 1.2825 24 P 0 ;1
L 5.3325 1.3325 5.3325 1.3325 24 P 0 ;1
L 5.3325 1.3825 5.3325 1.3825 24 P 0 ;1
L 5.3325 1.4325 5.3325 1.4325 24 P 0 ;1
L 5.3325 1.4825 5.3325 1.4825 24 P 0 ;1
L 5.3325 3.4325 5.3325 3.4325 24 P 0 ;1
L 5.3325 3.4825 5.3325 3.4825 24 P 0 ;1
L 5.3325 3.5325 5.3325 3.5325 24 P 0 ;1
L 5.3325 3.5825 5.3325 3.5825 24 P 0 ;1
L 5.3325 3.6325 5.3325 3.6325 24 P 0 ;1
L 5.3325 3.6825 5.3325 3.6825 24 P 0 ;1
L 5.3325 3.7325 5.3325 3.7325 24 P 0 ;1
L 5.3325 3.7825 5.3325 3.7825 24 P 0 ;1
L 5.3325 3.8325 5.3325 3.8325 24 P 0 ;1
L 5.3325 3.8825 5.3325 3.8825 24 P 0 ;1
L 5.3325 3.9325 5.3325 3.9325 24 P 0 ;1
L 5.3325 3.9825 5.3325 3.9825 24 P 0 ;1
L 5.3325 4.0325 5.3325 4.0325 24 P 0 ;1
L 5.3325 4.0825 5.3325 4.0825 24 P 0 ;1
L 5.3325 4.1325 5.3325 4.1325 24 P 0 ;1
L 5.3325 4.1825 5.3325 4.1825 24 P 0 ;1
L 5.3325 4.2325 5.3325 4.2325 24 P 0 ;1
L 5.3325 4.2825 5.3325 4.2825 24 P 0 ;1
L 5.3325 4.3325 5.3325 4.3325 24 P 0 ;1
L 5.3325 4.3825 5.3325 4.3825 24 P 0 ;1
L 5.3325 4.4325 5.3325 4.4325 24 P 0 ;1
L 5.3325 4.4825 5.3325 4.4825 24 P 0 ;1
L 5.3325 4.5325 5.3325 4.5325 24 P 0 ;1
L 5.3325 4.5825 5.3325 4.5825 24 P 0 ;1
L 5.3325 4.6325 5.3325 4.6325 24 P 0 ;1
L 5.3325 4.6825 5.3325 4.6825 24 P 0 ;1
L 5.3325 4.7325 5.3325 4.7325 24 P 0 ;1
L 5.3325 4.7825 5.3325 4.7825 24 P 0 ;1
L 5.3325 4.8325 5.3325 4.8325 24 P 0 ;1
L 5.3325 5.2825 5.3325 5.2825 24 P 0 ;1
L 5.3325 5.3325 5.3325 5.3325 24 P 0 ;1
L 5.3325 5.3825 5.3325 5.3825 24 P 0 ;1
L 5.3325 5.4325 5.3325 5.4325 24 P 0 ;1
L 5.3325 5.4825 5.3325 5.4825 24 P 0 ;1
L 5.3325 5.5325 5.3325 5.5325 24 P 0 ;1
L 5.3325 5.5825 5.3325 5.5825 24 P 0 ;1
L 5.3325 5.8325 5.3325 5.8325 24 P 0 ;1
L 5.3325 5.8825 5.3325 5.8825 24 P 0 ;1
L 5.3825 0.6825 5.3825 0.6825 24 P 0 ;1
L 5.3825 0.7325 5.3825 0.7325 24 P 0 ;1
L 5.3825 0.7825 5.3825 0.7825 24 P 0 ;1
L 5.3825 0.8325 5.3825 0.8325 24 P 0 ;1
L 5.3825 0.8825 5.3825 0.8825 24 P 0 ;1
L 5.3825 0.9325 5.3825 0.9325 24 P 0 ;1
L 5.3825 0.9825 5.3825 0.9825 24 P 0 ;1
L 5.3825 1.0325 5.3825 1.0325 24 P 0 ;1
L 5.3825 1.0825 5.3825 1.0825 24 P 0 ;1
L 5.3825 1.1325 5.3825 1.1325 24 P 0 ;1
L 5.3825 1.1825 5.3825 1.1825 24 P 0 ;1
L 5.3825 1.2325 5.3825 1.2325 24 P 0 ;1
L 5.3825 1.2825 5.3825 1.2825 24 P 0 ;1
L 5.3825 1.3325 5.3825 1.3325 24 P 0 ;1
L 5.3825 1.3825 5.3825 1.3825 24 P 0 ;1
L 5.3825 1.4325 5.3825 1.4325 24 P 0 ;1
L 5.3825 1.4825 5.3825 1.4825 24 P 0 ;1
L 5.3825 3.4325 5.3825 3.4325 24 P 0 ;1
L 5.3825 3.4825 5.3825 3.4825 24 P 0 ;1
L 5.3825 3.5325 5.3825 3.5325 24 P 0 ;1
L 5.3825 3.5825 5.3825 3.5825 24 P 0 ;1
L 5.3825 3.6325 5.3825 3.6325 24 P 0 ;1
L 5.3825 3.6825 5.3825 3.6825 24 P 0 ;1
L 5.3825 3.7325 5.3825 3.7325 24 P 0 ;1
L 5.3825 3.7825 5.3825 3.7825 24 P 0 ;1
L 5.3825 3.8325 5.3825 3.8325 24 P 0 ;1
L 5.3825 3.8825 5.3825 3.8825 24 P 0 ;1
L 5.3825 3.9325 5.3825 3.9325 24 P 0 ;1
L 5.3825 3.9825 5.3825 3.9825 24 P 0 ;1
L 5.3825 4.0325 5.3825 4.0325 24 P 0 ;1
L 5.3825 4.0825 5.3825 4.0825 24 P 0 ;1
L 5.3825 4.1325 5.3825 4.1325 24 P 0 ;1
L 5.3825 4.1825 5.3825 4.1825 24 P 0 ;1
L 5.3825 4.2325 5.3825 4.2325 24 P 0 ;1
L 5.3825 4.2825 5.3825 4.2825 24 P 0 ;1
L 5.3825 4.3325 5.3825 4.3325 24 P 0 ;1
L 5.3825 4.3825 5.3825 4.3825 24 P 0 ;1
L 5.3825 4.4325 5.3825 4.4325 24 P 0 ;1
L 5.3825 4.4825 5.3825 4.4825 24 P 0 ;1
L 5.3825 4.5325 5.3825 4.5325 24 P 0 ;1
L 5.3825 4.5825 5.3825 4.5825 24 P 0 ;1
L 5.3825 4.6325 5.3825 4.6325 24 P 0 ;1
L 5.3825 4.6825 5.3825 4.6825 24 P 0 ;1
L 5.3825 4.7325 5.3825 4.7325 24 P 0 ;1
L 5.3825 4.7825 5.3825 4.7825 24 P 0 ;1
L 5.3825 4.8325 5.3825 4.8325 24 P 0 ;1
L 5.3825 4.8825 5.3825 4.8825 24 P 0 ;1
L 5.3825 4.9325 5.3825 4.9325 24 P 0 ;1
L 5.3825 4.9825 5.3825 4.9825 24 P 0 ;1
L 5.3825 5.0325 5.3825 5.0325 24 P 0 ;1
L 5.3825 5.0825 5.3825 5.0825 24 P 0 ;1
L 5.3825 5.1325 5.3825 5.1325 24 P 0 ;1
L 5.3825 5.1825 5.3825 5.1825 24 P 0 ;1
L 5.3825 5.2325 5.3825 5.2325 24 P 0 ;1
L 5.3825 5.2825 5.3825 5.2825 24 P 0 ;1
L 5.3825 5.3325 5.3825 5.3325 24 P 0 ;1
L 5.3825 5.3825 5.3825 5.3825 24 P 0 ;1
L 5.3825 5.4325 5.3825 5.4325 24 P 0 ;1
L 5.3825 5.4825 5.3825 5.4825 24 P 0 ;1
L 5.3825 5.5325 5.3825 5.5325 24 P 0 ;1
L 5.3825 5.5825 5.3825 5.5825 24 P 0 ;1
L 5.3825 5.8325 5.3825 5.8325 24 P 0 ;1
L 5.3825 5.8825 5.3825 5.8825 24 P 0 ;1
L 5.4325 0.6825 5.4325 0.6825 24 P 0 ;1
L 5.4325 0.7325 5.4325 0.7325 24 P 0 ;1
L 5.4325 0.7825 5.4325 0.7825 24 P 0 ;1
L 5.4325 0.8325 5.4325 0.8325 24 P 0 ;1
L 5.4325 0.8825 5.4325 0.8825 24 P 0 ;1
L 5.4325 0.9325 5.4325 0.9325 24 P 0 ;1
L 5.4325 0.9825 5.4325 0.9825 24 P 0 ;1
L 5.4325 1.0325 5.4325 1.0325 24 P 0 ;1
L 5.4325 1.0825 5.4325 1.0825 24 P 0 ;1
L 5.4325 1.1325 5.4325 1.1325 24 P 0 ;1
L 5.4325 1.1825 5.4325 1.1825 24 P 0 ;1
L 5.4325 1.2325 5.4325 1.2325 24 P 0 ;1
L 5.4325 1.2825 5.4325 1.2825 24 P 0 ;1
L 5.4325 1.3325 5.4325 1.3325 24 P 0 ;1
L 5.4325 1.3825 5.4325 1.3825 24 P 0 ;1
L 5.4325 1.4325 5.4325 1.4325 24 P 0 ;1
L 5.4325 1.4825 5.4325 1.4825 24 P 0 ;1
L 5.4325 3.4325 5.4325 3.4325 24 P 0 ;1
L 5.4325 3.4825 5.4325 3.4825 24 P 0 ;1
L 5.4325 3.5325 5.4325 3.5325 24 P 0 ;1
L 5.4325 3.5825 5.4325 3.5825 24 P 0 ;1
L 5.4325 3.6325 5.4325 3.6325 24 P 0 ;1
L 5.4325 3.6825 5.4325 3.6825 24 P 0 ;1
L 5.4325 3.7325 5.4325 3.7325 24 P 0 ;1
L 5.4325 3.7825 5.4325 3.7825 24 P 0 ;1
L 5.4325 3.8325 5.4325 3.8325 24 P 0 ;1
L 5.4325 3.8825 5.4325 3.8825 24 P 0 ;1
L 5.4325 3.9325 5.4325 3.9325 24 P 0 ;1
L 5.4325 3.9825 5.4325 3.9825 24 P 0 ;1
L 5.4325 4.0325 5.4325 4.0325 24 P 0 ;1
L 5.4325 4.0825 5.4325 4.0825 24 P 0 ;1
L 5.4325 4.1325 5.4325 4.1325 24 P 0 ;1
L 5.4325 4.1825 5.4325 4.1825 24 P 0 ;1
L 5.4325 4.2325 5.4325 4.2325 24 P 0 ;1
L 5.4325 4.2825 5.4325 4.2825 24 P 0 ;1
L 5.4325 4.3325 5.4325 4.3325 24 P 0 ;1
L 5.4325 4.3825 5.4325 4.3825 24 P 0 ;1
L 5.4325 4.4325 5.4325 4.4325 24 P 0 ;1
L 5.4325 4.4825 5.4325 4.4825 24 P 0 ;1
L 5.4325 4.5325 5.4325 4.5325 24 P 0 ;1
L 5.4325 4.5825 5.4325 4.5825 24 P 0 ;1
L 5.4325 4.6325 5.4325 4.6325 24 P 0 ;1
L 5.4325 4.6825 5.4325 4.6825 24 P 0 ;1
L 5.4325 4.7325 5.4325 4.7325 24 P 0 ;1
L 5.4325 4.7825 5.4325 4.7825 24 P 0 ;1
L 5.4325 4.8325 5.4325 4.8325 24 P 0 ;1
L 5.4325 4.8825 5.4325 4.8825 24 P 0 ;1
L 5.4325 4.9325 5.4325 4.9325 24 P 0 ;1
L 5.4325 4.9825 5.4325 4.9825 24 P 0 ;1
L 5.4325 5.0325 5.4325 5.0325 24 P 0 ;1
L 5.4325 5.0825 5.4325 5.0825 24 P 0 ;1
L 5.4325 5.1325 5.4325 5.1325 24 P 0 ;1
L 5.4325 5.1825 5.4325 5.1825 24 P 0 ;1
L 5.4325 5.2325 5.4325 5.2325 24 P 0 ;1
L 5.4325 5.2825 5.4325 5.2825 24 P 0 ;1
L 5.4325 5.3325 5.4325 5.3325 24 P 0 ;1
L 5.4325 5.3825 5.4325 5.3825 24 P 0 ;1
L 5.4325 5.4325 5.4325 5.4325 24 P 0 ;1
L 5.4325 5.4825 5.4325 5.4825 24 P 0 ;1
L 5.4325 5.5325 5.4325 5.5325 24 P 0 ;1
L 5.4325 5.5825 5.4325 5.5825 24 P 0 ;1
L 5.4325 5.8325 5.4325 5.8325 24 P 0 ;1
L 5.4325 5.8825 5.4325 5.8825 24 P 0 ;1
L 5.4825 0.6825 5.4825 0.6825 24 P 0 ;1
L 5.4825 0.7325 5.4825 0.7325 24 P 0 ;1
L 5.4825 0.7825 5.4825 0.7825 24 P 0 ;1
L 5.4825 0.8325 5.4825 0.8325 24 P 0 ;1
L 5.4825 0.8825 5.4825 0.8825 24 P 0 ;1
L 5.4825 0.9325 5.4825 0.9325 24 P 0 ;1
L 5.4825 0.9825 5.4825 0.9825 24 P 0 ;1
L 5.4825 1.0325 5.4825 1.0325 24 P 0 ;1
L 5.4825 1.0825 5.4825 1.0825 24 P 0 ;1
L 5.4825 1.1325 5.4825 1.1325 24 P 0 ;1
L 5.4825 1.1825 5.4825 1.1825 24 P 0 ;1
L 5.4825 1.2325 5.4825 1.2325 24 P 0 ;1
L 5.4825 1.2825 5.4825 1.2825 24 P 0 ;1
L 5.4825 1.3325 5.4825 1.3325 24 P 0 ;1
L 5.4825 1.3825 5.4825 1.3825 24 P 0 ;1
L 5.4825 1.4325 5.4825 1.4325 24 P 0 ;1
L 5.4825 1.4825 5.4825 1.4825 24 P 0 ;1
L 5.4825 1.5325 5.4825 1.5325 24 P 0 ;1
L 5.4825 3.4325 5.4825 3.4325 24 P 0 ;1
L 5.4825 3.4825 5.4825 3.4825 24 P 0 ;1
L 5.4825 3.5325 5.4825 3.5325 24 P 0 ;1
L 5.4825 3.5825 5.4825 3.5825 24 P 0 ;1
L 5.4825 3.6325 5.4825 3.6325 24 P 0 ;1
L 5.4825 3.6825 5.4825 3.6825 24 P 0 ;1
L 5.4825 3.7325 5.4825 3.7325 24 P 0 ;1
L 5.4825 3.7825 5.4825 3.7825 24 P 0 ;1
L 5.4825 3.8325 5.4825 3.8325 24 P 0 ;1
L 5.4825 3.8825 5.4825 3.8825 24 P 0 ;1
L 5.4825 3.9325 5.4825 3.9325 24 P 0 ;1
L 5.4825 3.9825 5.4825 3.9825 24 P 0 ;1
L 5.4825 4.0325 5.4825 4.0325 24 P 0 ;1
L 5.4825 4.0825 5.4825 4.0825 24 P 0 ;1
L 5.4825 4.1325 5.4825 4.1325 24 P 0 ;1
L 5.4825 4.1825 5.4825 4.1825 24 P 0 ;1
L 5.4825 4.2325 5.4825 4.2325 24 P 0 ;1
L 5.4825 4.2825 5.4825 4.2825 24 P 0 ;1
L 5.4825 4.3325 5.4825 4.3325 24 P 0 ;1
L 5.4825 4.3825 5.4825 4.3825 24 P 0 ;1
L 5.4825 4.4325 5.4825 4.4325 24 P 0 ;1
L 5.4825 4.6825 5.4825 4.6825 24 P 0 ;1
L 5.4825 4.7325 5.4825 4.7325 24 P 0 ;1
L 5.4825 4.7825 5.4825 4.7825 24 P 0 ;1
L 5.4825 4.8325 5.4825 4.8325 24 P 0 ;1
L 5.4825 4.8825 5.4825 4.8825 24 P 0 ;1
L 5.4825 4.9325 5.4825 4.9325 24 P 0 ;1
L 5.4825 4.9825 5.4825 4.9825 24 P 0 ;1
L 5.4825 5.0325 5.4825 5.0325 24 P 0 ;1
L 5.4825 5.0825 5.4825 5.0825 24 P 0 ;1
L 5.4825 5.1325 5.4825 5.1325 24 P 0 ;1
L 5.4825 5.1825 5.4825 5.1825 24 P 0 ;1
L 5.4825 5.2325 5.4825 5.2325 24 P 0 ;1
L 5.4825 5.2825 5.4825 5.2825 24 P 0 ;1
L 5.4825 5.3325 5.4825 5.3325 24 P 0 ;1
L 5.4825 5.3825 5.4825 5.3825 24 P 0 ;1
L 5.4825 5.4325 5.4825 5.4325 24 P 0 ;1
L 5.4825 5.4825 5.4825 5.4825 24 P 0 ;1
L 5.4825 5.5325 5.4825 5.5325 24 P 0 ;1
L 5.4825 5.5825 5.4825 5.5825 24 P 0 ;1
L 5.4825 5.8325 5.4825 5.8325 24 P 0 ;1
L 5.4825 5.8825 5.4825 5.8825 24 P 0 ;1
L 5.5325 0.6825 5.5325 0.6825 24 P 0 ;1
L 5.5325 0.7325 5.5325 0.7325 24 P 0 ;1
L 5.5325 0.7825 5.5325 0.7825 24 P 0 ;1
L 5.5325 0.8325 5.5325 0.8325 24 P 0 ;1
L 5.5325 0.8825 5.5325 0.8825 24 P 0 ;1
L 5.5325 0.9325 5.5325 0.9325 24 P 0 ;1
L 5.5325 0.9825 5.5325 0.9825 24 P 0 ;1
L 5.5325 1.0325 5.5325 1.0325 24 P 0 ;1
L 5.5325 1.0825 5.5325 1.0825 24 P 0 ;1
L 5.5325 1.1325 5.5325 1.1325 24 P 0 ;1
L 5.5325 1.1825 5.5325 1.1825 24 P 0 ;1
L 5.5325 1.2325 5.5325 1.2325 24 P 0 ;1
L 5.5325 1.2825 5.5325 1.2825 24 P 0 ;1
L 5.5325 1.3325 5.5325 1.3325 24 P 0 ;1
L 5.5325 1.3825 5.5325 1.3825 24 P 0 ;1
L 5.5325 1.4325 5.5325 1.4325 24 P 0 ;1
L 5.5325 1.4825 5.5325 1.4825 24 P 0 ;1
L 5.5325 1.5325 5.5325 1.5325 24 P 0 ;1
L 5.5325 3.3825 5.5325 3.3825 24 P 0 ;1
L 5.5325 3.4325 5.5325 3.4325 24 P 0 ;1
L 5.5325 3.4825 5.5325 3.4825 24 P 0 ;1
L 5.5325 3.5325 5.5325 3.5325 24 P 0 ;1
L 5.5325 3.5825 5.5325 3.5825 24 P 0 ;1
L 5.5325 3.6325 5.5325 3.6325 24 P 0 ;1
L 5.5325 3.6825 5.5325 3.6825 24 P 0 ;1
L 5.5325 3.7325 5.5325 3.7325 24 P 0 ;1
L 5.5325 3.7825 5.5325 3.7825 24 P 0 ;1
L 5.5325 3.8325 5.5325 3.8325 24 P 0 ;1
L 5.5325 3.8825 5.5325 3.8825 24 P 0 ;1
L 5.5325 3.9325 5.5325 3.9325 24 P 0 ;1
L 5.5325 3.9825 5.5325 3.9825 24 P 0 ;1
L 5.5325 4.0325 5.5325 4.0325 24 P 0 ;1
L 5.5325 4.0825 5.5325 4.0825 24 P 0 ;1
L 5.5325 4.1325 5.5325 4.1325 24 P 0 ;1
L 5.5325 4.1825 5.5325 4.1825 24 P 0 ;1
L 5.5325 4.2325 5.5325 4.2325 24 P 0 ;1
L 5.5325 4.2825 5.5325 4.2825 24 P 0 ;1
L 5.5325 4.3325 5.5325 4.3325 24 P 0 ;1
L 5.5325 4.3825 5.5325 4.3825 24 P 0 ;1
L 5.5325 5.0325 5.5325 5.0325 24 P 0 ;1
L 5.5325 5.0825 5.5325 5.0825 24 P 0 ;1
L 5.5325 5.1325 5.5325 5.1325 24 P 0 ;1
L 5.5325 5.1825 5.5325 5.1825 24 P 0 ;1
L 5.5325 5.2325 5.5325 5.2325 24 P 0 ;1
L 5.5325 5.2825 5.5325 5.2825 24 P 0 ;1
L 5.5325 5.5825 5.5325 5.5825 24 P 0 ;1
L 5.5325 5.8325 5.5325 5.8325 24 P 0 ;1
L 5.5325 5.8825 5.5325 5.8825 24 P 0 ;1
L 5.5825 0.6825 5.5825 0.6825 24 P 0 ;1
L 5.5825 0.7325 5.5825 0.7325 24 P 0 ;1
L 5.5825 0.7825 5.5825 0.7825 24 P 0 ;1
L 5.5825 0.8325 5.5825 0.8325 24 P 0 ;1
L 5.5825 0.8825 5.5825 0.8825 24 P 0 ;1
L 5.5825 0.9325 5.5825 0.9325 24 P 0 ;1
L 5.5825 0.9825 5.5825 0.9825 24 P 0 ;1
L 5.5825 1.0325 5.5825 1.0325 24 P 0 ;1
L 5.5825 1.0825 5.5825 1.0825 24 P 0 ;1
L 5.5825 1.1325 5.5825 1.1325 24 P 0 ;1
L 5.5825 1.1825 5.5825 1.1825 24 P 0 ;1
L 5.5825 1.2325 5.5825 1.2325 24 P 0 ;1
L 5.5825 1.2825 5.5825 1.2825 24 P 0 ;1
L 5.5825 1.3325 5.5825 1.3325 24 P 0 ;1
L 5.5825 1.3825 5.5825 1.3825 24 P 0 ;1
L 5.5825 1.4325 5.5825 1.4325 24 P 0 ;1
L 5.5825 1.4825 5.5825 1.4825 24 P 0 ;1
L 5.5825 1.5325 5.5825 1.5325 24 P 0 ;1
L 5.5825 3.1825 5.5825 3.1825 24 P 0 ;1
L 5.5825 3.2325 5.5825 3.2325 24 P 0 ;1
L 5.5825 3.2825 5.5825 3.2825 24 P 0 ;1
L 5.5825 3.3325 5.5825 3.3325 24 P 0 ;1
L 5.5825 3.3825 5.5825 3.3825 24 P 0 ;1
L 5.5825 3.4325 5.5825 3.4325 24 P 0 ;1
L 5.5825 3.4825 5.5825 3.4825 24 P 0 ;1
L 5.5825 3.5325 5.5825 3.5325 24 P 0 ;1
L 5.5825 3.5825 5.5825 3.5825 24 P 0 ;1
L 5.5825 3.6325 5.5825 3.6325 24 P 0 ;1
L 5.5825 3.6825 5.5825 3.6825 24 P 0 ;1
L 5.5825 3.7325 5.5825 3.7325 24 P 0 ;1
L 5.5825 3.7825 5.5825 3.7825 24 P 0 ;1
L 5.5825 3.8325 5.5825 3.8325 24 P 0 ;1
L 5.5825 3.8825 5.5825 3.8825 24 P 0 ;1
L 5.5825 3.9325 5.5825 3.9325 24 P 0 ;1
L 5.5825 3.9825 5.5825 3.9825 24 P 0 ;1
L 5.5825 4.0325 5.5825 4.0325 24 P 0 ;1
L 5.5825 4.0825 5.5825 4.0825 24 P 0 ;1
L 5.5825 4.1325 5.5825 4.1325 24 P 0 ;1
L 5.5825 4.1825 5.5825 4.1825 24 P 0 ;1
L 5.5825 4.2325 5.5825 4.2325 24 P 0 ;1
L 5.5825 4.2825 5.5825 4.2825 24 P 0 ;1
L 5.5825 4.3325 5.5825 4.3325 24 P 0 ;1
L 5.5825 5.0325 5.5825 5.0325 24 P 0 ;1
L 5.5825 5.0825 5.5825 5.0825 24 P 0 ;1
L 5.5825 5.1325 5.5825 5.1325 24 P 0 ;1
L 5.5825 5.1825 5.5825 5.1825 24 P 0 ;1
L 5.5825 5.2325 5.5825 5.2325 24 P 0 ;1
L 5.5825 5.8325 5.5825 5.8325 24 P 0 ;1
L 5.5825 5.8825 5.5825 5.8825 24 P 0 ;1
L 5.6325 0.6825 5.6325 0.6825 24 P 0 ;1
L 5.6325 0.7325 5.6325 0.7325 24 P 0 ;1
L 5.6325 0.7825 5.6325 0.7825 24 P 0 ;1
L 5.6325 0.8325 5.6325 0.8325 24 P 0 ;1
L 5.6325 0.8825 5.6325 0.8825 24 P 0 ;1
L 5.6325 0.9325 5.6325 0.9325 24 P 0 ;1
L 5.6325 0.9825 5.6325 0.9825 24 P 0 ;1
L 5.6325 1.0325 5.6325 1.0325 24 P 0 ;1
L 5.6325 1.0825 5.6325 1.0825 24 P 0 ;1
L 5.6325 1.1325 5.6325 1.1325 24 P 0 ;1
L 5.6325 1.1825 5.6325 1.1825 24 P 0 ;1
L 5.6325 1.2325 5.6325 1.2325 24 P 0 ;1
L 5.6325 1.2825 5.6325 1.2825 24 P 0 ;1
L 5.6325 1.3325 5.6325 1.3325 24 P 0 ;1
L 5.6325 1.3825 5.6325 1.3825 24 P 0 ;1
L 5.6325 1.4325 5.6325 1.4325 24 P 0 ;1
L 5.6325 1.4825 5.6325 1.4825 24 P 0 ;1
L 5.6325 1.5325 5.6325 1.5325 24 P 0 ;1
L 5.6325 1.5825 5.6325 1.5825 24 P 0 ;1
L 5.6325 3.2325 5.6325 3.2325 24 P 0 ;1
L 5.6325 3.2825 5.6325 3.2825 24 P 0 ;1
L 5.6325 3.3325 5.6325 3.3325 24 P 0 ;1
L 5.6325 3.3825 5.6325 3.3825 24 P 0 ;1
L 5.6325 3.4325 5.6325 3.4325 24 P 0 ;1
L 5.6325 3.4825 5.6325 3.4825 24 P 0 ;1
L 5.6325 3.5325 5.6325 3.5325 24 P 0 ;1
L 5.6325 3.5825 5.6325 3.5825 24 P 0 ;1
L 5.6325 3.6325 5.6325 3.6325 24 P 0 ;1
L 5.6325 3.6825 5.6325 3.6825 24 P 0 ;1
L 5.6325 3.7325 5.6325 3.7325 24 P 0 ;1
L 5.6325 3.7825 5.6325 3.7825 24 P 0 ;1
L 5.6325 3.8325 5.6325 3.8325 24 P 0 ;1
L 5.6325 3.8825 5.6325 3.8825 24 P 0 ;1
L 5.6325 3.9325 5.6325 3.9325 24 P 0 ;1
L 5.6325 3.9825 5.6325 3.9825 24 P 0 ;1
L 5.6325 4.0325 5.6325 4.0325 24 P 0 ;1
L 5.6325 4.0825 5.6325 4.0825 24 P 0 ;1
L 5.6325 4.1325 5.6325 4.1325 24 P 0 ;1
L 5.6325 4.1825 5.6325 4.1825 24 P 0 ;1
L 5.6325 4.2325 5.6325 4.2325 24 P 0 ;1
L 5.6325 4.2825 5.6325 4.2825 24 P 0 ;1
L 5.6325 4.3325 5.6325 4.3325 24 P 0 ;1
L 5.6325 5.0325 5.6325 5.0325 24 P 0 ;1
L 5.6325 5.0825 5.6325 5.0825 24 P 0 ;1
L 5.6325 5.1325 5.6325 5.1325 24 P 0 ;1
L 5.6325 5.1825 5.6325 5.1825 24 P 0 ;1
L 5.6325 5.8325 5.6325 5.8325 24 P 0 ;1
L 5.6325 5.8825 5.6325 5.8825 24 P 0 ;1
L 5.6825 0.6825 5.6825 0.6825 24 P 0 ;1
L 5.6825 0.7325 5.6825 0.7325 24 P 0 ;1
L 5.6825 0.7825 5.6825 0.7825 24 P 0 ;1
L 5.6825 0.8325 5.6825 0.8325 24 P 0 ;1
L 5.6825 0.8825 5.6825 0.8825 24 P 0 ;1
L 5.6825 0.9325 5.6825 0.9325 24 P 0 ;1
L 5.6825 0.9825 5.6825 0.9825 24 P 0 ;1
L 5.6825 1.0325 5.6825 1.0325 24 P 0 ;1
L 5.6825 1.0825 5.6825 1.0825 24 P 0 ;1
L 5.6825 1.1325 5.6825 1.1325 24 P 0 ;1
L 5.6825 1.1825 5.6825 1.1825 24 P 0 ;1
L 5.6825 1.2325 5.6825 1.2325 24 P 0 ;1
L 5.6825 1.2825 5.6825 1.2825 24 P 0 ;1
L 5.6825 1.3325 5.6825 1.3325 24 P 0 ;1
L 5.6825 1.3825 5.6825 1.3825 24 P 0 ;1
L 5.6825 1.4325 5.6825 1.4325 24 P 0 ;1
L 5.6825 1.4825 5.6825 1.4825 24 P 0 ;1
L 5.6825 1.5325 5.6825 1.5325 24 P 0 ;1
L 5.6825 1.5825 5.6825 1.5825 24 P 0 ;1
L 5.6825 1.6325 5.6825 1.6325 24 P 0 ;1
L 5.6825 1.6825 5.6825 1.6825 24 P 0 ;1
L 5.6825 1.7325 5.6825 1.7325 24 P 0 ;1
L 5.6825 1.7825 5.6825 1.7825 24 P 0 ;1
L 5.6825 1.8325 5.6825 1.8325 24 P 0 ;1
L 5.6825 1.8825 5.6825 1.8825 24 P 0 ;1
L 5.6825 1.9325 5.6825 1.9325 24 P 0 ;1
L 5.6825 1.9825 5.6825 1.9825 24 P 0 ;1
L 5.6825 2.0325 5.6825 2.0325 24 P 0 ;1
L 5.6825 2.0825 5.6825 2.0825 24 P 0 ;1
L 5.6825 2.1325 5.6825 2.1325 24 P 0 ;1
L 5.6825 2.1825 5.6825 2.1825 24 P 0 ;1
L 5.6825 2.2325 5.6825 2.2325 24 P 0 ;1
L 5.6825 2.2825 5.6825 2.2825 24 P 0 ;1
L 5.6825 2.3325 5.6825 2.3325 24 P 0 ;1
L 5.6825 2.3825 5.6825 2.3825 24 P 0 ;1
L 5.6825 2.4325 5.6825 2.4325 24 P 0 ;1
L 5.6825 2.4825 5.6825 2.4825 24 P 0 ;1
L 5.6825 2.5325 5.6825 2.5325 24 P 0 ;1
L 5.6825 2.5825 5.6825 2.5825 24 P 0 ;1
L 5.6825 3.2325 5.6825 3.2325 24 P 0 ;1
L 5.6825 3.2825 5.6825 3.2825 24 P 0 ;1
L 5.6825 3.3325 5.6825 3.3325 24 P 0 ;1
L 5.6825 3.3825 5.6825 3.3825 24 P 0 ;1
L 5.6825 3.4325 5.6825 3.4325 24 P 0 ;1
L 5.6825 3.4825 5.6825 3.4825 24 P 0 ;1
L 5.6825 3.5325 5.6825 3.5325 24 P 0 ;1
L 5.6825 3.5825 5.6825 3.5825 24 P 0 ;1
L 5.6825 3.6325 5.6825 3.6325 24 P 0 ;1
L 5.6825 3.6825 5.6825 3.6825 24 P 0 ;1
L 5.6825 3.7325 5.6825 3.7325 24 P 0 ;1
L 5.6825 3.7825 5.6825 3.7825 24 P 0 ;1
L 5.6825 3.8325 5.6825 3.8325 24 P 0 ;1
L 5.6825 3.8825 5.6825 3.8825 24 P 0 ;1
L 5.6825 3.9325 5.6825 3.9325 24 P 0 ;1
L 5.6825 3.9825 5.6825 3.9825 24 P 0 ;1
L 5.6825 4.0325 5.6825 4.0325 24 P 0 ;1
L 5.6825 4.0825 5.6825 4.0825 24 P 0 ;1
L 5.6825 4.1325 5.6825 4.1325 24 P 0 ;1
L 5.6825 4.1825 5.6825 4.1825 24 P 0 ;1
L 5.6825 4.2325 5.6825 4.2325 24 P 0 ;1
L 5.6825 4.2825 5.6825 4.2825 24 P 0 ;1
L 5.6825 4.3325 5.6825 4.3325 24 P 0 ;1
L 5.6825 5.0325 5.6825 5.0325 24 P 0 ;1
L 5.6825 5.0825 5.6825 5.0825 24 P 0 ;1
L 5.6825 5.1325 5.6825 5.1325 24 P 0 ;1
L 5.6825 5.8325 5.6825 5.8325 24 P 0 ;1
L 5.6825 5.8825 5.6825 5.8825 24 P 0 ;1
L 5.7325 0.6825 5.7325 0.6825 24 P 0 ;1
L 5.7325 0.7325 5.7325 0.7325 24 P 0 ;1
L 5.7325 0.7825 5.7325 0.7825 24 P 0 ;1
L 5.7325 0.8325 5.7325 0.8325 24 P 0 ;1
L 5.7325 3.2325 5.7325 3.2325 24 P 0 ;1
L 5.7325 3.2825 5.7325 3.2825 24 P 0 ;1
L 5.7325 3.3325 5.7325 3.3325 24 P 0 ;1
L 5.7325 3.3825 5.7325 3.3825 24 P 0 ;1
L 5.7325 3.4325 5.7325 3.4325 24 P 0 ;1
L 5.7325 3.4825 5.7325 3.4825 24 P 0 ;1
L 5.7325 3.5325 5.7325 3.5325 24 P 0 ;1
L 5.7325 3.5825 5.7325 3.5825 24 P 0 ;1
L 5.7325 3.6325 5.7325 3.6325 24 P 0 ;1
L 5.7325 3.6825 5.7325 3.6825 24 P 0 ;1
L 5.7325 3.7325 5.7325 3.7325 24 P 0 ;1
L 5.7325 3.7825 5.7325 3.7825 24 P 0 ;1
L 5.7325 3.8325 5.7325 3.8325 24 P 0 ;1
L 5.7325 3.8825 5.7325 3.8825 24 P 0 ;1
L 5.7325 3.9325 5.7325 3.9325 24 P 0 ;1
L 5.7325 3.9825 5.7325 3.9825 24 P 0 ;1
L 5.7325 4.0325 5.7325 4.0325 24 P 0 ;1
L 5.7325 4.0825 5.7325 4.0825 24 P 0 ;1
L 5.7325 4.1325 5.7325 4.1325 24 P 0 ;1
L 5.7325 4.1825 5.7325 4.1825 24 P 0 ;1
L 5.7325 4.2325 5.7325 4.2325 24 P 0 ;1
L 5.7325 4.2825 5.7325 4.2825 24 P 0 ;1
L 5.7325 4.3325 5.7325 4.3325 24 P 0 ;1
L 5.7325 5.0325 5.7325 5.0325 24 P 0 ;1
L 5.7325 5.0825 5.7325 5.0825 24 P 0 ;1
L 5.7325 5.1325 5.7325 5.1325 24 P 0 ;1
L 5.7325 5.8325 5.7325 5.8325 24 P 0 ;1
L 5.7325 5.8825 5.7325 5.8825 24 P 0 ;1
L 5.7825 0.6825 5.7825 0.6825 24 P 0 ;1
L 5.7825 0.7325 5.7825 0.7325 24 P 0 ;1
L 5.7825 0.7825 5.7825 0.7825 24 P 0 ;1
L 5.7825 3.2325 5.7825 3.2325 24 P 0 ;1
L 5.7825 3.2825 5.7825 3.2825 24 P 0 ;1
L 5.7825 3.3325 5.7825 3.3325 24 P 0 ;1
L 5.7825 3.3825 5.7825 3.3825 24 P 0 ;1
L 5.7825 3.4325 5.7825 3.4325 24 P 0 ;1
L 5.7825 3.4825 5.7825 3.4825 24 P 0 ;1
L 5.7825 3.5325 5.7825 3.5325 24 P 0 ;1
L 5.7825 3.5825 5.7825 3.5825 24 P 0 ;1
L 5.7825 3.6325 5.7825 3.6325 24 P 0 ;1
L 5.7825 3.6825 5.7825 3.6825 24 P 0 ;1
L 5.7825 3.7325 5.7825 3.7325 24 P 0 ;1
L 5.7825 3.7825 5.7825 3.7825 24 P 0 ;1
L 5.7825 3.8325 5.7825 3.8325 24 P 0 ;1
L 5.7825 3.8825 5.7825 3.8825 24 P 0 ;1
L 5.7825 3.9325 5.7825 3.9325 24 P 0 ;1
L 5.7825 3.9825 5.7825 3.9825 24 P 0 ;1
L 5.7825 4.0325 5.7825 4.0325 24 P 0 ;1
L 5.7825 4.0825 5.7825 4.0825 24 P 0 ;1
L 5.7825 4.1325 5.7825 4.1325 24 P 0 ;1
L 5.7825 4.1825 5.7825 4.1825 24 P 0 ;1
L 5.7825 4.2325 5.7825 4.2325 24 P 0 ;1
L 5.7825 4.2825 5.7825 4.2825 24 P 0 ;1
L 5.7825 4.3325 5.7825 4.3325 24 P 0 ;1
L 5.7825 5.0325 5.7825 5.0325 24 P 0 ;1
L 5.7825 5.0825 5.7825 5.0825 24 P 0 ;1
L 5.7825 5.1325 5.7825 5.1325 24 P 0 ;1
L 5.7825 5.8325 5.7825 5.8325 24 P 0 ;1
L 5.7825 5.8825 5.7825 5.8825 24 P 0 ;1
L 5.8325 0.6825 5.8325 0.6825 24 P 0 ;1
L 5.8325 0.7325 5.8325 0.7325 24 P 0 ;1
L 5.8325 0.7825 5.8325 0.7825 24 P 0 ;1
L 5.8325 3.2325 5.8325 3.2325 24 P 0 ;1
L 5.8325 3.2825 5.8325 3.2825 24 P 0 ;1
L 5.8325 3.3325 5.8325 3.3325 24 P 0 ;1
L 5.8325 3.3825 5.8325 3.3825 24 P 0 ;1
L 5.8325 3.4325 5.8325 3.4325 24 P 0 ;1
L 5.8325 3.4825 5.8325 3.4825 24 P 0 ;1
L 5.8325 3.5325 5.8325 3.5325 24 P 0 ;1
L 5.8325 3.5825 5.8325 3.5825 24 P 0 ;1
L 5.8325 3.6325 5.8325 3.6325 24 P 0 ;1
L 5.8325 3.6825 5.8325 3.6825 24 P 0 ;1
L 5.8325 3.7325 5.8325 3.7325 24 P 0 ;1
L 5.8325 3.7825 5.8325 3.7825 24 P 0 ;1
L 5.8325 3.8325 5.8325 3.8325 24 P 0 ;1
L 5.8325 3.8825 5.8325 3.8825 24 P 0 ;1
L 5.8325 3.9325 5.8325 3.9325 24 P 0 ;1
L 5.8325 3.9825 5.8325 3.9825 24 P 0 ;1
L 5.8325 4.0325 5.8325 4.0325 24 P 0 ;1
L 5.8325 4.0825 5.8325 4.0825 24 P 0 ;1
L 5.8325 4.1325 5.8325 4.1325 24 P 0 ;1
L 5.8325 4.1825 5.8325 4.1825 24 P 0 ;1
L 5.8325 4.2325 5.8325 4.2325 24 P 0 ;1
L 5.8325 4.2825 5.8325 4.2825 24 P 0 ;1
L 5.8325 4.3325 5.8325 4.3325 24 P 0 ;1
L 5.8325 5.0325 5.8325 5.0325 24 P 0 ;1
L 5.8325 5.0825 5.8325 5.0825 24 P 0 ;1
L 5.8325 5.1325 5.8325 5.1325 24 P 0 ;1
L 5.8325 5.8325 5.8325 5.8325 24 P 0 ;1
L 5.8325 5.8825 5.8325 5.8825 24 P 0 ;1
L 5.8825 0.6825 5.8825 0.6825 24 P 0 ;1
L 5.8825 0.7325 5.8825 0.7325 24 P 0 ;1
L 5.8825 0.7825 5.8825 0.7825 24 P 0 ;1
L 5.8825 0.8325 5.8825 0.8325 24 P 0 ;1
L 5.8825 3.2325 5.8825 3.2325 24 P 0 ;1
L 5.8825 3.2825 5.8825 3.2825 24 P 0 ;1
L 5.8825 3.3325 5.8825 3.3325 24 P 0 ;1
L 5.8825 3.3825 5.8825 3.3825 24 P 0 ;1
L 5.8825 3.4325 5.8825 3.4325 24 P 0 ;1
L 5.8825 3.4825 5.8825 3.4825 24 P 0 ;1
L 5.8825 3.5325 5.8825 3.5325 24 P 0 ;1
L 5.8825 3.5825 5.8825 3.5825 24 P 0 ;1
L 5.8825 3.6325 5.8825 3.6325 24 P 0 ;1
L 5.8825 3.6825 5.8825 3.6825 24 P 0 ;1
L 5.8825 3.7325 5.8825 3.7325 24 P 0 ;1
L 5.8825 3.7825 5.8825 3.7825 24 P 0 ;1
L 5.8825 3.8325 5.8825 3.8325 24 P 0 ;1
L 5.8825 3.8825 5.8825 3.8825 24 P 0 ;1
L 5.8825 3.9325 5.8825 3.9325 24 P 0 ;1
L 5.8825 3.9825 5.8825 3.9825 24 P 0 ;1
L 5.8825 4.0325 5.8825 4.0325 24 P 0 ;1
L 5.8825 4.0825 5.8825 4.0825 24 P 0 ;1
L 5.8825 4.1325 5.8825 4.1325 24 P 0 ;1
L 5.8825 4.2825 5.8825 4.2825 24 P 0 ;1
L 5.8825 4.3325 5.8825 4.3325 24 P 0 ;1
L 5.8825 5.0325 5.8825 5.0325 24 P 0 ;1
L 5.8825 5.0825 5.8825 5.0825 24 P 0 ;1
L 5.8825 5.1325 5.8825 5.1325 24 P 0 ;1
L 5.8825 5.8325 5.8825 5.8325 24 P 0 ;1
L 5.8825 5.8825 5.8825 5.8825 24 P 0 ;1
L 5.9325 0.6825 5.9325 0.6825 24 P 0 ;1
L 5.9325 0.7325 5.9325 0.7325 24 P 0 ;1
L 5.9325 0.7825 5.9325 0.7825 24 P 0 ;1
L 5.9325 0.8325 5.9325 0.8325 24 P 0 ;1
L 5.9325 3.2325 5.9325 3.2325 24 P 0 ;1
L 5.9325 3.2825 5.9325 3.2825 24 P 0 ;1
L 5.9325 3.3325 5.9325 3.3325 24 P 0 ;1
L 5.9325 3.3825 5.9325 3.3825 24 P 0 ;1
L 5.9325 3.4325 5.9325 3.4325 24 P 0 ;1
L 5.9325 3.4825 5.9325 3.4825 24 P 0 ;1
L 5.9325 3.5325 5.9325 3.5325 24 P 0 ;1
L 5.9325 3.5825 5.9325 3.5825 24 P 0 ;1
L 5.9325 3.6325 5.9325 3.6325 24 P 0 ;1
L 5.9325 3.6825 5.9325 3.6825 24 P 0 ;1
L 5.9325 3.7325 5.9325 3.7325 24 P 0 ;1
L 5.9325 3.7825 5.9325 3.7825 24 P 0 ;1
L 5.9325 3.8325 5.9325 3.8325 24 P 0 ;1
L 5.9325 3.8825 5.9325 3.8825 24 P 0 ;1
L 5.9325 3.9325 5.9325 3.9325 24 P 0 ;1
L 5.9325 3.9825 5.9325 3.9825 24 P 0 ;1
L 5.9325 4.0325 5.9325 4.0325 24 P 0 ;1
L 5.9325 5.0325 5.9325 5.0325 24 P 0 ;1
L 5.9325 5.0825 5.9325 5.0825 24 P 0 ;1
L 5.9325 5.1325 5.9325 5.1325 24 P 0 ;1
L 5.9325 5.1825 5.9325 5.1825 24 P 0 ;1
L 5.9325 5.8325 5.9325 5.8325 24 P 0 ;1
L 5.9325 5.8825 5.9325 5.8825 24 P 0 ;1
L 5.9825 0.6825 5.9825 0.6825 24 P 0 ;1
L 5.9825 0.7325 5.9825 0.7325 24 P 0 ;1
L 5.9825 0.7825 5.9825 0.7825 24 P 0 ;1
L 5.9825 0.8325 5.9825 0.8325 24 P 0 ;1
L 5.9825 0.8825 5.9825 0.8825 24 P 0 ;1
L 5.9825 0.9325 5.9825 0.9325 24 P 0 ;1
L 5.9825 0.9825 5.9825 0.9825 24 P 0 ;1
L 5.9825 1.0325 5.9825 1.0325 24 P 0 ;1
L 5.9825 1.0825 5.9825 1.0825 24 P 0 ;1
L 5.9825 1.1325 5.9825 1.1325 24 P 0 ;1
L 5.9825 1.1825 5.9825 1.1825 24 P 0 ;1
L 5.9825 1.2325 5.9825 1.2325 24 P 0 ;1
L 5.9825 1.2825 5.9825 1.2825 24 P 0 ;1
L 5.9825 1.7325 5.9825 1.7325 24 P 0 ;1
L 5.9825 1.7825 5.9825 1.7825 24 P 0 ;1
L 5.9825 1.8325 5.9825 1.8325 24 P 0 ;1
L 5.9825 1.8825 5.9825 1.8825 24 P 0 ;1
L 5.9825 1.9325 5.9825 1.9325 24 P 0 ;1
L 5.9825 1.9825 5.9825 1.9825 24 P 0 ;1
L 5.9825 2.0325 5.9825 2.0325 24 P 0 ;1
L 5.9825 2.0825 5.9825 2.0825 24 P 0 ;1
L 5.9825 2.1325 5.9825 2.1325 24 P 0 ;1
L 5.9825 2.1825 5.9825 2.1825 24 P 0 ;1
L 5.9825 2.2325 5.9825 2.2325 24 P 0 ;1
L 5.9825 2.2825 5.9825 2.2825 24 P 0 ;1
L 5.9825 2.3325 5.9825 2.3325 24 P 0 ;1
L 5.9825 2.3825 5.9825 2.3825 24 P 0 ;1
L 5.9825 2.4325 5.9825 2.4325 24 P 0 ;1
L 5.9825 3.2325 5.9825 3.2325 24 P 0 ;1
L 5.9825 3.2825 5.9825 3.2825 24 P 0 ;1
L 5.9825 3.3325 5.9825 3.3325 24 P 0 ;1
L 5.9825 3.3825 5.9825 3.3825 24 P 0 ;1
L 5.9825 3.4325 5.9825 3.4325 24 P 0 ;1
L 5.9825 3.4825 5.9825 3.4825 24 P 0 ;1
L 5.9825 3.5325 5.9825 3.5325 24 P 0 ;1
L 5.9825 3.5825 5.9825 3.5825 24 P 0 ;1
L 5.9825 3.6325 5.9825 3.6325 24 P 0 ;1
L 5.9825 3.6825 5.9825 3.6825 24 P 0 ;1
L 5.9825 3.7325 5.9825 3.7325 24 P 0 ;1
L 5.9825 3.7825 5.9825 3.7825 24 P 0 ;1
L 5.9825 3.8325 5.9825 3.8325 24 P 0 ;1
L 5.9825 3.8825 5.9825 3.8825 24 P 0 ;1
L 5.9825 3.9325 5.9825 3.9325 24 P 0 ;1
L 5.9825 3.9825 5.9825 3.9825 24 P 0 ;1
L 5.9825 5.0325 5.9825 5.0325 24 P 0 ;1
L 5.9825 5.0825 5.9825 5.0825 24 P 0 ;1
L 5.9825 5.1325 5.9825 5.1325 24 P 0 ;1
L 5.9825 5.1825 5.9825 5.1825 24 P 0 ;1
L 5.9825 5.2325 5.9825 5.2325 24 P 0 ;1
L 5.9825 5.8325 5.9825 5.8325 24 P 0 ;1
L 5.9825 5.8825 5.9825 5.8825 24 P 0 ;1
L 6.0325 0.6825 6.0325 0.6825 24 P 0 ;1
L 6.0325 0.7325 6.0325 0.7325 24 P 0 ;1
L 6.0325 0.7825 6.0325 0.7825 24 P 0 ;1
L 6.0325 0.8325 6.0325 0.8325 24 P 0 ;1
L 6.0325 0.8825 6.0325 0.8825 24 P 0 ;1
L 6.0325 0.9325 6.0325 0.9325 24 P 0 ;1
L 6.0325 0.9825 6.0325 0.9825 24 P 0 ;1
L 6.0325 1.0325 6.0325 1.0325 24 P 0 ;1
L 6.0325 1.0825 6.0325 1.0825 24 P 0 ;1
L 6.0325 1.1325 6.0325 1.1325 24 P 0 ;1
L 6.0325 1.1825 6.0325 1.1825 24 P 0 ;1
L 6.0325 1.2325 6.0325 1.2325 24 P 0 ;1
L 6.0325 1.2825 6.0325 1.2825 24 P 0 ;1
L 6.0325 1.7825 6.0325 1.7825 24 P 0 ;1
L 6.0325 1.8325 6.0325 1.8325 24 P 0 ;1
L 6.0325 1.8825 6.0325 1.8825 24 P 0 ;1
L 6.0325 1.9325 6.0325 1.9325 24 P 0 ;1
L 6.0325 1.9825 6.0325 1.9825 24 P 0 ;1
L 6.0325 2.0325 6.0325 2.0325 24 P 0 ;1
L 6.0325 2.0825 6.0325 2.0825 24 P 0 ;1
L 6.0325 2.1325 6.0325 2.1325 24 P 0 ;1
L 6.0325 2.1825 6.0325 2.1825 24 P 0 ;1
L 6.0325 2.2325 6.0325 2.2325 24 P 0 ;1
L 6.0325 2.2825 6.0325 2.2825 24 P 0 ;1
L 6.0325 2.3325 6.0325 2.3325 24 P 0 ;1
L 6.0325 2.3825 6.0325 2.3825 24 P 0 ;1
L 6.0325 3.1825 6.0325 3.1825 24 P 0 ;1
L 6.0325 3.2325 6.0325 3.2325 24 P 0 ;1
L 6.0325 3.2825 6.0325 3.2825 24 P 0 ;1
L 6.0325 3.3325 6.0325 3.3325 24 P 0 ;1
L 6.0325 3.3825 6.0325 3.3825 24 P 0 ;1
L 6.0325 3.4325 6.0325 3.4325 24 P 0 ;1
L 6.0325 3.4825 6.0325 3.4825 24 P 0 ;1
L 6.0325 3.5325 6.0325 3.5325 24 P 0 ;1
L 6.0325 3.5825 6.0325 3.5825 24 P 0 ;1
L 6.0325 3.6325 6.0325 3.6325 24 P 0 ;1
L 6.0325 3.6825 6.0325 3.6825 24 P 0 ;1
L 6.0325 3.7325 6.0325 3.7325 24 P 0 ;1
L 6.0325 3.7825 6.0325 3.7825 24 P 0 ;1
L 6.0325 3.8325 6.0325 3.8325 24 P 0 ;1
L 6.0325 3.8825 6.0325 3.8825 24 P 0 ;1
L 6.0325 3.9325 6.0325 3.9325 24 P 0 ;1
L 6.0325 5.0325 6.0325 5.0325 24 P 0 ;1
L 6.0325 5.0825 6.0325 5.0825 24 P 0 ;1
L 6.0325 5.1325 6.0325 5.1325 24 P 0 ;1
L 6.0325 5.1825 6.0325 5.1825 24 P 0 ;1
L 6.0325 5.2325 6.0325 5.2325 24 P 0 ;1
L 6.0325 5.2825 6.0325 5.2825 24 P 0 ;1
L 6.0325 5.5825 6.0325 5.5825 24 P 0 ;1
L 6.0325 5.8325 6.0325 5.8325 24 P 0 ;1
L 6.0325 5.8825 6.0325 5.8825 24 P 0 ;1
L 6.0825 0.6825 6.0825 0.6825 24 P 0 ;1
L 6.0825 0.7325 6.0825 0.7325 24 P 0 ;1
L 6.0825 0.7825 6.0825 0.7825 24 P 0 ;1
L 6.0825 0.8325 6.0825 0.8325 24 P 0 ;1
L 6.0825 0.8825 6.0825 0.8825 24 P 0 ;1
L 6.0825 0.9325 6.0825 0.9325 24 P 0 ;1
L 6.0825 0.9825 6.0825 0.9825 24 P 0 ;1
L 6.0825 1.0325 6.0825 1.0325 24 P 0 ;1
L 6.0825 1.0825 6.0825 1.0825 24 P 0 ;1
L 6.0825 1.1325 6.0825 1.1325 24 P 0 ;1
L 6.0825 1.1825 6.0825 1.1825 24 P 0 ;1
L 6.0825 1.2325 6.0825 1.2325 24 P 0 ;1
L 6.0825 1.2825 6.0825 1.2825 24 P 0 ;1
L 6.0825 1.7825 6.0825 1.7825 24 P 0 ;1
L 6.0825 1.8325 6.0825 1.8325 24 P 0 ;1
L 6.0825 1.8825 6.0825 1.8825 24 P 0 ;1
L 6.0825 1.9325 6.0825 1.9325 24 P 0 ;1
L 6.0825 1.9825 6.0825 1.9825 24 P 0 ;1
L 6.0825 2.0325 6.0825 2.0325 24 P 0 ;1
L 6.0825 2.0825 6.0825 2.0825 24 P 0 ;1
L 6.0825 2.1325 6.0825 2.1325 24 P 0 ;1
L 6.0825 2.1825 6.0825 2.1825 24 P 0 ;1
L 6.0825 2.2325 6.0825 2.2325 24 P 0 ;1
L 6.0825 2.2825 6.0825 2.2825 24 P 0 ;1
L 6.0825 2.3325 6.0825 2.3325 24 P 0 ;1
L 6.0825 2.3825 6.0825 2.3825 24 P 0 ;1
L 6.0825 2.4325 6.0825 2.4325 24 P 0 ;1
L 6.0825 2.7325 6.0825 2.7325 24 P 0 ;1
L 6.0825 2.7825 6.0825 2.7825 24 P 0 ;1
L 6.0825 2.8325 6.0825 2.8325 24 P 0 ;1
L 6.0825 2.8825 6.0825 2.8825 24 P 0 ;1
L 6.0825 2.9325 6.0825 2.9325 24 P 0 ;1
L 6.0825 2.9825 6.0825 2.9825 24 P 0 ;1
L 6.0825 3.0325 6.0825 3.0325 24 P 0 ;1
L 6.0825 3.0825 6.0825 3.0825 24 P 0 ;1
L 6.0825 3.1325 6.0825 3.1325 24 P 0 ;1
L 6.0825 3.1825 6.0825 3.1825 24 P 0 ;1
L 6.0825 3.2325 6.0825 3.2325 24 P 0 ;1
L 6.0825 3.2825 6.0825 3.2825 24 P 0 ;1
L 6.0825 3.3325 6.0825 3.3325 24 P 0 ;1
L 6.0825 3.3825 6.0825 3.3825 24 P 0 ;1
L 6.0825 3.4325 6.0825 3.4325 24 P 0 ;1
L 6.0825 3.4825 6.0825 3.4825 24 P 0 ;1
L 6.0825 3.5325 6.0825 3.5325 24 P 0 ;1
L 6.0825 3.5825 6.0825 3.5825 24 P 0 ;1
L 6.0825 3.6325 6.0825 3.6325 24 P 0 ;1
L 6.0825 3.6825 6.0825 3.6825 24 P 0 ;1
L 6.0825 3.7325 6.0825 3.7325 24 P 0 ;1
L 6.0825 3.7825 6.0825 3.7825 24 P 0 ;1
L 6.0825 3.8325 6.0825 3.8325 24 P 0 ;1
L 6.0825 3.8825 6.0825 3.8825 24 P 0 ;1
L 6.0825 3.9325 6.0825 3.9325 24 P 0 ;1
L 6.0825 5.0325 6.0825 5.0325 24 P 0 ;1
L 6.0825 5.0825 6.0825 5.0825 24 P 0 ;1
L 6.0825 5.1325 6.0825 5.1325 24 P 0 ;1
L 6.0825 5.1825 6.0825 5.1825 24 P 0 ;1
L 6.0825 5.2325 6.0825 5.2325 24 P 0 ;1
L 6.0825 5.2825 6.0825 5.2825 24 P 0 ;1
L 6.0825 5.3325 6.0825 5.3325 24 P 0 ;1
L 6.0825 5.3825 6.0825 5.3825 24 P 0 ;1
L 6.0825 5.4325 6.0825 5.4325 24 P 0 ;1
L 6.0825 5.4825 6.0825 5.4825 24 P 0 ;1
L 6.0825 5.5325 6.0825 5.5325 24 P 0 ;1
L 6.0825 5.5825 6.0825 5.5825 24 P 0 ;1
L 6.0825 5.8325 6.0825 5.8325 24 P 0 ;1
L 6.0825 5.8825 6.0825 5.8825 24 P 0 ;1
L 6.1325 0.6825 6.1325 0.6825 24 P 0 ;1
L 6.1325 0.7325 6.1325 0.7325 24 P 0 ;1
L 6.1325 0.7825 6.1325 0.7825 24 P 0 ;1
L 6.1325 0.8325 6.1325 0.8325 24 P 0 ;1
L 6.1325 0.8825 6.1325 0.8825 24 P 0 ;1
L 6.1325 0.9325 6.1325 0.9325 24 P 0 ;1
L 6.1325 0.9825 6.1325 0.9825 24 P 0 ;1
L 6.1325 1.0325 6.1325 1.0325 24 P 0 ;1
L 6.1325 1.0825 6.1325 1.0825 24 P 0 ;1
L 6.1325 1.1325 6.1325 1.1325 24 P 0 ;1
L 6.1325 1.1825 6.1325 1.1825 24 P 0 ;1
L 6.1325 1.2325 6.1325 1.2325 24 P 0 ;1
L 6.1325 1.2825 6.1325 1.2825 24 P 0 ;1
L 6.1325 1.7825 6.1325 1.7825 24 P 0 ;1
L 6.1325 1.8325 6.1325 1.8325 24 P 0 ;1
L 6.1325 1.8825 6.1325 1.8825 24 P 0 ;1
L 6.1325 1.9325 6.1325 1.9325 24 P 0 ;1
L 6.1325 1.9825 6.1325 1.9825 24 P 0 ;1
L 6.1325 2.0325 6.1325 2.0325 24 P 0 ;1
L 6.1325 2.0825 6.1325 2.0825 24 P 0 ;1
L 6.1325 2.1325 6.1325 2.1325 24 P 0 ;1
L 6.1325 2.1825 6.1325 2.1825 24 P 0 ;1
L 6.1325 2.2325 6.1325 2.2325 24 P 0 ;1
L 6.1325 2.2825 6.1325 2.2825 24 P 0 ;1
L 6.1325 2.3325 6.1325 2.3325 24 P 0 ;1
L 6.1325 2.3825 6.1325 2.3825 24 P 0 ;1
L 6.1325 2.4325 6.1325 2.4325 24 P 0 ;1
L 6.1325 2.7325 6.1325 2.7325 24 P 0 ;1
L 6.1325 2.7825 6.1325 2.7825 24 P 0 ;1
L 6.1325 2.8325 6.1325 2.8325 24 P 0 ;1
L 6.1325 2.8825 6.1325 2.8825 24 P 0 ;1
L 6.1325 2.9325 6.1325 2.9325 24 P 0 ;1
L 6.1325 2.9825 6.1325 2.9825 24 P 0 ;1
L 6.1325 3.0325 6.1325 3.0325 24 P 0 ;1
L 6.1325 3.0825 6.1325 3.0825 24 P 0 ;1
L 6.1325 3.1325 6.1325 3.1325 24 P 0 ;1
L 6.1325 3.1825 6.1325 3.1825 24 P 0 ;1
L 6.1325 3.2325 6.1325 3.2325 24 P 0 ;1
L 6.1325 3.2825 6.1325 3.2825 24 P 0 ;1
L 6.1325 3.3325 6.1325 3.3325 24 P 0 ;1
L 6.1325 3.3825 6.1325 3.3825 24 P 0 ;1
L 6.1325 3.4325 6.1325 3.4325 24 P 0 ;1
L 6.1325 3.4825 6.1325 3.4825 24 P 0 ;1
L 6.1325 3.5325 6.1325 3.5325 24 P 0 ;1
L 6.1325 3.5825 6.1325 3.5825 24 P 0 ;1
L 6.1325 3.6325 6.1325 3.6325 24 P 0 ;1
L 6.1325 3.6825 6.1325 3.6825 24 P 0 ;1
L 6.1325 3.7325 6.1325 3.7325 24 P 0 ;1
L 6.1325 3.7825 6.1325 3.7825 24 P 0 ;1
L 6.1325 3.8325 6.1325 3.8325 24 P 0 ;1
L 6.1325 3.8825 6.1325 3.8825 24 P 0 ;1
L 6.1325 3.9325 6.1325 3.9325 24 P 0 ;1
L 6.1325 5.0325 6.1325 5.0325 24 P 0 ;1
L 6.1325 5.0825 6.1325 5.0825 24 P 0 ;1
L 6.1325 5.1325 6.1325 5.1325 24 P 0 ;1
L 6.1325 5.1825 6.1325 5.1825 24 P 0 ;1
L 6.1325 5.2325 6.1325 5.2325 24 P 0 ;1
L 6.1325 5.2825 6.1325 5.2825 24 P 0 ;1
L 6.1325 5.3325 6.1325 5.3325 24 P 0 ;1
L 6.1325 5.3825 6.1325 5.3825 24 P 0 ;1
L 6.1325 5.4325 6.1325 5.4325 24 P 0 ;1
L 6.1325 5.4825 6.1325 5.4825 24 P 0 ;1
L 6.1325 5.5325 6.1325 5.5325 24 P 0 ;1
L 6.1325 5.5825 6.1325 5.5825 24 P 0 ;1
L 6.1325 5.8325 6.1325 5.8325 24 P 0 ;1
L 6.1325 5.8825 6.1325 5.8825 24 P 0 ;1
L 6.1825 0.6825 6.1825 0.6825 24 P 0 ;1
L 6.1825 0.7325 6.1825 0.7325 24 P 0 ;1
L 6.1825 0.7825 6.1825 0.7825 24 P 0 ;1
L 6.1825 0.8325 6.1825 0.8325 24 P 0 ;1
L 6.1825 0.8825 6.1825 0.8825 24 P 0 ;1
L 6.1825 0.9325 6.1825 0.9325 24 P 0 ;1
L 6.1825 0.9825 6.1825 0.9825 24 P 0 ;1
L 6.1825 1.0325 6.1825 1.0325 24 P 0 ;1
L 6.1825 1.0825 6.1825 1.0825 24 P 0 ;1
L 6.1825 1.1325 6.1825 1.1325 24 P 0 ;1
L 6.1825 1.1825 6.1825 1.1825 24 P 0 ;1
L 6.1825 1.2325 6.1825 1.2325 24 P 0 ;1
L 6.1825 1.2825 6.1825 1.2825 24 P 0 ;1
L 6.1825 1.7825 6.1825 1.7825 24 P 0 ;1
L 6.1825 1.8325 6.1825 1.8325 24 P 0 ;1
L 6.1825 1.8825 6.1825 1.8825 24 P 0 ;1
L 6.1825 1.9325 6.1825 1.9325 24 P 0 ;1
L 6.1825 1.9825 6.1825 1.9825 24 P 0 ;1
L 6.1825 2.0325 6.1825 2.0325 24 P 0 ;1
L 6.1825 2.0825 6.1825 2.0825 24 P 0 ;1
L 6.1825 2.1325 6.1825 2.1325 24 P 0 ;1
L 6.1825 2.1825 6.1825 2.1825 24 P 0 ;1
L 6.1825 2.2325 6.1825 2.2325 24 P 0 ;1
L 6.1825 2.2825 6.1825 2.2825 24 P 0 ;1
L 6.1825 2.3325 6.1825 2.3325 24 P 0 ;1
L 6.1825 2.3825 6.1825 2.3825 24 P 0 ;1
L 6.1825 2.4325 6.1825 2.4325 24 P 0 ;1
L 6.1825 2.4825 6.1825 2.4825 24 P 0 ;1
L 6.1825 2.6825 6.1825 2.6825 24 P 0 ;1
L 6.1825 2.7325 6.1825 2.7325 24 P 0 ;1
L 6.1825 2.7825 6.1825 2.7825 24 P 0 ;1
L 6.1825 2.8325 6.1825 2.8325 24 P 0 ;1
L 6.1825 2.8825 6.1825 2.8825 24 P 0 ;1
L 6.1825 2.9325 6.1825 2.9325 24 P 0 ;1
L 6.1825 2.9825 6.1825 2.9825 24 P 0 ;1
L 6.1825 3.0325 6.1825 3.0325 24 P 0 ;1
L 6.1825 3.0825 6.1825 3.0825 24 P 0 ;1
L 6.1825 3.1325 6.1825 3.1325 24 P 0 ;1
L 6.1825 3.1825 6.1825 3.1825 24 P 0 ;1
L 6.1825 3.2325 6.1825 3.2325 24 P 0 ;1
L 6.1825 3.2825 6.1825 3.2825 24 P 0 ;1
L 6.1825 3.3325 6.1825 3.3325 24 P 0 ;1
L 6.1825 3.3825 6.1825 3.3825 24 P 0 ;1
L 6.1825 3.4325 6.1825 3.4325 24 P 0 ;1
L 6.1825 3.4825 6.1825 3.4825 24 P 0 ;1
L 6.1825 3.5325 6.1825 3.5325 24 P 0 ;1
L 6.1825 3.5825 6.1825 3.5825 24 P 0 ;1
L 6.1825 3.6325 6.1825 3.6325 24 P 0 ;1
L 6.1825 3.6825 6.1825 3.6825 24 P 0 ;1
L 6.1825 3.7325 6.1825 3.7325 24 P 0 ;1
L 6.1825 3.7825 6.1825 3.7825 24 P 0 ;1
L 6.1825 3.8325 6.1825 3.8325 24 P 0 ;1
L 6.1825 3.8825 6.1825 3.8825 24 P 0 ;1
L 6.1825 3.9325 6.1825 3.9325 24 P 0 ;1
L 6.1825 5.0325 6.1825 5.0325 24 P 0 ;1
L 6.1825 5.0825 6.1825 5.0825 24 P 0 ;1
L 6.1825 5.1325 6.1825 5.1325 24 P 0 ;1
L 6.1825 5.1825 6.1825 5.1825 24 P 0 ;1
L 6.1825 5.2325 6.1825 5.2325 24 P 0 ;1
L 6.1825 5.2825 6.1825 5.2825 24 P 0 ;1
L 6.1825 5.3325 6.1825 5.3325 24 P 0 ;1
L 6.1825 5.3825 6.1825 5.3825 24 P 0 ;1
L 6.1825 5.4325 6.1825 5.4325 24 P 0 ;1
L 6.1825 5.4825 6.1825 5.4825 24 P 0 ;1
L 6.1825 5.5325 6.1825 5.5325 24 P 0 ;1
L 6.1825 5.5825 6.1825 5.5825 24 P 0 ;1
L 6.1825 5.8325 6.1825 5.8325 24 P 0 ;1
L 6.1825 5.8825 6.1825 5.8825 24 P 0 ;1
L 6.2325 0.6825 6.2325 0.6825 24 P 0 ;1
L 6.2325 0.7325 6.2325 0.7325 24 P 0 ;1
L 6.2325 0.7825 6.2325 0.7825 24 P 0 ;1
L 6.2325 0.8325 6.2325 0.8325 24 P 0 ;1
L 6.2325 0.8825 6.2325 0.8825 24 P 0 ;1
L 6.2325 0.9325 6.2325 0.9325 24 P 0 ;1
L 6.2325 0.9825 6.2325 0.9825 24 P 0 ;1
L 6.2325 1.0325 6.2325 1.0325 24 P 0 ;1
L 6.2325 1.0825 6.2325 1.0825 24 P 0 ;1
L 6.2325 1.1325 6.2325 1.1325 24 P 0 ;1
L 6.2325 1.1825 6.2325 1.1825 24 P 0 ;1
L 6.2325 1.2325 6.2325 1.2325 24 P 0 ;1
L 6.2325 1.2825 6.2325 1.2825 24 P 0 ;1
L 6.2325 1.7825 6.2325 1.7825 24 P 0 ;1
L 6.2325 1.8325 6.2325 1.8325 24 P 0 ;1
L 6.2325 1.8825 6.2325 1.8825 24 P 0 ;1
L 6.2325 1.9325 6.2325 1.9325 24 P 0 ;1
L 6.2325 1.9825 6.2325 1.9825 24 P 0 ;1
L 6.2325 2.0325 6.2325 2.0325 24 P 0 ;1
L 6.2325 2.0825 6.2325 2.0825 24 P 0 ;1
L 6.2325 2.1325 6.2325 2.1325 24 P 0 ;1
L 6.2325 2.1825 6.2325 2.1825 24 P 0 ;1
L 6.2325 2.2325 6.2325 2.2325 24 P 0 ;1
L 6.2325 2.2825 6.2325 2.2825 24 P 0 ;1
L 6.2325 2.3325 6.2325 2.3325 24 P 0 ;1
L 6.2325 2.3825 6.2325 2.3825 24 P 0 ;1
L 6.2325 2.4325 6.2325 2.4325 24 P 0 ;1
L 6.2325 2.4825 6.2325 2.4825 24 P 0 ;1
L 6.2325 2.5325 6.2325 2.5325 24 P 0 ;1
L 6.2325 2.5825 6.2325 2.5825 24 P 0 ;1
L 6.2325 2.6325 6.2325 2.6325 24 P 0 ;1
L 6.2325 2.6825 6.2325 2.6825 24 P 0 ;1
L 6.2325 2.7325 6.2325 2.7325 24 P 0 ;1
L 6.2325 2.7825 6.2325 2.7825 24 P 0 ;1
L 6.2325 2.8325 6.2325 2.8325 24 P 0 ;1
L 6.2325 2.8825 6.2325 2.8825 24 P 0 ;1
L 6.2325 2.9325 6.2325 2.9325 24 P 0 ;1
L 6.2325 2.9825 6.2325 2.9825 24 P 0 ;1
L 6.2325 3.0325 6.2325 3.0325 24 P 0 ;1
L 6.2325 3.0825 6.2325 3.0825 24 P 0 ;1
L 6.2325 3.1325 6.2325 3.1325 24 P 0 ;1
L 6.2325 3.1825 6.2325 3.1825 24 P 0 ;1
L 6.2325 3.2325 6.2325 3.2325 24 P 0 ;1
L 6.2325 3.2825 6.2325 3.2825 24 P 0 ;1
L 6.2325 3.3325 6.2325 3.3325 24 P 0 ;1
L 6.2325 3.3825 6.2325 3.3825 24 P 0 ;1
L 6.2325 3.4325 6.2325 3.4325 24 P 0 ;1
L 6.2325 3.4825 6.2325 3.4825 24 P 0 ;1
L 6.2325 3.5325 6.2325 3.5325 24 P 0 ;1
L 6.2325 3.5825 6.2325 3.5825 24 P 0 ;1
L 6.2325 3.6325 6.2325 3.6325 24 P 0 ;1
L 6.2325 3.6825 6.2325 3.6825 24 P 0 ;1
L 6.2325 3.7325 6.2325 3.7325 24 P 0 ;1
L 6.2325 3.7825 6.2325 3.7825 24 P 0 ;1
L 6.2325 3.8325 6.2325 3.8325 24 P 0 ;1
L 6.2325 3.8825 6.2325 3.8825 24 P 0 ;1
L 6.2325 3.9325 6.2325 3.9325 24 P 0 ;1
L 6.2325 3.9825 6.2325 3.9825 24 P 0 ;1
L 6.2325 4.4325 6.2325 4.4325 24 P 0 ;1
L 6.2325 4.4825 6.2325 4.4825 24 P 0 ;1
L 6.2325 5.0825 6.2325 5.0825 24 P 0 ;1
L 6.2325 5.1325 6.2325 5.1325 24 P 0 ;1
L 6.2325 5.1825 6.2325 5.1825 24 P 0 ;1
L 6.2325 5.2325 6.2325 5.2325 24 P 0 ;1
L 6.2325 5.2825 6.2325 5.2825 24 P 0 ;1
L 6.2325 5.3325 6.2325 5.3325 24 P 0 ;1
L 6.2325 5.3825 6.2325 5.3825 24 P 0 ;1
L 6.2325 5.4325 6.2325 5.4325 24 P 0 ;1
L 6.2325 5.4825 6.2325 5.4825 24 P 0 ;1
L 6.2325 5.5325 6.2325 5.5325 24 P 0 ;1
L 6.2325 5.5825 6.2325 5.5825 24 P 0 ;1
L 6.2325 5.8325 6.2325 5.8325 24 P 0 ;1
L 6.2325 5.8825 6.2325 5.8825 24 P 0 ;1
L 6.2825 0.6825 6.2825 0.6825 24 P 0 ;1
L 6.2825 0.7325 6.2825 0.7325 24 P 0 ;1
L 6.2825 0.7825 6.2825 0.7825 24 P 0 ;1
L 6.2825 0.8325 6.2825 0.8325 24 P 0 ;1
L 6.2825 0.8825 6.2825 0.8825 24 P 0 ;1
L 6.2825 0.9325 6.2825 0.9325 24 P 0 ;1
L 6.2825 0.9825 6.2825 0.9825 24 P 0 ;1
L 6.2825 1.0325 6.2825 1.0325 24 P 0 ;1
L 6.2825 1.0825 6.2825 1.0825 24 P 0 ;1
L 6.2825 1.1325 6.2825 1.1325 24 P 0 ;1
L 6.2825 1.1825 6.2825 1.1825 24 P 0 ;1
L 6.2825 1.2325 6.2825 1.2325 24 P 0 ;1
L 6.2825 1.2825 6.2825 1.2825 24 P 0 ;1
L 6.2825 1.3325 6.2825 1.3325 24 P 0 ;1
L 6.2825 1.7325 6.2825 1.7325 24 P 0 ;1
L 6.2825 1.7825 6.2825 1.7825 24 P 0 ;1
L 6.2825 1.8325 6.2825 1.8325 24 P 0 ;1
L 6.2825 1.8825 6.2825 1.8825 24 P 0 ;1
L 6.2825 1.9325 6.2825 1.9325 24 P 0 ;1
L 6.2825 1.9825 6.2825 1.9825 24 P 0 ;1
L 6.2825 2.0325 6.2825 2.0325 24 P 0 ;1
L 6.2825 2.0825 6.2825 2.0825 24 P 0 ;1
L 6.2825 2.1325 6.2825 2.1325 24 P 0 ;1
L 6.2825 2.1825 6.2825 2.1825 24 P 0 ;1
L 6.2825 2.2325 6.2825 2.2325 24 P 0 ;1
L 6.2825 2.2825 6.2825 2.2825 24 P 0 ;1
L 6.2825 2.3325 6.2825 2.3325 24 P 0 ;1
L 6.2825 2.3825 6.2825 2.3825 24 P 0 ;1
L 6.2825 2.4325 6.2825 2.4325 24 P 0 ;1
L 6.2825 2.4825 6.2825 2.4825 24 P 0 ;1
L 6.2825 2.5325 6.2825 2.5325 24 P 0 ;1
L 6.2825 2.5825 6.2825 2.5825 24 P 0 ;1
L 6.2825 2.6325 6.2825 2.6325 24 P 0 ;1
L 6.2825 2.6825 6.2825 2.6825 24 P 0 ;1
L 6.2825 2.7325 6.2825 2.7325 24 P 0 ;1
L 6.2825 2.7825 6.2825 2.7825 24 P 0 ;1
L 6.2825 2.8325 6.2825 2.8325 24 P 0 ;1
L 6.2825 2.8825 6.2825 2.8825 24 P 0 ;1
L 6.2825 2.9325 6.2825 2.9325 24 P 0 ;1
L 6.2825 2.9825 6.2825 2.9825 24 P 0 ;1
L 6.2825 3.0325 6.2825 3.0325 24 P 0 ;1
L 6.2825 3.0825 6.2825 3.0825 24 P 0 ;1
L 6.2825 3.1325 6.2825 3.1325 24 P 0 ;1
L 6.2825 3.1825 6.2825 3.1825 24 P 0 ;1
L 6.2825 3.2325 6.2825 3.2325 24 P 0 ;1
L 6.2825 3.2825 6.2825 3.2825 24 P 0 ;1
L 6.2825 3.3325 6.2825 3.3325 24 P 0 ;1
L 6.2825 3.3825 6.2825 3.3825 24 P 0 ;1
L 6.2825 3.4325 6.2825 3.4325 24 P 0 ;1
L 6.2825 3.4825 6.2825 3.4825 24 P 0 ;1
L 6.2825 3.5325 6.2825 3.5325 24 P 0 ;1
L 6.2825 3.5825 6.2825 3.5825 24 P 0 ;1
L 6.2825 3.6325 6.2825 3.6325 24 P 0 ;1
L 6.2825 3.6825 6.2825 3.6825 24 P 0 ;1
L 6.2825 3.7325 6.2825 3.7325 24 P 0 ;1
L 6.2825 3.7825 6.2825 3.7825 24 P 0 ;1
L 6.2825 3.8325 6.2825 3.8325 24 P 0 ;1
L 6.2825 3.8825 6.2825 3.8825 24 P 0 ;1
L 6.2825 3.9325 6.2825 3.9325 24 P 0 ;1
L 6.2825 3.9825 6.2825 3.9825 24 P 0 ;1
L 6.2825 4.4325 6.2825 4.4325 24 P 0 ;1
L 6.2825 4.4825 6.2825 4.4825 24 P 0 ;1
L 6.2825 5.1325 6.2825 5.1325 24 P 0 ;1
L 6.2825 5.1825 6.2825 5.1825 24 P 0 ;1
L 6.2825 5.2325 6.2825 5.2325 24 P 0 ;1
L 6.2825 5.2825 6.2825 5.2825 24 P 0 ;1
L 6.2825 5.3325 6.2825 5.3325 24 P 0 ;1
L 6.2825 5.3825 6.2825 5.3825 24 P 0 ;1
L 6.2825 5.4325 6.2825 5.4325 24 P 0 ;1
L 6.2825 5.4825 6.2825 5.4825 24 P 0 ;1
L 6.2825 5.5325 6.2825 5.5325 24 P 0 ;1
L 6.2825 5.5825 6.2825 5.5825 24 P 0 ;1
L 6.2825 5.8325 6.2825 5.8325 24 P 0 ;1
L 6.2825 5.8825 6.2825 5.8825 24 P 0 ;1
L 6.3325 0.6825 6.3325 0.6825 24 P 0 ;1
L 6.3325 0.7325 6.3325 0.7325 24 P 0 ;1
L 6.3325 0.7825 6.3325 0.7825 24 P 0 ;1
L 6.3325 0.8325 6.3325 0.8325 24 P 0 ;1
L 6.3325 0.8825 6.3325 0.8825 24 P 0 ;1
L 6.3325 0.9325 6.3325 0.9325 24 P 0 ;1
L 6.3325 0.9825 6.3325 0.9825 24 P 0 ;1
L 6.3325 1.0325 6.3325 1.0325 24 P 0 ;1
L 6.3325 1.0825 6.3325 1.0825 24 P 0 ;1
L 6.3325 1.1325 6.3325 1.1325 24 P 0 ;1
L 6.3325 1.1825 6.3325 1.1825 24 P 0 ;1
L 6.3325 1.2325 6.3325 1.2325 24 P 0 ;1
L 6.3325 1.2825 6.3325 1.2825 24 P 0 ;1
L 6.3325 1.3325 6.3325 1.3325 24 P 0 ;1
L 6.3325 1.3825 6.3325 1.3825 24 P 0 ;1
L 6.3325 1.6825 6.3325 1.6825 24 P 0 ;1
L 6.3325 1.7325 6.3325 1.7325 24 P 0 ;1
L 6.3325 1.7825 6.3325 1.7825 24 P 0 ;1
L 6.3325 1.8325 6.3325 1.8325 24 P 0 ;1
L 6.3325 1.8825 6.3325 1.8825 24 P 0 ;1
L 6.3325 1.9325 6.3325 1.9325 24 P 0 ;1
L 6.3325 1.9825 6.3325 1.9825 24 P 0 ;1
L 6.3325 2.0325 6.3325 2.0325 24 P 0 ;1
L 6.3325 2.0825 6.3325 2.0825 24 P 0 ;1
L 6.3325 2.1325 6.3325 2.1325 24 P 0 ;1
L 6.3325 2.1825 6.3325 2.1825 24 P 0 ;1
L 6.3325 2.2325 6.3325 2.2325 24 P 0 ;1
L 6.3325 2.2825 6.3325 2.2825 24 P 0 ;1
L 6.3325 2.3325 6.3325 2.3325 24 P 0 ;1
L 6.3325 2.3825 6.3325 2.3825 24 P 0 ;1
L 6.3325 2.4325 6.3325 2.4325 24 P 0 ;1
L 6.3325 2.4825 6.3325 2.4825 24 P 0 ;1
L 6.3325 2.5325 6.3325 2.5325 24 P 0 ;1
L 6.3325 2.5825 6.3325 2.5825 24 P 0 ;1
L 6.3325 2.6325 6.3325 2.6325 24 P 0 ;1
L 6.3325 2.6825 6.3325 2.6825 24 P 0 ;1
L 6.3325 2.7325 6.3325 2.7325 24 P 0 ;1
L 6.3325 2.7825 6.3325 2.7825 24 P 0 ;1
L 6.3325 2.8325 6.3325 2.8325 24 P 0 ;1
L 6.3325 2.8825 6.3325 2.8825 24 P 0 ;1
L 6.3325 2.9325 6.3325 2.9325 24 P 0 ;1
L 6.3325 2.9825 6.3325 2.9825 24 P 0 ;1
L 6.3325 3.0325 6.3325 3.0325 24 P 0 ;1
L 6.3325 3.0825 6.3325 3.0825 24 P 0 ;1
L 6.3325 3.1325 6.3325 3.1325 24 P 0 ;1
L 6.3325 3.1825 6.3325 3.1825 24 P 0 ;1
L 6.3325 3.2325 6.3325 3.2325 24 P 0 ;1
L 6.3325 3.2825 6.3325 3.2825 24 P 0 ;1
L 6.3325 3.3325 6.3325 3.3325 24 P 0 ;1
L 6.3325 3.3825 6.3325 3.3825 24 P 0 ;1
L 6.3325 3.4325 6.3325 3.4325 24 P 0 ;1
L 6.3325 3.4825 6.3325 3.4825 24 P 0 ;1
L 6.3325 3.5325 6.3325 3.5325 24 P 0 ;1
L 6.3325 3.5825 6.3325 3.5825 24 P 0 ;1
L 6.3325 3.6325 6.3325 3.6325 24 P 0 ;1
L 6.3325 3.6825 6.3325 3.6825 24 P 0 ;1
L 6.3325 3.7325 6.3325 3.7325 24 P 0 ;1
L 6.3325 3.7825 6.3325 3.7825 24 P 0 ;1
L 6.3325 3.8325 6.3325 3.8325 24 P 0 ;1
L 6.3325 3.8825 6.3325 3.8825 24 P 0 ;1
L 6.3325 3.9325 6.3325 3.9325 24 P 0 ;1
L 6.3325 3.9825 6.3325 3.9825 24 P 0 ;1
L 6.3325 4.0325 6.3325 4.0325 24 P 0 ;1
L 6.3325 4.0825 6.3325 4.0825 24 P 0 ;1
L 6.3325 4.3325 6.3325 4.3325 24 P 0 ;1
L 6.3325 4.3825 6.3325 4.3825 24 P 0 ;1
L 6.3325 4.4325 6.3325 4.4325 24 P 0 ;1
L 6.3325 4.4825 6.3325 4.4825 24 P 0 ;1
L 6.3325 5.1825 6.3325 5.1825 24 P 0 ;1
L 6.3325 5.2325 6.3325 5.2325 24 P 0 ;1
L 6.3325 5.2825 6.3325 5.2825 24 P 0 ;1
L 6.3325 5.3325 6.3325 5.3325 24 P 0 ;1
L 6.3325 5.3825 6.3325 5.3825 24 P 0 ;1
L 6.3325 5.4325 6.3325 5.4325 24 P 0 ;1
L 6.3325 5.4825 6.3325 5.4825 24 P 0 ;1
L 6.3325 5.5325 6.3325 5.5325 24 P 0 ;1
L 6.3325 5.5825 6.3325 5.5825 24 P 0 ;1
L 6.3325 5.8325 6.3325 5.8325 24 P 0 ;1
L 6.3325 5.8825 6.3325 5.8825 24 P 0 ;1
L 6.3825 0.6825 6.3825 0.6825 24 P 0 ;1
L 6.3825 0.7325 6.3825 0.7325 24 P 0 ;1
L 6.3825 0.7825 6.3825 0.7825 24 P 0 ;1
L 6.3825 0.8325 6.3825 0.8325 24 P 0 ;1
L 6.3825 0.8825 6.3825 0.8825 24 P 0 ;1
L 6.3825 0.9325 6.3825 0.9325 24 P 0 ;1
L 6.3825 0.9825 6.3825 0.9825 24 P 0 ;1
L 6.3825 1.0325 6.3825 1.0325 24 P 0 ;1
L 6.3825 1.0825 6.3825 1.0825 24 P 0 ;1
L 6.3825 1.1325 6.3825 1.1325 24 P 0 ;1
L 6.3825 1.1825 6.3825 1.1825 24 P 0 ;1
L 6.3825 1.2325 6.3825 1.2325 24 P 0 ;1
L 6.3825 1.2825 6.3825 1.2825 24 P 0 ;1
L 6.3825 1.3325 6.3825 1.3325 24 P 0 ;1
L 6.3825 1.3825 6.3825 1.3825 24 P 0 ;1
L 6.3825 1.4325 6.3825 1.4325 24 P 0 ;1
L 6.3825 1.4825 6.3825 1.4825 24 P 0 ;1
L 6.3825 1.5325 6.3825 1.5325 24 P 0 ;1
L 6.3825 1.5825 6.3825 1.5825 24 P 0 ;1
L 6.3825 1.6325 6.3825 1.6325 24 P 0 ;1
L 6.3825 1.6825 6.3825 1.6825 24 P 0 ;1
L 6.3825 1.7325 6.3825 1.7325 24 P 0 ;1
L 6.3825 1.7825 6.3825 1.7825 24 P 0 ;1
L 6.3825 1.8325 6.3825 1.8325 24 P 0 ;1
L 6.3825 1.8825 6.3825 1.8825 24 P 0 ;1
L 6.3825 1.9325 6.3825 1.9325 24 P 0 ;1
L 6.3825 1.9825 6.3825 1.9825 24 P 0 ;1
L 6.3825 2.0325 6.3825 2.0325 24 P 0 ;1
L 6.3825 2.0825 6.3825 2.0825 24 P 0 ;1
L 6.3825 2.1325 6.3825 2.1325 24 P 0 ;1
L 6.3825 2.1825 6.3825 2.1825 24 P 0 ;1
L 6.3825 2.2325 6.3825 2.2325 24 P 0 ;1
L 6.3825 2.2825 6.3825 2.2825 24 P 0 ;1
L 6.3825 2.3325 6.3825 2.3325 24 P 0 ;1
L 6.3825 2.3825 6.3825 2.3825 24 P 0 ;1
L 6.3825 2.4325 6.3825 2.4325 24 P 0 ;1
L 6.3825 2.4825 6.3825 2.4825 24 P 0 ;1
L 6.3825 2.5325 6.3825 2.5325 24 P 0 ;1
L 6.3825 2.5825 6.3825 2.5825 24 P 0 ;1
L 6.3825 2.6325 6.3825 2.6325 24 P 0 ;1
L 6.3825 2.6825 6.3825 2.6825 24 P 0 ;1
L 6.3825 2.7325 6.3825 2.7325 24 P 0 ;1
L 6.3825 2.7825 6.3825 2.7825 24 P 0 ;1
L 6.3825 2.8325 6.3825 2.8325 24 P 0 ;1
L 6.3825 2.8825 6.3825 2.8825 24 P 0 ;1
L 6.3825 2.9325 6.3825 2.9325 24 P 0 ;1
L 6.3825 2.9825 6.3825 2.9825 24 P 0 ;1
L 6.3825 3.0325 6.3825 3.0325 24 P 0 ;1
L 6.3825 3.0825 6.3825 3.0825 24 P 0 ;1
L 6.3825 3.1325 6.3825 3.1325 24 P 0 ;1
L 6.3825 3.1825 6.3825 3.1825 24 P 0 ;1
L 6.3825 3.2325 6.3825 3.2325 24 P 0 ;1
L 6.3825 3.2825 6.3825 3.2825 24 P 0 ;1
L 6.3825 3.3325 6.3825 3.3325 24 P 0 ;1
L 6.3825 3.3825 6.3825 3.3825 24 P 0 ;1
L 6.3825 3.4325 6.3825 3.4325 24 P 0 ;1
L 6.3825 3.4825 6.3825 3.4825 24 P 0 ;1
L 6.3825 3.5325 6.3825 3.5325 24 P 0 ;1
L 6.3825 3.5825 6.3825 3.5825 24 P 0 ;1
L 6.3825 3.6325 6.3825 3.6325 24 P 0 ;1
L 6.3825 3.6825 6.3825 3.6825 24 P 0 ;1
L 6.3825 3.7325 6.3825 3.7325 24 P 0 ;1
L 6.3825 3.7825 6.3825 3.7825 24 P 0 ;1
L 6.3825 3.8325 6.3825 3.8325 24 P 0 ;1
L 6.3825 3.8825 6.3825 3.8825 24 P 0 ;1
L 6.3825 3.9325 6.3825 3.9325 24 P 0 ;1
L 6.3825 3.9825 6.3825 3.9825 24 P 0 ;1
L 6.3825 4.0325 6.3825 4.0325 24 P 0 ;1
L 6.3825 4.0825 6.3825 4.0825 24 P 0 ;1
L 6.3825 4.1325 6.3825 4.1325 24 P 0 ;1
L 6.3825 4.1825 6.3825 4.1825 24 P 0 ;1
L 6.3825 4.2325 6.3825 4.2325 24 P 0 ;1
L 6.3825 4.2825 6.3825 4.2825 24 P 0 ;1
L 6.3825 4.3325 6.3825 4.3325 24 P 0 ;1
L 6.3825 4.3825 6.3825 4.3825 24 P 0 ;1
L 6.3825 4.4325 6.3825 4.4325 24 P 0 ;1
L 6.3825 4.4825 6.3825 4.4825 24 P 0 ;1
L 6.3825 4.5325 6.3825 4.5325 24 P 0 ;1
L 6.3825 5.1825 6.3825 5.1825 24 P 0 ;1
L 6.3825 5.2325 6.3825 5.2325 24 P 0 ;1
L 6.3825 5.2825 6.3825 5.2825 24 P 0 ;1
L 6.3825 5.3325 6.3825 5.3325 24 P 0 ;1
L 6.3825 5.3825 6.3825 5.3825 24 P 0 ;1
L 6.3825 5.4325 6.3825 5.4325 24 P 0 ;1
L 6.3825 5.4825 6.3825 5.4825 24 P 0 ;1
L 6.3825 5.5325 6.3825 5.5325 24 P 0 ;1
L 6.3825 5.5825 6.3825 5.5825 24 P 0 ;1
L 6.3825 5.8325 6.3825 5.8325 24 P 0 ;1
L 6.3825 5.8825 6.3825 5.8825 24 P 0 ;1
L 6.4325 0.6825 6.4325 0.6825 24 P 0 ;1
L 6.4325 0.7325 6.4325 0.7325 24 P 0 ;1
L 6.4325 0.7825 6.4325 0.7825 24 P 0 ;1
L 6.4325 0.8325 6.4325 0.8325 24 P 0 ;1
L 6.4325 0.8825 6.4325 0.8825 24 P 0 ;1
L 6.4325 0.9325 6.4325 0.9325 24 P 0 ;1
L 6.4325 0.9825 6.4325 0.9825 24 P 0 ;1
L 6.4325 1.0325 6.4325 1.0325 24 P 0 ;1
L 6.4325 1.0825 6.4325 1.0825 24 P 0 ;1
L 6.4325 1.1325 6.4325 1.1325 24 P 0 ;1
L 6.4325 1.1825 6.4325 1.1825 24 P 0 ;1
L 6.4325 1.2325 6.4325 1.2325 24 P 0 ;1
L 6.4325 1.2825 6.4325 1.2825 24 P 0 ;1
L 6.4325 1.3325 6.4325 1.3325 24 P 0 ;1
L 6.4325 1.3825 6.4325 1.3825 24 P 0 ;1
L 6.4325 1.4325 6.4325 1.4325 24 P 0 ;1
L 6.4325 1.4825 6.4325 1.4825 24 P 0 ;1
L 6.4325 1.5325 6.4325 1.5325 24 P 0 ;1
L 6.4325 1.5825 6.4325 1.5825 24 P 0 ;1
L 6.4325 1.6325 6.4325 1.6325 24 P 0 ;1
L 6.4325 1.6825 6.4325 1.6825 24 P 0 ;1
L 6.4325 1.7325 6.4325 1.7325 24 P 0 ;1
L 6.4325 1.7825 6.4325 1.7825 24 P 0 ;1
L 6.4325 1.8325 6.4325 1.8325 24 P 0 ;1
L 6.4325 1.8825 6.4325 1.8825 24 P 0 ;1
L 6.4325 1.9325 6.4325 1.9325 24 P 0 ;1
L 6.4325 1.9825 6.4325 1.9825 24 P 0 ;1
L 6.4325 2.0325 6.4325 2.0325 24 P 0 ;1
L 6.4325 2.0825 6.4325 2.0825 24 P 0 ;1
L 6.4325 2.1325 6.4325 2.1325 24 P 0 ;1
L 6.4325 2.1825 6.4325 2.1825 24 P 0 ;1
L 6.4325 2.2325 6.4325 2.2325 24 P 0 ;1
L 6.4325 2.2825 6.4325 2.2825 24 P 0 ;1
L 6.4325 2.3325 6.4325 2.3325 24 P 0 ;1
L 6.4325 2.3825 6.4325 2.3825 24 P 0 ;1
L 6.4325 2.4325 6.4325 2.4325 24 P 0 ;1
L 6.4325 2.4825 6.4325 2.4825 24 P 0 ;1
L 6.4325 2.5325 6.4325 2.5325 24 P 0 ;1
L 6.4325 2.5825 6.4325 2.5825 24 P 0 ;1
L 6.4325 2.6325 6.4325 2.6325 24 P 0 ;1
L 6.4325 2.6825 6.4325 2.6825 24 P 0 ;1
L 6.4325 2.7325 6.4325 2.7325 24 P 0 ;1
L 6.4325 2.7825 6.4325 2.7825 24 P 0 ;1
L 6.4325 2.8325 6.4325 2.8325 24 P 0 ;1
L 6.4325 2.8825 6.4325 2.8825 24 P 0 ;1
L 6.4325 2.9325 6.4325 2.9325 24 P 0 ;1
L 6.4325 2.9825 6.4325 2.9825 24 P 0 ;1
L 6.4325 3.0325 6.4325 3.0325 24 P 0 ;1
L 6.4325 3.0825 6.4325 3.0825 24 P 0 ;1
L 6.4325 3.1325 6.4325 3.1325 24 P 0 ;1
L 6.4325 3.1825 6.4325 3.1825 24 P 0 ;1
L 6.4325 3.2325 6.4325 3.2325 24 P 0 ;1
L 6.4325 3.2825 6.4325 3.2825 24 P 0 ;1
L 6.4325 3.3325 6.4325 3.3325 24 P 0 ;1
L 6.4325 3.3825 6.4325 3.3825 24 P 0 ;1
L 6.4325 3.4325 6.4325 3.4325 24 P 0 ;1
L 6.4325 3.4825 6.4325 3.4825 24 P 0 ;1
L 6.4325 3.5325 6.4325 3.5325 24 P 0 ;1
L 6.4325 3.5825 6.4325 3.5825 24 P 0 ;1
L 6.4325 3.6325 6.4325 3.6325 24 P 0 ;1
L 6.4325 3.6825 6.4325 3.6825 24 P 0 ;1
L 6.4325 3.7325 6.4325 3.7325 24 P 0 ;1
L 6.4325 3.7825 6.4325 3.7825 24 P 0 ;1
L 6.4325 3.8325 6.4325 3.8325 24 P 0 ;1
L 6.4325 3.8825 6.4325 3.8825 24 P 0 ;1
L 6.4325 3.9325 6.4325 3.9325 24 P 0 ;1
L 6.4325 3.9825 6.4325 3.9825 24 P 0 ;1
L 6.4325 4.0325 6.4325 4.0325 24 P 0 ;1
L 6.4325 4.0825 6.4325 4.0825 24 P 0 ;1
L 6.4325 4.1325 6.4325 4.1325 24 P 0 ;1
L 6.4325 4.1825 6.4325 4.1825 24 P 0 ;1
L 6.4325 4.2325 6.4325 4.2325 24 P 0 ;1
L 6.4325 4.2825 6.4325 4.2825 24 P 0 ;1
L 6.4325 4.3325 6.4325 4.3325 24 P 0 ;1
L 6.4325 4.3825 6.4325 4.3825 24 P 0 ;1
L 6.4325 4.4325 6.4325 4.4325 24 P 0 ;1
L 6.4325 4.4825 6.4325 4.4825 24 P 0 ;1
L 6.4325 4.5325 6.4325 4.5325 24 P 0 ;1
L 6.4325 4.5825 6.4325 4.5825 24 P 0 ;1
L 6.4325 4.6325 6.4325 4.6325 24 P 0 ;1
L 6.4325 4.6825 6.4325 4.6825 24 P 0 ;1
L 6.4325 4.7325 6.4325 4.7325 24 P 0 ;1
L 6.4325 4.7825 6.4325 4.7825 24 P 0 ;1
L 6.4325 4.8325 6.4325 4.8325 24 P 0 ;1
L 6.4325 5.1825 6.4325 5.1825 24 P 0 ;1
L 6.4325 5.2325 6.4325 5.2325 24 P 0 ;1
L 6.4325 5.2825 6.4325 5.2825 24 P 0 ;1
L 6.4325 5.3325 6.4325 5.3325 24 P 0 ;1
L 6.4325 5.3825 6.4325 5.3825 24 P 0 ;1
L 6.4325 5.4325 6.4325 5.4325 24 P 0 ;1
L 6.4325 5.4825 6.4325 5.4825 24 P 0 ;1
L 6.4325 5.5325 6.4325 5.5325 24 P 0 ;1
L 6.4325 5.7825 6.4325 5.7825 24 P 0 ;1
L 6.4325 5.8325 6.4325 5.8325 24 P 0 ;1
L 6.4325 5.8825 6.4325 5.8825 24 P 0 ;1
L 6.4825 0.6825 6.4825 0.6825 24 P 0 ;1
L 6.4825 0.7325 6.4825 0.7325 24 P 0 ;1
L 6.4825 0.7825 6.4825 0.7825 24 P 0 ;1
L 6.4825 0.8325 6.4825 0.8325 24 P 0 ;1
L 6.4825 0.8825 6.4825 0.8825 24 P 0 ;1
L 6.4825 0.9325 6.4825 0.9325 24 P 0 ;1
L 6.4825 0.9825 6.4825 0.9825 24 P 0 ;1
L 6.4825 1.0325 6.4825 1.0325 24 P 0 ;1
L 6.4825 1.0825 6.4825 1.0825 24 P 0 ;1
L 6.4825 1.1325 6.4825 1.1325 24 P 0 ;1
L 6.4825 1.1825 6.4825 1.1825 24 P 0 ;1
L 6.4825 1.2325 6.4825 1.2325 24 P 0 ;1
L 6.4825 1.2825 6.4825 1.2825 24 P 0 ;1
L 6.4825 1.3325 6.4825 1.3325 24 P 0 ;1
L 6.4825 1.3825 6.4825 1.3825 24 P 0 ;1
L 6.4825 1.4325 6.4825 1.4325 24 P 0 ;1
L 6.4825 1.4825 6.4825 1.4825 24 P 0 ;1
L 6.4825 1.5325 6.4825 1.5325 24 P 0 ;1
L 6.4825 1.5825 6.4825 1.5825 24 P 0 ;1
L 6.4825 1.6325 6.4825 1.6325 24 P 0 ;1
L 6.4825 1.6825 6.4825 1.6825 24 P 0 ;1
L 6.4825 1.7325 6.4825 1.7325 24 P 0 ;1
L 6.4825 1.7825 6.4825 1.7825 24 P 0 ;1
L 6.4825 1.8325 6.4825 1.8325 24 P 0 ;1
L 6.4825 1.8825 6.4825 1.8825 24 P 0 ;1
L 6.4825 1.9325 6.4825 1.9325 24 P 0 ;1
L 6.4825 1.9825 6.4825 1.9825 24 P 0 ;1
L 6.4825 2.0325 6.4825 2.0325 24 P 0 ;1
L 6.4825 2.0825 6.4825 2.0825 24 P 0 ;1
L 6.4825 2.1325 6.4825 2.1325 24 P 0 ;1
L 6.4825 2.1825 6.4825 2.1825 24 P 0 ;1
L 6.4825 2.2325 6.4825 2.2325 24 P 0 ;1
L 6.4825 2.2825 6.4825 2.2825 24 P 0 ;1
L 6.4825 2.3325 6.4825 2.3325 24 P 0 ;1
L 6.4825 2.3825 6.4825 2.3825 24 P 0 ;1
L 6.4825 2.4325 6.4825 2.4325 24 P 0 ;1
L 6.4825 2.4825 6.4825 2.4825 24 P 0 ;1
L 6.4825 2.5325 6.4825 2.5325 24 P 0 ;1
L 6.4825 2.5825 6.4825 2.5825 24 P 0 ;1
L 6.4825 2.6325 6.4825 2.6325 24 P 0 ;1
L 6.4825 2.6825 6.4825 2.6825 24 P 0 ;1
L 6.4825 2.7325 6.4825 2.7325 24 P 0 ;1
L 6.4825 2.7825 6.4825 2.7825 24 P 0 ;1
L 6.4825 2.8325 6.4825 2.8325 24 P 0 ;1
L 6.4825 2.8825 6.4825 2.8825 24 P 0 ;1
L 6.4825 2.9325 6.4825 2.9325 24 P 0 ;1
L 6.4825 2.9825 6.4825 2.9825 24 P 0 ;1
L 6.4825 3.0325 6.4825 3.0325 24 P 0 ;1
L 6.4825 3.0825 6.4825 3.0825 24 P 0 ;1
L 6.4825 3.1325 6.4825 3.1325 24 P 0 ;1
L 6.4825 3.1825 6.4825 3.1825 24 P 0 ;1
L 6.4825 3.2325 6.4825 3.2325 24 P 0 ;1
L 6.4825 3.2825 6.4825 3.2825 24 P 0 ;1
L 6.4825 3.3325 6.4825 3.3325 24 P 0 ;1
L 6.4825 3.3825 6.4825 3.3825 24 P 0 ;1
L 6.4825 3.4325 6.4825 3.4325 24 P 0 ;1
L 6.4825 3.4825 6.4825 3.4825 24 P 0 ;1
L 6.4825 3.5325 6.4825 3.5325 24 P 0 ;1
L 6.4825 3.5825 6.4825 3.5825 24 P 0 ;1
L 6.4825 3.6325 6.4825 3.6325 24 P 0 ;1
L 6.4825 3.6825 6.4825 3.6825 24 P 0 ;1
L 6.4825 3.7325 6.4825 3.7325 24 P 0 ;1
L 6.4825 3.7825 6.4825 3.7825 24 P 0 ;1
L 6.4825 3.8325 6.4825 3.8325 24 P 0 ;1
L 6.4825 3.8825 6.4825 3.8825 24 P 0 ;1
L 6.4825 3.9325 6.4825 3.9325 24 P 0 ;1
L 6.4825 3.9825 6.4825 3.9825 24 P 0 ;1
L 6.4825 4.0325 6.4825 4.0325 24 P 0 ;1
L 6.4825 4.0825 6.4825 4.0825 24 P 0 ;1
L 6.4825 4.1325 6.4825 4.1325 24 P 0 ;1
L 6.4825 4.1825 6.4825 4.1825 24 P 0 ;1
L 6.4825 4.2325 6.4825 4.2325 24 P 0 ;1
L 6.4825 4.2825 6.4825 4.2825 24 P 0 ;1
L 6.4825 4.3325 6.4825 4.3325 24 P 0 ;1
L 6.4825 4.3825 6.4825 4.3825 24 P 0 ;1
L 6.4825 4.4325 6.4825 4.4325 24 P 0 ;1
L 6.4825 4.4825 6.4825 4.4825 24 P 0 ;1
L 6.4825 4.5325 6.4825 4.5325 24 P 0 ;1
L 6.4825 4.5825 6.4825 4.5825 24 P 0 ;1
L 6.4825 4.6325 6.4825 4.6325 24 P 0 ;1
L 6.4825 4.6825 6.4825 4.6825 24 P 0 ;1
L 6.4825 4.7325 6.4825 4.7325 24 P 0 ;1
L 6.4825 4.7825 6.4825 4.7825 24 P 0 ;1
L 6.4825 4.8325 6.4825 4.8325 24 P 0 ;1
L 6.4825 5.2325 6.4825 5.2325 24 P 0 ;1
L 6.4825 5.2825 6.4825 5.2825 24 P 0 ;1
L 6.4825 5.3325 6.4825 5.3325 24 P 0 ;1
L 6.4825 5.3825 6.4825 5.3825 24 P 0 ;1
L 6.4825 5.4325 6.4825 5.4325 24 P 0 ;1
L 6.4825 5.4825 6.4825 5.4825 24 P 0 ;1
L 6.4825 5.7825 6.4825 5.7825 24 P 0 ;1
L 6.4825 5.8325 6.4825 5.8325 24 P 0 ;1
L 6.4825 5.8825 6.4825 5.8825 24 P 0 ;1
L 6.5325 0.6825 6.5325 0.6825 24 P 0 ;1
L 6.5325 0.7325 6.5325 0.7325 24 P 0 ;1
L 6.5325 0.7825 6.5325 0.7825 24 P 0 ;1
L 6.5325 0.8325 6.5325 0.8325 24 P 0 ;1
L 6.5325 0.8825 6.5325 0.8825 24 P 0 ;1
L 6.5325 0.9325 6.5325 0.9325 24 P 0 ;1
L 6.5325 0.9825 6.5325 0.9825 24 P 0 ;1
L 6.5325 1.0325 6.5325 1.0325 24 P 0 ;1
L 6.5325 1.0825 6.5325 1.0825 24 P 0 ;1
L 6.5325 1.1325 6.5325 1.1325 24 P 0 ;1
L 6.5325 1.1825 6.5325 1.1825 24 P 0 ;1
L 6.5325 1.2325 6.5325 1.2325 24 P 0 ;1
L 6.5325 1.2825 6.5325 1.2825 24 P 0 ;1
L 6.5325 1.3325 6.5325 1.3325 24 P 0 ;1
L 6.5325 1.3825 6.5325 1.3825 24 P 0 ;1
L 6.5325 1.4325 6.5325 1.4325 24 P 0 ;1
L 6.5325 1.4825 6.5325 1.4825 24 P 0 ;1
L 6.5325 1.5325 6.5325 1.5325 24 P 0 ;1
L 6.5325 1.5825 6.5325 1.5825 24 P 0 ;1
L 6.5325 1.6325 6.5325 1.6325 24 P 0 ;1
L 6.5325 1.6825 6.5325 1.6825 24 P 0 ;1
L 6.5325 1.7325 6.5325 1.7325 24 P 0 ;1
L 6.5325 1.7825 6.5325 1.7825 24 P 0 ;1
L 6.5325 1.8325 6.5325 1.8325 24 P 0 ;1
L 6.5325 1.8825 6.5325 1.8825 24 P 0 ;1
L 6.5325 1.9325 6.5325 1.9325 24 P 0 ;1
L 6.5325 1.9825 6.5325 1.9825 24 P 0 ;1
L 6.5325 2.0325 6.5325 2.0325 24 P 0 ;1
L 6.5325 2.0825 6.5325 2.0825 24 P 0 ;1
L 6.5325 2.1325 6.5325 2.1325 24 P 0 ;1
L 6.5325 2.1825 6.5325 2.1825 24 P 0 ;1
L 6.5325 2.2325 6.5325 2.2325 24 P 0 ;1
L 6.5325 2.2825 6.5325 2.2825 24 P 0 ;1
L 6.5325 2.3325 6.5325 2.3325 24 P 0 ;1
L 6.5325 2.3825 6.5325 2.3825 24 P 0 ;1
L 6.5325 2.4325 6.5325 2.4325 24 P 0 ;1
L 6.5325 2.4825 6.5325 2.4825 24 P 0 ;1
L 6.5325 2.5325 6.5325 2.5325 24 P 0 ;1
L 6.5325 2.5825 6.5325 2.5825 24 P 0 ;1
L 6.5325 2.6325 6.5325 2.6325 24 P 0 ;1
L 6.5325 2.6825 6.5325 2.6825 24 P 0 ;1
L 6.5325 2.7325 6.5325 2.7325 24 P 0 ;1
L 6.5325 2.7825 6.5325 2.7825 24 P 0 ;1
L 6.5325 2.8325 6.5325 2.8325 24 P 0 ;1
L 6.5325 2.8825 6.5325 2.8825 24 P 0 ;1
L 6.5325 2.9325 6.5325 2.9325 24 P 0 ;1
L 6.5325 2.9825 6.5325 2.9825 24 P 0 ;1
L 6.5325 3.0325 6.5325 3.0325 24 P 0 ;1
L 6.5325 3.0825 6.5325 3.0825 24 P 0 ;1
L 6.5325 3.1325 6.5325 3.1325 24 P 0 ;1
L 6.5325 3.1825 6.5325 3.1825 24 P 0 ;1
L 6.5325 3.2325 6.5325 3.2325 24 P 0 ;1
L 6.5325 3.2825 6.5325 3.2825 24 P 0 ;1
L 6.5325 3.3325 6.5325 3.3325 24 P 0 ;1
L 6.5325 3.3825 6.5325 3.3825 24 P 0 ;1
L 6.5325 3.4325 6.5325 3.4325 24 P 0 ;1
L 6.5325 3.4825 6.5325 3.4825 24 P 0 ;1
L 6.5325 3.5325 6.5325 3.5325 24 P 0 ;1
L 6.5325 3.5825 6.5325 3.5825 24 P 0 ;1
L 6.5325 3.6325 6.5325 3.6325 24 P 0 ;1
L 6.5325 3.6825 6.5325 3.6825 24 P 0 ;1
L 6.5325 3.7325 6.5325 3.7325 24 P 0 ;1
L 6.5325 3.7825 6.5325 3.7825 24 P 0 ;1
L 6.5325 3.8325 6.5325 3.8325 24 P 0 ;1
L 6.5325 3.8825 6.5325 3.8825 24 P 0 ;1
L 6.5325 3.9325 6.5325 3.9325 24 P 0 ;1
L 6.5325 3.9825 6.5325 3.9825 24 P 0 ;1
L 6.5325 4.0325 6.5325 4.0325 24 P 0 ;1
L 6.5325 4.0825 6.5325 4.0825 24 P 0 ;1
L 6.5325 4.1325 6.5325 4.1325 24 P 0 ;1
L 6.5325 4.1825 6.5325 4.1825 24 P 0 ;1
L 6.5325 4.2325 6.5325 4.2325 24 P 0 ;1
L 6.5325 4.2825 6.5325 4.2825 24 P 0 ;1
L 6.5325 4.3325 6.5325 4.3325 24 P 0 ;1
L 6.5325 4.3825 6.5325 4.3825 24 P 0 ;1
L 6.5325 4.4325 6.5325 4.4325 24 P 0 ;1
L 6.5325 4.4825 6.5325 4.4825 24 P 0 ;1
L 6.5325 5.7325 6.5325 5.7325 24 P 0 ;1
L 6.5325 5.7825 6.5325 5.7825 24 P 0 ;1
L 6.5325 5.8325 6.5325 5.8325 24 P 0 ;1
L 6.5325 5.8825 6.5325 5.8825 24 P 0 ;1
L 6.5825 0.6825 6.5825 0.6825 24 P 0 ;1
L 6.5825 0.7325 6.5825 0.7325 24 P 0 ;1
L 6.5825 0.7825 6.5825 0.7825 24 P 0 ;1
L 6.5825 0.8325 6.5825 0.8325 24 P 0 ;1
L 6.5825 0.8825 6.5825 0.8825 24 P 0 ;1
L 6.5825 0.9325 6.5825 0.9325 24 P 0 ;1
L 6.5825 0.9825 6.5825 0.9825 24 P 0 ;1
L 6.5825 1.0325 6.5825 1.0325 24 P 0 ;1
L 6.5825 1.0825 6.5825 1.0825 24 P 0 ;1
L 6.5825 1.1325 6.5825 1.1325 24 P 0 ;1
L 6.5825 1.1825 6.5825 1.1825 24 P 0 ;1
L 6.5825 1.2325 6.5825 1.2325 24 P 0 ;1
L 6.5825 1.2825 6.5825 1.2825 24 P 0 ;1
L 6.5825 1.3325 6.5825 1.3325 24 P 0 ;1
L 6.5825 1.3825 6.5825 1.3825 24 P 0 ;1
L 6.5825 1.4325 6.5825 1.4325 24 P 0 ;1
L 6.5825 1.4825 6.5825 1.4825 24 P 0 ;1
L 6.5825 1.5325 6.5825 1.5325 24 P 0 ;1
L 6.5825 1.5825 6.5825 1.5825 24 P 0 ;1
L 6.5825 1.6325 6.5825 1.6325 24 P 0 ;1
L 6.5825 1.6825 6.5825 1.6825 24 P 0 ;1
L 6.5825 1.7325 6.5825 1.7325 24 P 0 ;1
L 6.5825 1.7825 6.5825 1.7825 24 P 0 ;1
L 6.5825 1.8325 6.5825 1.8325 24 P 0 ;1
L 6.5825 1.8825 6.5825 1.8825 24 P 0 ;1
L 6.5825 1.9325 6.5825 1.9325 24 P 0 ;1
L 6.5825 1.9825 6.5825 1.9825 24 P 0 ;1
L 6.5825 2.0325 6.5825 2.0325 24 P 0 ;1
L 6.5825 2.0825 6.5825 2.0825 24 P 0 ;1
L 6.5825 2.1325 6.5825 2.1325 24 P 0 ;1
L 6.5825 2.1825 6.5825 2.1825 24 P 0 ;1
L 6.5825 2.2325 6.5825 2.2325 24 P 0 ;1
L 6.5825 2.2825 6.5825 2.2825 24 P 0 ;1
L 6.5825 2.3325 6.5825 2.3325 24 P 0 ;1
L 6.5825 2.3825 6.5825 2.3825 24 P 0 ;1
L 6.5825 2.4325 6.5825 2.4325 24 P 0 ;1
L 6.5825 2.4825 6.5825 2.4825 24 P 0 ;1
L 6.5825 2.5325 6.5825 2.5325 24 P 0 ;1
L 6.5825 2.5825 6.5825 2.5825 24 P 0 ;1
L 6.5825 2.6325 6.5825 2.6325 24 P 0 ;1
L 6.5825 2.6825 6.5825 2.6825 24 P 0 ;1
L 6.5825 2.7325 6.5825 2.7325 24 P 0 ;1
L 6.5825 2.7825 6.5825 2.7825 24 P 0 ;1
L 6.5825 2.8325 6.5825 2.8325 24 P 0 ;1
L 6.5825 2.8825 6.5825 2.8825 24 P 0 ;1
L 6.5825 2.9325 6.5825 2.9325 24 P 0 ;1
L 6.5825 2.9825 6.5825 2.9825 24 P 0 ;1
L 6.5825 3.0325 6.5825 3.0325 24 P 0 ;1
L 6.5825 3.0825 6.5825 3.0825 24 P 0 ;1
L 6.5825 3.1325 6.5825 3.1325 24 P 0 ;1
L 6.5825 3.1825 6.5825 3.1825 24 P 0 ;1
L 6.5825 3.2325 6.5825 3.2325 24 P 0 ;1
L 6.5825 3.2825 6.5825 3.2825 24 P 0 ;1
L 6.5825 3.3325 6.5825 3.3325 24 P 0 ;1
L 6.5825 3.3825 6.5825 3.3825 24 P 0 ;1
L 6.5825 3.4325 6.5825 3.4325 24 P 0 ;1
L 6.5825 3.4825 6.5825 3.4825 24 P 0 ;1
L 6.5825 3.5325 6.5825 3.5325 24 P 0 ;1
L 6.5825 3.5825 6.5825 3.5825 24 P 0 ;1
L 6.5825 3.6325 6.5825 3.6325 24 P 0 ;1
L 6.5825 3.6825 6.5825 3.6825 24 P 0 ;1
L 6.5825 3.7325 6.5825 3.7325 24 P 0 ;1
L 6.5825 3.7825 6.5825 3.7825 24 P 0 ;1
L 6.5825 3.8325 6.5825 3.8325 24 P 0 ;1
L 6.5825 3.8825 6.5825 3.8825 24 P 0 ;1
L 6.5825 3.9325 6.5825 3.9325 24 P 0 ;1
L 6.5825 3.9825 6.5825 3.9825 24 P 0 ;1
L 6.5825 4.0325 6.5825 4.0325 24 P 0 ;1
L 6.5825 4.0825 6.5825 4.0825 24 P 0 ;1
L 6.5825 4.1325 6.5825 4.1325 24 P 0 ;1
L 6.5825 4.1825 6.5825 4.1825 24 P 0 ;1
L 6.5825 4.2325 6.5825 4.2325 24 P 0 ;1
L 6.5825 4.2825 6.5825 4.2825 24 P 0 ;1
L 6.5825 4.3325 6.5825 4.3325 24 P 0 ;1
L 6.5825 4.3825 6.5825 4.3825 24 P 0 ;1
L 6.5825 4.4325 6.5825 4.4325 24 P 0 ;1
L 6.5825 4.4825 6.5825 4.4825 24 P 0 ;1
L 6.5825 5.6825 6.5825 5.6825 24 P 0 ;1
L 6.5825 5.7325 6.5825 5.7325 24 P 0 ;1
L 6.5825 5.7825 6.5825 5.7825 24 P 0 ;1
L 6.5825 5.8325 6.5825 5.8325 24 P 0 ;1
L 6.5825 5.8825 6.5825 5.8825 24 P 0 ;1
L 6.6325 0.6825 6.6325 0.6825 24 P 0 ;1
L 6.6325 0.7325 6.6325 0.7325 24 P 0 ;1
L 6.6325 0.7825 6.6325 0.7825 24 P 0 ;1
L 6.6325 0.8325 6.6325 0.8325 24 P 0 ;1
L 6.6325 0.8825 6.6325 0.8825 24 P 0 ;1
L 6.6325 0.9325 6.6325 0.9325 24 P 0 ;1
L 6.6325 0.9825 6.6325 0.9825 24 P 0 ;1
L 6.6325 1.0325 6.6325 1.0325 24 P 0 ;1
L 6.6325 1.0825 6.6325 1.0825 24 P 0 ;1
L 6.6325 1.1325 6.6325 1.1325 24 P 0 ;1
L 6.6325 1.1825 6.6325 1.1825 24 P 0 ;1
L 6.6325 1.2325 6.6325 1.2325 24 P 0 ;1
L 6.6325 1.2825 6.6325 1.2825 24 P 0 ;1
L 6.6325 1.3325 6.6325 1.3325 24 P 0 ;1
L 6.6325 1.3825 6.6325 1.3825 24 P 0 ;1
L 6.6325 1.4325 6.6325 1.4325 24 P 0 ;1
L 6.6325 1.4825 6.6325 1.4825 24 P 0 ;1
L 6.6325 1.5325 6.6325 1.5325 24 P 0 ;1
L 6.6325 1.5825 6.6325 1.5825 24 P 0 ;1
L 6.6325 1.6325 6.6325 1.6325 24 P 0 ;1
L 6.6325 1.6825 6.6325 1.6825 24 P 0 ;1
L 6.6325 1.7325 6.6325 1.7325 24 P 0 ;1
L 6.6325 1.7825 6.6325 1.7825 24 P 0 ;1
L 6.6325 1.8325 6.6325 1.8325 24 P 0 ;1
L 6.6325 1.8825 6.6325 1.8825 24 P 0 ;1
L 6.6325 1.9325 6.6325 1.9325 24 P 0 ;1
L 6.6325 1.9825 6.6325 1.9825 24 P 0 ;1
L 6.6325 2.0325 6.6325 2.0325 24 P 0 ;1
L 6.6325 2.0825 6.6325 2.0825 24 P 0 ;1
L 6.6325 2.1325 6.6325 2.1325 24 P 0 ;1
L 6.6325 2.1825 6.6325 2.1825 24 P 0 ;1
L 6.6325 2.2325 6.6325 2.2325 24 P 0 ;1
L 6.6325 2.2825 6.6325 2.2825 24 P 0 ;1
L 6.6325 2.3325 6.6325 2.3325 24 P 0 ;1
L 6.6325 2.3825 6.6325 2.3825 24 P 0 ;1
L 6.6325 2.4325 6.6325 2.4325 24 P 0 ;1
L 6.6325 2.4825 6.6325 2.4825 24 P 0 ;1
L 6.6325 2.5325 6.6325 2.5325 24 P 0 ;1
L 6.6325 2.5825 6.6325 2.5825 24 P 0 ;1
L 6.6325 2.6325 6.6325 2.6325 24 P 0 ;1
L 6.6325 2.6825 6.6325 2.6825 24 P 0 ;1
L 6.6325 2.7325 6.6325 2.7325 24 P 0 ;1
L 6.6325 2.7825 6.6325 2.7825 24 P 0 ;1
L 6.6325 2.8325 6.6325 2.8325 24 P 0 ;1
L 6.6325 2.8825 6.6325 2.8825 24 P 0 ;1
L 6.6325 2.9325 6.6325 2.9325 24 P 0 ;1
L 6.6325 2.9825 6.6325 2.9825 24 P 0 ;1
L 6.6325 3.0325 6.6325 3.0325 24 P 0 ;1
L 6.6325 3.0825 6.6325 3.0825 24 P 0 ;1
L 6.6325 3.1325 6.6325 3.1325 24 P 0 ;1
L 6.6325 3.1825 6.6325 3.1825 24 P 0 ;1
L 6.6325 3.2325 6.6325 3.2325 24 P 0 ;1
L 6.6325 3.2825 6.6325 3.2825 24 P 0 ;1
L 6.6325 3.3325 6.6325 3.3325 24 P 0 ;1
L 6.6325 3.3825 6.6325 3.3825 24 P 0 ;1
L 6.6325 3.4325 6.6325 3.4325 24 P 0 ;1
L 6.6325 3.4825 6.6325 3.4825 24 P 0 ;1
L 6.6325 3.5325 6.6325 3.5325 24 P 0 ;1
L 6.6325 3.5825 6.6325 3.5825 24 P 0 ;1
L 6.6325 3.6325 6.6325 3.6325 24 P 0 ;1
L 6.6325 3.6825 6.6325 3.6825 24 P 0 ;1
L 6.6325 3.7325 6.6325 3.7325 24 P 0 ;1
L 6.6325 3.7825 6.6325 3.7825 24 P 0 ;1
L 6.6325 3.8325 6.6325 3.8325 24 P 0 ;1
L 6.6325 3.8825 6.6325 3.8825 24 P 0 ;1
L 6.6325 3.9325 6.6325 3.9325 24 P 0 ;1
L 6.6325 3.9825 6.6325 3.9825 24 P 0 ;1
L 6.6325 4.0325 6.6325 4.0325 24 P 0 ;1
L 6.6325 4.0825 6.6325 4.0825 24 P 0 ;1
L 6.6325 4.1325 6.6325 4.1325 24 P 0 ;1
L 6.6325 4.1825 6.6325 4.1825 24 P 0 ;1
L 6.6325 4.2325 6.6325 4.2325 24 P 0 ;1
L 6.6325 4.2825 6.6325 4.2825 24 P 0 ;1
L 6.6325 4.3325 6.6325 4.3325 24 P 0 ;1
L 6.6325 4.3825 6.6325 4.3825 24 P 0 ;1
L 6.6325 4.4325 6.6325 4.4325 24 P 0 ;1
L 6.6325 4.4825 6.6325 4.4825 24 P 0 ;1
L 6.6325 5.6325 6.6325 5.6325 24 P 0 ;1
L 6.6325 5.6825 6.6325 5.6825 24 P 0 ;1
L 6.6325 5.7325 6.6325 5.7325 24 P 0 ;1
L 6.6325 5.7825 6.6325 5.7825 24 P 0 ;1
L 6.6325 5.8325 6.6325 5.8325 24 P 0 ;1
L 6.6325 5.8825 6.6325 5.8825 24 P 0 ;1
L 6.6825 0.6825 6.6825 0.6825 24 P 0 ;1
L 6.6825 0.7325 6.6825 0.7325 24 P 0 ;1
L 6.6825 0.7825 6.6825 0.7825 24 P 0 ;1
L 6.6825 0.8325 6.6825 0.8325 24 P 0 ;1
L 6.6825 0.8825 6.6825 0.8825 24 P 0 ;1
L 6.6825 0.9325 6.6825 0.9325 24 P 0 ;1
L 6.6825 0.9825 6.6825 0.9825 24 P 0 ;1
L 6.6825 1.0325 6.6825 1.0325 24 P 0 ;1
L 6.6825 1.0825 6.6825 1.0825 24 P 0 ;1
L 6.6825 1.1325 6.6825 1.1325 24 P 0 ;1
L 6.6825 1.1825 6.6825 1.1825 24 P 0 ;1
L 6.6825 1.2325 6.6825 1.2325 24 P 0 ;1
L 6.6825 1.2825 6.6825 1.2825 24 P 0 ;1
L 6.6825 1.3325 6.6825 1.3325 24 P 0 ;1
L 6.6825 1.3825 6.6825 1.3825 24 P 0 ;1
L 6.6825 1.4325 6.6825 1.4325 24 P 0 ;1
L 6.6825 1.4825 6.6825 1.4825 24 P 0 ;1
L 6.6825 1.5325 6.6825 1.5325 24 P 0 ;1
L 6.6825 1.5825 6.6825 1.5825 24 P 0 ;1
L 6.6825 1.6325 6.6825 1.6325 24 P 0 ;1
L 6.6825 1.6825 6.6825 1.6825 24 P 0 ;1
L 6.6825 1.7325 6.6825 1.7325 24 P 0 ;1
L 6.6825 1.7825 6.6825 1.7825 24 P 0 ;1
L 6.6825 1.8325 6.6825 1.8325 24 P 0 ;1
L 6.6825 1.8825 6.6825 1.8825 24 P 0 ;1
L 6.6825 1.9325 6.6825 1.9325 24 P 0 ;1
L 6.6825 1.9825 6.6825 1.9825 24 P 0 ;1
L 6.6825 2.0325 6.6825 2.0325 24 P 0 ;1
L 6.6825 2.0825 6.6825 2.0825 24 P 0 ;1
L 6.6825 2.1325 6.6825 2.1325 24 P 0 ;1
L 6.6825 2.1825 6.6825 2.1825 24 P 0 ;1
L 6.6825 2.2325 6.6825 2.2325 24 P 0 ;1
L 6.6825 2.2825 6.6825 2.2825 24 P 0 ;1
L 6.6825 2.3325 6.6825 2.3325 24 P 0 ;1
L 6.6825 2.3825 6.6825 2.3825 24 P 0 ;1
L 6.6825 2.4325 6.6825 2.4325 24 P 0 ;1
L 6.6825 2.4825 6.6825 2.4825 24 P 0 ;1
L 6.6825 2.5325 6.6825 2.5325 24 P 0 ;1
L 6.6825 2.5825 6.6825 2.5825 24 P 0 ;1
L 6.6825 2.6325 6.6825 2.6325 24 P 0 ;1
L 6.6825 2.6825 6.6825 2.6825 24 P 0 ;1
L 6.6825 2.7325 6.6825 2.7325 24 P 0 ;1
L 6.6825 2.7825 6.6825 2.7825 24 P 0 ;1
L 6.6825 2.8325 6.6825 2.8325 24 P 0 ;1
L 6.6825 2.8825 6.6825 2.8825 24 P 0 ;1
L 6.6825 2.9325 6.6825 2.9325 24 P 0 ;1
L 6.6825 2.9825 6.6825 2.9825 24 P 0 ;1
L 6.6825 3.0325 6.6825 3.0325 24 P 0 ;1
L 6.6825 3.0825 6.6825 3.0825 24 P 0 ;1
L 6.6825 3.1325 6.6825 3.1325 24 P 0 ;1
L 6.6825 3.1825 6.6825 3.1825 24 P 0 ;1
L 6.6825 3.2325 6.6825 3.2325 24 P 0 ;1
L 6.6825 3.2825 6.6825 3.2825 24 P 0 ;1
L 6.6825 3.3325 6.6825 3.3325 24 P 0 ;1
L 6.6825 3.3825 6.6825 3.3825 24 P 0 ;1
L 6.6825 3.4325 6.6825 3.4325 24 P 0 ;1
L 6.6825 3.4825 6.6825 3.4825 24 P 0 ;1
L 6.6825 3.5325 6.6825 3.5325 24 P 0 ;1
L 6.6825 3.5825 6.6825 3.5825 24 P 0 ;1
L 6.6825 3.6325 6.6825 3.6325 24 P 0 ;1
L 6.6825 3.6825 6.6825 3.6825 24 P 0 ;1
L 6.6825 3.7325 6.6825 3.7325 24 P 0 ;1
L 6.6825 3.7825 6.6825 3.7825 24 P 0 ;1
L 6.6825 3.8325 6.6825 3.8325 24 P 0 ;1
L 6.6825 3.8825 6.6825 3.8825 24 P 0 ;1
L 6.6825 3.9325 6.6825 3.9325 24 P 0 ;1
L 6.6825 3.9825 6.6825 3.9825 24 P 0 ;1
L 6.6825 4.0325 6.6825 4.0325 24 P 0 ;1
L 6.6825 4.0825 6.6825 4.0825 24 P 0 ;1
L 6.6825 4.1325 6.6825 4.1325 24 P 0 ;1
L 6.6825 4.1825 6.6825 4.1825 24 P 0 ;1
L 6.6825 4.2325 6.6825 4.2325 24 P 0 ;1
L 6.6825 4.2825 6.6825 4.2825 24 P 0 ;1
L 6.6825 4.3325 6.6825 4.3325 24 P 0 ;1
L 6.6825 4.3825 6.6825 4.3825 24 P 0 ;1
L 6.6825 4.4325 6.6825 4.4325 24 P 0 ;1
L 6.6825 5.1825 6.6825 5.1825 24 P 0 ;1
L 6.6825 5.2325 6.6825 5.2325 24 P 0 ;1
L 6.6825 5.2825 6.6825 5.2825 24 P 0 ;1
L 6.6825 5.3325 6.6825 5.3325 24 P 0 ;1
L 6.6825 5.3825 6.6825 5.3825 24 P 0 ;1
L 6.6825 5.4325 6.6825 5.4325 24 P 0 ;1
L 6.6825 5.4825 6.6825 5.4825 24 P 0 ;1
L 6.6825 5.5325 6.6825 5.5325 24 P 0 ;1
L 6.6825 5.5825 6.6825 5.5825 24 P 0 ;1
L 6.6825 5.6325 6.6825 5.6325 24 P 0 ;1
L 6.6825 5.6825 6.6825 5.6825 24 P 0 ;1
L 6.6825 5.7325 6.6825 5.7325 24 P 0 ;1
L 6.6825 5.7825 6.6825 5.7825 24 P 0 ;1
L 6.6825 5.8325 6.6825 5.8325 24 P 0 ;1
L 6.6825 5.8825 6.6825 5.8825 24 P 0 ;1
L 6.7325 0.1325 6.7325 0.1325 24 P 0 ;1
L 6.7325 0.1825 6.7325 0.1825 24 P 0 ;1
L 6.7325 0.2325 6.7325 0.2325 24 P 0 ;1
L 6.7325 0.2825 6.7325 0.2825 24 P 0 ;1
L 6.7325 0.3325 6.7325 0.3325 24 P 0 ;1
L 6.7325 0.3825 6.7325 0.3825 24 P 0 ;1
L 6.7325 0.4325 6.7325 0.4325 24 P 0 ;1
L 6.7325 0.6825 6.7325 0.6825 24 P 0 ;1
L 6.7325 0.7325 6.7325 0.7325 24 P 0 ;1
L 6.7325 0.7825 6.7325 0.7825 24 P 0 ;1
L 6.7325 0.8325 6.7325 0.8325 24 P 0 ;1
L 6.7325 0.8825 6.7325 0.8825 24 P 0 ;1
L 6.7325 0.9325 6.7325 0.9325 24 P 0 ;1
L 6.7325 0.9825 6.7325 0.9825 24 P 0 ;1
L 6.7325 1.0325 6.7325 1.0325 24 P 0 ;1
L 6.7325 1.0825 6.7325 1.0825 24 P 0 ;1
L 6.7325 1.1325 6.7325 1.1325 24 P 0 ;1
L 6.7325 1.1825 6.7325 1.1825 24 P 0 ;1
L 6.7325 1.2325 6.7325 1.2325 24 P 0 ;1
L 6.7325 1.2825 6.7325 1.2825 24 P 0 ;1
L 6.7325 1.3325 6.7325 1.3325 24 P 0 ;1
L 6.7325 1.3825 6.7325 1.3825 24 P 0 ;1
L 6.7325 1.4325 6.7325 1.4325 24 P 0 ;1
L 6.7325 1.6325 6.7325 1.6325 24 P 0 ;1
L 6.7325 1.6825 6.7325 1.6825 24 P 0 ;1
L 6.7325 1.7325 6.7325 1.7325 24 P 0 ;1
L 6.7325 1.7825 6.7325 1.7825 24 P 0 ;1
L 6.7325 1.8325 6.7325 1.8325 24 P 0 ;1
L 6.7325 1.8825 6.7325 1.8825 24 P 0 ;1
L 6.7325 1.9325 6.7325 1.9325 24 P 0 ;1
L 6.7325 1.9825 6.7325 1.9825 24 P 0 ;1
L 6.7325 2.0325 6.7325 2.0325 24 P 0 ;1
L 6.7325 2.0825 6.7325 2.0825 24 P 0 ;1
L 6.7325 2.1325 6.7325 2.1325 24 P 0 ;1
L 6.7325 2.1825 6.7325 2.1825 24 P 0 ;1
L 6.7325 2.2325 6.7325 2.2325 24 P 0 ;1
L 6.7325 2.2825 6.7325 2.2825 24 P 0 ;1
L 6.7325 2.3325 6.7325 2.3325 24 P 0 ;1
L 6.7325 2.3825 6.7325 2.3825 24 P 0 ;1
L 6.7325 2.4325 6.7325 2.4325 24 P 0 ;1
L 6.7325 2.4825 6.7325 2.4825 24 P 0 ;1
L 6.7325 2.5325 6.7325 2.5325 24 P 0 ;1
L 6.7325 2.5825 6.7325 2.5825 24 P 0 ;1
L 6.7325 2.6325 6.7325 2.6325 24 P 0 ;1
L 6.7325 2.6825 6.7325 2.6825 24 P 0 ;1
L 6.7325 2.7325 6.7325 2.7325 24 P 0 ;1
L 6.7325 2.7825 6.7325 2.7825 24 P 0 ;1
L 6.7325 2.8325 6.7325 2.8325 24 P 0 ;1
L 6.7325 2.8825 6.7325 2.8825 24 P 0 ;1
L 6.7325 2.9325 6.7325 2.9325 24 P 0 ;1
L 6.7325 2.9825 6.7325 2.9825 24 P 0 ;1
L 6.7325 3.0325 6.7325 3.0325 24 P 0 ;1
L 6.7325 3.0825 6.7325 3.0825 24 P 0 ;1
L 6.7325 3.1325 6.7325 3.1325 24 P 0 ;1
L 6.7325 3.1825 6.7325 3.1825 24 P 0 ;1
L 6.7325 3.2325 6.7325 3.2325 24 P 0 ;1
L 6.7325 3.2825 6.7325 3.2825 24 P 0 ;1
L 6.7325 3.3325 6.7325 3.3325 24 P 0 ;1
L 6.7325 3.3825 6.7325 3.3825 24 P 0 ;1
L 6.7325 3.4325 6.7325 3.4325 24 P 0 ;1
L 6.7325 3.4825 6.7325 3.4825 24 P 0 ;1
L 6.7325 3.5325 6.7325 3.5325 24 P 0 ;1
L 6.7325 3.5825 6.7325 3.5825 24 P 0 ;1
L 6.7325 3.6325 6.7325 3.6325 24 P 0 ;1
L 6.7325 3.6825 6.7325 3.6825 24 P 0 ;1
L 6.7325 3.7325 6.7325 3.7325 24 P 0 ;1
L 6.7325 3.7825 6.7325 3.7825 24 P 0 ;1
L 6.7325 3.8325 6.7325 3.8325 24 P 0 ;1
L 6.7325 3.8825 6.7325 3.8825 24 P 0 ;1
L 6.7325 3.9325 6.7325 3.9325 24 P 0 ;1
L 6.7325 3.9825 6.7325 3.9825 24 P 0 ;1
L 6.7325 4.0325 6.7325 4.0325 24 P 0 ;1
L 6.7325 4.0825 6.7325 4.0825 24 P 0 ;1
L 6.7325 4.1325 6.7325 4.1325 24 P 0 ;1
L 6.7325 4.2825 6.7325 4.2825 24 P 0 ;1
L 6.7325 4.3325 6.7325 4.3325 24 P 0 ;1
L 6.7325 4.3825 6.7325 4.3825 24 P 0 ;1
L 6.7325 4.4325 6.7325 4.4325 24 P 0 ;1
L 6.7325 5.1325 6.7325 5.1325 24 P 0 ;1
L 6.7325 5.1825 6.7325 5.1825 24 P 0 ;1
L 6.7325 5.2325 6.7325 5.2325 24 P 0 ;1
L 6.7325 5.2825 6.7325 5.2825 24 P 0 ;1
L 6.7325 5.3325 6.7325 5.3325 24 P 0 ;1
L 6.7325 5.3825 6.7325 5.3825 24 P 0 ;1
L 6.7325 5.4325 6.7325 5.4325 24 P 0 ;1
L 6.7325 5.4825 6.7325 5.4825 24 P 0 ;1
L 6.7325 5.5325 6.7325 5.5325 24 P 0 ;1
L 6.7325 5.5825 6.7325 5.5825 24 P 0 ;1
L 6.7325 5.6325 6.7325 5.6325 24 P 0 ;1
L 6.7325 5.6825 6.7325 5.6825 24 P 0 ;1
L 6.7325 5.7325 6.7325 5.7325 24 P 0 ;1
L 6.7325 5.7825 6.7325 5.7825 24 P 0 ;1
L 6.7325 5.8325 6.7325 5.8325 24 P 0 ;1
L 6.7325 5.8825 6.7325 5.8825 24 P 0 ;1
L 6.7825 0.1325 6.7825 0.1325 24 P 0 ;1
L 6.7825 0.1825 6.7825 0.1825 24 P 0 ;1
L 6.7825 0.2325 6.7825 0.2325 24 P 0 ;1
L 6.7825 0.2825 6.7825 0.2825 24 P 0 ;1
L 6.7825 0.3325 6.7825 0.3325 24 P 0 ;1
L 6.7825 0.3825 6.7825 0.3825 24 P 0 ;1
L 6.7825 0.4325 6.7825 0.4325 24 P 0 ;1
L 6.7825 0.6825 6.7825 0.6825 24 P 0 ;1
L 6.7825 0.7325 6.7825 0.7325 24 P 0 ;1
L 6.7825 0.7825 6.7825 0.7825 24 P 0 ;1
L 6.7825 0.8325 6.7825 0.8325 24 P 0 ;1
L 6.7825 0.8825 6.7825 0.8825 24 P 0 ;1
L 6.7825 0.9325 6.7825 0.9325 24 P 0 ;1
L 6.7825 0.9825 6.7825 0.9825 24 P 0 ;1
L 6.7825 1.0325 6.7825 1.0325 24 P 0 ;1
L 6.7825 1.0825 6.7825 1.0825 24 P 0 ;1
L 6.7825 1.1325 6.7825 1.1325 24 P 0 ;1
L 6.7825 1.1825 6.7825 1.1825 24 P 0 ;1
L 6.7825 1.2325 6.7825 1.2325 24 P 0 ;1
L 6.7825 1.2825 6.7825 1.2825 24 P 0 ;1
L 6.7825 1.3325 6.7825 1.3325 24 P 0 ;1
L 6.7825 1.7325 6.7825 1.7325 24 P 0 ;1
L 6.7825 1.7825 6.7825 1.7825 24 P 0 ;1
L 6.7825 1.8325 6.7825 1.8325 24 P 0 ;1
L 6.7825 1.8825 6.7825 1.8825 24 P 0 ;1
L 6.7825 1.9325 6.7825 1.9325 24 P 0 ;1
L 6.7825 1.9825 6.7825 1.9825 24 P 0 ;1
L 6.7825 2.0325 6.7825 2.0325 24 P 0 ;1
L 6.7825 2.0825 6.7825 2.0825 24 P 0 ;1
L 6.7825 2.1325 6.7825 2.1325 24 P 0 ;1
L 6.7825 2.1825 6.7825 2.1825 24 P 0 ;1
L 6.7825 2.2325 6.7825 2.2325 24 P 0 ;1
L 6.7825 2.2825 6.7825 2.2825 24 P 0 ;1
L 6.7825 2.3325 6.7825 2.3325 24 P 0 ;1
L 6.7825 2.3825 6.7825 2.3825 24 P 0 ;1
L 6.7825 2.4325 6.7825 2.4325 24 P 0 ;1
L 6.7825 2.4825 6.7825 2.4825 24 P 0 ;1
L 6.7825 2.5325 6.7825 2.5325 24 P 0 ;1
L 6.7825 2.5825 6.7825 2.5825 24 P 0 ;1
L 6.7825 2.6325 6.7825 2.6325 24 P 0 ;1
L 6.7825 2.6825 6.7825 2.6825 24 P 0 ;1
L 6.7825 2.7325 6.7825 2.7325 24 P 0 ;1
L 6.7825 2.7825 6.7825 2.7825 24 P 0 ;1
L 6.7825 2.8325 6.7825 2.8325 24 P 0 ;1
L 6.7825 2.8825 6.7825 2.8825 24 P 0 ;1
L 6.7825 2.9325 6.7825 2.9325 24 P 0 ;1
L 6.7825 2.9825 6.7825 2.9825 24 P 0 ;1
L 6.7825 3.0325 6.7825 3.0325 24 P 0 ;1
L 6.7825 3.0825 6.7825 3.0825 24 P 0 ;1
L 6.7825 3.1325 6.7825 3.1325 24 P 0 ;1
L 6.7825 3.1825 6.7825 3.1825 24 P 0 ;1
L 6.7825 3.2325 6.7825 3.2325 24 P 0 ;1
L 6.7825 3.2825 6.7825 3.2825 24 P 0 ;1
L 6.7825 3.3325 6.7825 3.3325 24 P 0 ;1
L 6.7825 3.3825 6.7825 3.3825 24 P 0 ;1
L 6.7825 3.4325 6.7825 3.4325 24 P 0 ;1
L 6.7825 3.4825 6.7825 3.4825 24 P 0 ;1
L 6.7825 3.5325 6.7825 3.5325 24 P 0 ;1
L 6.7825 3.5825 6.7825 3.5825 24 P 0 ;1
L 6.7825 3.6325 6.7825 3.6325 24 P 0 ;1
L 6.7825 3.6825 6.7825 3.6825 24 P 0 ;1
L 6.7825 3.7325 6.7825 3.7325 24 P 0 ;1
L 6.7825 3.7825 6.7825 3.7825 24 P 0 ;1
L 6.7825 3.8325 6.7825 3.8325 24 P 0 ;1
L 6.7825 3.8825 6.7825 3.8825 24 P 0 ;1
L 6.7825 3.9325 6.7825 3.9325 24 P 0 ;1
L 6.7825 3.9825 6.7825 3.9825 24 P 0 ;1
L 6.7825 4.0325 6.7825 4.0325 24 P 0 ;1
L 6.7825 4.3825 6.7825 4.3825 24 P 0 ;1
L 6.7825 4.4325 6.7825 4.4325 24 P 0 ;1
L 6.7825 5.1325 6.7825 5.1325 24 P 0 ;1
L 6.7825 5.1825 6.7825 5.1825 24 P 0 ;1
L 6.7825 5.2325 6.7825 5.2325 24 P 0 ;1
L 6.7825 5.2825 6.7825 5.2825 24 P 0 ;1
L 6.7825 5.3325 6.7825 5.3325 24 P 0 ;1
L 6.7825 5.3825 6.7825 5.3825 24 P 0 ;1
L 6.7825 5.4325 6.7825 5.4325 24 P 0 ;1
L 6.7825 5.4825 6.7825 5.4825 24 P 0 ;1
L 6.7825 5.5325 6.7825 5.5325 24 P 0 ;1
L 6.7825 5.5825 6.7825 5.5825 24 P 0 ;1
L 6.7825 5.6325 6.7825 5.6325 24 P 0 ;1
L 6.7825 5.6825 6.7825 5.6825 24 P 0 ;1
L 6.7825 5.7325 6.7825 5.7325 24 P 0 ;1
L 6.7825 5.7825 6.7825 5.7825 24 P 0 ;1
L 6.7825 5.8325 6.7825 5.8325 24 P 0 ;1
L 6.7825 5.8825 6.7825 5.8825 24 P 0 ;1
L 6.8325 0.1325 6.8325 0.1325 24 P 0 ;1
L 6.8325 0.1825 6.8325 0.1825 24 P 0 ;1
L 6.8325 0.2325 6.8325 0.2325 24 P 0 ;1
L 6.8325 0.2825 6.8325 0.2825 24 P 0 ;1
L 6.8325 0.3325 6.8325 0.3325 24 P 0 ;1
L 6.8325 0.3825 6.8325 0.3825 24 P 0 ;1
L 6.8325 0.4325 6.8325 0.4325 24 P 0 ;1
L 6.8325 0.6825 6.8325 0.6825 24 P 0 ;1
L 6.8325 0.7325 6.8325 0.7325 24 P 0 ;1
L 6.8325 0.7825 6.8325 0.7825 24 P 0 ;1
L 6.8325 0.8325 6.8325 0.8325 24 P 0 ;1
L 6.8325 0.8825 6.8325 0.8825 24 P 0 ;1
L 6.8325 0.9325 6.8325 0.9325 24 P 0 ;1
L 6.8325 0.9825 6.8325 0.9825 24 P 0 ;1
L 6.8325 1.0325 6.8325 1.0325 24 P 0 ;1
L 6.8325 1.0825 6.8325 1.0825 24 P 0 ;1
L 6.8325 1.1325 6.8325 1.1325 24 P 0 ;1
L 6.8325 1.1825 6.8325 1.1825 24 P 0 ;1
L 6.8325 1.2325 6.8325 1.2325 24 P 0 ;1
L 6.8325 1.2825 6.8325 1.2825 24 P 0 ;1
L 6.8325 1.7325 6.8325 1.7325 24 P 0 ;1
L 6.8325 1.7825 6.8325 1.7825 24 P 0 ;1
L 6.8325 1.8325 6.8325 1.8325 24 P 0 ;1
L 6.8325 1.8825 6.8325 1.8825 24 P 0 ;1
L 6.8325 1.9325 6.8325 1.9325 24 P 0 ;1
L 6.8325 1.9825 6.8325 1.9825 24 P 0 ;1
L 6.8325 2.0325 6.8325 2.0325 24 P 0 ;1
L 6.8325 2.0825 6.8325 2.0825 24 P 0 ;1
L 6.8325 2.1325 6.8325 2.1325 24 P 0 ;1
L 6.8325 2.1825 6.8325 2.1825 24 P 0 ;1
L 6.8325 2.2325 6.8325 2.2325 24 P 0 ;1
L 6.8325 2.2825 6.8325 2.2825 24 P 0 ;1
L 6.8325 2.3325 6.8325 2.3325 24 P 0 ;1
L 6.8325 2.3825 6.8325 2.3825 24 P 0 ;1
L 6.8325 2.4325 6.8325 2.4325 24 P 0 ;1
L 6.8325 2.4825 6.8325 2.4825 24 P 0 ;1
L 6.8325 2.5325 6.8325 2.5325 24 P 0 ;1
L 6.8325 2.5825 6.8325 2.5825 24 P 0 ;1
L 6.8325 2.6325 6.8325 2.6325 24 P 0 ;1
L 6.8325 2.6825 6.8325 2.6825 24 P 0 ;1
L 6.8325 2.7325 6.8325 2.7325 24 P 0 ;1
L 6.8325 2.7825 6.8325 2.7825 24 P 0 ;1
L 6.8325 2.8325 6.8325 2.8325 24 P 0 ;1
L 6.8325 2.8825 6.8325 2.8825 24 P 0 ;1
L 6.8325 2.9325 6.8325 2.9325 24 P 0 ;1
L 6.8325 2.9825 6.8325 2.9825 24 P 0 ;1
L 6.8325 3.0325 6.8325 3.0325 24 P 0 ;1
L 6.8325 3.0825 6.8325 3.0825 24 P 0 ;1
L 6.8325 3.1325 6.8325 3.1325 24 P 0 ;1
L 6.8325 3.1825 6.8325 3.1825 24 P 0 ;1
L 6.8325 3.2325 6.8325 3.2325 24 P 0 ;1
L 6.8325 3.2825 6.8325 3.2825 24 P 0 ;1
L 6.8325 3.3325 6.8325 3.3325 24 P 0 ;1
L 6.8325 3.3825 6.8325 3.3825 24 P 0 ;1
L 6.8325 3.4325 6.8325 3.4325 24 P 0 ;1
L 6.8325 3.4825 6.8325 3.4825 24 P 0 ;1
L 6.8325 3.5325 6.8325 3.5325 24 P 0 ;1
L 6.8325 3.5825 6.8325 3.5825 24 P 0 ;1
L 6.8325 3.6325 6.8325 3.6325 24 P 0 ;1
L 6.8325 3.6825 6.8325 3.6825 24 P 0 ;1
L 6.8325 3.7325 6.8325 3.7325 24 P 0 ;1
L 6.8325 3.7825 6.8325 3.7825 24 P 0 ;1
L 6.8325 3.8325 6.8325 3.8325 24 P 0 ;1
L 6.8325 3.8825 6.8325 3.8825 24 P 0 ;1
L 6.8325 3.9325 6.8325 3.9325 24 P 0 ;1
L 6.8325 3.9825 6.8325 3.9825 24 P 0 ;1
L 6.8325 4.4325 6.8325 4.4325 24 P 0 ;1
L 6.8325 5.1325 6.8325 5.1325 24 P 0 ;1
L 6.8325 5.1825 6.8325 5.1825 24 P 0 ;1
L 6.8325 5.2325 6.8325 5.2325 24 P 0 ;1
L 6.8325 5.2825 6.8325 5.2825 24 P 0 ;1
L 6.8325 5.3325 6.8325 5.3325 24 P 0 ;1
L 6.8325 5.3825 6.8325 5.3825 24 P 0 ;1
L 6.8325 5.4325 6.8325 5.4325 24 P 0 ;1
L 6.8325 5.4825 6.8325 5.4825 24 P 0 ;1
L 6.8325 5.5325 6.8325 5.5325 24 P 0 ;1
L 6.8325 5.5825 6.8325 5.5825 24 P 0 ;1
L 6.8325 5.6325 6.8325 5.6325 24 P 0 ;1
L 6.8325 5.6825 6.8325 5.6825 24 P 0 ;1
L 6.8325 5.7325 6.8325 5.7325 24 P 0 ;1
L 6.8325 5.7825 6.8325 5.7825 24 P 0 ;1
L 6.8325 5.8325 6.8325 5.8325 24 P 0 ;1
L 6.8325 5.8825 6.8325 5.8825 24 P 0 ;1
L 6.8825 0.1325 6.8825 0.1325 24 P 0 ;1
L 6.8825 0.1825 6.8825 0.1825 24 P 0 ;1
L 6.8825 0.2325 6.8825 0.2325 24 P 0 ;1
L 6.8825 0.2825 6.8825 0.2825 24 P 0 ;1
L 6.8825 0.3325 6.8825 0.3325 24 P 0 ;1
L 6.8825 0.3825 6.8825 0.3825 24 P 0 ;1
L 6.8825 0.4325 6.8825 0.4325 24 P 0 ;1
L 6.8825 0.6825 6.8825 0.6825 24 P 0 ;1
L 6.8825 0.7325 6.8825 0.7325 24 P 0 ;1
L 6.8825 0.7825 6.8825 0.7825 24 P 0 ;1
L 6.8825 0.8325 6.8825 0.8325 24 P 0 ;1
L 6.8825 0.8825 6.8825 0.8825 24 P 0 ;1
L 6.8825 0.9325 6.8825 0.9325 24 P 0 ;1
L 6.8825 0.9825 6.8825 0.9825 24 P 0 ;1
L 6.8825 1.0325 6.8825 1.0325 24 P 0 ;1
L 6.8825 1.0825 6.8825 1.0825 24 P 0 ;1
L 6.8825 1.1325 6.8825 1.1325 24 P 0 ;1
L 6.8825 1.1825 6.8825 1.1825 24 P 0 ;1
L 6.8825 1.2325 6.8825 1.2325 24 P 0 ;1
L 6.8825 1.2825 6.8825 1.2825 24 P 0 ;1
L 6.8825 1.7825 6.8825 1.7825 24 P 0 ;1
L 6.8825 1.8325 6.8825 1.8325 24 P 0 ;1
L 6.8825 1.8825 6.8825 1.8825 24 P 0 ;1
L 6.8825 1.9325 6.8825 1.9325 24 P 0 ;1
L 6.8825 1.9825 6.8825 1.9825 24 P 0 ;1
L 6.8825 2.0325 6.8825 2.0325 24 P 0 ;1
L 6.8825 2.0825 6.8825 2.0825 24 P 0 ;1
L 6.8825 2.1325 6.8825 2.1325 24 P 0 ;1
L 6.8825 2.1825 6.8825 2.1825 24 P 0 ;1
L 6.8825 2.2325 6.8825 2.2325 24 P 0 ;1
L 6.8825 2.2825 6.8825 2.2825 24 P 0 ;1
L 6.8825 2.3325 6.8825 2.3325 24 P 0 ;1
L 6.8825 2.3825 6.8825 2.3825 24 P 0 ;1
L 6.8825 2.4325 6.8825 2.4325 24 P 0 ;1
L 6.8825 2.4825 6.8825 2.4825 24 P 0 ;1
L 6.8825 2.5325 6.8825 2.5325 24 P 0 ;1
L 6.8825 2.6325 6.8825 2.6325 24 P 0 ;1
L 6.8825 2.6825 6.8825 2.6825 24 P 0 ;1
L 6.8825 2.7325 6.8825 2.7325 24 P 0 ;1
L 6.8825 2.7825 6.8825 2.7825 24 P 0 ;1
L 6.8825 2.8325 6.8825 2.8325 24 P 0 ;1
L 6.8825 2.8825 6.8825 2.8825 24 P 0 ;1
L 6.8825 2.9325 6.8825 2.9325 24 P 0 ;1
L 6.8825 2.9825 6.8825 2.9825 24 P 0 ;1
L 6.8825 3.0325 6.8825 3.0325 24 P 0 ;1
L 6.8825 3.0825 6.8825 3.0825 24 P 0 ;1
L 6.8825 3.1325 6.8825 3.1325 24 P 0 ;1
L 6.8825 3.1825 6.8825 3.1825 24 P 0 ;1
L 6.8825 3.2325 6.8825 3.2325 24 P 0 ;1
L 6.8825 3.2825 6.8825 3.2825 24 P 0 ;1
L 6.8825 3.3325 6.8825 3.3325 24 P 0 ;1
L 6.8825 3.3825 6.8825 3.3825 24 P 0 ;1
L 6.8825 3.4325 6.8825 3.4325 24 P 0 ;1
L 6.8825 3.4825 6.8825 3.4825 24 P 0 ;1
L 6.8825 3.5325 6.8825 3.5325 24 P 0 ;1
L 6.8825 3.5825 6.8825 3.5825 24 P 0 ;1
L 6.8825 3.6325 6.8825 3.6325 24 P 0 ;1
L 6.8825 3.6825 6.8825 3.6825 24 P 0 ;1
L 6.8825 3.7325 6.8825 3.7325 24 P 0 ;1
L 6.8825 3.7825 6.8825 3.7825 24 P 0 ;1
L 6.8825 3.8325 6.8825 3.8325 24 P 0 ;1
L 6.8825 3.8825 6.8825 3.8825 24 P 0 ;1
L 6.8825 3.9325 6.8825 3.9325 24 P 0 ;1
L 6.8825 4.4325 6.8825 4.4325 24 P 0 ;1
L 6.8825 5.1325 6.8825 5.1325 24 P 0 ;1
L 6.8825 5.1825 6.8825 5.1825 24 P 0 ;1
L 6.8825 5.2325 6.8825 5.2325 24 P 0 ;1
L 6.8825 5.2825 6.8825 5.2825 24 P 0 ;1
L 6.8825 5.3325 6.8825 5.3325 24 P 0 ;1
L 6.8825 5.3825 6.8825 5.3825 24 P 0 ;1
L 6.8825 5.4325 6.8825 5.4325 24 P 0 ;1
L 6.8825 5.4825 6.8825 5.4825 24 P 0 ;1
L 6.8825 5.5325 6.8825 5.5325 24 P 0 ;1
L 6.8825 5.5825 6.8825 5.5825 24 P 0 ;1
L 6.8825 5.6325 6.8825 5.6325 24 P 0 ;1
L 6.8825 5.6825 6.8825 5.6825 24 P 0 ;1
L 6.8825 5.7325 6.8825 5.7325 24 P 0 ;1
L 6.8825 5.7825 6.8825 5.7825 24 P 0 ;1
L 6.8825 5.8325 6.8825 5.8325 24 P 0 ;1
L 6.8825 5.8825 6.8825 5.8825 24 P 0 ;1
L 6.9325 0.1325 6.9325 0.1325 24 P 0 ;1
L 6.9325 0.3325 6.9325 0.3325 24 P 0 ;1
L 6.9325 0.3825 6.9325 0.3825 24 P 0 ;1
L 6.9325 0.4325 6.9325 0.4325 24 P 0 ;1
L 6.9325 0.6825 6.9325 0.6825 24 P 0 ;1
L 6.9325 0.7325 6.9325 0.7325 24 P 0 ;1
L 6.9325 0.7825 6.9325 0.7825 24 P 0 ;1
L 6.9325 0.8325 6.9325 0.8325 24 P 0 ;1
L 6.9325 0.8825 6.9325 0.8825 24 P 0 ;1
L 6.9325 0.9325 6.9325 0.9325 24 P 0 ;1
L 6.9325 0.9825 6.9325 0.9825 24 P 0 ;1
L 6.9325 1.0325 6.9325 1.0325 24 P 0 ;1
L 6.9325 1.0825 6.9325 1.0825 24 P 0 ;1
L 6.9325 1.1325 6.9325 1.1325 24 P 0 ;1
L 6.9325 1.1825 6.9325 1.1825 24 P 0 ;1
L 6.9325 1.2325 6.9325 1.2325 24 P 0 ;1
L 6.9325 1.2825 6.9325 1.2825 24 P 0 ;1
L 6.9325 1.7825 6.9325 1.7825 24 P 0 ;1
L 6.9325 1.8325 6.9325 1.8325 24 P 0 ;1
L 6.9325 1.8825 6.9325 1.8825 24 P 0 ;1
L 6.9325 1.9325 6.9325 1.9325 24 P 0 ;1
L 6.9325 1.9825 6.9325 1.9825 24 P 0 ;1
L 6.9325 2.0325 6.9325 2.0325 24 P 0 ;1
L 6.9325 2.0825 6.9325 2.0825 24 P 0 ;1
L 6.9325 2.1325 6.9325 2.1325 24 P 0 ;1
L 6.9325 2.1825 6.9325 2.1825 24 P 0 ;1
L 6.9325 2.2325 6.9325 2.2325 24 P 0 ;1
L 6.9325 2.2825 6.9325 2.2825 24 P 0 ;1
L 6.9325 2.3325 6.9325 2.3325 24 P 0 ;1
L 6.9325 2.3825 6.9325 2.3825 24 P 0 ;1
L 6.9325 2.4325 6.9325 2.4325 24 P 0 ;1
L 6.9325 2.7325 6.9325 2.7325 24 P 0 ;1
L 6.9325 2.7825 6.9325 2.7825 24 P 0 ;1
L 6.9325 2.8325 6.9325 2.8325 24 P 0 ;1
L 6.9325 2.8825 6.9325 2.8825 24 P 0 ;1
L 6.9325 2.9325 6.9325 2.9325 24 P 0 ;1
L 6.9325 2.9825 6.9325 2.9825 24 P 0 ;1
L 6.9325 3.0325 6.9325 3.0325 24 P 0 ;1
L 6.9325 3.0825 6.9325 3.0825 24 P 0 ;1
L 6.9325 3.1325 6.9325 3.1325 24 P 0 ;1
L 6.9325 3.1825 6.9325 3.1825 24 P 0 ;1
L 6.9325 3.2325 6.9325 3.2325 24 P 0 ;1
L 6.9325 3.2825 6.9325 3.2825 24 P 0 ;1
L 6.9325 3.3325 6.9325 3.3325 24 P 0 ;1
L 6.9325 3.3825 6.9325 3.3825 24 P 0 ;1
L 6.9325 3.4325 6.9325 3.4325 24 P 0 ;1
L 6.9325 3.4825 6.9325 3.4825 24 P 0 ;1
L 6.9325 3.5325 6.9325 3.5325 24 P 0 ;1
L 6.9325 3.5825 6.9325 3.5825 24 P 0 ;1
L 6.9325 3.6325 6.9325 3.6325 24 P 0 ;1
L 6.9325 3.6825 6.9325 3.6825 24 P 0 ;1
L 6.9325 3.7325 6.9325 3.7325 24 P 0 ;1
L 6.9325 3.7825 6.9325 3.7825 24 P 0 ;1
L 6.9325 3.8325 6.9325 3.8325 24 P 0 ;1
L 6.9325 3.8825 6.9325 3.8825 24 P 0 ;1
L 6.9325 3.9325 6.9325 3.9325 24 P 0 ;1
L 6.9325 5.0825 6.9325 5.0825 24 P 0 ;1
L 6.9325 5.1325 6.9325 5.1325 24 P 0 ;1
L 6.9325 5.1825 6.9325 5.1825 24 P 0 ;1
L 6.9325 5.2325 6.9325 5.2325 24 P 0 ;1
L 6.9325 5.2825 6.9325 5.2825 24 P 0 ;1
L 6.9325 5.3325 6.9325 5.3325 24 P 0 ;1
L 6.9325 5.3825 6.9325 5.3825 24 P 0 ;1
L 6.9325 5.4325 6.9325 5.4325 24 P 0 ;1
L 6.9325 5.4825 6.9325 5.4825 24 P 0 ;1
L 6.9325 5.5325 6.9325 5.5325 24 P 0 ;1
L 6.9325 5.5825 6.9325 5.5825 24 P 0 ;1
L 6.9325 5.6325 6.9325 5.6325 24 P 0 ;1
L 6.9325 5.6825 6.9325 5.6825 24 P 0 ;1
L 6.9325 5.8825 6.9325 5.8825 24 P 0 ;1
L 6.9825 0.4325 6.9825 0.4325 24 P 0 ;1
L 6.9825 0.6825 6.9825 0.6825 24 P 0 ;1
L 6.9825 0.7325 6.9825 0.7325 24 P 0 ;1
L 6.9825 0.7825 6.9825 0.7825 24 P 0 ;1
L 6.9825 0.8325 6.9825 0.8325 24 P 0 ;1
L 6.9825 0.8825 6.9825 0.8825 24 P 0 ;1
L 6.9825 0.9325 6.9825 0.9325 24 P 0 ;1
L 6.9825 0.9825 6.9825 0.9825 24 P 0 ;1
L 6.9825 1.0325 6.9825 1.0325 24 P 0 ;1
L 6.9825 1.0825 6.9825 1.0825 24 P 0 ;1
L 6.9825 1.1325 6.9825 1.1325 24 P 0 ;1
L 6.9825 1.1825 6.9825 1.1825 24 P 0 ;1
L 6.9825 1.2325 6.9825 1.2325 24 P 0 ;1
L 6.9825 1.2825 6.9825 1.2825 24 P 0 ;1
L 6.9825 1.7825 6.9825 1.7825 24 P 0 ;1
L 6.9825 1.8325 6.9825 1.8325 24 P 0 ;1
L 6.9825 1.8825 6.9825 1.8825 24 P 0 ;1
L 6.9825 1.9325 6.9825 1.9325 24 P 0 ;1
L 6.9825 1.9825 6.9825 1.9825 24 P 0 ;1
L 6.9825 2.0325 6.9825 2.0325 24 P 0 ;1
L 6.9825 2.0825 6.9825 2.0825 24 P 0 ;1
L 6.9825 2.1325 6.9825 2.1325 24 P 0 ;1
L 6.9825 2.1825 6.9825 2.1825 24 P 0 ;1
L 6.9825 2.2325 6.9825 2.2325 24 P 0 ;1
L 6.9825 2.2825 6.9825 2.2825 24 P 0 ;1
L 6.9825 2.3325 6.9825 2.3325 24 P 0 ;1
L 6.9825 2.3825 6.9825 2.3825 24 P 0 ;1
L 6.9825 2.4325 6.9825 2.4325 24 P 0 ;1
L 6.9825 2.7325 6.9825 2.7325 24 P 0 ;1
L 6.9825 2.7825 6.9825 2.7825 24 P 0 ;1
L 6.9825 2.8325 6.9825 2.8325 24 P 0 ;1
L 6.9825 2.8825 6.9825 2.8825 24 P 0 ;1
L 6.9825 2.9325 6.9825 2.9325 24 P 0 ;1
L 6.9825 2.9825 6.9825 2.9825 24 P 0 ;1
L 6.9825 3.0325 6.9825 3.0325 24 P 0 ;1
L 6.9825 3.0825 6.9825 3.0825 24 P 0 ;1
L 6.9825 3.1325 6.9825 3.1325 24 P 0 ;1
L 6.9825 3.1825 6.9825 3.1825 24 P 0 ;1
L 6.9825 3.2325 6.9825 3.2325 24 P 0 ;1
L 6.9825 3.2825 6.9825 3.2825 24 P 0 ;1
L 6.9825 3.3325 6.9825 3.3325 24 P 0 ;1
L 6.9825 3.3825 6.9825 3.3825 24 P 0 ;1
L 6.9825 3.4325 6.9825 3.4325 24 P 0 ;1
L 6.9825 3.4825 6.9825 3.4825 24 P 0 ;1
L 6.9825 3.5325 6.9825 3.5325 24 P 0 ;1
L 6.9825 3.5825 6.9825 3.5825 24 P 0 ;1
L 6.9825 3.6325 6.9825 3.6325 24 P 0 ;1
L 6.9825 3.6825 6.9825 3.6825 24 P 0 ;1
L 6.9825 3.7325 6.9825 3.7325 24 P 0 ;1
L 6.9825 3.7825 6.9825 3.7825 24 P 0 ;1
L 6.9825 3.8325 6.9825 3.8325 24 P 0 ;1
L 6.9825 3.8825 6.9825 3.8825 24 P 0 ;1
L 6.9825 3.9325 6.9825 3.9325 24 P 0 ;1
L 6.9825 4.4825 6.9825 4.4825 24 P 0 ;1
L 6.9825 5.0325 6.9825 5.0325 24 P 0 ;1
L 6.9825 5.0825 6.9825 5.0825 24 P 0 ;1
L 6.9825 5.1325 6.9825 5.1325 24 P 0 ;1
L 6.9825 5.1825 6.9825 5.1825 24 P 0 ;1
L 6.9825 5.2325 6.9825 5.2325 24 P 0 ;1
L 6.9825 5.2825 6.9825 5.2825 24 P 0 ;1
L 6.9825 5.3325 6.9825 5.3325 24 P 0 ;1
L 6.9825 5.3825 6.9825 5.3825 24 P 0 ;1
L 6.9825 5.4325 6.9825 5.4325 24 P 0 ;1
L 6.9825 5.4825 6.9825 5.4825 24 P 0 ;1
L 6.9825 5.5325 6.9825 5.5325 24 P 0 ;1
L 6.9825 5.5825 6.9825 5.5825 24 P 0 ;1
L 7.0325 0.6825 7.0325 0.6825 24 P 0 ;1
L 7.0325 0.7325 7.0325 0.7325 24 P 0 ;1
L 7.0325 0.7825 7.0325 0.7825 24 P 0 ;1
L 7.0325 0.8325 7.0325 0.8325 24 P 0 ;1
L 7.0325 0.8825 7.0325 0.8825 24 P 0 ;1
L 7.0325 0.9325 7.0325 0.9325 24 P 0 ;1
L 7.0325 0.9825 7.0325 0.9825 24 P 0 ;1
L 7.0325 1.0325 7.0325 1.0325 24 P 0 ;1
L 7.0325 1.0825 7.0325 1.0825 24 P 0 ;1
L 7.0325 1.1325 7.0325 1.1325 24 P 0 ;1
L 7.0325 1.1825 7.0325 1.1825 24 P 0 ;1
L 7.0325 1.2325 7.0325 1.2325 24 P 0 ;1
L 7.0325 1.2825 7.0325 1.2825 24 P 0 ;1
L 7.0325 1.7825 7.0325 1.7825 24 P 0 ;1
L 7.0325 1.8325 7.0325 1.8325 24 P 0 ;1
L 7.0325 1.8825 7.0325 1.8825 24 P 0 ;1
L 7.0325 1.9325 7.0325 1.9325 24 P 0 ;1
L 7.0325 1.9825 7.0325 1.9825 24 P 0 ;1
L 7.0325 2.0325 7.0325 2.0325 24 P 0 ;1
L 7.0325 2.0825 7.0325 2.0825 24 P 0 ;1
L 7.0325 2.1325 7.0325 2.1325 24 P 0 ;1
L 7.0325 2.1825 7.0325 2.1825 24 P 0 ;1
L 7.0325 2.2325 7.0325 2.2325 24 P 0 ;1
L 7.0325 2.2825 7.0325 2.2825 24 P 0 ;1
L 7.0325 2.3325 7.0325 2.3325 24 P 0 ;1
L 7.0325 2.3825 7.0325 2.3825 24 P 0 ;1
L 7.0325 2.7825 7.0325 2.7825 24 P 0 ;1
L 7.0325 2.8325 7.0325 2.8325 24 P 0 ;1
L 7.0325 2.8825 7.0325 2.8825 24 P 0 ;1
L 7.0325 2.9325 7.0325 2.9325 24 P 0 ;1
L 7.0325 2.9825 7.0325 2.9825 24 P 0 ;1
L 7.0325 3.0325 7.0325 3.0325 24 P 0 ;1
L 7.0325 3.0825 7.0325 3.0825 24 P 0 ;1
L 7.0325 3.1325 7.0325 3.1325 24 P 0 ;1
L 7.0325 3.1825 7.0325 3.1825 24 P 0 ;1
L 7.0325 3.2325 7.0325 3.2325 24 P 0 ;1
L 7.0325 3.2825 7.0325 3.2825 24 P 0 ;1
L 7.0325 3.3325 7.0325 3.3325 24 P 0 ;1
L 7.0325 3.3825 7.0325 3.3825 24 P 0 ;1
L 7.0325 3.4325 7.0325 3.4325 24 P 0 ;1
L 7.0325 3.4825 7.0325 3.4825 24 P 0 ;1
L 7.0325 3.5325 7.0325 3.5325 24 P 0 ;1
L 7.0325 3.5825 7.0325 3.5825 24 P 0 ;1
L 7.0325 3.6325 7.0325 3.6325 24 P 0 ;1
L 7.0325 3.6825 7.0325 3.6825 24 P 0 ;1
L 7.0325 3.7325 7.0325 3.7325 24 P 0 ;1
L 7.0325 3.7825 7.0325 3.7825 24 P 0 ;1
L 7.0325 3.8325 7.0325 3.8325 24 P 0 ;1
L 7.0325 3.8825 7.0325 3.8825 24 P 0 ;1
L 7.0325 3.9325 7.0325 3.9325 24 P 0 ;1
L 7.0325 4.4825 7.0325 4.4825 24 P 0 ;1
L 7.0325 4.5325 7.0325 4.5325 24 P 0 ;1
L 7.0325 4.5825 7.0325 4.5825 24 P 0 ;1
L 7.0325 4.6325 7.0325 4.6325 24 P 0 ;1
L 7.0325 4.9325 7.0325 4.9325 24 P 0 ;1
L 7.0325 4.9825 7.0325 4.9825 24 P 0 ;1
L 7.0325 5.0325 7.0325 5.0325 24 P 0 ;1
L 7.0325 5.0825 7.0325 5.0825 24 P 0 ;1
L 7.0325 5.1325 7.0325 5.1325 24 P 0 ;1
L 7.0325 5.1825 7.0325 5.1825 24 P 0 ;1
L 7.0325 5.2325 7.0325 5.2325 24 P 0 ;1
L 7.0325 5.2825 7.0325 5.2825 24 P 0 ;1
L 7.0325 5.3325 7.0325 5.3325 24 P 0 ;1
L 7.0325 5.3825 7.0325 5.3825 24 P 0 ;1
L 7.0325 5.4325 7.0325 5.4325 24 P 0 ;1
L 7.0325 5.4825 7.0325 5.4825 24 P 0 ;1
L 7.0325 5.5325 7.0325 5.5325 24 P 0 ;1
L 7.0825 0.6825 7.0825 0.6825 24 P 0 ;1
L 7.0825 0.7325 7.0825 0.7325 24 P 0 ;1
L 7.0825 0.7825 7.0825 0.7825 24 P 0 ;1
L 7.0825 0.8325 7.0825 0.8325 24 P 0 ;1
L 7.0825 0.8825 7.0825 0.8825 24 P 0 ;1
L 7.0825 0.9325 7.0825 0.9325 24 P 0 ;1
L 7.0825 0.9825 7.0825 0.9825 24 P 0 ;1
L 7.0825 1.0325 7.0825 1.0325 24 P 0 ;1
L 7.0825 1.0825 7.0825 1.0825 24 P 0 ;1
L 7.0825 1.1325 7.0825 1.1325 24 P 0 ;1
L 7.0825 1.1825 7.0825 1.1825 24 P 0 ;1
L 7.0825 1.2325 7.0825 1.2325 24 P 0 ;1
L 7.0825 1.2825 7.0825 1.2825 24 P 0 ;1
L 7.0825 1.7825 7.0825 1.7825 24 P 0 ;1
L 7.0825 1.8325 7.0825 1.8325 24 P 0 ;1
L 7.0825 1.8825 7.0825 1.8825 24 P 0 ;1
L 7.0825 1.9325 7.0825 1.9325 24 P 0 ;1
L 7.0825 1.9825 7.0825 1.9825 24 P 0 ;1
L 7.0825 2.0325 7.0825 2.0325 24 P 0 ;1
L 7.0825 2.0825 7.0825 2.0825 24 P 0 ;1
L 7.0825 2.1325 7.0825 2.1325 24 P 0 ;1
L 7.0825 2.1825 7.0825 2.1825 24 P 0 ;1
L 7.0825 2.2325 7.0825 2.2325 24 P 0 ;1
L 7.0825 2.2825 7.0825 2.2825 24 P 0 ;1
L 7.0825 2.3325 7.0825 2.3325 24 P 0 ;1
L 7.0825 2.3825 7.0825 2.3825 24 P 0 ;1
L 7.0825 2.7825 7.0825 2.7825 24 P 0 ;1
L 7.0825 2.8325 7.0825 2.8325 24 P 0 ;1
L 7.0825 2.8825 7.0825 2.8825 24 P 0 ;1
L 7.0825 2.9325 7.0825 2.9325 24 P 0 ;1
L 7.0825 2.9825 7.0825 2.9825 24 P 0 ;1
L 7.0825 3.0325 7.0825 3.0325 24 P 0 ;1
L 7.0825 3.0825 7.0825 3.0825 24 P 0 ;1
L 7.0825 3.1325 7.0825 3.1325 24 P 0 ;1
L 7.0825 3.1825 7.0825 3.1825 24 P 0 ;1
L 7.0825 3.2325 7.0825 3.2325 24 P 0 ;1
L 7.0825 3.2825 7.0825 3.2825 24 P 0 ;1
L 7.0825 3.3325 7.0825 3.3325 24 P 0 ;1
L 7.0825 3.3825 7.0825 3.3825 24 P 0 ;1
L 7.0825 3.4325 7.0825 3.4325 24 P 0 ;1
L 7.0825 3.4825 7.0825 3.4825 24 P 0 ;1
L 7.0825 3.5325 7.0825 3.5325 24 P 0 ;1
L 7.0825 3.5825 7.0825 3.5825 24 P 0 ;1
L 7.0825 3.6325 7.0825 3.6325 24 P 0 ;1
L 7.0825 3.6825 7.0825 3.6825 24 P 0 ;1
L 7.0825 3.7325 7.0825 3.7325 24 P 0 ;1
L 7.0825 3.7825 7.0825 3.7825 24 P 0 ;1
L 7.0825 3.8325 7.0825 3.8325 24 P 0 ;1
L 7.0825 3.8825 7.0825 3.8825 24 P 0 ;1
L 7.0825 3.9325 7.0825 3.9325 24 P 0 ;1
L 7.0825 3.9825 7.0825 3.9825 24 P 0 ;1
L 7.0825 4.4325 7.0825 4.4325 24 P 0 ;1
L 7.0825 4.4825 7.0825 4.4825 24 P 0 ;1
L 7.0825 4.5325 7.0825 4.5325 24 P 0 ;1
L 7.0825 4.5825 7.0825 4.5825 24 P 0 ;1
L 7.0825 4.6325 7.0825 4.6325 24 P 0 ;1
L 7.0825 4.6825 7.0825 4.6825 24 P 0 ;1
L 7.0825 4.7325 7.0825 4.7325 24 P 0 ;1
L 7.0825 4.7825 7.0825 4.7825 24 P 0 ;1
L 7.0825 4.8325 7.0825 4.8325 24 P 0 ;1
L 7.0825 4.8825 7.0825 4.8825 24 P 0 ;1
L 7.0825 4.9325 7.0825 4.9325 24 P 0 ;1
L 7.0825 4.9825 7.0825 4.9825 24 P 0 ;1
L 7.0825 5.0325 7.0825 5.0325 24 P 0 ;1
L 7.0825 5.0825 7.0825 5.0825 24 P 0 ;1
L 7.0825 5.1325 7.0825 5.1325 24 P 0 ;1
L 7.0825 5.1825 7.0825 5.1825 24 P 0 ;1
L 7.0825 5.2325 7.0825 5.2325 24 P 0 ;1
L 7.0825 5.2825 7.0825 5.2825 24 P 0 ;1
L 7.0825 5.3325 7.0825 5.3325 24 P 0 ;1
L 7.0825 5.3825 7.0825 5.3825 24 P 0 ;1
L 7.0825 5.4325 7.0825 5.4325 24 P 0 ;1
L 7.0825 5.4825 7.0825 5.4825 24 P 0 ;1
L 7.0825 5.5325 7.0825 5.5325 24 P 0 ;1
L 7.1325 0.6825 7.1325 0.6825 24 P 0 ;1
L 7.1325 0.7325 7.1325 0.7325 24 P 0 ;1
L 7.1325 0.7825 7.1325 0.7825 24 P 0 ;1
L 7.1325 0.8325 7.1325 0.8325 24 P 0 ;1
L 7.1325 0.8825 7.1325 0.8825 24 P 0 ;1
L 7.1325 0.9325 7.1325 0.9325 24 P 0 ;1
L 7.1325 0.9825 7.1325 0.9825 24 P 0 ;1
L 7.1325 1.0325 7.1325 1.0325 24 P 0 ;1
L 7.1325 1.0825 7.1325 1.0825 24 P 0 ;1
L 7.1325 1.1325 7.1325 1.1325 24 P 0 ;1
L 7.1325 1.1825 7.1325 1.1825 24 P 0 ;1
L 7.1325 1.2325 7.1325 1.2325 24 P 0 ;1
L 7.1325 1.2825 7.1325 1.2825 24 P 0 ;1
L 7.1325 1.3325 7.1325 1.3325 24 P 0 ;1
L 7.1325 1.7325 7.1325 1.7325 24 P 0 ;1
L 7.1325 1.7825 7.1325 1.7825 24 P 0 ;1
L 7.1325 1.8325 7.1325 1.8325 24 P 0 ;1
L 7.1325 1.8825 7.1325 1.8825 24 P 0 ;1
L 7.1325 1.9325 7.1325 1.9325 24 P 0 ;1
L 7.1325 1.9825 7.1325 1.9825 24 P 0 ;1
L 7.1325 2.0325 7.1325 2.0325 24 P 0 ;1
L 7.1325 2.0825 7.1325 2.0825 24 P 0 ;1
L 7.1325 2.1325 7.1325 2.1325 24 P 0 ;1
L 7.1325 2.1825 7.1325 2.1825 24 P 0 ;1
L 7.1325 2.2325 7.1325 2.2325 24 P 0 ;1
L 7.1325 2.2825 7.1325 2.2825 24 P 0 ;1
L 7.1325 2.3325 7.1325 2.3325 24 P 0 ;1
L 7.1325 2.3825 7.1325 2.3825 24 P 0 ;1
L 7.1325 2.4325 7.1325 2.4325 24 P 0 ;1
L 7.1325 2.7325 7.1325 2.7325 24 P 0 ;1
L 7.1325 2.7825 7.1325 2.7825 24 P 0 ;1
L 7.1325 2.8325 7.1325 2.8325 24 P 0 ;1
L 7.1325 2.8825 7.1325 2.8825 24 P 0 ;1
L 7.1325 2.9325 7.1325 2.9325 24 P 0 ;1
L 7.1325 2.9825 7.1325 2.9825 24 P 0 ;1
L 7.1325 3.0325 7.1325 3.0325 24 P 0 ;1
L 7.1325 3.0825 7.1325 3.0825 24 P 0 ;1
L 7.1325 3.1325 7.1325 3.1325 24 P 0 ;1
L 7.1325 3.1825 7.1325 3.1825 24 P 0 ;1
L 7.1325 3.2325 7.1325 3.2325 24 P 0 ;1
L 7.1325 3.2825 7.1325 3.2825 24 P 0 ;1
L 7.1325 3.3325 7.1325 3.3325 24 P 0 ;1
L 7.1325 3.3825 7.1325 3.3825 24 P 0 ;1
L 7.1325 3.4325 7.1325 3.4325 24 P 0 ;1
L 7.1325 3.4825 7.1325 3.4825 24 P 0 ;1
L 7.1325 3.5325 7.1325 3.5325 24 P 0 ;1
L 7.1325 3.5825 7.1325 3.5825 24 P 0 ;1
L 7.1325 3.6325 7.1325 3.6325 24 P 0 ;1
L 7.1325 3.6825 7.1325 3.6825 24 P 0 ;1
L 7.1325 3.7325 7.1325 3.7325 24 P 0 ;1
L 7.1325 3.7825 7.1325 3.7825 24 P 0 ;1
L 7.1325 3.8325 7.1325 3.8325 24 P 0 ;1
L 7.1325 3.8825 7.1325 3.8825 24 P 0 ;1
L 7.1325 3.9325 7.1325 3.9325 24 P 0 ;1
L 7.1325 3.9825 7.1325 3.9825 24 P 0 ;1
L 7.1325 4.3825 7.1325 4.3825 24 P 0 ;1
L 7.1325 4.4325 7.1325 4.4325 24 P 0 ;1
L 7.1325 4.4825 7.1325 4.4825 24 P 0 ;1
L 7.1325 4.5325 7.1325 4.5325 24 P 0 ;1
L 7.1325 4.5825 7.1325 4.5825 24 P 0 ;1
L 7.1325 4.6325 7.1325 4.6325 24 P 0 ;1
L 7.1325 4.6825 7.1325 4.6825 24 P 0 ;1
L 7.1325 4.7325 7.1325 4.7325 24 P 0 ;1
L 7.1325 4.7825 7.1325 4.7825 24 P 0 ;1
L 7.1325 4.8325 7.1325 4.8325 24 P 0 ;1
L 7.1325 5.2825 7.1325 5.2825 24 P 0 ;1
L 7.1325 5.3325 7.1325 5.3325 24 P 0 ;1
L 7.1325 5.3825 7.1325 5.3825 24 P 0 ;1
L 7.1325 5.4325 7.1325 5.4325 24 P 0 ;1
L 7.1325 5.4825 7.1325 5.4825 24 P 0 ;1
L 7.1825 0.6825 7.1825 0.6825 24 P 0 ;1
L 7.1825 0.7325 7.1825 0.7325 24 P 0 ;1
L 7.1825 0.7825 7.1825 0.7825 24 P 0 ;1
L 7.1825 0.8325 7.1825 0.8325 24 P 0 ;1
L 7.1825 0.8825 7.1825 0.8825 24 P 0 ;1
L 7.1825 0.9325 7.1825 0.9325 24 P 0 ;1
L 7.1825 0.9825 7.1825 0.9825 24 P 0 ;1
L 7.1825 1.0325 7.1825 1.0325 24 P 0 ;1
L 7.1825 1.0825 7.1825 1.0825 24 P 0 ;1
L 7.1825 1.1325 7.1825 1.1325 24 P 0 ;1
L 7.1825 1.1825 7.1825 1.1825 24 P 0 ;1
L 7.1825 1.2325 7.1825 1.2325 24 P 0 ;1
L 7.1825 1.2825 7.1825 1.2825 24 P 0 ;1
L 7.1825 1.3325 7.1825 1.3325 24 P 0 ;1
L 7.1825 1.3825 7.1825 1.3825 24 P 0 ;1
L 7.1825 1.6825 7.1825 1.6825 24 P 0 ;1
L 7.1825 1.7325 7.1825 1.7325 24 P 0 ;1
L 7.1825 1.7825 7.1825 1.7825 24 P 0 ;1
L 7.1825 1.8325 7.1825 1.8325 24 P 0 ;1
L 7.1825 1.8825 7.1825 1.8825 24 P 0 ;1
L 7.1825 1.9325 7.1825 1.9325 24 P 0 ;1
L 7.1825 1.9825 7.1825 1.9825 24 P 0 ;1
L 7.1825 2.0325 7.1825 2.0325 24 P 0 ;1
L 7.1825 2.0825 7.1825 2.0825 24 P 0 ;1
L 7.1825 2.1325 7.1825 2.1325 24 P 0 ;1
L 7.1825 2.1825 7.1825 2.1825 24 P 0 ;1
L 7.1825 2.2325 7.1825 2.2325 24 P 0 ;1
L 7.1825 2.2825 7.1825 2.2825 24 P 0 ;1
L 7.1825 2.3325 7.1825 2.3325 24 P 0 ;1
L 7.1825 2.3825 7.1825 2.3825 24 P 0 ;1
L 7.1825 2.4325 7.1825 2.4325 24 P 0 ;1
L 7.1825 2.7325 7.1825 2.7325 24 P 0 ;1
L 7.1825 2.7825 7.1825 2.7825 24 P 0 ;1
L 7.1825 2.8325 7.1825 2.8325 24 P 0 ;1
L 7.1825 2.8825 7.1825 2.8825 24 P 0 ;1
L 7.1825 2.9325 7.1825 2.9325 24 P 0 ;1
L 7.1825 2.9825 7.1825 2.9825 24 P 0 ;1
L 7.1825 3.0325 7.1825 3.0325 24 P 0 ;1
L 7.1825 3.0825 7.1825 3.0825 24 P 0 ;1
L 7.1825 3.1325 7.1825 3.1325 24 P 0 ;1
L 7.1825 3.1825 7.1825 3.1825 24 P 0 ;1
L 7.1825 3.2325 7.1825 3.2325 24 P 0 ;1
L 7.1825 3.2825 7.1825 3.2825 24 P 0 ;1
L 7.1825 3.3325 7.1825 3.3325 24 P 0 ;1
L 7.1825 3.3825 7.1825 3.3825 24 P 0 ;1
L 7.1825 3.4325 7.1825 3.4325 24 P 0 ;1
L 7.1825 3.4825 7.1825 3.4825 24 P 0 ;1
L 7.1825 3.5325 7.1825 3.5325 24 P 0 ;1
L 7.1825 3.5825 7.1825 3.5825 24 P 0 ;1
L 7.1825 3.6325 7.1825 3.6325 24 P 0 ;1
L 7.1825 3.6825 7.1825 3.6825 24 P 0 ;1
L 7.1825 3.7325 7.1825 3.7325 24 P 0 ;1
L 7.1825 3.7825 7.1825 3.7825 24 P 0 ;1
L 7.1825 3.8325 7.1825 3.8325 24 P 0 ;1
L 7.1825 3.8825 7.1825 3.8825 24 P 0 ;1
L 7.1825 3.9325 7.1825 3.9325 24 P 0 ;1
L 7.1825 3.9825 7.1825 3.9825 24 P 0 ;1
L 7.1825 4.0325 7.1825 4.0325 24 P 0 ;1
L 7.1825 4.0825 7.1825 4.0825 24 P 0 ;1
L 7.1825 4.3325 7.1825 4.3325 24 P 0 ;1
L 7.1825 4.3825 7.1825 4.3825 24 P 0 ;1
L 7.1825 4.4325 7.1825 4.4325 24 P 0 ;1
L 7.1825 4.4825 7.1825 4.4825 24 P 0 ;1
L 7.1825 4.7825 7.1825 4.7825 24 P 0 ;1
L 7.1825 4.8325 7.1825 4.8325 24 P 0 ;1
L 7.1825 5.2825 7.1825 5.2825 24 P 0 ;1
L 7.1825 5.3325 7.1825 5.3325 24 P 0 ;1
L 7.1825 5.3825 7.1825 5.3825 24 P 0 ;1
L 7.1825 5.4325 7.1825 5.4325 24 P 0 ;1
L 7.1825 5.4825 7.1825 5.4825 24 P 0 ;1
L 7.2325 0.6825 7.2325 0.6825 24 P 0 ;1
L 7.2325 0.7325 7.2325 0.7325 24 P 0 ;1
L 7.2325 0.7825 7.2325 0.7825 24 P 0 ;1
L 7.2325 0.8325 7.2325 0.8325 24 P 0 ;1
L 7.2325 0.8825 7.2325 0.8825 24 P 0 ;1
L 7.2325 0.9325 7.2325 0.9325 24 P 0 ;1
L 7.2325 0.9825 7.2325 0.9825 24 P 0 ;1
L 7.2325 1.0325 7.2325 1.0325 24 P 0 ;1
L 7.2325 1.0825 7.2325 1.0825 24 P 0 ;1
L 7.2325 1.1325 7.2325 1.1325 24 P 0 ;1
L 7.2325 1.1825 7.2325 1.1825 24 P 0 ;1
L 7.2325 1.2325 7.2325 1.2325 24 P 0 ;1
L 7.2325 1.2825 7.2325 1.2825 24 P 0 ;1
L 7.2325 1.3325 7.2325 1.3325 24 P 0 ;1
L 7.2325 1.3825 7.2325 1.3825 24 P 0 ;1
L 7.2325 1.4325 7.2325 1.4325 24 P 0 ;1
L 7.2325 1.4825 7.2325 1.4825 24 P 0 ;1
L 7.2325 1.5325 7.2325 1.5325 24 P 0 ;1
L 7.2325 1.5825 7.2325 1.5825 24 P 0 ;1
L 7.2325 1.6325 7.2325 1.6325 24 P 0 ;1
L 7.2325 1.6825 7.2325 1.6825 24 P 0 ;1
L 7.2325 1.7325 7.2325 1.7325 24 P 0 ;1
L 7.2325 1.7825 7.2325 1.7825 24 P 0 ;1
L 7.2325 1.8325 7.2325 1.8325 24 P 0 ;1
L 7.2325 1.8825 7.2325 1.8825 24 P 0 ;1
L 7.2325 1.9325 7.2325 1.9325 24 P 0 ;1
L 7.2325 1.9825 7.2325 1.9825 24 P 0 ;1
L 7.2325 2.0325 7.2325 2.0325 24 P 0 ;1
L 7.2325 2.0825 7.2325 2.0825 24 P 0 ;1
L 7.2325 2.1325 7.2325 2.1325 24 P 0 ;1
L 7.2325 2.1825 7.2325 2.1825 24 P 0 ;1
L 7.2325 2.2325 7.2325 2.2325 24 P 0 ;1
L 7.2325 2.2825 7.2325 2.2825 24 P 0 ;1
L 7.2325 2.3325 7.2325 2.3325 24 P 0 ;1
L 7.2325 2.3825 7.2325 2.3825 24 P 0 ;1
L 7.2325 2.4325 7.2325 2.4325 24 P 0 ;1
L 7.2325 2.4825 7.2325 2.4825 24 P 0 ;1
L 7.2325 2.6825 7.2325 2.6825 24 P 0 ;1
L 7.2325 2.7325 7.2325 2.7325 24 P 0 ;1
L 7.2325 2.7825 7.2325 2.7825 24 P 0 ;1
L 7.2325 2.8325 7.2325 2.8325 24 P 0 ;1
L 7.2325 2.8825 7.2325 2.8825 24 P 0 ;1
L 7.2325 2.9325 7.2325 2.9325 24 P 0 ;1
L 7.2325 2.9825 7.2325 2.9825 24 P 0 ;1
L 7.2325 3.0325 7.2325 3.0325 24 P 0 ;1
L 7.2325 3.0825 7.2325 3.0825 24 P 0 ;1
L 7.2325 3.1325 7.2325 3.1325 24 P 0 ;1
L 7.2325 3.1825 7.2325 3.1825 24 P 0 ;1
L 7.2325 3.2325 7.2325 3.2325 24 P 0 ;1
L 7.2325 3.2825 7.2325 3.2825 24 P 0 ;1
L 7.2325 3.3325 7.2325 3.3325 24 P 0 ;1
L 7.2325 3.3825 7.2325 3.3825 24 P 0 ;1
L 7.2325 3.4325 7.2325 3.4325 24 P 0 ;1
L 7.2325 3.4825 7.2325 3.4825 24 P 0 ;1
L 7.2325 3.5325 7.2325 3.5325 24 P 0 ;1
L 7.2325 3.5825 7.2325 3.5825 24 P 0 ;1
L 7.2325 3.6325 7.2325 3.6325 24 P 0 ;1
L 7.2325 3.6825 7.2325 3.6825 24 P 0 ;1
L 7.2325 3.7325 7.2325 3.7325 24 P 0 ;1
L 7.2325 3.7825 7.2325 3.7825 24 P 0 ;1
L 7.2325 3.8325 7.2325 3.8325 24 P 0 ;1
L 7.2325 3.8825 7.2325 3.8825 24 P 0 ;1
L 7.2325 3.9325 7.2325 3.9325 24 P 0 ;1
L 7.2325 3.9825 7.2325 3.9825 24 P 0 ;1
L 7.2325 4.0325 7.2325 4.0325 24 P 0 ;1
L 7.2325 4.0825 7.2325 4.0825 24 P 0 ;1
L 7.2325 4.1325 7.2325 4.1325 24 P 0 ;1
L 7.2325 4.1825 7.2325 4.1825 24 P 0 ;1
L 7.2325 4.2325 7.2325 4.2325 24 P 0 ;1
L 7.2325 4.2825 7.2325 4.2825 24 P 0 ;1
L 7.2325 4.3325 7.2325 4.3325 24 P 0 ;1
L 7.2325 4.3825 7.2325 4.3825 24 P 0 ;1
L 7.2325 4.4325 7.2325 4.4325 24 P 0 ;1
L 7.2325 4.4825 7.2325 4.4825 24 P 0 ;1
L 7.2325 5.2825 7.2325 5.2825 24 P 0 ;1
L 7.2325 5.3325 7.2325 5.3325 24 P 0 ;1
L 7.2325 5.3825 7.2325 5.3825 24 P 0 ;1
L 7.2325 5.4325 7.2325 5.4325 24 P 0 ;1
L 7.2325 5.4825 7.2325 5.4825 24 P 0 ;1
L 7.2825 0.6825 7.2825 0.6825 24 P 0 ;1
L 7.2825 0.7325 7.2825 0.7325 24 P 0 ;1
L 7.2825 0.7825 7.2825 0.7825 24 P 0 ;1
L 7.2825 0.8325 7.2825 0.8325 24 P 0 ;1
L 7.2825 0.8825 7.2825 0.8825 24 P 0 ;1
L 7.2825 0.9325 7.2825 0.9325 24 P 0 ;1
L 7.2825 0.9825 7.2825 0.9825 24 P 0 ;1
L 7.2825 1.0325 7.2825 1.0325 24 P 0 ;1
L 7.2825 1.0825 7.2825 1.0825 24 P 0 ;1
L 7.2825 1.1325 7.2825 1.1325 24 P 0 ;1
L 7.2825 1.1825 7.2825 1.1825 24 P 0 ;1
L 7.2825 1.2325 7.2825 1.2325 24 P 0 ;1
L 7.2825 1.2825 7.2825 1.2825 24 P 0 ;1
L 7.2825 1.3325 7.2825 1.3325 24 P 0 ;1
L 7.2825 1.3825 7.2825 1.3825 24 P 0 ;1
L 7.2825 1.4325 7.2825 1.4325 24 P 0 ;1
L 7.2825 1.4825 7.2825 1.4825 24 P 0 ;1
L 7.2825 1.5325 7.2825 1.5325 24 P 0 ;1
L 7.2825 1.5825 7.2825 1.5825 24 P 0 ;1
L 7.2825 1.6325 7.2825 1.6325 24 P 0 ;1
L 7.2825 1.6825 7.2825 1.6825 24 P 0 ;1
L 7.2825 1.7325 7.2825 1.7325 24 P 0 ;1
L 7.2825 1.7825 7.2825 1.7825 24 P 0 ;1
L 7.2825 1.8325 7.2825 1.8325 24 P 0 ;1
L 7.2825 1.8825 7.2825 1.8825 24 P 0 ;1
L 7.2825 1.9325 7.2825 1.9325 24 P 0 ;1
L 7.2825 1.9825 7.2825 1.9825 24 P 0 ;1
L 7.2825 2.0325 7.2825 2.0325 24 P 0 ;1
L 7.2825 2.0825 7.2825 2.0825 24 P 0 ;1
L 7.2825 2.1325 7.2825 2.1325 24 P 0 ;1
L 7.2825 2.1825 7.2825 2.1825 24 P 0 ;1
L 7.2825 2.2325 7.2825 2.2325 24 P 0 ;1
L 7.2825 2.2825 7.2825 2.2825 24 P 0 ;1
L 7.2825 2.3325 7.2825 2.3325 24 P 0 ;1
L 7.2825 2.3825 7.2825 2.3825 24 P 0 ;1
L 7.2825 2.4325 7.2825 2.4325 24 P 0 ;1
L 7.2825 2.4825 7.2825 2.4825 24 P 0 ;1
L 7.2825 2.5325 7.2825 2.5325 24 P 0 ;1
L 7.2825 2.5825 7.2825 2.5825 24 P 0 ;1
L 7.2825 2.6325 7.2825 2.6325 24 P 0 ;1
L 7.2825 2.6825 7.2825 2.6825 24 P 0 ;1
L 7.2825 2.7325 7.2825 2.7325 24 P 0 ;1
L 7.2825 2.7825 7.2825 2.7825 24 P 0 ;1
L 7.2825 2.8325 7.2825 2.8325 24 P 0 ;1
L 7.2825 2.8825 7.2825 2.8825 24 P 0 ;1
L 7.2825 2.9325 7.2825 2.9325 24 P 0 ;1
L 7.2825 2.9825 7.2825 2.9825 24 P 0 ;1
L 7.2825 3.0325 7.2825 3.0325 24 P 0 ;1
L 7.2825 3.0825 7.2825 3.0825 24 P 0 ;1
L 7.2825 3.1325 7.2825 3.1325 24 P 0 ;1
L 7.2825 3.1825 7.2825 3.1825 24 P 0 ;1
L 7.2825 3.2325 7.2825 3.2325 24 P 0 ;1
L 7.2825 3.2825 7.2825 3.2825 24 P 0 ;1
L 7.2825 3.3325 7.2825 3.3325 24 P 0 ;1
L 7.2825 5.2825 7.2825 5.2825 24 P 0 ;1
L 7.2825 5.3325 7.2825 5.3325 24 P 0 ;1
L 7.2825 5.3825 7.2825 5.3825 24 P 0 ;1
L 7.2825 5.4325 7.2825 5.4325 24 P 0 ;1
L 7.2825 5.4825 7.2825 5.4825 24 P 0 ;1
L 7.2825 5.5325 7.2825 5.5325 24 P 0 ;1
L 7.3325 0.6825 7.3325 0.6825 24 P 0 ;1
L 7.3325 0.7325 7.3325 0.7325 24 P 0 ;1
L 7.3325 0.7825 7.3325 0.7825 24 P 0 ;1
L 7.3325 0.8325 7.3325 0.8325 24 P 0 ;1
L 7.3325 0.8825 7.3325 0.8825 24 P 0 ;1
L 7.3325 0.9325 7.3325 0.9325 24 P 0 ;1
L 7.3325 0.9825 7.3325 0.9825 24 P 0 ;1
L 7.3325 1.0325 7.3325 1.0325 24 P 0 ;1
L 7.3325 1.0825 7.3325 1.0825 24 P 0 ;1
L 7.3325 1.1325 7.3325 1.1325 24 P 0 ;1
L 7.3325 1.1825 7.3325 1.1825 24 P 0 ;1
L 7.3325 1.2325 7.3325 1.2325 24 P 0 ;1
L 7.3325 1.2825 7.3325 1.2825 24 P 0 ;1
L 7.3325 1.3325 7.3325 1.3325 24 P 0 ;1
L 7.3325 1.3825 7.3325 1.3825 24 P 0 ;1
L 7.3325 1.4325 7.3325 1.4325 24 P 0 ;1
L 7.3325 1.4825 7.3325 1.4825 24 P 0 ;1
L 7.3325 1.5325 7.3325 1.5325 24 P 0 ;1
L 7.3325 1.5825 7.3325 1.5825 24 P 0 ;1
L 7.3325 1.6325 7.3325 1.6325 24 P 0 ;1
L 7.3325 1.6825 7.3325 1.6825 24 P 0 ;1
L 7.3325 1.7325 7.3325 1.7325 24 P 0 ;1
L 7.3325 1.7825 7.3325 1.7825 24 P 0 ;1
L 7.3325 1.8325 7.3325 1.8325 24 P 0 ;1
L 7.3325 1.8825 7.3325 1.8825 24 P 0 ;1
L 7.3325 1.9325 7.3325 1.9325 24 P 0 ;1
L 7.3325 1.9825 7.3325 1.9825 24 P 0 ;1
L 7.3325 2.0325 7.3325 2.0325 24 P 0 ;1
L 7.3325 2.0825 7.3325 2.0825 24 P 0 ;1
L 7.3325 2.1325 7.3325 2.1325 24 P 0 ;1
L 7.3325 2.1825 7.3325 2.1825 24 P 0 ;1
L 7.3325 2.2325 7.3325 2.2325 24 P 0 ;1
L 7.3325 2.2825 7.3325 2.2825 24 P 0 ;1
L 7.3325 2.3325 7.3325 2.3325 24 P 0 ;1
L 7.3325 2.3825 7.3325 2.3825 24 P 0 ;1
L 7.3325 2.4325 7.3325 2.4325 24 P 0 ;1
L 7.3325 2.4825 7.3325 2.4825 24 P 0 ;1
L 7.3325 2.5325 7.3325 2.5325 24 P 0 ;1
L 7.3325 2.5825 7.3325 2.5825 24 P 0 ;1
L 7.3325 2.6325 7.3325 2.6325 24 P 0 ;1
L 7.3325 2.6825 7.3325 2.6825 24 P 0 ;1
L 7.3325 2.7325 7.3325 2.7325 24 P 0 ;1
L 7.3325 2.7825 7.3325 2.7825 24 P 0 ;1
L 7.3325 2.8325 7.3325 2.8325 24 P 0 ;1
L 7.3325 2.8825 7.3325 2.8825 24 P 0 ;1
L 7.3325 2.9325 7.3325 2.9325 24 P 0 ;1
L 7.3325 2.9825 7.3325 2.9825 24 P 0 ;1
L 7.3325 3.0325 7.3325 3.0325 24 P 0 ;1
L 7.3325 3.0825 7.3325 3.0825 24 P 0 ;1
L 7.3325 3.1325 7.3325 3.1325 24 P 0 ;1
L 7.3325 3.1825 7.3325 3.1825 24 P 0 ;1
L 7.3325 3.2325 7.3325 3.2325 24 P 0 ;1
L 7.3325 3.2825 7.3325 3.2825 24 P 0 ;1
L 7.3325 5.2825 7.3325 5.2825 24 P 0 ;1
L 7.3325 5.3325 7.3325 5.3325 24 P 0 ;1
L 7.3325 5.3825 7.3325 5.3825 24 P 0 ;1
L 7.3325 5.4325 7.3325 5.4325 24 P 0 ;1
L 7.3325 5.4825 7.3325 5.4825 24 P 0 ;1
L 7.3325 5.5325 7.3325 5.5325 24 P 0 ;1
L 7.3825 0.4325 7.3825 0.4325 24 P 0 ;1
L 7.3825 0.6825 7.3825 0.6825 24 P 0 ;1
L 7.3825 0.7325 7.3825 0.7325 24 P 0 ;1
L 7.3825 0.7825 7.3825 0.7825 24 P 0 ;1
L 7.3825 0.8325 7.3825 0.8325 24 P 0 ;1
L 7.3825 0.8825 7.3825 0.8825 24 P 0 ;1
L 7.3825 0.9325 7.3825 0.9325 24 P 0 ;1
L 7.3825 0.9825 7.3825 0.9825 24 P 0 ;1
L 7.3825 1.0325 7.3825 1.0325 24 P 0 ;1
L 7.3825 1.0825 7.3825 1.0825 24 P 0 ;1
L 7.3825 1.1325 7.3825 1.1325 24 P 0 ;1
L 7.3825 1.1825 7.3825 1.1825 24 P 0 ;1
L 7.3825 1.2325 7.3825 1.2325 24 P 0 ;1
L 7.3825 1.2825 7.3825 1.2825 24 P 0 ;1
L 7.3825 1.3325 7.3825 1.3325 24 P 0 ;1
L 7.3825 1.3825 7.3825 1.3825 24 P 0 ;1
L 7.3825 1.4325 7.3825 1.4325 24 P 0 ;1
L 7.3825 1.4825 7.3825 1.4825 24 P 0 ;1
L 7.3825 1.5325 7.3825 1.5325 24 P 0 ;1
L 7.3825 1.5825 7.3825 1.5825 24 P 0 ;1
L 7.3825 1.6325 7.3825 1.6325 24 P 0 ;1
L 7.3825 1.7825 7.3825 1.7825 24 P 0 ;1
L 7.3825 1.8325 7.3825 1.8325 24 P 0 ;1
L 7.3825 1.8825 7.3825 1.8825 24 P 0 ;1
L 7.3825 1.9325 7.3825 1.9325 24 P 0 ;1
L 7.3825 1.9825 7.3825 1.9825 24 P 0 ;1
L 7.3825 2.0325 7.3825 2.0325 24 P 0 ;1
L 7.3825 2.0825 7.3825 2.0825 24 P 0 ;1
L 7.3825 2.1325 7.3825 2.1325 24 P 0 ;1
L 7.3825 2.1825 7.3825 2.1825 24 P 0 ;1
L 7.3825 2.2325 7.3825 2.2325 24 P 0 ;1
L 7.3825 2.2825 7.3825 2.2825 24 P 0 ;1
L 7.3825 2.3325 7.3825 2.3325 24 P 0 ;1
L 7.3825 2.3825 7.3825 2.3825 24 P 0 ;1
L 7.3825 2.4325 7.3825 2.4325 24 P 0 ;1
L 7.3825 2.4825 7.3825 2.4825 24 P 0 ;1
L 7.3825 2.5325 7.3825 2.5325 24 P 0 ;1
L 7.3825 2.5825 7.3825 2.5825 24 P 0 ;1
L 7.3825 2.6325 7.3825 2.6325 24 P 0 ;1
L 7.3825 2.6825 7.3825 2.6825 24 P 0 ;1
L 7.3825 2.7325 7.3825 2.7325 24 P 0 ;1
L 7.3825 2.7825 7.3825 2.7825 24 P 0 ;1
L 7.3825 2.8325 7.3825 2.8325 24 P 0 ;1
L 7.3825 2.8825 7.3825 2.8825 24 P 0 ;1
L 7.3825 2.9325 7.3825 2.9325 24 P 0 ;1
L 7.3825 2.9825 7.3825 2.9825 24 P 0 ;1
L 7.3825 3.0325 7.3825 3.0325 24 P 0 ;1
L 7.3825 3.0825 7.3825 3.0825 24 P 0 ;1
L 7.3825 3.1325 7.3825 3.1325 24 P 0 ;1
L 7.3825 3.1825 7.3825 3.1825 24 P 0 ;1
L 7.3825 3.2325 7.3825 3.2325 24 P 0 ;1
L 7.3825 5.5325 7.3825 5.5325 24 P 0 ;1
L 7.3825 5.5825 7.3825 5.5825 24 P 0 ;1
L 7.4325 0.1325 7.4325 0.1325 24 P 0 ;1
L 7.4325 0.3325 7.4325 0.3325 24 P 0 ;1
L 7.4325 0.3825 7.4325 0.3825 24 P 0 ;1
L 7.4325 0.4325 7.4325 0.4325 24 P 0 ;1
L 7.4325 0.6825 7.4325 0.6825 24 P 0 ;1
L 7.4325 0.7325 7.4325 0.7325 24 P 0 ;1
L 7.4325 0.7825 7.4325 0.7825 24 P 0 ;1
L 7.4325 0.8325 7.4325 0.8325 24 P 0 ;1
L 7.4325 0.8825 7.4325 0.8825 24 P 0 ;1
L 7.4325 0.9325 7.4325 0.9325 24 P 0 ;1
L 7.4325 0.9825 7.4325 0.9825 24 P 0 ;1
L 7.4325 1.0325 7.4325 1.0325 24 P 0 ;1
L 7.4325 1.0825 7.4325 1.0825 24 P 0 ;1
L 7.4325 1.1325 7.4325 1.1325 24 P 0 ;1
L 7.4325 1.1825 7.4325 1.1825 24 P 0 ;1
L 7.4325 1.2325 7.4325 1.2325 24 P 0 ;1
L 7.4325 1.2825 7.4325 1.2825 24 P 0 ;1
L 7.4325 1.3325 7.4325 1.3325 24 P 0 ;1
L 7.4325 1.3825 7.4325 1.3825 24 P 0 ;1
L 7.4325 1.4325 7.4325 1.4325 24 P 0 ;1
L 7.4325 1.4825 7.4325 1.4825 24 P 0 ;1
L 7.4325 1.5325 7.4325 1.5325 24 P 0 ;1
L 7.4325 1.5825 7.4325 1.5825 24 P 0 ;1
L 7.4325 1.8325 7.4325 1.8325 24 P 0 ;1
L 7.4325 1.8825 7.4325 1.8825 24 P 0 ;1
L 7.4325 1.9325 7.4325 1.9325 24 P 0 ;1
L 7.4325 1.9825 7.4325 1.9825 24 P 0 ;1
L 7.4325 2.0325 7.4325 2.0325 24 P 0 ;1
L 7.4325 2.0825 7.4325 2.0825 24 P 0 ;1
L 7.4325 2.1325 7.4325 2.1325 24 P 0 ;1
L 7.4325 2.1825 7.4325 2.1825 24 P 0 ;1
L 7.4325 2.2325 7.4325 2.2325 24 P 0 ;1
L 7.4325 2.2825 7.4325 2.2825 24 P 0 ;1
L 7.4325 2.3325 7.4325 2.3325 24 P 0 ;1
L 7.4325 2.3825 7.4325 2.3825 24 P 0 ;1
L 7.4325 2.4325 7.4325 2.4325 24 P 0 ;1
L 7.4325 2.4825 7.4325 2.4825 24 P 0 ;1
L 7.4325 2.5325 7.4325 2.5325 24 P 0 ;1
L 7.4325 2.5825 7.4325 2.5825 24 P 0 ;1
L 7.4325 2.6325 7.4325 2.6325 24 P 0 ;1
L 7.4325 2.6825 7.4325 2.6825 24 P 0 ;1
L 7.4325 2.7325 7.4325 2.7325 24 P 0 ;1
L 7.4325 2.7825 7.4325 2.7825 24 P 0 ;1
L 7.4325 2.8325 7.4325 2.8325 24 P 0 ;1
L 7.4325 2.8825 7.4325 2.8825 24 P 0 ;1
L 7.4325 2.9325 7.4325 2.9325 24 P 0 ;1
L 7.4325 2.9825 7.4325 2.9825 24 P 0 ;1
L 7.4325 3.0325 7.4325 3.0325 24 P 0 ;1
L 7.4325 3.0825 7.4325 3.0825 24 P 0 ;1
L 7.4325 3.1325 7.4325 3.1325 24 P 0 ;1
L 7.4325 3.1825 7.4325 3.1825 24 P 0 ;1
L 7.4325 3.2325 7.4325 3.2325 24 P 0 ;1
L 7.4325 5.5325 7.4325 5.5325 24 P 0 ;1
L 7.4325 5.5825 7.4325 5.5825 24 P 0 ;1
L 7.4325 5.6325 7.4325 5.6325 24 P 0 ;1
L 7.4325 5.6825 7.4325 5.6825 24 P 0 ;1
L 7.4325 5.7325 7.4325 5.7325 24 P 0 ;1
L 7.4325 5.8825 7.4325 5.8825 24 P 0 ;1
L 7.4825 0.1325 7.4825 0.1325 24 P 0 ;1
L 7.4825 0.1825 7.4825 0.1825 24 P 0 ;1
L 7.4825 0.2325 7.4825 0.2325 24 P 0 ;1
L 7.4825 0.2825 7.4825 0.2825 24 P 0 ;1
L 7.4825 0.3325 7.4825 0.3325 24 P 0 ;1
L 7.4825 0.3825 7.4825 0.3825 24 P 0 ;1
L 7.4825 0.4325 7.4825 0.4325 24 P 0 ;1
L 7.4825 0.6825 7.4825 0.6825 24 P 0 ;1
L 7.4825 0.7325 7.4825 0.7325 24 P 0 ;1
L 7.4825 0.7825 7.4825 0.7825 24 P 0 ;1
L 7.4825 0.8325 7.4825 0.8325 24 P 0 ;1
L 7.4825 0.8825 7.4825 0.8825 24 P 0 ;1
L 7.4825 0.9325 7.4825 0.9325 24 P 0 ;1
L 7.4825 0.9825 7.4825 0.9825 24 P 0 ;1
L 7.4825 1.0325 7.4825 1.0325 24 P 0 ;1
L 7.4825 1.0825 7.4825 1.0825 24 P 0 ;1
L 7.4825 1.1325 7.4825 1.1325 24 P 0 ;1
L 7.4825 1.1825 7.4825 1.1825 24 P 0 ;1
L 7.4825 1.2325 7.4825 1.2325 24 P 0 ;1
L 7.4825 1.2825 7.4825 1.2825 24 P 0 ;1
L 7.4825 1.3325 7.4825 1.3325 24 P 0 ;1
L 7.4825 1.3825 7.4825 1.3825 24 P 0 ;1
L 7.4825 1.4325 7.4825 1.4325 24 P 0 ;1
L 7.4825 1.4825 7.4825 1.4825 24 P 0 ;1
L 7.4825 1.5325 7.4825 1.5325 24 P 0 ;1
L 7.4825 1.5825 7.4825 1.5825 24 P 0 ;1
L 7.4825 1.8325 7.4825 1.8325 24 P 0 ;1
L 7.4825 1.8825 7.4825 1.8825 24 P 0 ;1
L 7.4825 1.9325 7.4825 1.9325 24 P 0 ;1
L 7.4825 1.9825 7.4825 1.9825 24 P 0 ;1
L 7.4825 2.0325 7.4825 2.0325 24 P 0 ;1
L 7.4825 2.0825 7.4825 2.0825 24 P 0 ;1
L 7.4825 2.1325 7.4825 2.1325 24 P 0 ;1
L 7.4825 2.1825 7.4825 2.1825 24 P 0 ;1
L 7.4825 2.2325 7.4825 2.2325 24 P 0 ;1
L 7.4825 2.2825 7.4825 2.2825 24 P 0 ;1
L 7.4825 2.3325 7.4825 2.3325 24 P 0 ;1
L 7.4825 2.3825 7.4825 2.3825 24 P 0 ;1
L 7.4825 2.4325 7.4825 2.4325 24 P 0 ;1
L 7.4825 2.4825 7.4825 2.4825 24 P 0 ;1
L 7.4825 2.5325 7.4825 2.5325 24 P 0 ;1
L 7.4825 2.5825 7.4825 2.5825 24 P 0 ;1
L 7.4825 2.6325 7.4825 2.6325 24 P 0 ;1
L 7.4825 2.6825 7.4825 2.6825 24 P 0 ;1
L 7.4825 2.7325 7.4825 2.7325 24 P 0 ;1
L 7.4825 2.7825 7.4825 2.7825 24 P 0 ;1
L 7.4825 2.8325 7.4825 2.8325 24 P 0 ;1
L 7.4825 2.8825 7.4825 2.8825 24 P 0 ;1
L 7.4825 2.9325 7.4825 2.9325 24 P 0 ;1
L 7.4825 2.9825 7.4825 2.9825 24 P 0 ;1
L 7.4825 3.0325 7.4825 3.0325 24 P 0 ;1
L 7.4825 3.0825 7.4825 3.0825 24 P 0 ;1
L 7.4825 3.1325 7.4825 3.1325 24 P 0 ;1
L 7.4825 3.1825 7.4825 3.1825 24 P 0 ;1
L 7.4825 3.2325 7.4825 3.2325 24 P 0 ;1
L 7.4825 3.5825 7.4825 3.5825 24 P 0 ;1
L 7.4825 3.6325 7.4825 3.6325 24 P 0 ;1
L 7.4825 3.6825 7.4825 3.6825 24 P 0 ;1
L 7.4825 3.7325 7.4825 3.7325 24 P 0 ;1
L 7.4825 3.7825 7.4825 3.7825 24 P 0 ;1
L 7.4825 3.8325 7.4825 3.8325 24 P 0 ;1
L 7.4825 3.8825 7.4825 3.8825 24 P 0 ;1
L 7.4825 3.9325 7.4825 3.9325 24 P 0 ;1
L 7.4825 3.9825 7.4825 3.9825 24 P 0 ;1
L 7.4825 4.0325 7.4825 4.0325 24 P 0 ;1
L 7.4825 4.0825 7.4825 4.0825 24 P 0 ;1
L 7.4825 4.1325 7.4825 4.1325 24 P 0 ;1
L 7.4825 4.1825 7.4825 4.1825 24 P 0 ;1
L 7.4825 4.2325 7.4825 4.2325 24 P 0 ;1
L 7.4825 4.2825 7.4825 4.2825 24 P 0 ;1
L 7.4825 5.5325 7.4825 5.5325 24 P 0 ;1
L 7.4825 5.5825 7.4825 5.5825 24 P 0 ;1
L 7.4825 5.6325 7.4825 5.6325 24 P 0 ;1
L 7.4825 5.6825 7.4825 5.6825 24 P 0 ;1
L 7.4825 5.7325 7.4825 5.7325 24 P 0 ;1
L 7.4825 5.7825 7.4825 5.7825 24 P 0 ;1
L 7.4825 5.8325 7.4825 5.8325 24 P 0 ;1
L 7.4825 5.8825 7.4825 5.8825 24 P 0 ;1
L 7.5325 0.1325 7.5325 0.1325 24 P 0 ;1
L 7.5325 0.1825 7.5325 0.1825 24 P 0 ;1
L 7.5325 0.2325 7.5325 0.2325 24 P 0 ;1
L 7.5325 0.2825 7.5325 0.2825 24 P 0 ;1
L 7.5325 0.3325 7.5325 0.3325 24 P 0 ;1
L 7.5325 0.3825 7.5325 0.3825 24 P 0 ;1
L 7.5325 0.4325 7.5325 0.4325 24 P 0 ;1
L 7.5325 0.6825 7.5325 0.6825 24 P 0 ;1
L 7.5325 0.7325 7.5325 0.7325 24 P 0 ;1
L 7.5325 0.7825 7.5325 0.7825 24 P 0 ;1
L 7.5325 0.8325 7.5325 0.8325 24 P 0 ;1
L 7.5325 0.8825 7.5325 0.8825 24 P 0 ;1
L 7.5325 0.9325 7.5325 0.9325 24 P 0 ;1
L 7.5325 0.9825 7.5325 0.9825 24 P 0 ;1
L 7.5325 1.0325 7.5325 1.0325 24 P 0 ;1
L 7.5325 1.0825 7.5325 1.0825 24 P 0 ;1
L 7.5325 1.1325 7.5325 1.1325 24 P 0 ;1
L 7.5325 1.1825 7.5325 1.1825 24 P 0 ;1
L 7.5325 1.2325 7.5325 1.2325 24 P 0 ;1
L 7.5325 1.2825 7.5325 1.2825 24 P 0 ;1
L 7.5325 1.3325 7.5325 1.3325 24 P 0 ;1
L 7.5325 1.3825 7.5325 1.3825 24 P 0 ;1
L 7.5325 1.4325 7.5325 1.4325 24 P 0 ;1
L 7.5325 1.4825 7.5325 1.4825 24 P 0 ;1
L 7.5325 1.5325 7.5325 1.5325 24 P 0 ;1
L 7.5325 1.5825 7.5325 1.5825 24 P 0 ;1
L 7.5325 1.6325 7.5325 1.6325 24 P 0 ;1
L 7.5325 1.7825 7.5325 1.7825 24 P 0 ;1
L 7.5325 1.8325 7.5325 1.8325 24 P 0 ;1
L 7.5325 1.8825 7.5325 1.8825 24 P 0 ;1
L 7.5325 1.9325 7.5325 1.9325 24 P 0 ;1
L 7.5325 1.9825 7.5325 1.9825 24 P 0 ;1
L 7.5325 2.0325 7.5325 2.0325 24 P 0 ;1
L 7.5325 2.0825 7.5325 2.0825 24 P 0 ;1
L 7.5325 2.1325 7.5325 2.1325 24 P 0 ;1
L 7.5325 2.1825 7.5325 2.1825 24 P 0 ;1
L 7.5325 2.2325 7.5325 2.2325 24 P 0 ;1
L 7.5325 2.2825 7.5325 2.2825 24 P 0 ;1
L 7.5325 2.3325 7.5325 2.3325 24 P 0 ;1
L 7.5325 2.3825 7.5325 2.3825 24 P 0 ;1
L 7.5325 2.4325 7.5325 2.4325 24 P 0 ;1
L 7.5325 2.4825 7.5325 2.4825 24 P 0 ;1
L 7.5325 2.5325 7.5325 2.5325 24 P 0 ;1
L 7.5325 2.5825 7.5325 2.5825 24 P 0 ;1
L 7.5325 2.6325 7.5325 2.6325 24 P 0 ;1
L 7.5325 2.6825 7.5325 2.6825 24 P 0 ;1
L 7.5325 2.7325 7.5325 2.7325 24 P 0 ;1
L 7.5325 2.7825 7.5325 2.7825 24 P 0 ;1
L 7.5325 2.8325 7.5325 2.8325 24 P 0 ;1
L 7.5325 2.8825 7.5325 2.8825 24 P 0 ;1
L 7.5325 2.9325 7.5325 2.9325 24 P 0 ;1
L 7.5325 2.9825 7.5325 2.9825 24 P 0 ;1
L 7.5325 3.0325 7.5325 3.0325 24 P 0 ;1
L 7.5325 3.0825 7.5325 3.0825 24 P 0 ;1
L 7.5325 3.1325 7.5325 3.1325 24 P 0 ;1
L 7.5325 3.1825 7.5325 3.1825 24 P 0 ;1
L 7.5325 3.2325 7.5325 3.2325 24 P 0 ;1
L 7.5325 3.2825 7.5325 3.2825 24 P 0 ;1
L 7.5325 3.6325 7.5325 3.6325 24 P 0 ;1
L 7.5325 3.6825 7.5325 3.6825 24 P 0 ;1
L 7.5325 3.7325 7.5325 3.7325 24 P 0 ;1
L 7.5325 3.7825 7.5325 3.7825 24 P 0 ;1
L 7.5325 3.8325 7.5325 3.8325 24 P 0 ;1
L 7.5325 3.8825 7.5325 3.8825 24 P 0 ;1
L 7.5325 3.9325 7.5325 3.9325 24 P 0 ;1
L 7.5325 3.9825 7.5325 3.9825 24 P 0 ;1
L 7.5325 4.0325 7.5325 4.0325 24 P 0 ;1
L 7.5325 4.0825 7.5325 4.0825 24 P 0 ;1
L 7.5325 4.1325 7.5325 4.1325 24 P 0 ;1
L 7.5325 4.1825 7.5325 4.1825 24 P 0 ;1
L 7.5325 4.2325 7.5325 4.2325 24 P 0 ;1
L 7.5325 5.2825 7.5325 5.2825 24 P 0 ;1
L 7.5325 5.5325 7.5325 5.5325 24 P 0 ;1
L 7.5325 5.5825 7.5325 5.5825 24 P 0 ;1
L 7.5325 5.6325 7.5325 5.6325 24 P 0 ;1
L 7.5325 5.6825 7.5325 5.6825 24 P 0 ;1
L 7.5325 5.7325 7.5325 5.7325 24 P 0 ;1
L 7.5325 5.7825 7.5325 5.7825 24 P 0 ;1
L 7.5325 5.8325 7.5325 5.8325 24 P 0 ;1
L 7.5325 5.8825 7.5325 5.8825 24 P 0 ;1
L 7.5825 0.1325 7.5825 0.1325 24 P 0 ;1
L 7.5825 0.1825 7.5825 0.1825 24 P 0 ;1
L 7.5825 0.2325 7.5825 0.2325 24 P 0 ;1
L 7.5825 0.2825 7.5825 0.2825 24 P 0 ;1
L 7.5825 0.3325 7.5825 0.3325 24 P 0 ;1
L 7.5825 0.3825 7.5825 0.3825 24 P 0 ;1
L 7.5825 0.4325 7.5825 0.4325 24 P 0 ;1
L 7.5825 0.6825 7.5825 0.6825 24 P 0 ;1
L 7.5825 0.7325 7.5825 0.7325 24 P 0 ;1
L 7.5825 0.7825 7.5825 0.7825 24 P 0 ;1
L 7.5825 0.8325 7.5825 0.8325 24 P 0 ;1
L 7.5825 0.8825 7.5825 0.8825 24 P 0 ;1
L 7.5825 0.9325 7.5825 0.9325 24 P 0 ;1
L 7.5825 0.9825 7.5825 0.9825 24 P 0 ;1
L 7.5825 1.0325 7.5825 1.0325 24 P 0 ;1
L 7.5825 1.0825 7.5825 1.0825 24 P 0 ;1
L 7.5825 1.1325 7.5825 1.1325 24 P 0 ;1
L 7.5825 1.1825 7.5825 1.1825 24 P 0 ;1
L 7.5825 1.2325 7.5825 1.2325 24 P 0 ;1
L 7.5825 1.2825 7.5825 1.2825 24 P 0 ;1
L 7.5825 1.3325 7.5825 1.3325 24 P 0 ;1
L 7.5825 1.3825 7.5825 1.3825 24 P 0 ;1
L 7.5825 1.4325 7.5825 1.4325 24 P 0 ;1
L 7.5825 1.4825 7.5825 1.4825 24 P 0 ;1
L 7.5825 1.5325 7.5825 1.5325 24 P 0 ;1
L 7.5825 1.5825 7.5825 1.5825 24 P 0 ;1
L 7.5825 1.6325 7.5825 1.6325 24 P 0 ;1
L 7.5825 1.6825 7.5825 1.6825 24 P 0 ;1
L 7.5825 1.7325 7.5825 1.7325 24 P 0 ;1
L 7.5825 1.7825 7.5825 1.7825 24 P 0 ;1
L 7.5825 1.8325 7.5825 1.8325 24 P 0 ;1
L 7.5825 1.8825 7.5825 1.8825 24 P 0 ;1
L 7.5825 1.9325 7.5825 1.9325 24 P 0 ;1
L 7.5825 1.9825 7.5825 1.9825 24 P 0 ;1
L 7.5825 2.0325 7.5825 2.0325 24 P 0 ;1
L 7.5825 2.0825 7.5825 2.0825 24 P 0 ;1
L 7.5825 2.1325 7.5825 2.1325 24 P 0 ;1
L 7.5825 2.1825 7.5825 2.1825 24 P 0 ;1
L 7.5825 2.2325 7.5825 2.2325 24 P 0 ;1
L 7.5825 2.2825 7.5825 2.2825 24 P 0 ;1
L 7.5825 2.3325 7.5825 2.3325 24 P 0 ;1
L 7.5825 2.3825 7.5825 2.3825 24 P 0 ;1
L 7.5825 2.4325 7.5825 2.4325 24 P 0 ;1
L 7.5825 2.4825 7.5825 2.4825 24 P 0 ;1
L 7.5825 2.5325 7.5825 2.5325 24 P 0 ;1
L 7.5825 2.5825 7.5825 2.5825 24 P 0 ;1
L 7.5825 2.6325 7.5825 2.6325 24 P 0 ;1
L 7.5825 2.6825 7.5825 2.6825 24 P 0 ;1
L 7.5825 2.7325 7.5825 2.7325 24 P 0 ;1
L 7.5825 2.7825 7.5825 2.7825 24 P 0 ;1
L 7.5825 2.8325 7.5825 2.8325 24 P 0 ;1
L 7.5825 2.8825 7.5825 2.8825 24 P 0 ;1
L 7.5825 2.9325 7.5825 2.9325 24 P 0 ;1
L 7.5825 2.9825 7.5825 2.9825 24 P 0 ;1
L 7.5825 3.0325 7.5825 3.0325 24 P 0 ;1
L 7.5825 3.0825 7.5825 3.0825 24 P 0 ;1
L 7.5825 3.1325 7.5825 3.1325 24 P 0 ;1
L 7.5825 3.1825 7.5825 3.1825 24 P 0 ;1
L 7.5825 3.2325 7.5825 3.2325 24 P 0 ;1
L 7.5825 3.2825 7.5825 3.2825 24 P 0 ;1
L 7.5825 3.3325 7.5825 3.3325 24 P 0 ;1
L 7.5825 3.6825 7.5825 3.6825 24 P 0 ;1
L 7.5825 3.7325 7.5825 3.7325 24 P 0 ;1
L 7.5825 3.7825 7.5825 3.7825 24 P 0 ;1
L 7.5825 3.8325 7.5825 3.8325 24 P 0 ;1
L 7.5825 3.8825 7.5825 3.8825 24 P 0 ;1
L 7.5825 3.9325 7.5825 3.9325 24 P 0 ;1
L 7.5825 3.9825 7.5825 3.9825 24 P 0 ;1
L 7.5825 4.0325 7.5825 4.0325 24 P 0 ;1
L 7.5825 4.0825 7.5825 4.0825 24 P 0 ;1
L 7.5825 4.1325 7.5825 4.1325 24 P 0 ;1
L 7.5825 4.1825 7.5825 4.1825 24 P 0 ;1
L 7.5825 4.2325 7.5825 4.2325 24 P 0 ;1
L 7.5825 5.2825 7.5825 5.2825 24 P 0 ;1
L 7.5825 5.5325 7.5825 5.5325 24 P 0 ;1
L 7.5825 5.5825 7.5825 5.5825 24 P 0 ;1
L 7.5825 5.6325 7.5825 5.6325 24 P 0 ;1
L 7.5825 5.6825 7.5825 5.6825 24 P 0 ;1
L 7.5825 5.7325 7.5825 5.7325 24 P 0 ;1
L 7.5825 5.7825 7.5825 5.7825 24 P 0 ;1
L 7.5825 5.8325 7.5825 5.8325 24 P 0 ;1
L 7.5825 5.8825 7.5825 5.8825 24 P 0 ;1
L 7.6325 0.1325 7.6325 0.1325 24 P 0 ;1
L 7.6325 0.1825 7.6325 0.1825 24 P 0 ;1
L 7.6325 0.2325 7.6325 0.2325 24 P 0 ;1
L 7.6325 0.2825 7.6325 0.2825 24 P 0 ;1
L 7.6325 0.3325 7.6325 0.3325 24 P 0 ;1
L 7.6325 0.3825 7.6325 0.3825 24 P 0 ;1
L 7.6325 0.4325 7.6325 0.4325 24 P 0 ;1
L 7.6325 0.6825 7.6325 0.6825 24 P 0 ;1
L 7.6325 0.7325 7.6325 0.7325 24 P 0 ;1
L 7.6325 0.7825 7.6325 0.7825 24 P 0 ;1
L 7.6325 0.8325 7.6325 0.8325 24 P 0 ;1
L 7.6325 0.8825 7.6325 0.8825 24 P 0 ;1
L 7.6325 0.9325 7.6325 0.9325 24 P 0 ;1
L 7.6325 0.9825 7.6325 0.9825 24 P 0 ;1
L 7.6325 1.0325 7.6325 1.0325 24 P 0 ;1
L 7.6325 1.0825 7.6325 1.0825 24 P 0 ;1
L 7.6325 1.1325 7.6325 1.1325 24 P 0 ;1
L 7.6325 1.1825 7.6325 1.1825 24 P 0 ;1
L 7.6325 1.2325 7.6325 1.2325 24 P 0 ;1
L 7.6325 1.2825 7.6325 1.2825 24 P 0 ;1
L 7.6325 1.3325 7.6325 1.3325 24 P 0 ;1
L 7.6325 1.3825 7.6325 1.3825 24 P 0 ;1
L 7.6325 1.4325 7.6325 1.4325 24 P 0 ;1
L 7.6325 1.4825 7.6325 1.4825 24 P 0 ;1
L 7.6325 1.5325 7.6325 1.5325 24 P 0 ;1
L 7.6325 1.5825 7.6325 1.5825 24 P 0 ;1
L 7.6325 1.6325 7.6325 1.6325 24 P 0 ;1
L 7.6325 1.6825 7.6325 1.6825 24 P 0 ;1
L 7.6325 1.7325 7.6325 1.7325 24 P 0 ;1
L 7.6325 1.7825 7.6325 1.7825 24 P 0 ;1
L 7.6325 1.8325 7.6325 1.8325 24 P 0 ;1
L 7.6325 1.8825 7.6325 1.8825 24 P 0 ;1
L 7.6325 1.9325 7.6325 1.9325 24 P 0 ;1
L 7.6325 1.9825 7.6325 1.9825 24 P 0 ;1
L 7.6325 2.0325 7.6325 2.0325 24 P 0 ;1
L 7.6325 2.0825 7.6325 2.0825 24 P 0 ;1
L 7.6325 2.1325 7.6325 2.1325 24 P 0 ;1
L 7.6325 2.1825 7.6325 2.1825 24 P 0 ;1
L 7.6325 2.2325 7.6325 2.2325 24 P 0 ;1
L 7.6325 2.2825 7.6325 2.2825 24 P 0 ;1
L 7.6325 2.3325 7.6325 2.3325 24 P 0 ;1
L 7.6325 2.3825 7.6325 2.3825 24 P 0 ;1
L 7.6325 2.4325 7.6325 2.4325 24 P 0 ;1
L 7.6325 2.4825 7.6325 2.4825 24 P 0 ;1
L 7.6325 2.5325 7.6325 2.5325 24 P 0 ;1
L 7.6325 2.5825 7.6325 2.5825 24 P 0 ;1
L 7.6325 2.6325 7.6325 2.6325 24 P 0 ;1
L 7.6325 2.6825 7.6325 2.6825 24 P 0 ;1
L 7.6325 2.7325 7.6325 2.7325 24 P 0 ;1
L 7.6325 2.7825 7.6325 2.7825 24 P 0 ;1
L 7.6325 2.8325 7.6325 2.8325 24 P 0 ;1
L 7.6325 2.8825 7.6325 2.8825 24 P 0 ;1
L 7.6325 2.9325 7.6325 2.9325 24 P 0 ;1
L 7.6325 2.9825 7.6325 2.9825 24 P 0 ;1
L 7.6325 3.0325 7.6325 3.0325 24 P 0 ;1
L 7.6325 3.0825 7.6325 3.0825 24 P 0 ;1
L 7.6325 3.1325 7.6325 3.1325 24 P 0 ;1
L 7.6325 3.1825 7.6325 3.1825 24 P 0 ;1
L 7.6325 3.2325 7.6325 3.2325 24 P 0 ;1
L 7.6325 3.2825 7.6325 3.2825 24 P 0 ;1
L 7.6325 3.3325 7.6325 3.3325 24 P 0 ;1
L 7.6325 3.3825 7.6325 3.3825 24 P 0 ;1
L 7.6325 3.7325 7.6325 3.7325 24 P 0 ;1
L 7.6325 3.7825 7.6325 3.7825 24 P 0 ;1
L 7.6325 3.8325 7.6325 3.8325 24 P 0 ;1
L 7.6325 3.8825 7.6325 3.8825 24 P 0 ;1
L 7.6325 3.9325 7.6325 3.9325 24 P 0 ;1
L 7.6325 3.9825 7.6325 3.9825 24 P 0 ;1
L 7.6325 4.0325 7.6325 4.0325 24 P 0 ;1
L 7.6325 4.0825 7.6325 4.0825 24 P 0 ;1
L 7.6325 4.1325 7.6325 4.1325 24 P 0 ;1
L 7.6325 4.1825 7.6325 4.1825 24 P 0 ;1
L 7.6325 4.2325 7.6325 4.2325 24 P 0 ;1
L 7.6325 5.2825 7.6325 5.2825 24 P 0 ;1
L 7.6325 5.5325 7.6325 5.5325 24 P 0 ;1
L 7.6325 5.5825 7.6325 5.5825 24 P 0 ;1
L 7.6325 5.6325 7.6325 5.6325 24 P 0 ;1
L 7.6325 5.6825 7.6325 5.6825 24 P 0 ;1
L 7.6325 5.7325 7.6325 5.7325 24 P 0 ;1
L 7.6325 5.7825 7.6325 5.7825 24 P 0 ;1
L 7.6325 5.8325 7.6325 5.8325 24 P 0 ;1
L 7.6325 5.8825 7.6325 5.8825 24 P 0 ;1
L 7.6825 0.1325 7.6825 0.1325 24 P 0 ;1
L 7.6825 0.1825 7.6825 0.1825 24 P 0 ;1
L 7.6825 0.2325 7.6825 0.2325 24 P 0 ;1
L 7.6825 0.2825 7.6825 0.2825 24 P 0 ;1
L 7.6825 0.3325 7.6825 0.3325 24 P 0 ;1
L 7.6825 0.3825 7.6825 0.3825 24 P 0 ;1
L 7.6825 0.4325 7.6825 0.4325 24 P 0 ;1
L 7.6825 0.6825 7.6825 0.6825 24 P 0 ;1
L 7.6825 0.7325 7.6825 0.7325 24 P 0 ;1
L 7.6825 0.7825 7.6825 0.7825 24 P 0 ;1
L 7.6825 0.8325 7.6825 0.8325 24 P 0 ;1
L 7.6825 0.8825 7.6825 0.8825 24 P 0 ;1
L 7.6825 0.9325 7.6825 0.9325 24 P 0 ;1
L 7.6825 0.9825 7.6825 0.9825 24 P 0 ;1
L 7.6825 1.0325 7.6825 1.0325 24 P 0 ;1
L 7.6825 1.0825 7.6825 1.0825 24 P 0 ;1
L 7.6825 1.1325 7.6825 1.1325 24 P 0 ;1
L 7.6825 1.1825 7.6825 1.1825 24 P 0 ;1
L 7.6825 1.2325 7.6825 1.2325 24 P 0 ;1
L 7.6825 1.2825 7.6825 1.2825 24 P 0 ;1
L 7.6825 1.3325 7.6825 1.3325 24 P 0 ;1
L 7.6825 1.3825 7.6825 1.3825 24 P 0 ;1
L 7.6825 1.4325 7.6825 1.4325 24 P 0 ;1
L 7.6825 1.4825 7.6825 1.4825 24 P 0 ;1
L 7.6825 1.5325 7.6825 1.5325 24 P 0 ;1
L 7.6825 1.5825 7.6825 1.5825 24 P 0 ;1
L 7.6825 1.6325 7.6825 1.6325 24 P 0 ;1
L 7.6825 1.6825 7.6825 1.6825 24 P 0 ;1
L 7.6825 1.7325 7.6825 1.7325 24 P 0 ;1
L 7.6825 1.7825 7.6825 1.7825 24 P 0 ;1
L 7.6825 1.8325 7.6825 1.8325 24 P 0 ;1
L 7.6825 1.8825 7.6825 1.8825 24 P 0 ;1
L 7.6825 1.9325 7.6825 1.9325 24 P 0 ;1
L 7.6825 1.9825 7.6825 1.9825 24 P 0 ;1
L 7.6825 2.0325 7.6825 2.0325 24 P 0 ;1
L 7.6825 2.0825 7.6825 2.0825 24 P 0 ;1
L 7.6825 2.1325 7.6825 2.1325 24 P 0 ;1
L 7.6825 2.1825 7.6825 2.1825 24 P 0 ;1
L 7.6825 2.2325 7.6825 2.2325 24 P 0 ;1
L 7.6825 2.2825 7.6825 2.2825 24 P 0 ;1
L 7.6825 2.3325 7.6825 2.3325 24 P 0 ;1
L 7.6825 2.3825 7.6825 2.3825 24 P 0 ;1
L 7.6825 2.4325 7.6825 2.4325 24 P 0 ;1
L 7.6825 2.5325 7.6825 2.5325 24 P 0 ;1
L 7.6825 2.5825 7.6825 2.5825 24 P 0 ;1
L 7.6825 2.6325 7.6825 2.6325 24 P 0 ;1
L 7.6825 2.6825 7.6825 2.6825 24 P 0 ;1
L 7.6825 2.7325 7.6825 2.7325 24 P 0 ;1
L 7.6825 2.7825 7.6825 2.7825 24 P 0 ;1
L 7.6825 2.8325 7.6825 2.8325 24 P 0 ;1
L 7.6825 2.8825 7.6825 2.8825 24 P 0 ;1
L 7.6825 2.9325 7.6825 2.9325 24 P 0 ;1
L 7.6825 2.9825 7.6825 2.9825 24 P 0 ;1
L 7.6825 3.0325 7.6825 3.0325 24 P 0 ;1
L 7.6825 3.0825 7.6825 3.0825 24 P 0 ;1
L 7.6825 3.1325 7.6825 3.1325 24 P 0 ;1
L 7.6825 3.1825 7.6825 3.1825 24 P 0 ;1
L 7.6825 3.2325 7.6825 3.2325 24 P 0 ;1
L 7.6825 3.2825 7.6825 3.2825 24 P 0 ;1
L 7.6825 3.3325 7.6825 3.3325 24 P 0 ;1
L 7.6825 3.3825 7.6825 3.3825 24 P 0 ;1
L 7.6825 3.4325 7.6825 3.4325 24 P 0 ;1
L 7.6825 3.7325 7.6825 3.7325 24 P 0 ;1
L 7.6825 3.7825 7.6825 3.7825 24 P 0 ;1
L 7.6825 3.8325 7.6825 3.8325 24 P 0 ;1
L 7.6825 3.8825 7.6825 3.8825 24 P 0 ;1
L 7.6825 3.9325 7.6825 3.9325 24 P 0 ;1
L 7.6825 3.9825 7.6825 3.9825 24 P 0 ;1
L 7.6825 4.0325 7.6825 4.0325 24 P 0 ;1
L 7.6825 4.0825 7.6825 4.0825 24 P 0 ;1
L 7.6825 4.1325 7.6825 4.1325 24 P 0 ;1
L 7.6825 4.1825 7.6825 4.1825 24 P 0 ;1
L 7.6825 4.2325 7.6825 4.2325 24 P 0 ;1
L 7.6825 5.2825 7.6825 5.2825 24 P 0 ;1
L 7.6825 5.5325 7.6825 5.5325 24 P 0 ;1
L 7.6825 5.5825 7.6825 5.5825 24 P 0 ;1
L 7.6825 5.6325 7.6825 5.6325 24 P 0 ;1
L 7.6825 5.6825 7.6825 5.6825 24 P 0 ;1
L 7.6825 5.7325 7.6825 5.7325 24 P 0 ;1
L 7.6825 5.7825 7.6825 5.7825 24 P 0 ;1
L 7.6825 5.8325 7.6825 5.8325 24 P 0 ;1
L 7.6825 5.8825 7.6825 5.8825 24 P 0 ;1
L 7.7325 0.1325 7.7325 0.1325 24 P 0 ;1
L 7.7325 0.1825 7.7325 0.1825 24 P 0 ;1
L 7.7325 0.2325 7.7325 0.2325 24 P 0 ;1
L 7.7325 0.2825 7.7325 0.2825 24 P 0 ;1
L 7.7325 0.3325 7.7325 0.3325 24 P 0 ;1
L 7.7325 0.3825 7.7325 0.3825 24 P 0 ;1
L 7.7325 0.4325 7.7325 0.4325 24 P 0 ;1
L 7.7325 0.6825 7.7325 0.6825 24 P 0 ;1
L 7.7325 0.7325 7.7325 0.7325 24 P 0 ;1
L 7.7325 0.7825 7.7325 0.7825 24 P 0 ;1
L 7.7325 0.8325 7.7325 0.8325 24 P 0 ;1
L 7.7325 0.8825 7.7325 0.8825 24 P 0 ;1
L 7.7325 0.9325 7.7325 0.9325 24 P 0 ;1
L 7.7325 0.9825 7.7325 0.9825 24 P 0 ;1
L 7.7325 1.0325 7.7325 1.0325 24 P 0 ;1
L 7.7325 1.0825 7.7325 1.0825 24 P 0 ;1
L 7.7325 1.1325 7.7325 1.1325 24 P 0 ;1
L 7.7325 1.1825 7.7325 1.1825 24 P 0 ;1
L 7.7325 1.2325 7.7325 1.2325 24 P 0 ;1
L 7.7325 1.2825 7.7325 1.2825 24 P 0 ;1
L 7.7325 1.3325 7.7325 1.3325 24 P 0 ;1
L 7.7325 1.3825 7.7325 1.3825 24 P 0 ;1
L 7.7325 1.4325 7.7325 1.4325 24 P 0 ;1
L 7.7325 1.4825 7.7325 1.4825 24 P 0 ;1
L 7.7325 1.5325 7.7325 1.5325 24 P 0 ;1
L 7.7325 1.5825 7.7325 1.5825 24 P 0 ;1
L 7.7325 1.6325 7.7325 1.6325 24 P 0 ;1
L 7.7325 1.6825 7.7325 1.6825 24 P 0 ;1
L 7.7325 1.7325 7.7325 1.7325 24 P 0 ;1
L 7.7325 1.7825 7.7325 1.7825 24 P 0 ;1
L 7.7325 1.8325 7.7325 1.8325 24 P 0 ;1
L 7.7325 1.8825 7.7325 1.8825 24 P 0 ;1
L 7.7325 1.9325 7.7325 1.9325 24 P 0 ;1
L 7.7325 1.9825 7.7325 1.9825 24 P 0 ;1
L 7.7325 2.0325 7.7325 2.0325 24 P 0 ;1
L 7.7325 2.0825 7.7325 2.0825 24 P 0 ;1
L 7.7325 2.1325 7.7325 2.1325 24 P 0 ;1
L 7.7325 2.1825 7.7325 2.1825 24 P 0 ;1
L 7.7325 2.2325 7.7325 2.2325 24 P 0 ;1
L 7.7325 2.2825 7.7325 2.2825 24 P 0 ;1
L 7.7325 2.3325 7.7325 2.3325 24 P 0 ;1
L 7.7325 2.3825 7.7325 2.3825 24 P 0 ;1
L 7.7325 2.5825 7.7325 2.5825 24 P 0 ;1
L 7.7325 2.6325 7.7325 2.6325 24 P 0 ;1
L 7.7325 2.6825 7.7325 2.6825 24 P 0 ;1
L 7.7325 2.7325 7.7325 2.7325 24 P 0 ;1
L 7.7325 2.7825 7.7325 2.7825 24 P 0 ;1
L 7.7325 2.8325 7.7325 2.8325 24 P 0 ;1
L 7.7325 2.8825 7.7325 2.8825 24 P 0 ;1
L 7.7325 2.9325 7.7325 2.9325 24 P 0 ;1
L 7.7325 2.9825 7.7325 2.9825 24 P 0 ;1
L 7.7325 3.0325 7.7325 3.0325 24 P 0 ;1
L 7.7325 3.0825 7.7325 3.0825 24 P 0 ;1
L 7.7325 3.1325 7.7325 3.1325 24 P 0 ;1
L 7.7325 3.1825 7.7325 3.1825 24 P 0 ;1
L 7.7325 3.2325 7.7325 3.2325 24 P 0 ;1
L 7.7325 3.2825 7.7325 3.2825 24 P 0 ;1
L 7.7325 3.3325 7.7325 3.3325 24 P 0 ;1
L 7.7325 3.3825 7.7325 3.3825 24 P 0 ;1
L 7.7325 3.4325 7.7325 3.4325 24 P 0 ;1
L 7.7325 3.7325 7.7325 3.7325 24 P 0 ;1
L 7.7325 3.7825 7.7325 3.7825 24 P 0 ;1
L 7.7325 3.8325 7.7325 3.8325 24 P 0 ;1
L 7.7325 3.8825 7.7325 3.8825 24 P 0 ;1
L 7.7325 3.9325 7.7325 3.9325 24 P 0 ;1
L 7.7325 3.9825 7.7325 3.9825 24 P 0 ;1
L 7.7325 4.0325 7.7325 4.0325 24 P 0 ;1
L 7.7325 4.0825 7.7325 4.0825 24 P 0 ;1
L 7.7325 4.1325 7.7325 4.1325 24 P 0 ;1
L 7.7325 4.1825 7.7325 4.1825 24 P 0 ;1
L 7.7325 4.2325 7.7325 4.2325 24 P 0 ;1
L 7.7325 5.1825 7.7325 5.1825 24 P 0 ;1
L 7.7325 5.2325 7.7325 5.2325 24 P 0 ;1
L 7.7325 5.2825 7.7325 5.2825 24 P 0 ;1
L 7.7325 5.5325 7.7325 5.5325 24 P 0 ;1
L 7.7325 5.5825 7.7325 5.5825 24 P 0 ;1
L 7.7325 5.6325 7.7325 5.6325 24 P 0 ;1
L 7.7325 5.6825 7.7325 5.6825 24 P 0 ;1
L 7.7325 5.7325 7.7325 5.7325 24 P 0 ;1
L 7.7325 5.7825 7.7325 5.7825 24 P 0 ;1
L 7.7325 5.8325 7.7325 5.8325 24 P 0 ;1
L 7.7325 5.8825 7.7325 5.8825 24 P 0 ;1
L 7.7825 0.1325 7.7825 0.1325 24 P 0 ;1
L 7.7825 0.1825 7.7825 0.1825 24 P 0 ;1
L 7.7825 0.2325 7.7825 0.2325 24 P 0 ;1
L 7.7825 0.2825 7.7825 0.2825 24 P 0 ;1
L 7.7825 0.3325 7.7825 0.3325 24 P 0 ;1
L 7.7825 0.3825 7.7825 0.3825 24 P 0 ;1
L 7.7825 0.4325 7.7825 0.4325 24 P 0 ;1
L 7.7825 0.6825 7.7825 0.6825 24 P 0 ;1
L 7.7825 0.7325 7.7825 0.7325 24 P 0 ;1
L 7.7825 0.7825 7.7825 0.7825 24 P 0 ;1
L 7.7825 0.8325 7.7825 0.8325 24 P 0 ;1
L 7.7825 0.8825 7.7825 0.8825 24 P 0 ;1
L 7.7825 0.9325 7.7825 0.9325 24 P 0 ;1
L 7.7825 0.9825 7.7825 0.9825 24 P 0 ;1
L 7.7825 1.0325 7.7825 1.0325 24 P 0 ;1
L 7.7825 1.0825 7.7825 1.0825 24 P 0 ;1
L 7.7825 1.1325 7.7825 1.1325 24 P 0 ;1
L 7.7825 1.1825 7.7825 1.1825 24 P 0 ;1
L 7.7825 1.2325 7.7825 1.2325 24 P 0 ;1
L 7.7825 1.2825 7.7825 1.2825 24 P 0 ;1
L 7.7825 1.3325 7.7825 1.3325 24 P 0 ;1
L 7.7825 1.3825 7.7825 1.3825 24 P 0 ;1
L 7.7825 1.4325 7.7825 1.4325 24 P 0 ;1
L 7.7825 1.4825 7.7825 1.4825 24 P 0 ;1
L 7.7825 1.5325 7.7825 1.5325 24 P 0 ;1
L 7.7825 1.5825 7.7825 1.5825 24 P 0 ;1
L 7.7825 1.6325 7.7825 1.6325 24 P 0 ;1
L 7.7825 1.6825 7.7825 1.6825 24 P 0 ;1
L 7.7825 1.7325 7.7825 1.7325 24 P 0 ;1
L 7.7825 1.7825 7.7825 1.7825 24 P 0 ;1
L 7.7825 1.8325 7.7825 1.8325 24 P 0 ;1
L 7.7825 1.8825 7.7825 1.8825 24 P 0 ;1
L 7.7825 1.9325 7.7825 1.9325 24 P 0 ;1
L 7.7825 1.9825 7.7825 1.9825 24 P 0 ;1
L 7.7825 2.0325 7.7825 2.0325 24 P 0 ;1
L 7.7825 2.0825 7.7825 2.0825 24 P 0 ;1
L 7.7825 2.1325 7.7825 2.1325 24 P 0 ;1
L 7.7825 2.1825 7.7825 2.1825 24 P 0 ;1
L 7.7825 2.2325 7.7825 2.2325 24 P 0 ;1
L 7.7825 2.2825 7.7825 2.2825 24 P 0 ;1
L 7.7825 2.3325 7.7825 2.3325 24 P 0 ;1
L 7.7825 2.5825 7.7825 2.5825 24 P 0 ;1
L 7.7825 2.6325 7.7825 2.6325 24 P 0 ;1
L 7.7825 2.6825 7.7825 2.6825 24 P 0 ;1
L 7.7825 2.7325 7.7825 2.7325 24 P 0 ;1
L 7.7825 2.7825 7.7825 2.7825 24 P 0 ;1
L 7.7825 2.8325 7.7825 2.8325 24 P 0 ;1
L 7.7825 2.8825 7.7825 2.8825 24 P 0 ;1
L 7.7825 2.9325 7.7825 2.9325 24 P 0 ;1
L 7.7825 2.9825 7.7825 2.9825 24 P 0 ;1
L 7.7825 3.0325 7.7825 3.0325 24 P 0 ;1
L 7.7825 3.0825 7.7825 3.0825 24 P 0 ;1
L 7.7825 3.1325 7.7825 3.1325 24 P 0 ;1
L 7.7825 3.1825 7.7825 3.1825 24 P 0 ;1
L 7.7825 3.2325 7.7825 3.2325 24 P 0 ;1
L 7.7825 3.2825 7.7825 3.2825 24 P 0 ;1
L 7.7825 3.3325 7.7825 3.3325 24 P 0 ;1
L 7.7825 3.3825 7.7825 3.3825 24 P 0 ;1
L 7.7825 3.7325 7.7825 3.7325 24 P 0 ;1
L 7.7825 3.7825 7.7825 3.7825 24 P 0 ;1
L 7.7825 3.8325 7.7825 3.8325 24 P 0 ;1
L 7.7825 3.8825 7.7825 3.8825 24 P 0 ;1
L 7.7825 3.9325 7.7825 3.9325 24 P 0 ;1
L 7.7825 3.9825 7.7825 3.9825 24 P 0 ;1
L 7.7825 4.0325 7.7825 4.0325 24 P 0 ;1
L 7.7825 4.0825 7.7825 4.0825 24 P 0 ;1
L 7.7825 4.1325 7.7825 4.1325 24 P 0 ;1
L 7.7825 4.1825 7.7825 4.1825 24 P 0 ;1
L 7.7825 4.2325 7.7825 4.2325 24 P 0 ;1
L 7.7825 5.2325 7.7825 5.2325 24 P 0 ;1
L 7.7825 5.2825 7.7825 5.2825 24 P 0 ;1
L 7.7825 5.5325 7.7825 5.5325 24 P 0 ;1
L 7.7825 5.5825 7.7825 5.5825 24 P 0 ;1
L 7.7825 5.6325 7.7825 5.6325 24 P 0 ;1
L 7.7825 5.6825 7.7825 5.6825 24 P 0 ;1
L 7.7825 5.7325 7.7825 5.7325 24 P 0 ;1
L 7.7825 5.7825 7.7825 5.7825 24 P 0 ;1
L 7.7825 5.8325 7.7825 5.8325 24 P 0 ;1
L 7.7825 5.8825 7.7825 5.8825 24 P 0 ;1
L 7.8325 0.1325 7.8325 0.1325 24 P 0 ;1
L 7.8325 0.1825 7.8325 0.1825 24 P 0 ;1
L 7.8325 0.2325 7.8325 0.2325 24 P 0 ;1
L 7.8325 0.2825 7.8325 0.2825 24 P 0 ;1
L 7.8325 0.3325 7.8325 0.3325 24 P 0 ;1
L 7.8325 0.3825 7.8325 0.3825 24 P 0 ;1
L 7.8325 0.4325 7.8325 0.4325 24 P 0 ;1
L 7.8325 0.6825 7.8325 0.6825 24 P 0 ;1
L 7.8325 0.7325 7.8325 0.7325 24 P 0 ;1
L 7.8325 0.7825 7.8325 0.7825 24 P 0 ;1
L 7.8325 0.8325 7.8325 0.8325 24 P 0 ;1
L 7.8325 0.8825 7.8325 0.8825 24 P 0 ;1
L 7.8325 0.9325 7.8325 0.9325 24 P 0 ;1
L 7.8325 0.9825 7.8325 0.9825 24 P 0 ;1
L 7.8325 1.0325 7.8325 1.0325 24 P 0 ;1
L 7.8325 1.0825 7.8325 1.0825 24 P 0 ;1
L 7.8325 1.1325 7.8325 1.1325 24 P 0 ;1
L 7.8325 1.1825 7.8325 1.1825 24 P 0 ;1
L 7.8325 1.2325 7.8325 1.2325 24 P 0 ;1
L 7.8325 1.2825 7.8325 1.2825 24 P 0 ;1
L 7.8325 1.3325 7.8325 1.3325 24 P 0 ;1
L 7.8325 1.3825 7.8325 1.3825 24 P 0 ;1
L 7.8325 1.4325 7.8325 1.4325 24 P 0 ;1
L 7.8325 1.4825 7.8325 1.4825 24 P 0 ;1
L 7.8325 1.5325 7.8325 1.5325 24 P 0 ;1
L 7.8325 1.5825 7.8325 1.5825 24 P 0 ;1
L 7.8325 1.6325 7.8325 1.6325 24 P 0 ;1
L 7.8325 1.6825 7.8325 1.6825 24 P 0 ;1
L 7.8325 1.7325 7.8325 1.7325 24 P 0 ;1
L 7.8325 1.7825 7.8325 1.7825 24 P 0 ;1
L 7.8325 1.8325 7.8325 1.8325 24 P 0 ;1
L 7.8325 1.8825 7.8325 1.8825 24 P 0 ;1
L 7.8325 1.9325 7.8325 1.9325 24 P 0 ;1
L 7.8325 1.9825 7.8325 1.9825 24 P 0 ;1
L 7.8325 2.0325 7.8325 2.0325 24 P 0 ;1
L 7.8325 2.0825 7.8325 2.0825 24 P 0 ;1
L 7.8325 2.1325 7.8325 2.1325 24 P 0 ;1
L 7.8325 2.1825 7.8325 2.1825 24 P 0 ;1
L 7.8325 2.2325 7.8325 2.2325 24 P 0 ;1
L 7.8325 2.2825 7.8325 2.2825 24 P 0 ;1
L 7.8325 2.3325 7.8325 2.3325 24 P 0 ;1
L 7.8325 2.3825 7.8325 2.3825 24 P 0 ;1
L 7.8325 2.5825 7.8325 2.5825 24 P 0 ;1
L 7.8325 2.6325 7.8325 2.6325 24 P 0 ;1
L 7.8325 2.6825 7.8325 2.6825 24 P 0 ;1
L 7.8325 2.7325 7.8325 2.7325 24 P 0 ;1
L 7.8325 2.7825 7.8325 2.7825 24 P 0 ;1
L 7.8325 2.8325 7.8325 2.8325 24 P 0 ;1
L 7.8325 2.8825 7.8325 2.8825 24 P 0 ;1
L 7.8325 2.9325 7.8325 2.9325 24 P 0 ;1
L 7.8325 2.9825 7.8325 2.9825 24 P 0 ;1
L 7.8325 3.0325 7.8325 3.0325 24 P 0 ;1
L 7.8325 3.0825 7.8325 3.0825 24 P 0 ;1
L 7.8325 3.1325 7.8325 3.1325 24 P 0 ;1
L 7.8325 3.1825 7.8325 3.1825 24 P 0 ;1
L 7.8325 3.2325 7.8325 3.2325 24 P 0 ;1
L 7.8325 3.2825 7.8325 3.2825 24 P 0 ;1
L 7.8325 3.3325 7.8325 3.3325 24 P 0 ;1
L 7.8325 3.3825 7.8325 3.3825 24 P 0 ;1
L 7.8325 3.7325 7.8325 3.7325 24 P 0 ;1
L 7.8325 3.7825 7.8325 3.7825 24 P 0 ;1
L 7.8325 3.8325 7.8325 3.8325 24 P 0 ;1
L 7.8325 3.8825 7.8325 3.8825 24 P 0 ;1
L 7.8325 3.9325 7.8325 3.9325 24 P 0 ;1
L 7.8325 3.9825 7.8325 3.9825 24 P 0 ;1
L 7.8325 4.0325 7.8325 4.0325 24 P 0 ;1
L 7.8325 4.0825 7.8325 4.0825 24 P 0 ;1
L 7.8325 4.1325 7.8325 4.1325 24 P 0 ;1
L 7.8325 4.1825 7.8325 4.1825 24 P 0 ;1
L 7.8325 4.2325 7.8325 4.2325 24 P 0 ;1
L 7.8325 5.2825 7.8325 5.2825 24 P 0 ;1
L 7.8325 5.5325 7.8325 5.5325 24 P 0 ;1
L 7.8325 5.5825 7.8325 5.5825 24 P 0 ;1
L 7.8325 5.6325 7.8325 5.6325 24 P 0 ;1
L 7.8325 5.6825 7.8325 5.6825 24 P 0 ;1
L 7.8325 5.7325 7.8325 5.7325 24 P 0 ;1
L 7.8325 5.7825 7.8325 5.7825 24 P 0 ;1
L 7.8325 5.8325 7.8325 5.8325 24 P 0 ;1
L 7.8325 5.8825 7.8325 5.8825 24 P 0 ;1
L 7.8825 0.1325 7.8825 0.1325 24 P 0 ;1
L 7.8825 0.1825 7.8825 0.1825 24 P 0 ;1
L 7.8825 0.2325 7.8825 0.2325 24 P 0 ;1
L 7.8825 0.2825 7.8825 0.2825 24 P 0 ;1
L 7.8825 0.3325 7.8825 0.3325 24 P 0 ;1
L 7.8825 0.3825 7.8825 0.3825 24 P 0 ;1
L 7.8825 0.4325 7.8825 0.4325 24 P 0 ;1
L 7.8825 0.6825 7.8825 0.6825 24 P 0 ;1
L 7.8825 0.7325 7.8825 0.7325 24 P 0 ;1
L 7.8825 0.7825 7.8825 0.7825 24 P 0 ;1
L 7.8825 0.8325 7.8825 0.8325 24 P 0 ;1
L 7.8825 0.8825 7.8825 0.8825 24 P 0 ;1
L 7.8825 0.9325 7.8825 0.9325 24 P 0 ;1
L 7.8825 0.9825 7.8825 0.9825 24 P 0 ;1
L 7.8825 1.0325 7.8825 1.0325 24 P 0 ;1
L 7.8825 1.0825 7.8825 1.0825 24 P 0 ;1
L 7.8825 1.1325 7.8825 1.1325 24 P 0 ;1
L 7.8825 1.1825 7.8825 1.1825 24 P 0 ;1
L 7.8825 1.2325 7.8825 1.2325 24 P 0 ;1
L 7.8825 1.2825 7.8825 1.2825 24 P 0 ;1
L 7.8825 1.3325 7.8825 1.3325 24 P 0 ;1
L 7.8825 1.3825 7.8825 1.3825 24 P 0 ;1
L 7.8825 1.4325 7.8825 1.4325 24 P 0 ;1
L 7.8825 1.4825 7.8825 1.4825 24 P 0 ;1
L 7.8825 1.5325 7.8825 1.5325 24 P 0 ;1
L 7.8825 1.5825 7.8825 1.5825 24 P 0 ;1
L 7.8825 1.6325 7.8825 1.6325 24 P 0 ;1
L 7.8825 1.6825 7.8825 1.6825 24 P 0 ;1
L 7.8825 1.7325 7.8825 1.7325 24 P 0 ;1
L 7.8825 1.7825 7.8825 1.7825 24 P 0 ;1
L 7.8825 1.8325 7.8825 1.8325 24 P 0 ;1
L 7.8825 1.8825 7.8825 1.8825 24 P 0 ;1
L 7.8825 1.9325 7.8825 1.9325 24 P 0 ;1
L 7.8825 1.9825 7.8825 1.9825 24 P 0 ;1
L 7.8825 2.0325 7.8825 2.0325 24 P 0 ;1
L 7.8825 2.0825 7.8825 2.0825 24 P 0 ;1
L 7.8825 2.1325 7.8825 2.1325 24 P 0 ;1
L 7.8825 2.1825 7.8825 2.1825 24 P 0 ;1
L 7.8825 2.2325 7.8825 2.2325 24 P 0 ;1
L 7.8825 2.2825 7.8825 2.2825 24 P 0 ;1
L 7.8825 2.3325 7.8825 2.3325 24 P 0 ;1
L 7.8825 2.3825 7.8825 2.3825 24 P 0 ;1
L 7.8825 2.5825 7.8825 2.5825 24 P 0 ;1
L 7.8825 2.6325 7.8825 2.6325 24 P 0 ;1
L 7.8825 2.6825 7.8825 2.6825 24 P 0 ;1
L 7.8825 2.7325 7.8825 2.7325 24 P 0 ;1
L 7.8825 2.7825 7.8825 2.7825 24 P 0 ;1
L 7.8825 2.8325 7.8825 2.8325 24 P 0 ;1
L 7.8825 2.8825 7.8825 2.8825 24 P 0 ;1
L 7.8825 2.9325 7.8825 2.9325 24 P 0 ;1
L 7.8825 2.9825 7.8825 2.9825 24 P 0 ;1
L 7.8825 3.0325 7.8825 3.0325 24 P 0 ;1
L 7.8825 3.0825 7.8825 3.0825 24 P 0 ;1
L 7.8825 3.1325 7.8825 3.1325 24 P 0 ;1
L 7.8825 3.1825 7.8825 3.1825 24 P 0 ;1
L 7.8825 3.2325 7.8825 3.2325 24 P 0 ;1
L 7.8825 3.2825 7.8825 3.2825 24 P 0 ;1
L 7.8825 3.3325 7.8825 3.3325 24 P 0 ;1
L 7.8825 3.7325 7.8825 3.7325 24 P 0 ;1
L 7.8825 3.7825 7.8825 3.7825 24 P 0 ;1
L 7.8825 3.8325 7.8825 3.8325 24 P 0 ;1
L 7.8825 3.8825 7.8825 3.8825 24 P 0 ;1
L 7.8825 3.9325 7.8825 3.9325 24 P 0 ;1
L 7.8825 3.9825 7.8825 3.9825 24 P 0 ;1
L 7.8825 4.0325 7.8825 4.0325 24 P 0 ;1
L 7.8825 4.0825 7.8825 4.0825 24 P 0 ;1
L 7.8825 4.1325 7.8825 4.1325 24 P 0 ;1
L 7.8825 4.1825 7.8825 4.1825 24 P 0 ;1
L 7.8825 4.2325 7.8825 4.2325 24 P 0 ;1
L 7.8825 5.5325 7.8825 5.5325 24 P 0 ;1
L 7.8825 5.5825 7.8825 5.5825 24 P 0 ;1
L 7.8825 5.6325 7.8825 5.6325 24 P 0 ;1
L 7.8825 5.6825 7.8825 5.6825 24 P 0 ;1
L 7.8825 5.7325 7.8825 5.7325 24 P 0 ;1
L 7.8825 5.7825 7.8825 5.7825 24 P 0 ;1
L 7.8825 5.8325 7.8825 5.8325 24 P 0 ;1
L 7.8825 5.8825 7.8825 5.8825 24 P 0 ;1
L 7.9325 0.1325 7.9325 0.1325 24 P 0 ;1
L 7.9325 0.1825 7.9325 0.1825 24 P 0 ;1
L 7.9325 0.2325 7.9325 0.2325 24 P 0 ;1
L 7.9325 0.2825 7.9325 0.2825 24 P 0 ;1
L 7.9325 0.3325 7.9325 0.3325 24 P 0 ;1
L 7.9325 0.3825 7.9325 0.3825 24 P 0 ;1
L 7.9325 0.4325 7.9325 0.4325 24 P 0 ;1
L 7.9325 0.6825 7.9325 0.6825 24 P 0 ;1
L 7.9325 0.7325 7.9325 0.7325 24 P 0 ;1
L 7.9325 0.7825 7.9325 0.7825 24 P 0 ;1
L 7.9325 0.8325 7.9325 0.8325 24 P 0 ;1
L 7.9325 0.8825 7.9325 0.8825 24 P 0 ;1
L 7.9325 0.9325 7.9325 0.9325 24 P 0 ;1
L 7.9325 0.9825 7.9325 0.9825 24 P 0 ;1
L 7.9325 1.0325 7.9325 1.0325 24 P 0 ;1
L 7.9325 1.0825 7.9325 1.0825 24 P 0 ;1
L 7.9325 1.1325 7.9325 1.1325 24 P 0 ;1
L 7.9325 1.1825 7.9325 1.1825 24 P 0 ;1
L 7.9325 1.2325 7.9325 1.2325 24 P 0 ;1
L 7.9325 1.2825 7.9325 1.2825 24 P 0 ;1
L 7.9325 1.3325 7.9325 1.3325 24 P 0 ;1
L 7.9325 1.3825 7.9325 1.3825 24 P 0 ;1
L 7.9325 1.4325 7.9325 1.4325 24 P 0 ;1
L 7.9325 1.4825 7.9325 1.4825 24 P 0 ;1
L 7.9325 1.5325 7.9325 1.5325 24 P 0 ;1
L 7.9325 1.5825 7.9325 1.5825 24 P 0 ;1
L 7.9325 1.6325 7.9325 1.6325 24 P 0 ;1
L 7.9325 1.6825 7.9325 1.6825 24 P 0 ;1
L 7.9325 1.7325 7.9325 1.7325 24 P 0 ;1
L 7.9325 1.7825 7.9325 1.7825 24 P 0 ;1
L 7.9325 1.8325 7.9325 1.8325 24 P 0 ;1
L 7.9325 1.8825 7.9325 1.8825 24 P 0 ;1
L 7.9325 1.9325 7.9325 1.9325 24 P 0 ;1
L 7.9325 1.9825 7.9325 1.9825 24 P 0 ;1
L 7.9325 2.0325 7.9325 2.0325 24 P 0 ;1
L 7.9325 2.0825 7.9325 2.0825 24 P 0 ;1
L 7.9325 2.1325 7.9325 2.1325 24 P 0 ;1
L 7.9325 2.1825 7.9325 2.1825 24 P 0 ;1
L 7.9325 2.2325 7.9325 2.2325 24 P 0 ;1
L 7.9325 2.2825 7.9325 2.2825 24 P 0 ;1
L 7.9325 2.3325 7.9325 2.3325 24 P 0 ;1
L 7.9325 2.3825 7.9325 2.3825 24 P 0 ;1
L 7.9325 2.5825 7.9325 2.5825 24 P 0 ;1
L 7.9325 2.6325 7.9325 2.6325 24 P 0 ;1
L 7.9325 2.9325 7.9325 2.9325 24 P 0 ;1
L 7.9325 2.9825 7.9325 2.9825 24 P 0 ;1
L 7.9325 3.0325 7.9325 3.0325 24 P 0 ;1
L 7.9325 3.0825 7.9325 3.0825 24 P 0 ;1
L 7.9325 3.1325 7.9325 3.1325 24 P 0 ;1
L 7.9325 3.1825 7.9325 3.1825 24 P 0 ;1
L 7.9325 3.2325 7.9325 3.2325 24 P 0 ;1
L 7.9325 3.2825 7.9325 3.2825 24 P 0 ;1
L 7.9325 3.7325 7.9325 3.7325 24 P 0 ;1
L 7.9325 3.7825 7.9325 3.7825 24 P 0 ;1
L 7.9325 3.8325 7.9325 3.8325 24 P 0 ;1
L 7.9325 3.8825 7.9325 3.8825 24 P 0 ;1
L 7.9325 3.9325 7.9325 3.9325 24 P 0 ;1
L 7.9325 3.9825 7.9325 3.9825 24 P 0 ;1
L 7.9325 4.0325 7.9325 4.0325 24 P 0 ;1
L 7.9325 4.0825 7.9325 4.0825 24 P 0 ;1
L 7.9325 4.1325 7.9325 4.1325 24 P 0 ;1
L 7.9325 4.1825 7.9325 4.1825 24 P 0 ;1
L 7.9325 4.2325 7.9325 4.2325 24 P 0 ;1
L 7.9325 5.5325 7.9325 5.5325 24 P 0 ;1
L 7.9325 5.5825 7.9325 5.5825 24 P 0 ;1
L 7.9325 5.6325 7.9325 5.6325 24 P 0 ;1
L 7.9325 5.6825 7.9325 5.6825 24 P 0 ;1
L 7.9325 5.7325 7.9325 5.7325 24 P 0 ;1
L 7.9325 5.7825 7.9325 5.7825 24 P 0 ;1
L 7.9325 5.8325 7.9325 5.8325 24 P 0 ;1
L 7.9325 5.8825 7.9325 5.8825 24 P 0 ;1
L 7.9825 0.1325 7.9825 0.1325 24 P 0 ;1
L 7.9825 0.1825 7.9825 0.1825 24 P 0 ;1
L 7.9825 0.2325 7.9825 0.2325 24 P 0 ;1
L 7.9825 0.2825 7.9825 0.2825 24 P 0 ;1
L 7.9825 0.3325 7.9825 0.3325 24 P 0 ;1
L 7.9825 0.3825 7.9825 0.3825 24 P 0 ;1
L 7.9825 0.4325 7.9825 0.4325 24 P 0 ;1
L 7.9825 0.6825 7.9825 0.6825 24 P 0 ;1
L 7.9825 0.7325 7.9825 0.7325 24 P 0 ;1
L 7.9825 0.7825 7.9825 0.7825 24 P 0 ;1
L 7.9825 0.8325 7.9825 0.8325 24 P 0 ;1
L 7.9825 0.8825 7.9825 0.8825 24 P 0 ;1
L 7.9825 0.9325 7.9825 0.9325 24 P 0 ;1
L 7.9825 0.9825 7.9825 0.9825 24 P 0 ;1
L 7.9825 1.0325 7.9825 1.0325 24 P 0 ;1
L 7.9825 1.0825 7.9825 1.0825 24 P 0 ;1
L 7.9825 1.1325 7.9825 1.1325 24 P 0 ;1
L 7.9825 1.1825 7.9825 1.1825 24 P 0 ;1
L 7.9825 1.2325 7.9825 1.2325 24 P 0 ;1
L 7.9825 1.2825 7.9825 1.2825 24 P 0 ;1
L 7.9825 1.3325 7.9825 1.3325 24 P 0 ;1
L 7.9825 1.3825 7.9825 1.3825 24 P 0 ;1
L 7.9825 1.4325 7.9825 1.4325 24 P 0 ;1
L 7.9825 1.4825 7.9825 1.4825 24 P 0 ;1
L 7.9825 1.5325 7.9825 1.5325 24 P 0 ;1
L 7.9825 1.5825 7.9825 1.5825 24 P 0 ;1
L 7.9825 1.6325 7.9825 1.6325 24 P 0 ;1
L 7.9825 1.6825 7.9825 1.6825 24 P 0 ;1
L 7.9825 1.7325 7.9825 1.7325 24 P 0 ;1
L 7.9825 1.7825 7.9825 1.7825 24 P 0 ;1
L 7.9825 3.9325 7.9825 3.9325 24 P 0 ;1
L 7.9825 3.9825 7.9825 3.9825 24 P 0 ;1
L 7.9825 4.0325 7.9825 4.0325 24 P 0 ;1
L 7.9825 4.0825 7.9825 4.0825 24 P 0 ;1
L 7.9825 4.1325 7.9825 4.1325 24 P 0 ;1
L 7.9825 4.1825 7.9825 4.1825 24 P 0 ;1
L 7.9825 4.2325 7.9825 4.2325 24 P 0 ;1
L 7.9825 5.5325 7.9825 5.5325 24 P 0 ;1
L 7.9825 5.5825 7.9825 5.5825 24 P 0 ;1
L 7.9825 5.6325 7.9825 5.6325 24 P 0 ;1
L 7.9825 5.6825 7.9825 5.6825 24 P 0 ;1
L 7.9825 5.7325 7.9825 5.7325 24 P 0 ;1
L 7.9825 5.7825 7.9825 5.7825 24 P 0 ;1
L 7.9825 5.8325 7.9825 5.8325 24 P 0 ;1
L 7.9825 5.8825 7.9825 5.8825 24 P 0 ;1
L 8.0325 0.1325 8.0325 0.1325 24 P 0 ;1
L 8.0325 0.1825 8.0325 0.1825 24 P 0 ;1
L 8.0325 0.2325 8.0325 0.2325 24 P 0 ;1
L 8.0325 0.2825 8.0325 0.2825 24 P 0 ;1
L 8.0325 0.3325 8.0325 0.3325 24 P 0 ;1
L 8.0325 0.3825 8.0325 0.3825 24 P 0 ;1
L 8.0325 0.4325 8.0325 0.4325 24 P 0 ;1
L 8.0325 0.6825 8.0325 0.6825 24 P 0 ;1
L 8.0325 0.7325 8.0325 0.7325 24 P 0 ;1
L 8.0325 0.7825 8.0325 0.7825 24 P 0 ;1
L 8.0325 0.8325 8.0325 0.8325 24 P 0 ;1
L 8.0325 0.8825 8.0325 0.8825 24 P 0 ;1
L 8.0325 0.9325 8.0325 0.9325 24 P 0 ;1
L 8.0325 0.9825 8.0325 0.9825 24 P 0 ;1
L 8.0325 1.0325 8.0325 1.0325 24 P 0 ;1
L 8.0325 1.0825 8.0325 1.0825 24 P 0 ;1
L 8.0325 1.1325 8.0325 1.1325 24 P 0 ;1
L 8.0325 1.1825 8.0325 1.1825 24 P 0 ;1
L 8.0325 1.2325 8.0325 1.2325 24 P 0 ;1
L 8.0325 1.2825 8.0325 1.2825 24 P 0 ;1
L 8.0325 1.3325 8.0325 1.3325 24 P 0 ;1
L 8.0325 1.3825 8.0325 1.3825 24 P 0 ;1
L 8.0325 1.6325 8.0325 1.6325 24 P 0 ;1
L 8.0325 1.6825 8.0325 1.6825 24 P 0 ;1
L 8.0325 1.7325 8.0325 1.7325 24 P 0 ;1
L 8.0325 3.9825 8.0325 3.9825 24 P 0 ;1
L 8.0325 4.0325 8.0325 4.0325 24 P 0 ;1
L 8.0325 4.0825 8.0325 4.0825 24 P 0 ;1
L 8.0325 5.5325 8.0325 5.5325 24 P 0 ;1
L 8.0325 5.5825 8.0325 5.5825 24 P 0 ;1
L 8.0325 5.6325 8.0325 5.6325 24 P 0 ;1
L 8.0325 5.6825 8.0325 5.6825 24 P 0 ;1
L 8.0325 5.7325 8.0325 5.7325 24 P 0 ;1
L 8.0325 5.7825 8.0325 5.7825 24 P 0 ;1
L 8.0325 5.8325 8.0325 5.8325 24 P 0 ;1
L 8.0325 5.8825 8.0325 5.8825 24 P 0 ;1
L 8.0825 0.1325 8.0825 0.1325 24 P 0 ;1
L 8.0825 0.1825 8.0825 0.1825 24 P 0 ;1
L 8.0825 0.2325 8.0825 0.2325 24 P 0 ;1
L 8.0825 0.2825 8.0825 0.2825 24 P 0 ;1
L 8.0825 0.3325 8.0825 0.3325 24 P 0 ;1
L 8.0825 0.3825 8.0825 0.3825 24 P 0 ;1
L 8.0825 0.4325 8.0825 0.4325 24 P 0 ;1
L 8.0825 0.6825 8.0825 0.6825 24 P 0 ;1
L 8.0825 0.7325 8.0825 0.7325 24 P 0 ;1
L 8.0825 0.7825 8.0825 0.7825 24 P 0 ;1
L 8.0825 0.8325 8.0825 0.8325 24 P 0 ;1
L 8.0825 0.8825 8.0825 0.8825 24 P 0 ;1
L 8.0825 0.9325 8.0825 0.9325 24 P 0 ;1
L 8.0825 0.9825 8.0825 0.9825 24 P 0 ;1
L 8.0825 1.0325 8.0825 1.0325 24 P 0 ;1
L 8.0825 1.0825 8.0825 1.0825 24 P 0 ;1
L 8.0825 1.1325 8.0825 1.1325 24 P 0 ;1
L 8.0825 1.1825 8.0825 1.1825 24 P 0 ;1
L 8.0825 1.2325 8.0825 1.2325 24 P 0 ;1
L 8.0825 1.2825 8.0825 1.2825 24 P 0 ;1
L 8.0825 1.7325 8.0825 1.7325 24 P 0 ;1
L 8.0825 3.9825 8.0825 3.9825 24 P 0 ;1
L 8.0825 4.0325 8.0825 4.0325 24 P 0 ;1
L 8.0825 5.5325 8.0825 5.5325 24 P 0 ;1
L 8.0825 5.5825 8.0825 5.5825 24 P 0 ;1
L 8.0825 5.6325 8.0825 5.6325 24 P 0 ;1
L 8.0825 5.6825 8.0825 5.6825 24 P 0 ;1
L 8.0825 5.7325 8.0825 5.7325 24 P 0 ;1
L 8.0825 5.7825 8.0825 5.7825 24 P 0 ;1
L 8.0825 5.8325 8.0825 5.8325 24 P 0 ;1
L 8.0825 5.8825 8.0825 5.8825 24 P 0 ;1
L 8.1325 0.1325 8.1325 0.1325 24 P 0 ;1
L 8.1325 0.1825 8.1325 0.1825 24 P 0 ;1
L 8.1325 0.2325 8.1325 0.2325 24 P 0 ;1
L 8.1325 0.2825 8.1325 0.2825 24 P 0 ;1
L 8.1325 0.3325 8.1325 0.3325 24 P 0 ;1
L 8.1325 0.3825 8.1325 0.3825 24 P 0 ;1
L 8.1325 0.4325 8.1325 0.4325 24 P 0 ;1
L 8.1325 0.6825 8.1325 0.6825 24 P 0 ;1
L 8.1325 0.7325 8.1325 0.7325 24 P 0 ;1
L 8.1325 0.7825 8.1325 0.7825 24 P 0 ;1
L 8.1325 0.8325 8.1325 0.8325 24 P 0 ;1
L 8.1325 0.8825 8.1325 0.8825 24 P 0 ;1
L 8.1325 0.9325 8.1325 0.9325 24 P 0 ;1
L 8.1325 0.9825 8.1325 0.9825 24 P 0 ;1
L 8.1325 1.0325 8.1325 1.0325 24 P 0 ;1
L 8.1325 1.0825 8.1325 1.0825 24 P 0 ;1
L 8.1325 1.1325 8.1325 1.1325 24 P 0 ;1
L 8.1325 1.1825 8.1325 1.1825 24 P 0 ;1
L 8.1325 1.2325 8.1325 1.2325 24 P 0 ;1
L 8.1325 1.2825 8.1325 1.2825 24 P 0 ;1
L 8.1325 1.7325 8.1325 1.7325 24 P 0 ;1
L 8.1325 3.9825 8.1325 3.9825 24 P 0 ;1
L 8.1325 5.5325 8.1325 5.5325 24 P 0 ;1
L 8.1325 5.5825 8.1325 5.5825 24 P 0 ;1
L 8.1325 5.6325 8.1325 5.6325 24 P 0 ;1
L 8.1325 5.6825 8.1325 5.6825 24 P 0 ;1
L 8.1325 5.7325 8.1325 5.7325 24 P 0 ;1
L 8.1325 5.7825 8.1325 5.7825 24 P 0 ;1
L 8.1325 5.8325 8.1325 5.8325 24 P 0 ;1
L 8.1325 5.8825 8.1325 5.8825 24 P 0 ;1
L 8.1825 0.1325 8.1825 0.1325 24 P 0 ;1
L 8.1825 0.1825 8.1825 0.1825 24 P 0 ;1
L 8.1825 0.2325 8.1825 0.2325 24 P 0 ;1
L 8.1825 0.2825 8.1825 0.2825 24 P 0 ;1
L 8.1825 0.3325 8.1825 0.3325 24 P 0 ;1
L 8.1825 0.3825 8.1825 0.3825 24 P 0 ;1
L 8.1825 0.4325 8.1825 0.4325 24 P 0 ;1
L 8.1825 0.6825 8.1825 0.6825 24 P 0 ;1
L 8.1825 0.7325 8.1825 0.7325 24 P 0 ;1
L 8.1825 0.7825 8.1825 0.7825 24 P 0 ;1
L 8.1825 0.8325 8.1825 0.8325 24 P 0 ;1
L 8.1825 0.8825 8.1825 0.8825 24 P 0 ;1
L 8.1825 0.9325 8.1825 0.9325 24 P 0 ;1
L 8.1825 0.9825 8.1825 0.9825 24 P 0 ;1
L 8.1825 1.0325 8.1825 1.0325 24 P 0 ;1
L 8.1825 1.0825 8.1825 1.0825 24 P 0 ;1
L 8.1825 1.1325 8.1825 1.1325 24 P 0 ;1
L 8.1825 1.1825 8.1825 1.1825 24 P 0 ;1
L 8.1825 1.2325 8.1825 1.2325 24 P 0 ;1
L 8.1825 3.9825 8.1825 3.9825 24 P 0 ;1
L 8.1825 5.5325 8.1825 5.5325 24 P 0 ;1
L 8.1825 5.5825 8.1825 5.5825 24 P 0 ;1
L 8.1825 5.6325 8.1825 5.6325 24 P 0 ;1
L 8.1825 5.6825 8.1825 5.6825 24 P 0 ;1
L 8.1825 5.7325 8.1825 5.7325 24 P 0 ;1
L 8.1825 5.7825 8.1825 5.7825 24 P 0 ;1
L 8.1825 5.8325 8.1825 5.8325 24 P 0 ;1
L 8.1825 5.8825 8.1825 5.8825 24 P 0 ;1
L 8.2325 0.1325 8.2325 0.1325 24 P 0 ;1
L 8.2325 0.1825 8.2325 0.1825 24 P 0 ;1
L 8.2325 0.2325 8.2325 0.2325 24 P 0 ;1
L 8.2325 0.2825 8.2325 0.2825 24 P 0 ;1
L 8.2325 0.3325 8.2325 0.3325 24 P 0 ;1
L 8.2325 0.3825 8.2325 0.3825 24 P 0 ;1
L 8.2325 0.4325 8.2325 0.4325 24 P 0 ;1
L 8.2325 0.6825 8.2325 0.6825 24 P 0 ;1
L 8.2325 0.7325 8.2325 0.7325 24 P 0 ;1
L 8.2325 0.7825 8.2325 0.7825 24 P 0 ;1
L 8.2325 0.8325 8.2325 0.8325 24 P 0 ;1
L 8.2325 0.8825 8.2325 0.8825 24 P 0 ;1
L 8.2325 0.9325 8.2325 0.9325 24 P 0 ;1
L 8.2325 0.9825 8.2325 0.9825 24 P 0 ;1
L 8.2325 1.0325 8.2325 1.0325 24 P 0 ;1
L 8.2325 1.0825 8.2325 1.0825 24 P 0 ;1
L 8.2325 1.1325 8.2325 1.1325 24 P 0 ;1
L 8.2325 1.1825 8.2325 1.1825 24 P 0 ;1
L 8.2325 1.2325 8.2325 1.2325 24 P 0 ;1
L 8.2325 3.9825 8.2325 3.9825 24 P 0 ;1
L 8.2325 5.1825 8.2325 5.1825 24 P 0 ;1
L 8.2325 5.2325 8.2325 5.2325 24 P 0 ;1
L 8.2325 5.2825 8.2325 5.2825 24 P 0 ;1
L 8.2325 5.5325 8.2325 5.5325 24 P 0 ;1
L 8.2325 5.5825 8.2325 5.5825 24 P 0 ;1
L 8.2325 5.6325 8.2325 5.6325 24 P 0 ;1
L 8.2325 5.6825 8.2325 5.6825 24 P 0 ;1
L 8.2325 5.7325 8.2325 5.7325 24 P 0 ;1
L 8.2325 5.7825 8.2325 5.7825 24 P 0 ;1
L 8.2325 5.8325 8.2325 5.8325 24 P 0 ;1
L 8.2325 5.8825 8.2325 5.8825 24 P 0 ;1
L 8.2825 0.1325 8.2825 0.1325 24 P 0 ;1
L 8.2825 0.1825 8.2825 0.1825 24 P 0 ;1
L 8.2825 0.2325 8.2825 0.2325 24 P 0 ;1
L 8.2825 0.2825 8.2825 0.2825 24 P 0 ;1
L 8.2825 0.3325 8.2825 0.3325 24 P 0 ;1
L 8.2825 0.3825 8.2825 0.3825 24 P 0 ;1
L 8.2825 0.4325 8.2825 0.4325 24 P 0 ;1
L 8.2825 0.6825 8.2825 0.6825 24 P 0 ;1
L 8.2825 0.7325 8.2825 0.7325 24 P 0 ;1
L 8.2825 0.7825 8.2825 0.7825 24 P 0 ;1
L 8.2825 0.8325 8.2825 0.8325 24 P 0 ;1
L 8.2825 0.8825 8.2825 0.8825 24 P 0 ;1
L 8.2825 0.9325 8.2825 0.9325 24 P 0 ;1
L 8.2825 0.9825 8.2825 0.9825 24 P 0 ;1
L 8.2825 1.0325 8.2825 1.0325 24 P 0 ;1
L 8.2825 1.0825 8.2825 1.0825 24 P 0 ;1
L 8.2825 1.1325 8.2825 1.1325 24 P 0 ;1
L 8.2825 1.1825 8.2825 1.1825 24 P 0 ;1
L 8.2825 1.2325 8.2825 1.2325 24 P 0 ;1
L 8.2825 3.9825 8.2825 3.9825 24 P 0 ;1
L 8.2825 5.2325 8.2825 5.2325 24 P 0 ;1
L 8.2825 5.2825 8.2825 5.2825 24 P 0 ;1
L 8.2825 5.5325 8.2825 5.5325 24 P 0 ;1
L 8.2825 5.5825 8.2825 5.5825 24 P 0 ;1
L 8.2825 5.6325 8.2825 5.6325 24 P 0 ;1
L 8.2825 5.6825 8.2825 5.6825 24 P 0 ;1
L 8.2825 5.7325 8.2825 5.7325 24 P 0 ;1
L 8.2825 5.7825 8.2825 5.7825 24 P 0 ;1
L 8.2825 5.8325 8.2825 5.8325 24 P 0 ;1
L 8.2825 5.8825 8.2825 5.8825 24 P 0 ;1
L 8.3325 0.1325 8.3325 0.1325 24 P 0 ;1
L 8.3325 0.1825 8.3325 0.1825 24 P 0 ;1
L 8.3325 0.2325 8.3325 0.2325 24 P 0 ;1
L 8.3325 0.2825 8.3325 0.2825 24 P 0 ;1
L 8.3325 0.3325 8.3325 0.3325 24 P 0 ;1
L 8.3325 0.3825 8.3325 0.3825 24 P 0 ;1
L 8.3325 0.4325 8.3325 0.4325 24 P 0 ;1
L 8.3325 0.6825 8.3325 0.6825 24 P 0 ;1
L 8.3325 0.7325 8.3325 0.7325 24 P 0 ;1
L 8.3325 0.7825 8.3325 0.7825 24 P 0 ;1
L 8.3325 0.8325 8.3325 0.8325 24 P 0 ;1
L 8.3325 0.8825 8.3325 0.8825 24 P 0 ;1
L 8.3325 0.9325 8.3325 0.9325 24 P 0 ;1
L 8.3325 0.9825 8.3325 0.9825 24 P 0 ;1
L 8.3325 1.0325 8.3325 1.0325 24 P 0 ;1
L 8.3325 1.0825 8.3325 1.0825 24 P 0 ;1
L 8.3325 1.1325 8.3325 1.1325 24 P 0 ;1
L 8.3325 1.1825 8.3325 1.1825 24 P 0 ;1
L 8.3325 1.2325 8.3325 1.2325 24 P 0 ;1
L 8.3325 3.9825 8.3325 3.9825 24 P 0 ;1
L 8.3325 5.2825 8.3325 5.2825 24 P 0 ;1
L 8.3325 5.5325 8.3325 5.5325 24 P 0 ;1
L 8.3325 5.5825 8.3325 5.5825 24 P 0 ;1
L 8.3325 5.6325 8.3325 5.6325 24 P 0 ;1
L 8.3325 5.6825 8.3325 5.6825 24 P 0 ;1
L 8.3325 5.7325 8.3325 5.7325 24 P 0 ;1
L 8.3325 5.7825 8.3325 5.7825 24 P 0 ;1
L 8.3325 5.8325 8.3325 5.8325 24 P 0 ;1
L 8.3325 5.8825 8.3325 5.8825 24 P 0 ;1
L 8.3825 0.1325 8.3825 0.1325 24 P 0 ;1
L 8.3825 0.1825 8.3825 0.1825 24 P 0 ;1
L 8.3825 0.2325 8.3825 0.2325 24 P 0 ;1
L 8.3825 0.2825 8.3825 0.2825 24 P 0 ;1
L 8.3825 0.3325 8.3825 0.3325 24 P 0 ;1
L 8.3825 0.3825 8.3825 0.3825 24 P 0 ;1
L 8.3825 0.4325 8.3825 0.4325 24 P 0 ;1
L 8.3825 0.6825 8.3825 0.6825 24 P 0 ;1
L 8.3825 0.7325 8.3825 0.7325 24 P 0 ;1
L 8.3825 0.7825 8.3825 0.7825 24 P 0 ;1
L 8.3825 0.8325 8.3825 0.8325 24 P 0 ;1
L 8.3825 0.8825 8.3825 0.8825 24 P 0 ;1
L 8.3825 0.9325 8.3825 0.9325 24 P 0 ;1
L 8.3825 0.9825 8.3825 0.9825 24 P 0 ;1
L 8.3825 1.0325 8.3825 1.0325 24 P 0 ;1
L 8.3825 1.0825 8.3825 1.0825 24 P 0 ;1
L 8.3825 1.1325 8.3825 1.1325 24 P 0 ;1
L 8.3825 1.1825 8.3825 1.1825 24 P 0 ;1
L 8.3825 1.2325 8.3825 1.2325 24 P 0 ;1
L 8.3825 1.2825 8.3825 1.2825 24 P 0 ;1
L 8.3825 1.7325 8.3825 1.7325 24 P 0 ;1
L 8.3825 3.9825 8.3825 3.9825 24 P 0 ;1
L 8.3825 5.2825 8.3825 5.2825 24 P 0 ;1
L 8.3825 5.4825 8.3825 5.4825 24 P 0 ;1
L 8.3825 5.5325 8.3825 5.5325 24 P 0 ;1
L 8.3825 5.5825 8.3825 5.5825 24 P 0 ;1
L 8.3825 5.6325 8.3825 5.6325 24 P 0 ;1
L 8.3825 5.6825 8.3825 5.6825 24 P 0 ;1
L 8.3825 5.7325 8.3825 5.7325 24 P 0 ;1
L 8.3825 5.7825 8.3825 5.7825 24 P 0 ;1
L 8.3825 5.8325 8.3825 5.8325 24 P 0 ;1
L 8.3825 5.8825 8.3825 5.8825 24 P 0 ;1
L 8.4325 0.1325 8.4325 0.1325 24 P 0 ;1
L 8.4325 0.1825 8.4325 0.1825 24 P 0 ;1
L 8.4325 0.2325 8.4325 0.2325 24 P 0 ;1
L 8.4325 0.2825 8.4325 0.2825 24 P 0 ;1
L 8.4325 0.3325 8.4325 0.3325 24 P 0 ;1
L 8.4325 0.3825 8.4325 0.3825 24 P 0 ;1
L 8.4325 0.4325 8.4325 0.4325 24 P 0 ;1
L 8.4325 0.6825 8.4325 0.6825 24 P 0 ;1
L 8.4325 0.7325 8.4325 0.7325 24 P 0 ;1
L 8.4325 0.7825 8.4325 0.7825 24 P 0 ;1
L 8.4325 0.8325 8.4325 0.8325 24 P 0 ;1
L 8.4325 0.8825 8.4325 0.8825 24 P 0 ;1
L 8.4325 0.9325 8.4325 0.9325 24 P 0 ;1
L 8.4325 0.9825 8.4325 0.9825 24 P 0 ;1
L 8.4325 1.0325 8.4325 1.0325 24 P 0 ;1
L 8.4325 1.0825 8.4325 1.0825 24 P 0 ;1
L 8.4325 1.1325 8.4325 1.1325 24 P 0 ;1
L 8.4325 1.1825 8.4325 1.1825 24 P 0 ;1
L 8.4325 1.2325 8.4325 1.2325 24 P 0 ;1
L 8.4325 1.2825 8.4325 1.2825 24 P 0 ;1
L 8.4325 1.3325 8.4325 1.3325 24 P 0 ;1
L 8.4325 1.6825 8.4325 1.6825 24 P 0 ;1
L 8.4325 1.7325 8.4325 1.7325 24 P 0 ;1
L 8.4325 3.9825 8.4325 3.9825 24 P 0 ;1
L 8.4325 4.0325 8.4325 4.0325 24 P 0 ;1
L 8.4325 5.2825 8.4325 5.2825 24 P 0 ;1
L 8.4325 5.4825 8.4325 5.4825 24 P 0 ;1
L 8.4325 5.5325 8.4325 5.5325 24 P 0 ;1
L 8.4325 5.5825 8.4325 5.5825 24 P 0 ;1
L 8.4325 5.6325 8.4325 5.6325 24 P 0 ;1
L 8.4325 5.6825 8.4325 5.6825 24 P 0 ;1
L 8.4325 5.7325 8.4325 5.7325 24 P 0 ;1
L 8.4325 5.7825 8.4325 5.7825 24 P 0 ;1
L 8.4325 5.8325 8.4325 5.8325 24 P 0 ;1
L 8.4325 5.8825 8.4325 5.8825 24 P 0 ;1
L 8.4825 0.1325 8.4825 0.1325 24 P 0 ;1
L 8.4825 0.1825 8.4825 0.1825 24 P 0 ;1
L 8.4825 0.2325 8.4825 0.2325 24 P 0 ;1
L 8.4825 0.2825 8.4825 0.2825 24 P 0 ;1
L 8.4825 0.3325 8.4825 0.3325 24 P 0 ;1
L 8.4825 0.3825 8.4825 0.3825 24 P 0 ;1
L 8.4825 0.4325 8.4825 0.4325 24 P 0 ;1
L 8.4825 0.6825 8.4825 0.6825 24 P 0 ;1
L 8.4825 0.7325 8.4825 0.7325 24 P 0 ;1
L 8.4825 0.7825 8.4825 0.7825 24 P 0 ;1
L 8.4825 0.8325 8.4825 0.8325 24 P 0 ;1
L 8.4825 0.8825 8.4825 0.8825 24 P 0 ;1
L 8.4825 0.9325 8.4825 0.9325 24 P 0 ;1
L 8.4825 0.9825 8.4825 0.9825 24 P 0 ;1
L 8.4825 1.0325 8.4825 1.0325 24 P 0 ;1
L 8.4825 1.0825 8.4825 1.0825 24 P 0 ;1
L 8.4825 1.1325 8.4825 1.1325 24 P 0 ;1
L 8.4825 1.1825 8.4825 1.1825 24 P 0 ;1
L 8.4825 1.2325 8.4825 1.2325 24 P 0 ;1
L 8.4825 1.2825 8.4825 1.2825 24 P 0 ;1
L 8.4825 1.3325 8.4825 1.3325 24 P 0 ;1
L 8.4825 1.3825 8.4825 1.3825 24 P 0 ;1
L 8.4825 1.4325 8.4825 1.4325 24 P 0 ;1
L 8.4825 1.5825 8.4825 1.5825 24 P 0 ;1
L 8.4825 1.6325 8.4825 1.6325 24 P 0 ;1
L 8.4825 1.6825 8.4825 1.6825 24 P 0 ;1
L 8.4825 1.7325 8.4825 1.7325 24 P 0 ;1
L 8.4825 3.9825 8.4825 3.9825 24 P 0 ;1
L 8.4825 4.0325 8.4825 4.0325 24 P 0 ;1
L 8.4825 4.0825 8.4825 4.0825 24 P 0 ;1
L 8.4825 4.1325 8.4825 4.1325 24 P 0 ;1
L 8.4825 4.3325 8.4825 4.3325 24 P 0 ;1
L 8.4825 4.3825 8.4825 4.3825 24 P 0 ;1
L 8.4825 5.2325 8.4825 5.2325 24 P 0 ;1
L 8.4825 5.2825 8.4825 5.2825 24 P 0 ;1
L 8.4825 5.4825 8.4825 5.4825 24 P 0 ;1
L 8.4825 5.5325 8.4825 5.5325 24 P 0 ;1
L 8.4825 5.5825 8.4825 5.5825 24 P 0 ;1
L 8.4825 5.6325 8.4825 5.6325 24 P 0 ;1
L 8.4825 5.6825 8.4825 5.6825 24 P 0 ;1
L 8.4825 5.7325 8.4825 5.7325 24 P 0 ;1
L 8.4825 5.7825 8.4825 5.7825 24 P 0 ;1
L 8.4825 5.8325 8.4825 5.8325 24 P 0 ;1
L 8.4825 5.8825 8.4825 5.8825 24 P 0 ;1
L 8.5325 0.1325 8.5325 0.1325 24 P 0 ;1
L 8.5325 0.1825 8.5325 0.1825 24 P 0 ;1
L 8.5325 0.2325 8.5325 0.2325 24 P 0 ;1
L 8.5325 0.2825 8.5325 0.2825 24 P 0 ;1
L 8.5325 0.3325 8.5325 0.3325 24 P 0 ;1
L 8.5325 0.3825 8.5325 0.3825 24 P 0 ;1
L 8.5325 0.4325 8.5325 0.4325 24 P 0 ;1
L 8.5325 0.6825 8.5325 0.6825 24 P 0 ;1
L 8.5325 0.7325 8.5325 0.7325 24 P 0 ;1
L 8.5325 0.7825 8.5325 0.7825 24 P 0 ;1
L 8.5325 0.8325 8.5325 0.8325 24 P 0 ;1
L 8.5325 0.8825 8.5325 0.8825 24 P 0 ;1
L 8.5325 0.9325 8.5325 0.9325 24 P 0 ;1
L 8.5325 0.9825 8.5325 0.9825 24 P 0 ;1
L 8.5325 1.0325 8.5325 1.0325 24 P 0 ;1
L 8.5325 1.0825 8.5325 1.0825 24 P 0 ;1
L 8.5325 1.1325 8.5325 1.1325 24 P 0 ;1
L 8.5325 1.1825 8.5325 1.1825 24 P 0 ;1
L 8.5325 1.2325 8.5325 1.2325 24 P 0 ;1
L 8.5325 1.2825 8.5325 1.2825 24 P 0 ;1
L 8.5325 1.3325 8.5325 1.3325 24 P 0 ;1
L 8.5325 1.3825 8.5325 1.3825 24 P 0 ;1
L 8.5325 1.4325 8.5325 1.4325 24 P 0 ;1
L 8.5325 1.4825 8.5325 1.4825 24 P 0 ;1
L 8.5325 1.5325 8.5325 1.5325 24 P 0 ;1
L 8.5325 1.5825 8.5325 1.5825 24 P 0 ;1
L 8.5325 1.6325 8.5325 1.6325 24 P 0 ;1
L 8.5325 1.6825 8.5325 1.6825 24 P 0 ;1
L 8.5325 1.7325 8.5325 1.7325 24 P 0 ;1
L 8.5325 3.9825 8.5325 3.9825 24 P 0 ;1
L 8.5325 4.0325 8.5325 4.0325 24 P 0 ;1
L 8.5325 4.0825 8.5325 4.0825 24 P 0 ;1
L 8.5325 4.1325 8.5325 4.1325 24 P 0 ;1
L 8.5325 4.1825 8.5325 4.1825 24 P 0 ;1
L 8.5325 4.2325 8.5325 4.2325 24 P 0 ;1
L 8.5325 4.2825 8.5325 4.2825 24 P 0 ;1
L 8.5325 4.3325 8.5325 4.3325 24 P 0 ;1
L 8.5325 4.3825 8.5325 4.3825 24 P 0 ;1
L 8.5325 4.6825 8.5325 4.6825 24 P 0 ;1
L 8.5325 4.8825 8.5325 4.8825 24 P 0 ;1
L 8.5325 4.9325 8.5325 4.9325 24 P 0 ;1
L 8.5325 4.9825 8.5325 4.9825 24 P 0 ;1
L 8.5325 5.1325 8.5325 5.1325 24 P 0 ;1
L 8.5325 5.1825 8.5325 5.1825 24 P 0 ;1
L 8.5325 5.2325 8.5325 5.2325 24 P 0 ;1
L 8.5325 5.2825 8.5325 5.2825 24 P 0 ;1
L 8.5325 5.4825 8.5325 5.4825 24 P 0 ;1
L 8.5325 5.5325 8.5325 5.5325 24 P 0 ;1
L 8.5325 5.5825 8.5325 5.5825 24 P 0 ;1
L 8.5325 5.6325 8.5325 5.6325 24 P 0 ;1
L 8.5325 5.6825 8.5325 5.6825 24 P 0 ;1
L 8.5325 5.7325 8.5325 5.7325 24 P 0 ;1
L 8.5325 5.7825 8.5325 5.7825 24 P 0 ;1
L 8.5325 5.8325 8.5325 5.8325 24 P 0 ;1
L 8.5325 5.8825 8.5325 5.8825 24 P 0 ;1
L 8.5825 0.1325 8.5825 0.1325 24 P 0 ;1
L 8.5825 0.1825 8.5825 0.1825 24 P 0 ;1
L 8.5825 0.2325 8.5825 0.2325 24 P 0 ;1
L 8.5825 0.2825 8.5825 0.2825 24 P 0 ;1
L 8.5825 0.3325 8.5825 0.3325 24 P 0 ;1
L 8.5825 0.3825 8.5825 0.3825 24 P 0 ;1
L 8.5825 0.4325 8.5825 0.4325 24 P 0 ;1
L 8.5825 0.6825 8.5825 0.6825 24 P 0 ;1
L 8.5825 0.7325 8.5825 0.7325 24 P 0 ;1
L 8.5825 0.7825 8.5825 0.7825 24 P 0 ;1
L 8.5825 0.8325 8.5825 0.8325 24 P 0 ;1
L 8.5825 0.8825 8.5825 0.8825 24 P 0 ;1
L 8.5825 0.9325 8.5825 0.9325 24 P 0 ;1
L 8.5825 0.9825 8.5825 0.9825 24 P 0 ;1
L 8.5825 1.0325 8.5825 1.0325 24 P 0 ;1
L 8.5825 1.0825 8.5825 1.0825 24 P 0 ;1
L 8.5825 1.1325 8.5825 1.1325 24 P 0 ;1
L 8.5825 1.1825 8.5825 1.1825 24 P 0 ;1
L 8.5825 1.2325 8.5825 1.2325 24 P 0 ;1
L 8.5825 1.2825 8.5825 1.2825 24 P 0 ;1
L 8.5825 1.3325 8.5825 1.3325 24 P 0 ;1
L 8.5825 1.3825 8.5825 1.3825 24 P 0 ;1
L 8.5825 1.4325 8.5825 1.4325 24 P 0 ;1
L 8.5825 1.4825 8.5825 1.4825 24 P 0 ;1
L 8.5825 1.5325 8.5825 1.5325 24 P 0 ;1
L 8.5825 1.5825 8.5825 1.5825 24 P 0 ;1
L 8.5825 1.6325 8.5825 1.6325 24 P 0 ;1
L 8.5825 1.6825 8.5825 1.6825 24 P 0 ;1
L 8.5825 1.7325 8.5825 1.7325 24 P 0 ;1
L 8.5825 1.7825 8.5825 1.7825 24 P 0 ;1
L 8.5825 3.9325 8.5825 3.9325 24 P 0 ;1
L 8.5825 3.9825 8.5825 3.9825 24 P 0 ;1
L 8.5825 4.0325 8.5825 4.0325 24 P 0 ;1
L 8.5825 4.0825 8.5825 4.0825 24 P 0 ;1
L 8.5825 4.1325 8.5825 4.1325 24 P 0 ;1
L 8.5825 4.1825 8.5825 4.1825 24 P 0 ;1
L 8.5825 4.2325 8.5825 4.2325 24 P 0 ;1
L 8.5825 4.2825 8.5825 4.2825 24 P 0 ;1
L 8.5825 4.3325 8.5825 4.3325 24 P 0 ;1
L 8.5825 4.3825 8.5825 4.3825 24 P 0 ;1
L 8.5825 4.6825 8.5825 4.6825 24 P 0 ;1
L 8.5825 4.7325 8.5825 4.7325 24 P 0 ;1
L 8.5825 4.8325 8.5825 4.8325 24 P 0 ;1
L 8.5825 4.8825 8.5825 4.8825 24 P 0 ;1
L 8.5825 4.9325 8.5825 4.9325 24 P 0 ;1
L 8.5825 4.9825 8.5825 4.9825 24 P 0 ;1
L 8.5825 5.0325 8.5825 5.0325 24 P 0 ;1
L 8.5825 5.0825 8.5825 5.0825 24 P 0 ;1
L 8.5825 5.1325 8.5825 5.1325 24 P 0 ;1
L 8.5825 5.1825 8.5825 5.1825 24 P 0 ;1
L 8.5825 5.2325 8.5825 5.2325 24 P 0 ;1
L 8.5825 5.2825 8.5825 5.2825 24 P 0 ;1
L 8.5825 5.4825 8.5825 5.4825 24 P 0 ;1
L 8.5825 5.5325 8.5825 5.5325 24 P 0 ;1
L 8.5825 5.5825 8.5825 5.5825 24 P 0 ;1
L 8.5825 5.6325 8.5825 5.6325 24 P 0 ;1
L 8.5825 5.6825 8.5825 5.6825 24 P 0 ;1
L 8.5825 5.7325 8.5825 5.7325 24 P 0 ;1
L 8.5825 5.7825 8.5825 5.7825 24 P 0 ;1
L 8.5825 5.8325 8.5825 5.8325 24 P 0 ;1
L 8.5825 5.8825 8.5825 5.8825 24 P 0 ;1
L 8.6325 0.1325 8.6325 0.1325 24 P 0 ;1
L 8.6325 0.1825 8.6325 0.1825 24 P 0 ;1
L 8.6325 0.2325 8.6325 0.2325 24 P 0 ;1
L 8.6325 0.2825 8.6325 0.2825 24 P 0 ;1
L 8.6325 0.3325 8.6325 0.3325 24 P 0 ;1
L 8.6325 0.3825 8.6325 0.3825 24 P 0 ;1
L 8.6325 0.4325 8.6325 0.4325 24 P 0 ;1
L 8.6325 0.6825 8.6325 0.6825 24 P 0 ;1
L 8.6325 0.7325 8.6325 0.7325 24 P 0 ;1
L 8.6325 0.7825 8.6325 0.7825 24 P 0 ;1
L 8.6325 0.8325 8.6325 0.8325 24 P 0 ;1
L 8.6325 0.8825 8.6325 0.8825 24 P 0 ;1
L 8.6325 0.9325 8.6325 0.9325 24 P 0 ;1
L 8.6325 0.9825 8.6325 0.9825 24 P 0 ;1
L 8.6325 1.0325 8.6325 1.0325 24 P 0 ;1
L 8.6325 1.0825 8.6325 1.0825 24 P 0 ;1
L 8.6325 1.1325 8.6325 1.1325 24 P 0 ;1
L 8.6325 1.1825 8.6325 1.1825 24 P 0 ;1
L 8.6325 1.2325 8.6325 1.2325 24 P 0 ;1
L 8.6325 1.2825 8.6325 1.2825 24 P 0 ;1
L 8.6325 1.3325 8.6325 1.3325 24 P 0 ;1
L 8.6325 1.3825 8.6325 1.3825 24 P 0 ;1
L 8.6325 1.4325 8.6325 1.4325 24 P 0 ;1
L 8.6325 1.4825 8.6325 1.4825 24 P 0 ;1
L 8.6325 1.5325 8.6325 1.5325 24 P 0 ;1
L 8.6325 1.5825 8.6325 1.5825 24 P 0 ;1
L 8.6325 1.6325 8.6325 1.6325 24 P 0 ;1
L 8.6325 1.6825 8.6325 1.6825 24 P 0 ;1
L 8.6325 1.7325 8.6325 1.7325 24 P 0 ;1
L 8.6325 1.7825 8.6325 1.7825 24 P 0 ;1
L 8.6325 1.8325 8.6325 1.8325 24 P 0 ;1
L 8.6325 1.8825 8.6325 1.8825 24 P 0 ;1
L 8.6325 1.9325 8.6325 1.9325 24 P 0 ;1
L 8.6325 1.9825 8.6325 1.9825 24 P 0 ;1
L 8.6325 2.0325 8.6325 2.0325 24 P 0 ;1
L 8.6325 2.0825 8.6325 2.0825 24 P 0 ;1
L 8.6325 2.1325 8.6325 2.1325 24 P 0 ;1
L 8.6325 2.1825 8.6325 2.1825 24 P 0 ;1
L 8.6325 2.2325 8.6325 2.2325 24 P 0 ;1
L 8.6325 2.2825 8.6325 2.2825 24 P 0 ;1
L 8.6325 2.3325 8.6325 2.3325 24 P 0 ;1
L 8.6325 2.3825 8.6325 2.3825 24 P 0 ;1
L 8.6325 2.4325 8.6325 2.4325 24 P 0 ;1
L 8.6325 2.4825 8.6325 2.4825 24 P 0 ;1
L 8.6325 2.5325 8.6325 2.5325 24 P 0 ;1
L 8.6325 2.5825 8.6325 2.5825 24 P 0 ;1
L 8.6325 2.6325 8.6325 2.6325 24 P 0 ;1
L 8.6325 2.6825 8.6325 2.6825 24 P 0 ;1
L 8.6325 2.9825 8.6325 2.9825 24 P 0 ;1
L 8.6325 3.0325 8.6325 3.0325 24 P 0 ;1
L 8.6325 3.0825 8.6325 3.0825 24 P 0 ;1
L 8.6325 3.1325 8.6325 3.1325 24 P 0 ;1
L 8.6325 3.1825 8.6325 3.1825 24 P 0 ;1
L 8.6325 3.2325 8.6325 3.2325 24 P 0 ;1
L 8.6325 3.2825 8.6325 3.2825 24 P 0 ;1
L 8.6325 3.3325 8.6325 3.3325 24 P 0 ;1
L 8.6325 3.3825 8.6325 3.3825 24 P 0 ;1
L 8.6325 3.4325 8.6325 3.4325 24 P 0 ;1
L 8.6325 3.4825 8.6325 3.4825 24 P 0 ;1
L 8.6325 3.5325 8.6325 3.5325 24 P 0 ;1
L 8.6325 3.5825 8.6325 3.5825 24 P 0 ;1
L 8.6325 3.6325 8.6325 3.6325 24 P 0 ;1
L 8.6325 3.6825 8.6325 3.6825 24 P 0 ;1
L 8.6325 3.7325 8.6325 3.7325 24 P 0 ;1
L 8.6325 3.7825 8.6325 3.7825 24 P 0 ;1
L 8.6325 3.8325 8.6325 3.8325 24 P 0 ;1
L 8.6325 3.8825 8.6325 3.8825 24 P 0 ;1
L 8.6325 3.9325 8.6325 3.9325 24 P 0 ;1
L 8.6325 3.9825 8.6325 3.9825 24 P 0 ;1
L 8.6325 4.0325 8.6325 4.0325 24 P 0 ;1
L 8.6325 4.0825 8.6325 4.0825 24 P 0 ;1
L 8.6325 4.1325 8.6325 4.1325 24 P 0 ;1
L 8.6325 4.1825 8.6325 4.1825 24 P 0 ;1
L 8.6325 4.2325 8.6325 4.2325 24 P 0 ;1
L 8.6325 4.2825 8.6325 4.2825 24 P 0 ;1
L 8.6325 4.3325 8.6325 4.3325 24 P 0 ;1
L 8.6325 4.3825 8.6325 4.3825 24 P 0 ;1
L 8.6325 4.6825 8.6325 4.6825 24 P 0 ;1
L 8.6325 5.1825 8.6325 5.1825 24 P 0 ;1
L 8.6325 5.2325 8.6325 5.2325 24 P 0 ;1
L 8.6325 5.2825 8.6325 5.2825 24 P 0 ;1
L 8.6325 5.4825 8.6325 5.4825 24 P 0 ;1
L 8.6325 5.5325 8.6325 5.5325 24 P 0 ;1
L 8.6325 5.5825 8.6325 5.5825 24 P 0 ;1
L 8.6325 5.6325 8.6325 5.6325 24 P 0 ;1
L 8.6325 5.6825 8.6325 5.6825 24 P 0 ;1
L 8.6325 5.7325 8.6325 5.7325 24 P 0 ;1
L 8.6325 5.7825 8.6325 5.7825 24 P 0 ;1
L 8.6325 5.8325 8.6325 5.8325 24 P 0 ;1
L 8.6325 5.8825 8.6325 5.8825 24 P 0 ;1
L 8.6825 0.1325 8.6825 0.1325 24 P 0 ;1
L 8.6825 0.1825 8.6825 0.1825 24 P 0 ;1
L 8.6825 0.2325 8.6825 0.2325 24 P 0 ;1
L 8.6825 0.2825 8.6825 0.2825 24 P 0 ;1
L 8.6825 0.3325 8.6825 0.3325 24 P 0 ;1
L 8.6825 0.3825 8.6825 0.3825 24 P 0 ;1
L 8.6825 0.4325 8.6825 0.4325 24 P 0 ;1
L 8.6825 0.6825 8.6825 0.6825 24 P 0 ;1
L 8.6825 0.7325 8.6825 0.7325 24 P 0 ;1
L 8.6825 0.7825 8.6825 0.7825 24 P 0 ;1
L 8.6825 0.8325 8.6825 0.8325 24 P 0 ;1
L 8.6825 0.8825 8.6825 0.8825 24 P 0 ;1
L 8.6825 0.9325 8.6825 0.9325 24 P 0 ;1
L 8.6825 0.9825 8.6825 0.9825 24 P 0 ;1
L 8.6825 1.0325 8.6825 1.0325 24 P 0 ;1
L 8.6825 1.0825 8.6825 1.0825 24 P 0 ;1
L 8.6825 1.1325 8.6825 1.1325 24 P 0 ;1
L 8.6825 1.1825 8.6825 1.1825 24 P 0 ;1
L 8.6825 1.2325 8.6825 1.2325 24 P 0 ;1
L 8.6825 1.2825 8.6825 1.2825 24 P 0 ;1
L 8.6825 1.3325 8.6825 1.3325 24 P 0 ;1
L 8.6825 1.3825 8.6825 1.3825 24 P 0 ;1
L 8.6825 1.4325 8.6825 1.4325 24 P 0 ;1
L 8.6825 1.4825 8.6825 1.4825 24 P 0 ;1
L 8.6825 1.5325 8.6825 1.5325 24 P 0 ;1
L 8.6825 1.5825 8.6825 1.5825 24 P 0 ;1
L 8.6825 1.6325 8.6825 1.6325 24 P 0 ;1
L 8.6825 1.6825 8.6825 1.6825 24 P 0 ;1
L 8.6825 1.7325 8.6825 1.7325 24 P 0 ;1
L 8.6825 1.7825 8.6825 1.7825 24 P 0 ;1
L 8.6825 1.8325 8.6825 1.8325 24 P 0 ;1
L 8.6825 1.8825 8.6825 1.8825 24 P 0 ;1
L 8.6825 1.9325 8.6825 1.9325 24 P 0 ;1
L 8.6825 1.9825 8.6825 1.9825 24 P 0 ;1
L 8.6825 2.0325 8.6825 2.0325 24 P 0 ;1
L 8.6825 2.0825 8.6825 2.0825 24 P 0 ;1
L 8.6825 2.1325 8.6825 2.1325 24 P 0 ;1
L 8.6825 2.1825 8.6825 2.1825 24 P 0 ;1
L 8.6825 2.2325 8.6825 2.2325 24 P 0 ;1
L 8.6825 2.2825 8.6825 2.2825 24 P 0 ;1
L 8.6825 2.3325 8.6825 2.3325 24 P 0 ;1
L 8.6825 2.3825 8.6825 2.3825 24 P 0 ;1
L 8.6825 2.4325 8.6825 2.4325 24 P 0 ;1
L 8.6825 2.4825 8.6825 2.4825 24 P 0 ;1
L 8.6825 2.5325 8.6825 2.5325 24 P 0 ;1
L 8.6825 2.5825 8.6825 2.5825 24 P 0 ;1
L 8.6825 2.6325 8.6825 2.6325 24 P 0 ;1
L 8.6825 2.6825 8.6825 2.6825 24 P 0 ;1
L 8.6825 2.9825 8.6825 2.9825 24 P 0 ;1
L 8.6825 3.0325 8.6825 3.0325 24 P 0 ;1
L 8.6825 3.0825 8.6825 3.0825 24 P 0 ;1
L 8.6825 3.1325 8.6825 3.1325 24 P 0 ;1
L 8.6825 3.1825 8.6825 3.1825 24 P 0 ;1
L 8.6825 3.2325 8.6825 3.2325 24 P 0 ;1
L 8.6825 3.2825 8.6825 3.2825 24 P 0 ;1
L 8.6825 3.3325 8.6825 3.3325 24 P 0 ;1
L 8.6825 3.3825 8.6825 3.3825 24 P 0 ;1
L 8.6825 3.4325 8.6825 3.4325 24 P 0 ;1
L 8.6825 3.4825 8.6825 3.4825 24 P 0 ;1
L 8.6825 3.5325 8.6825 3.5325 24 P 0 ;1
L 8.6825 3.5825 8.6825 3.5825 24 P 0 ;1
L 8.6825 3.6325 8.6825 3.6325 24 P 0 ;1
L 8.6825 3.6825 8.6825 3.6825 24 P 0 ;1
L 8.6825 3.7325 8.6825 3.7325 24 P 0 ;1
L 8.6825 3.7825 8.6825 3.7825 24 P 0 ;1
L 8.6825 3.8325 8.6825 3.8325 24 P 0 ;1
L 8.6825 3.8825 8.6825 3.8825 24 P 0 ;1
L 8.6825 3.9325 8.6825 3.9325 24 P 0 ;1
L 8.6825 3.9825 8.6825 3.9825 24 P 0 ;1
L 8.6825 4.0325 8.6825 4.0325 24 P 0 ;1
L 8.6825 4.0825 8.6825 4.0825 24 P 0 ;1
L 8.6825 4.1325 8.6825 4.1325 24 P 0 ;1
L 8.6825 4.1825 8.6825 4.1825 24 P 0 ;1
L 8.6825 4.2325 8.6825 4.2325 24 P 0 ;1
L 8.6825 4.2825 8.6825 4.2825 24 P 0 ;1
L 8.6825 4.3325 8.6825 4.3325 24 P 0 ;1
L 8.6825 4.3825 8.6825 4.3825 24 P 0 ;1
L 8.6825 5.2825 8.6825 5.2825 24 P 0 ;1
L 8.6825 5.4825 8.6825 5.4825 24 P 0 ;1
L 8.6825 5.5325 8.6825 5.5325 24 P 0 ;1
L 8.6825 5.5825 8.6825 5.5825 24 P 0 ;1
L 8.6825 5.6325 8.6825 5.6325 24 P 0 ;1
L 8.6825 5.6825 8.6825 5.6825 24 P 0 ;1
L 8.6825 5.7325 8.6825 5.7325 24 P 0 ;1
L 8.6825 5.7825 8.6825 5.7825 24 P 0 ;1
L 8.6825 5.8325 8.6825 5.8325 24 P 0 ;1
L 8.6825 5.8825 8.6825 5.8825 24 P 0 ;1
L 8.7325 0.1325 8.7325 0.1325 24 P 0 ;1
L 8.7325 0.1825 8.7325 0.1825 24 P 0 ;1
L 8.7325 0.2325 8.7325 0.2325 24 P 0 ;1
L 8.7325 0.2825 8.7325 0.2825 24 P 0 ;1
L 8.7325 0.3325 8.7325 0.3325 24 P 0 ;1
L 8.7325 0.3825 8.7325 0.3825 24 P 0 ;1
L 8.7325 0.4325 8.7325 0.4325 24 P 0 ;1
L 8.7325 0.6825 8.7325 0.6825 24 P 0 ;1
L 8.7325 0.7325 8.7325 0.7325 24 P 0 ;1
L 8.7325 0.7825 8.7325 0.7825 24 P 0 ;1
L 8.7325 0.8325 8.7325 0.8325 24 P 0 ;1
L 8.7325 0.8825 8.7325 0.8825 24 P 0 ;1
L 8.7325 0.9325 8.7325 0.9325 24 P 0 ;1
L 8.7325 0.9825 8.7325 0.9825 24 P 0 ;1
L 8.7325 1.0325 8.7325 1.0325 24 P 0 ;1
L 8.7325 1.0825 8.7325 1.0825 24 P 0 ;1
L 8.7325 1.1325 8.7325 1.1325 24 P 0 ;1
L 8.7325 1.1825 8.7325 1.1825 24 P 0 ;1
L 8.7325 1.2325 8.7325 1.2325 24 P 0 ;1
L 8.7325 1.2825 8.7325 1.2825 24 P 0 ;1
L 8.7325 1.3325 8.7325 1.3325 24 P 0 ;1
L 8.7325 1.3825 8.7325 1.3825 24 P 0 ;1
L 8.7325 1.4325 8.7325 1.4325 24 P 0 ;1
L 8.7325 1.4825 8.7325 1.4825 24 P 0 ;1
L 8.7325 1.5325 8.7325 1.5325 24 P 0 ;1
L 8.7325 1.5825 8.7325 1.5825 24 P 0 ;1
L 8.7325 1.6325 8.7325 1.6325 24 P 0 ;1
L 8.7325 1.6825 8.7325 1.6825 24 P 0 ;1
L 8.7325 1.7325 8.7325 1.7325 24 P 0 ;1
L 8.7325 1.7825 8.7325 1.7825 24 P 0 ;1
L 8.7325 1.8325 8.7325 1.8325 24 P 0 ;1
L 8.7325 1.8825 8.7325 1.8825 24 P 0 ;1
L 8.7325 1.9325 8.7325 1.9325 24 P 0 ;1
L 8.7325 1.9825 8.7325 1.9825 24 P 0 ;1
L 8.7325 2.0325 8.7325 2.0325 24 P 0 ;1
L 8.7325 2.0825 8.7325 2.0825 24 P 0 ;1
L 8.7325 2.1325 8.7325 2.1325 24 P 0 ;1
L 8.7325 2.1825 8.7325 2.1825 24 P 0 ;1
L 8.7325 2.2325 8.7325 2.2325 24 P 0 ;1
L 8.7325 2.2825 8.7325 2.2825 24 P 0 ;1
L 8.7325 2.3325 8.7325 2.3325 24 P 0 ;1
L 8.7325 2.3825 8.7325 2.3825 24 P 0 ;1
L 8.7325 2.4325 8.7325 2.4325 24 P 0 ;1
L 8.7325 2.4825 8.7325 2.4825 24 P 0 ;1
L 8.7325 2.5325 8.7325 2.5325 24 P 0 ;1
L 8.7325 2.5825 8.7325 2.5825 24 P 0 ;1
L 8.7325 2.6325 8.7325 2.6325 24 P 0 ;1
L 8.7325 2.6825 8.7325 2.6825 24 P 0 ;1
L 8.7325 2.7325 8.7325 2.7325 24 P 0 ;1
L 8.7325 2.9825 8.7325 2.9825 24 P 0 ;1
L 8.7325 3.0325 8.7325 3.0325 24 P 0 ;1
L 8.7325 3.0825 8.7325 3.0825 24 P 0 ;1
L 8.7325 3.1325 8.7325 3.1325 24 P 0 ;1
L 8.7325 3.1825 8.7325 3.1825 24 P 0 ;1
L 8.7325 3.2325 8.7325 3.2325 24 P 0 ;1
L 8.7325 3.2825 8.7325 3.2825 24 P 0 ;1
L 8.7325 3.3325 8.7325 3.3325 24 P 0 ;1
L 8.7325 3.3825 8.7325 3.3825 24 P 0 ;1
L 8.7325 3.4325 8.7325 3.4325 24 P 0 ;1
L 8.7325 3.4825 8.7325 3.4825 24 P 0 ;1
L 8.7325 3.5325 8.7325 3.5325 24 P 0 ;1
L 8.7325 3.5825 8.7325 3.5825 24 P 0 ;1
L 8.7325 3.6325 8.7325 3.6325 24 P 0 ;1
L 8.7325 3.6825 8.7325 3.6825 24 P 0 ;1
L 8.7325 3.7325 8.7325 3.7325 24 P 0 ;1
L 8.7325 3.7825 8.7325 3.7825 24 P 0 ;1
L 8.7325 3.8325 8.7325 3.8325 24 P 0 ;1
L 8.7325 3.8825 8.7325 3.8825 24 P 0 ;1
L 8.7325 3.9325 8.7325 3.9325 24 P 0 ;1
L 8.7325 3.9825 8.7325 3.9825 24 P 0 ;1
L 8.7325 4.0325 8.7325 4.0325 24 P 0 ;1
L 8.7325 4.0825 8.7325 4.0825 24 P 0 ;1
L 8.7325 4.1325 8.7325 4.1325 24 P 0 ;1
L 8.7325 4.1825 8.7325 4.1825 24 P 0 ;1
L 8.7325 4.2325 8.7325 4.2325 24 P 0 ;1
L 8.7325 4.2825 8.7325 4.2825 24 P 0 ;1
L 8.7325 4.3325 8.7325 4.3325 24 P 0 ;1
L 8.7325 4.3825 8.7325 4.3825 24 P 0 ;1
L 8.7325 5.2825 8.7325 5.2825 24 P 0 ;1
L 8.7325 5.4825 8.7325 5.4825 24 P 0 ;1
L 8.7325 5.5325 8.7325 5.5325 24 P 0 ;1
L 8.7325 5.5825 8.7325 5.5825 24 P 0 ;1
L 8.7325 5.6325 8.7325 5.6325 24 P 0 ;1
L 8.7325 5.6825 8.7325 5.6825 24 P 0 ;1
L 8.7325 5.7325 8.7325 5.7325 24 P 0 ;1
L 8.7325 5.7825 8.7325 5.7825 24 P 0 ;1
L 8.7325 5.8325 8.7325 5.8325 24 P 0 ;1
L 8.7325 5.8825 8.7325 5.8825 24 P 0 ;1
L 8.7825 0.1325 8.7825 0.1325 24 P 0 ;1
L 8.7825 0.1825 8.7825 0.1825 24 P 0 ;1
L 8.7825 0.2325 8.7825 0.2325 24 P 0 ;1
L 8.7825 0.2825 8.7825 0.2825 24 P 0 ;1
L 8.7825 0.3325 8.7825 0.3325 24 P 0 ;1
L 8.7825 0.3825 8.7825 0.3825 24 P 0 ;1
L 8.7825 0.4325 8.7825 0.4325 24 P 0 ;1
L 8.7825 0.6825 8.7825 0.6825 24 P 0 ;1
L 8.7825 0.7325 8.7825 0.7325 24 P 0 ;1
L 8.7825 0.7825 8.7825 0.7825 24 P 0 ;1
L 8.7825 0.8325 8.7825 0.8325 24 P 0 ;1
L 8.7825 0.8825 8.7825 0.8825 24 P 0 ;1
L 8.7825 0.9325 8.7825 0.9325 24 P 0 ;1
L 8.7825 0.9825 8.7825 0.9825 24 P 0 ;1
L 8.7825 1.0325 8.7825 1.0325 24 P 0 ;1
L 8.7825 1.0825 8.7825 1.0825 24 P 0 ;1
L 8.7825 1.1325 8.7825 1.1325 24 P 0 ;1
L 8.7825 1.1825 8.7825 1.1825 24 P 0 ;1
L 8.7825 1.2325 8.7825 1.2325 24 P 0 ;1
L 8.7825 1.2825 8.7825 1.2825 24 P 0 ;1
L 8.7825 1.3325 8.7825 1.3325 24 P 0 ;1
L 8.7825 1.3825 8.7825 1.3825 24 P 0 ;1
L 8.7825 1.4325 8.7825 1.4325 24 P 0 ;1
L 8.7825 1.4825 8.7825 1.4825 24 P 0 ;1
L 8.7825 1.5325 8.7825 1.5325 24 P 0 ;1
L 8.7825 1.5825 8.7825 1.5825 24 P 0 ;1
L 8.7825 1.6325 8.7825 1.6325 24 P 0 ;1
L 8.7825 1.6825 8.7825 1.6825 24 P 0 ;1
L 8.7825 1.7325 8.7825 1.7325 24 P 0 ;1
L 8.7825 1.7825 8.7825 1.7825 24 P 0 ;1
L 8.7825 1.8325 8.7825 1.8325 24 P 0 ;1
L 8.7825 1.8825 8.7825 1.8825 24 P 0 ;1
L 8.7825 1.9325 8.7825 1.9325 24 P 0 ;1
L 8.7825 1.9825 8.7825 1.9825 24 P 0 ;1
L 8.7825 2.0325 8.7825 2.0325 24 P 0 ;1
L 8.7825 2.0825 8.7825 2.0825 24 P 0 ;1
L 8.7825 2.1325 8.7825 2.1325 24 P 0 ;1
L 8.7825 2.1825 8.7825 2.1825 24 P 0 ;1
L 8.7825 2.2325 8.7825 2.2325 24 P 0 ;1
L 8.7825 2.2825 8.7825 2.2825 24 P 0 ;1
L 8.7825 2.3325 8.7825 2.3325 24 P 0 ;1
L 8.7825 2.3825 8.7825 2.3825 24 P 0 ;1
L 8.7825 2.4325 8.7825 2.4325 24 P 0 ;1
L 8.7825 2.4825 8.7825 2.4825 24 P 0 ;1
L 8.7825 2.5325 8.7825 2.5325 24 P 0 ;1
L 8.7825 2.5825 8.7825 2.5825 24 P 0 ;1
L 8.7825 2.6325 8.7825 2.6325 24 P 0 ;1
L 8.7825 2.6825 8.7825 2.6825 24 P 0 ;1
L 8.7825 2.7325 8.7825 2.7325 24 P 0 ;1
L 8.7825 2.9825 8.7825 2.9825 24 P 0 ;1
L 8.7825 3.0325 8.7825 3.0325 24 P 0 ;1
L 8.7825 3.0825 8.7825 3.0825 24 P 0 ;1
L 8.7825 3.1325 8.7825 3.1325 24 P 0 ;1
L 8.7825 3.1825 8.7825 3.1825 24 P 0 ;1
L 8.7825 3.2325 8.7825 3.2325 24 P 0 ;1
L 8.7825 3.2825 8.7825 3.2825 24 P 0 ;1
L 8.7825 3.3325 8.7825 3.3325 24 P 0 ;1
L 8.7825 3.3825 8.7825 3.3825 24 P 0 ;1
L 8.7825 3.4325 8.7825 3.4325 24 P 0 ;1
L 8.7825 3.4825 8.7825 3.4825 24 P 0 ;1
L 8.7825 3.5325 8.7825 3.5325 24 P 0 ;1
L 8.7825 3.5825 8.7825 3.5825 24 P 0 ;1
L 8.7825 3.6325 8.7825 3.6325 24 P 0 ;1
L 8.7825 3.6825 8.7825 3.6825 24 P 0 ;1
L 8.7825 3.7325 8.7825 3.7325 24 P 0 ;1
L 8.7825 3.7825 8.7825 3.7825 24 P 0 ;1
L 8.7825 3.8325 8.7825 3.8325 24 P 0 ;1
L 8.7825 3.8825 8.7825 3.8825 24 P 0 ;1
L 8.7825 3.9325 8.7825 3.9325 24 P 0 ;1
L 8.7825 3.9825 8.7825 3.9825 24 P 0 ;1
L 8.7825 4.0325 8.7825 4.0325 24 P 0 ;1
L 8.7825 4.0825 8.7825 4.0825 24 P 0 ;1
L 8.7825 4.1325 8.7825 4.1325 24 P 0 ;1
L 8.7825 4.1825 8.7825 4.1825 24 P 0 ;1
L 8.7825 4.2325 8.7825 4.2325 24 P 0 ;1
L 8.7825 4.2825 8.7825 4.2825 24 P 0 ;1
L 8.7825 4.3325 8.7825 4.3325 24 P 0 ;1
L 8.7825 4.3825 8.7825 4.3825 24 P 0 ;1
L 8.7825 5.2825 8.7825 5.2825 24 P 0 ;1
L 8.7825 5.4825 8.7825 5.4825 24 P 0 ;1
L 8.7825 5.5325 8.7825 5.5325 24 P 0 ;1
L 8.7825 5.5825 8.7825 5.5825 24 P 0 ;1
L 8.7825 5.6325 8.7825 5.6325 24 P 0 ;1
L 8.7825 5.6825 8.7825 5.6825 24 P 0 ;1
L 8.7825 5.7325 8.7825 5.7325 24 P 0 ;1
L 8.7825 5.7825 8.7825 5.7825 24 P 0 ;1
L 8.7825 5.8325 8.7825 5.8325 24 P 0 ;1
L 8.7825 5.8825 8.7825 5.8825 24 P 0 ;1
L 8.8325 0.1325 8.8325 0.1325 24 P 0 ;1
L 8.8325 0.1825 8.8325 0.1825 24 P 0 ;1
L 8.8325 0.2325 8.8325 0.2325 24 P 0 ;1
L 8.8325 0.2825 8.8325 0.2825 24 P 0 ;1
L 8.8325 0.3325 8.8325 0.3325 24 P 0 ;1
L 8.8325 0.3825 8.8325 0.3825 24 P 0 ;1
L 8.8325 0.4325 8.8325 0.4325 24 P 0 ;1
L 8.8325 0.6825 8.8325 0.6825 24 P 0 ;1
L 8.8325 0.7325 8.8325 0.7325 24 P 0 ;1
L 8.8325 0.7825 8.8325 0.7825 24 P 0 ;1
L 8.8325 0.8325 8.8325 0.8325 24 P 0 ;1
L 8.8325 0.8825 8.8325 0.8825 24 P 0 ;1
L 8.8325 0.9325 8.8325 0.9325 24 P 0 ;1
L 8.8325 0.9825 8.8325 0.9825 24 P 0 ;1
L 8.8325 1.0325 8.8325 1.0325 24 P 0 ;1
L 8.8325 1.0825 8.8325 1.0825 24 P 0 ;1
L 8.8325 1.1325 8.8325 1.1325 24 P 0 ;1
L 8.8325 1.1825 8.8325 1.1825 24 P 0 ;1
L 8.8325 1.2325 8.8325 1.2325 24 P 0 ;1
L 8.8325 1.2825 8.8325 1.2825 24 P 0 ;1
L 8.8325 1.3325 8.8325 1.3325 24 P 0 ;1
L 8.8325 1.3825 8.8325 1.3825 24 P 0 ;1
L 8.8325 1.4325 8.8325 1.4325 24 P 0 ;1
L 8.8325 1.4825 8.8325 1.4825 24 P 0 ;1
L 8.8325 1.5325 8.8325 1.5325 24 P 0 ;1
L 8.8325 1.5825 8.8325 1.5825 24 P 0 ;1
L 8.8325 1.6325 8.8325 1.6325 24 P 0 ;1
L 8.8325 1.6825 8.8325 1.6825 24 P 0 ;1
L 8.8325 1.7325 8.8325 1.7325 24 P 0 ;1
L 8.8325 1.7825 8.8325 1.7825 24 P 0 ;1
L 8.8325 1.8325 8.8325 1.8325 24 P 0 ;1
L 8.8325 1.8825 8.8325 1.8825 24 P 0 ;1
L 8.8325 1.9325 8.8325 1.9325 24 P 0 ;1
L 8.8325 1.9825 8.8325 1.9825 24 P 0 ;1
L 8.8325 2.0325 8.8325 2.0325 24 P 0 ;1
L 8.8325 2.0825 8.8325 2.0825 24 P 0 ;1
L 8.8325 2.1325 8.8325 2.1325 24 P 0 ;1
L 8.8325 2.1825 8.8325 2.1825 24 P 0 ;1
L 8.8325 2.2325 8.8325 2.2325 24 P 0 ;1
L 8.8325 2.2825 8.8325 2.2825 24 P 0 ;1
L 8.8325 2.3325 8.8325 2.3325 24 P 0 ;1
L 8.8325 2.3825 8.8325 2.3825 24 P 0 ;1
L 8.8325 2.4325 8.8325 2.4325 24 P 0 ;1
L 8.8325 2.4825 8.8325 2.4825 24 P 0 ;1
L 8.8325 2.5325 8.8325 2.5325 24 P 0 ;1
L 8.8325 2.5825 8.8325 2.5825 24 P 0 ;1
L 8.8325 2.6325 8.8325 2.6325 24 P 0 ;1
L 8.8325 2.6825 8.8325 2.6825 24 P 0 ;1
L 8.8325 2.7325 8.8325 2.7325 24 P 0 ;1
L 8.8325 2.9825 8.8325 2.9825 24 P 0 ;1
L 8.8325 3.0325 8.8325 3.0325 24 P 0 ;1
L 8.8325 3.0825 8.8325 3.0825 24 P 0 ;1
L 8.8325 3.1325 8.8325 3.1325 24 P 0 ;1
L 8.8325 3.1825 8.8325 3.1825 24 P 0 ;1
L 8.8325 3.2325 8.8325 3.2325 24 P 0 ;1
L 8.8325 3.2825 8.8325 3.2825 24 P 0 ;1
L 8.8325 3.3325 8.8325 3.3325 24 P 0 ;1
L 8.8325 3.3825 8.8325 3.3825 24 P 0 ;1
L 8.8325 3.4325 8.8325 3.4325 24 P 0 ;1
L 8.8325 3.4825 8.8325 3.4825 24 P 0 ;1
L 8.8325 3.5325 8.8325 3.5325 24 P 0 ;1
L 8.8325 3.5825 8.8325 3.5825 24 P 0 ;1
L 8.8325 3.6325 8.8325 3.6325 24 P 0 ;1
L 8.8325 3.6825 8.8325 3.6825 24 P 0 ;1
L 8.8325 3.7325 8.8325 3.7325 24 P 0 ;1
L 8.8325 3.7825 8.8325 3.7825 24 P 0 ;1
L 8.8325 3.8325 8.8325 3.8325 24 P 0 ;1
L 8.8325 3.8825 8.8325 3.8825 24 P 0 ;1
L 8.8325 3.9325 8.8325 3.9325 24 P 0 ;1
L 8.8325 3.9825 8.8325 3.9825 24 P 0 ;1
L 8.8325 4.0325 8.8325 4.0325 24 P 0 ;1
L 8.8325 4.0825 8.8325 4.0825 24 P 0 ;1
L 8.8325 4.1325 8.8325 4.1325 24 P 0 ;1
L 8.8325 4.1825 8.8325 4.1825 24 P 0 ;1
L 8.8325 4.2325 8.8325 4.2325 24 P 0 ;1
L 8.8325 4.2825 8.8325 4.2825 24 P 0 ;1
L 8.8325 4.3325 8.8325 4.3325 24 P 0 ;1
L 8.8325 4.3825 8.8325 4.3825 24 P 0 ;1
L 8.8325 5.4825 8.8325 5.4825 24 P 0 ;1
L 8.8325 5.5325 8.8325 5.5325 24 P 0 ;1
L 8.8325 5.5825 8.8325 5.5825 24 P 0 ;1
L 8.8325 5.6325 8.8325 5.6325 24 P 0 ;1
L 8.8325 5.6825 8.8325 5.6825 24 P 0 ;1
L 8.8325 5.7325 8.8325 5.7325 24 P 0 ;1
L 8.8325 5.7825 8.8325 5.7825 24 P 0 ;1
L 8.8325 5.8325 8.8325 5.8325 24 P 0 ;1
L 8.8325 5.8825 8.8325 5.8825 24 P 0 ;1
L 8.8825 0.1325 8.8825 0.1325 24 P 0 ;1
L 8.8825 0.1825 8.8825 0.1825 24 P 0 ;1
L 8.8825 0.2325 8.8825 0.2325 24 P 0 ;1
L 8.8825 0.2825 8.8825 0.2825 24 P 0 ;1
L 8.8825 0.3325 8.8825 0.3325 24 P 0 ;1
L 8.8825 0.3825 8.8825 0.3825 24 P 0 ;1
L 8.8825 0.4325 8.8825 0.4325 24 P 0 ;1
L 8.8825 0.6825 8.8825 0.6825 24 P 0 ;1
L 8.8825 0.7325 8.8825 0.7325 24 P 0 ;1
L 8.8825 0.7825 8.8825 0.7825 24 P 0 ;1
L 8.8825 0.8325 8.8825 0.8325 24 P 0 ;1
L 8.8825 0.8825 8.8825 0.8825 24 P 0 ;1
L 8.8825 0.9325 8.8825 0.9325 24 P 0 ;1
L 8.8825 0.9825 8.8825 0.9825 24 P 0 ;1
L 8.8825 1.0325 8.8825 1.0325 24 P 0 ;1
L 8.8825 1.0825 8.8825 1.0825 24 P 0 ;1
L 8.8825 1.1325 8.8825 1.1325 24 P 0 ;1
L 8.8825 1.1825 8.8825 1.1825 24 P 0 ;1
L 8.8825 1.2325 8.8825 1.2325 24 P 0 ;1
L 8.8825 1.2825 8.8825 1.2825 24 P 0 ;1
L 8.8825 1.3325 8.8825 1.3325 24 P 0 ;1
L 8.8825 1.3825 8.8825 1.3825 24 P 0 ;1
L 8.8825 1.4325 8.8825 1.4325 24 P 0 ;1
L 8.8825 1.4825 8.8825 1.4825 24 P 0 ;1
L 8.8825 1.5325 8.8825 1.5325 24 P 0 ;1
L 8.8825 1.5825 8.8825 1.5825 24 P 0 ;1
L 8.8825 1.6325 8.8825 1.6325 24 P 0 ;1
L 8.8825 1.6825 8.8825 1.6825 24 P 0 ;1
L 8.8825 1.7325 8.8825 1.7325 24 P 0 ;1
L 8.8825 1.7825 8.8825 1.7825 24 P 0 ;1
L 8.8825 1.8325 8.8825 1.8325 24 P 0 ;1
L 8.8825 1.8825 8.8825 1.8825 24 P 0 ;1
L 8.8825 1.9325 8.8825 1.9325 24 P 0 ;1
L 8.8825 1.9825 8.8825 1.9825 24 P 0 ;1
L 8.8825 2.0325 8.8825 2.0325 24 P 0 ;1
L 8.8825 2.0825 8.8825 2.0825 24 P 0 ;1
L 8.8825 2.1325 8.8825 2.1325 24 P 0 ;1
L 8.8825 2.1825 8.8825 2.1825 24 P 0 ;1
L 8.8825 2.2325 8.8825 2.2325 24 P 0 ;1
L 8.8825 2.2825 8.8825 2.2825 24 P 0 ;1
L 8.8825 2.3325 8.8825 2.3325 24 P 0 ;1
L 8.8825 2.3825 8.8825 2.3825 24 P 0 ;1
L 8.8825 2.4325 8.8825 2.4325 24 P 0 ;1
L 8.8825 2.4825 8.8825 2.4825 24 P 0 ;1
L 8.8825 2.5325 8.8825 2.5325 24 P 0 ;1
L 8.8825 2.5825 8.8825 2.5825 24 P 0 ;1
L 8.8825 2.6325 8.8825 2.6325 24 P 0 ;1
L 8.8825 2.6825 8.8825 2.6825 24 P 0 ;1
L 8.8825 2.7325 8.8825 2.7325 24 P 0 ;1
L 8.8825 3.0325 8.8825 3.0325 24 P 0 ;1
L 8.8825 3.0825 8.8825 3.0825 24 P 0 ;1
L 8.8825 3.1325 8.8825 3.1325 24 P 0 ;1
L 8.8825 3.1825 8.8825 3.1825 24 P 0 ;1
L 8.8825 3.2325 8.8825 3.2325 24 P 0 ;1
L 8.8825 3.2825 8.8825 3.2825 24 P 0 ;1
L 8.8825 3.3325 8.8825 3.3325 24 P 0 ;1
L 8.8825 3.3825 8.8825 3.3825 24 P 0 ;1
L 8.8825 3.4325 8.8825 3.4325 24 P 0 ;1
L 8.8825 3.4825 8.8825 3.4825 24 P 0 ;1
L 8.8825 3.5325 8.8825 3.5325 24 P 0 ;1
L 8.8825 3.5825 8.8825 3.5825 24 P 0 ;1
L 8.8825 3.6325 8.8825 3.6325 24 P 0 ;1
L 8.8825 3.6825 8.8825 3.6825 24 P 0 ;1
L 8.8825 3.7325 8.8825 3.7325 24 P 0 ;1
L 8.8825 3.7825 8.8825 3.7825 24 P 0 ;1
L 8.8825 3.8325 8.8825 3.8325 24 P 0 ;1
L 8.8825 3.8825 8.8825 3.8825 24 P 0 ;1
L 8.8825 3.9325 8.8825 3.9325 24 P 0 ;1
L 8.8825 3.9825 8.8825 3.9825 24 P 0 ;1
L 8.8825 4.0325 8.8825 4.0325 24 P 0 ;1
L 8.8825 4.0825 8.8825 4.0825 24 P 0 ;1
L 8.8825 4.1325 8.8825 4.1325 24 P 0 ;1
L 8.8825 4.1825 8.8825 4.1825 24 P 0 ;1
L 8.8825 4.2325 8.8825 4.2325 24 P 0 ;1
L 8.8825 4.2825 8.8825 4.2825 24 P 0 ;1
L 8.8825 4.3325 8.8825 4.3325 24 P 0 ;1
L 8.8825 4.3825 8.8825 4.3825 24 P 0 ;1
L 8.8825 5.4825 8.8825 5.4825 24 P 0 ;1
L 8.8825 5.5325 8.8825 5.5325 24 P 0 ;1
L 8.8825 5.5825 8.8825 5.5825 24 P 0 ;1
L 8.8825 5.6325 8.8825 5.6325 24 P 0 ;1
L 8.8825 5.6825 8.8825 5.6825 24 P 0 ;1
L 8.8825 5.7325 8.8825 5.7325 24 P 0 ;1
L 8.8825 5.7825 8.8825 5.7825 24 P 0 ;1
L 8.8825 5.8325 8.8825 5.8325 24 P 0 ;1
L 8.8825 5.8825 8.8825 5.8825 24 P 0 ;1
L 8.9325 0.1325 8.9325 0.1325 24 P 0 ;1
L 8.9325 0.1825 8.9325 0.1825 24 P 0 ;1
L 8.9325 0.2325 8.9325 0.2325 24 P 0 ;1
L 8.9325 0.2825 8.9325 0.2825 24 P 0 ;1
L 8.9325 0.3325 8.9325 0.3325 24 P 0 ;1
L 8.9325 0.3825 8.9325 0.3825 24 P 0 ;1
L 8.9325 0.4325 8.9325 0.4325 24 P 0 ;1
L 8.9325 0.6825 8.9325 0.6825 24 P 0 ;1
L 8.9325 0.7325 8.9325 0.7325 24 P 0 ;1
L 8.9325 0.7825 8.9325 0.7825 24 P 0 ;1
L 8.9325 0.8325 8.9325 0.8325 24 P 0 ;1
L 8.9325 0.8825 8.9325 0.8825 24 P 0 ;1
L 8.9325 0.9325 8.9325 0.9325 24 P 0 ;1
L 8.9325 0.9825 8.9325 0.9825 24 P 0 ;1
L 8.9325 1.0325 8.9325 1.0325 24 P 0 ;1
L 8.9325 1.0825 8.9325 1.0825 24 P 0 ;1
L 8.9325 1.1325 8.9325 1.1325 24 P 0 ;1
L 8.9325 1.1825 8.9325 1.1825 24 P 0 ;1
L 8.9325 1.2325 8.9325 1.2325 24 P 0 ;1
L 8.9325 1.2825 8.9325 1.2825 24 P 0 ;1
L 8.9325 1.3325 8.9325 1.3325 24 P 0 ;1
L 8.9325 1.3825 8.9325 1.3825 24 P 0 ;1
L 8.9325 1.4325 8.9325 1.4325 24 P 0 ;1
L 8.9325 1.4825 8.9325 1.4825 24 P 0 ;1
L 8.9325 1.5325 8.9325 1.5325 24 P 0 ;1
L 8.9325 1.5825 8.9325 1.5825 24 P 0 ;1
L 8.9325 1.6325 8.9325 1.6325 24 P 0 ;1
L 8.9325 1.6825 8.9325 1.6825 24 P 0 ;1
L 8.9325 1.7325 8.9325 1.7325 24 P 0 ;1
L 8.9325 1.7825 8.9325 1.7825 24 P 0 ;1
L 8.9325 1.8325 8.9325 1.8325 24 P 0 ;1
L 8.9325 1.8825 8.9325 1.8825 24 P 0 ;1
L 8.9325 1.9325 8.9325 1.9325 24 P 0 ;1
L 8.9325 1.9825 8.9325 1.9825 24 P 0 ;1
L 8.9325 2.0325 8.9325 2.0325 24 P 0 ;1
L 8.9325 2.0825 8.9325 2.0825 24 P 0 ;1
L 8.9325 2.1325 8.9325 2.1325 24 P 0 ;1
L 8.9325 2.1825 8.9325 2.1825 24 P 0 ;1
L 8.9325 2.2325 8.9325 2.2325 24 P 0 ;1
L 8.9325 2.2825 8.9325 2.2825 24 P 0 ;1
L 8.9325 2.3325 8.9325 2.3325 24 P 0 ;1
L 8.9325 2.3825 8.9325 2.3825 24 P 0 ;1
L 8.9325 2.4325 8.9325 2.4325 24 P 0 ;1
L 8.9325 2.4825 8.9325 2.4825 24 P 0 ;1
L 8.9325 2.5325 8.9325 2.5325 24 P 0 ;1
L 8.9325 2.5825 8.9325 2.5825 24 P 0 ;1
L 8.9325 2.6325 8.9325 2.6325 24 P 0 ;1
L 8.9325 2.6825 8.9325 2.6825 24 P 0 ;1
L 8.9325 3.0325 8.9325 3.0325 24 P 0 ;1
L 8.9325 3.0825 8.9325 3.0825 24 P 0 ;1
L 8.9325 3.1325 8.9325 3.1325 24 P 0 ;1
L 8.9325 3.1825 8.9325 3.1825 24 P 0 ;1
L 8.9325 3.2325 8.9325 3.2325 24 P 0 ;1
L 8.9325 3.2825 8.9325 3.2825 24 P 0 ;1
L 8.9325 3.3325 8.9325 3.3325 24 P 0 ;1
L 8.9325 3.3825 8.9325 3.3825 24 P 0 ;1
L 8.9325 3.4325 8.9325 3.4325 24 P 0 ;1
L 8.9325 3.4825 8.9325 3.4825 24 P 0 ;1
L 8.9325 3.5325 8.9325 3.5325 24 P 0 ;1
L 8.9325 3.5825 8.9325 3.5825 24 P 0 ;1
L 8.9325 3.6325 8.9325 3.6325 24 P 0 ;1
L 8.9325 3.6825 8.9325 3.6825 24 P 0 ;1
L 8.9325 3.7325 8.9325 3.7325 24 P 0 ;1
L 8.9325 3.7825 8.9325 3.7825 24 P 0 ;1
L 8.9325 3.8325 8.9325 3.8325 24 P 0 ;1
L 8.9325 3.8825 8.9325 3.8825 24 P 0 ;1
L 8.9325 3.9325 8.9325 3.9325 24 P 0 ;1
L 8.9325 3.9825 8.9325 3.9825 24 P 0 ;1
L 8.9325 4.0325 8.9325 4.0325 24 P 0 ;1
L 8.9325 4.0825 8.9325 4.0825 24 P 0 ;1
L 8.9325 4.1325 8.9325 4.1325 24 P 0 ;1
L 8.9325 4.1825 8.9325 4.1825 24 P 0 ;1
L 8.9325 4.2325 8.9325 4.2325 24 P 0 ;1
L 8.9325 4.2825 8.9325 4.2825 24 P 0 ;1
L 8.9325 4.3325 8.9325 4.3325 24 P 0 ;1
L 8.9325 4.3825 8.9325 4.3825 24 P 0 ;1
L 8.9325 5.4825 8.9325 5.4825 24 P 0 ;1
L 8.9325 5.5325 8.9325 5.5325 24 P 0 ;1
L 8.9325 5.5825 8.9325 5.5825 24 P 0 ;1
L 8.9325 5.6325 8.9325 5.6325 24 P 0 ;1
L 8.9325 5.6825 8.9325 5.6825 24 P 0 ;1
L 8.9325 5.7325 8.9325 5.7325 24 P 0 ;1
L 8.9325 5.7825 8.9325 5.7825 24 P 0 ;1
L 8.9325 5.8325 8.9325 5.8325 24 P 0 ;1
L 8.9325 5.8825 8.9325 5.8825 24 P 0 ;1
L 8.9825 0.1325 8.9825 0.1325 24 P 0 ;1
L 8.9825 0.1825 8.9825 0.1825 24 P 0 ;1
L 8.9825 0.2325 8.9825 0.2325 24 P 0 ;1
L 8.9825 0.2825 8.9825 0.2825 24 P 0 ;1
L 8.9825 0.3325 8.9825 0.3325 24 P 0 ;1
L 8.9825 0.3825 8.9825 0.3825 24 P 0 ;1
L 8.9825 0.4325 8.9825 0.4325 24 P 0 ;1
L 8.9825 0.6825 8.9825 0.6825 24 P 0 ;1
L 8.9825 0.7325 8.9825 0.7325 24 P 0 ;1
L 8.9825 0.7825 8.9825 0.7825 24 P 0 ;1
L 8.9825 0.8325 8.9825 0.8325 24 P 0 ;1
L 8.9825 0.8825 8.9825 0.8825 24 P 0 ;1
L 8.9825 0.9325 8.9825 0.9325 24 P 0 ;1
L 8.9825 0.9825 8.9825 0.9825 24 P 0 ;1
L 8.9825 1.0325 8.9825 1.0325 24 P 0 ;1
L 8.9825 1.0825 8.9825 1.0825 24 P 0 ;1
L 8.9825 1.1325 8.9825 1.1325 24 P 0 ;1
L 8.9825 1.1825 8.9825 1.1825 24 P 0 ;1
L 8.9825 1.2325 8.9825 1.2325 24 P 0 ;1
L 8.9825 1.2825 8.9825 1.2825 24 P 0 ;1
L 8.9825 1.3325 8.9825 1.3325 24 P 0 ;1
L 8.9825 1.3825 8.9825 1.3825 24 P 0 ;1
L 8.9825 1.4325 8.9825 1.4325 24 P 0 ;1
L 8.9825 1.4825 8.9825 1.4825 24 P 0 ;1
L 8.9825 1.5325 8.9825 1.5325 24 P 0 ;1
L 8.9825 1.5825 8.9825 1.5825 24 P 0 ;1
L 8.9825 1.6325 8.9825 1.6325 24 P 0 ;1
L 8.9825 1.6825 8.9825 1.6825 24 P 0 ;1
L 8.9825 1.7325 8.9825 1.7325 24 P 0 ;1
L 8.9825 1.7825 8.9825 1.7825 24 P 0 ;1
L 8.9825 1.8325 8.9825 1.8325 24 P 0 ;1
L 8.9825 1.8825 8.9825 1.8825 24 P 0 ;1
L 8.9825 1.9325 8.9825 1.9325 24 P 0 ;1
L 8.9825 1.9825 8.9825 1.9825 24 P 0 ;1
L 8.9825 2.0325 8.9825 2.0325 24 P 0 ;1
L 8.9825 2.0825 8.9825 2.0825 24 P 0 ;1
L 8.9825 2.1325 8.9825 2.1325 24 P 0 ;1
L 8.9825 2.1825 8.9825 2.1825 24 P 0 ;1
L 8.9825 2.2325 8.9825 2.2325 24 P 0 ;1
L 8.9825 2.2825 8.9825 2.2825 24 P 0 ;1
L 8.9825 2.3325 8.9825 2.3325 24 P 0 ;1
L 8.9825 2.3825 8.9825 2.3825 24 P 0 ;1
L 8.9825 2.4325 8.9825 2.4325 24 P 0 ;1
L 8.9825 2.4825 8.9825 2.4825 24 P 0 ;1
L 8.9825 2.5325 8.9825 2.5325 24 P 0 ;1
L 8.9825 2.5825 8.9825 2.5825 24 P 0 ;1
L 8.9825 2.6325 8.9825 2.6325 24 P 0 ;1
L 8.9825 2.6825 8.9825 2.6825 24 P 0 ;1
L 8.9825 3.0325 8.9825 3.0325 24 P 0 ;1
L 8.9825 3.0825 8.9825 3.0825 24 P 0 ;1
L 8.9825 3.1325 8.9825 3.1325 24 P 0 ;1
L 8.9825 3.1825 8.9825 3.1825 24 P 0 ;1
L 8.9825 3.2325 8.9825 3.2325 24 P 0 ;1
L 8.9825 3.2825 8.9825 3.2825 24 P 0 ;1
L 8.9825 3.3325 8.9825 3.3325 24 P 0 ;1
L 8.9825 3.3825 8.9825 3.3825 24 P 0 ;1
L 8.9825 3.4325 8.9825 3.4325 24 P 0 ;1
L 8.9825 3.4825 8.9825 3.4825 24 P 0 ;1
L 8.9825 3.5325 8.9825 3.5325 24 P 0 ;1
L 8.9825 3.5825 8.9825 3.5825 24 P 0 ;1
L 8.9825 3.6325 8.9825 3.6325 24 P 0 ;1
L 8.9825 3.6825 8.9825 3.6825 24 P 0 ;1
L 8.9825 3.7325 8.9825 3.7325 24 P 0 ;1
L 8.9825 3.7825 8.9825 3.7825 24 P 0 ;1
L 8.9825 3.8325 8.9825 3.8325 24 P 0 ;1
L 8.9825 3.8825 8.9825 3.8825 24 P 0 ;1
L 8.9825 3.9325 8.9825 3.9325 24 P 0 ;1
L 8.9825 3.9825 8.9825 3.9825 24 P 0 ;1
L 8.9825 4.0325 8.9825 4.0325 24 P 0 ;1
L 8.9825 4.0825 8.9825 4.0825 24 P 0 ;1
L 8.9825 4.1325 8.9825 4.1325 24 P 0 ;1
L 8.9825 4.1825 8.9825 4.1825 24 P 0 ;1
L 8.9825 4.2325 8.9825 4.2325 24 P 0 ;1
L 8.9825 4.2825 8.9825 4.2825 24 P 0 ;1
L 8.9825 4.3325 8.9825 4.3325 24 P 0 ;1
L 8.9825 5.4825 8.9825 5.4825 24 P 0 ;1
L 8.9825 5.5325 8.9825 5.5325 24 P 0 ;1
L 8.9825 5.5825 8.9825 5.5825 24 P 0 ;1
L 8.9825 5.6325 8.9825 5.6325 24 P 0 ;1
L 8.9825 5.6825 8.9825 5.6825 24 P 0 ;1
L 8.9825 5.7325 8.9825 5.7325 24 P 0 ;1
L 8.9825 5.7825 8.9825 5.7825 24 P 0 ;1
L 8.9825 5.8325 8.9825 5.8325 24 P 0 ;1
L 8.9825 5.8825 8.9825 5.8825 24 P 0 ;1
L 9.0325 0.1325 9.0325 0.1325 24 P 0 ;1
L 9.0325 0.1825 9.0325 0.1825 24 P 0 ;1
L 9.0325 0.2325 9.0325 0.2325 24 P 0 ;1
L 9.0325 0.2825 9.0325 0.2825 24 P 0 ;1
L 9.0325 0.3325 9.0325 0.3325 24 P 0 ;1
L 9.0325 0.3825 9.0325 0.3825 24 P 0 ;1
L 9.0325 0.4325 9.0325 0.4325 24 P 0 ;1
L 9.0325 0.6825 9.0325 0.6825 24 P 0 ;1
L 9.0325 0.7325 9.0325 0.7325 24 P 0 ;1
L 9.0325 0.7825 9.0325 0.7825 24 P 0 ;1
L 9.0325 0.8325 9.0325 0.8325 24 P 0 ;1
L 9.0325 0.8825 9.0325 0.8825 24 P 0 ;1
L 9.0325 0.9325 9.0325 0.9325 24 P 0 ;1
L 9.0325 0.9825 9.0325 0.9825 24 P 0 ;1
L 9.0325 1.0325 9.0325 1.0325 24 P 0 ;1
L 9.0325 1.0825 9.0325 1.0825 24 P 0 ;1
L 9.0325 1.1325 9.0325 1.1325 24 P 0 ;1
L 9.0325 1.1825 9.0325 1.1825 24 P 0 ;1
L 9.0325 1.2325 9.0325 1.2325 24 P 0 ;1
L 9.0325 1.2825 9.0325 1.2825 24 P 0 ;1
L 9.0325 1.3325 9.0325 1.3325 24 P 0 ;1
L 9.0325 1.3825 9.0325 1.3825 24 P 0 ;1
L 9.0325 1.4325 9.0325 1.4325 24 P 0 ;1
L 9.0325 1.4825 9.0325 1.4825 24 P 0 ;1
L 9.0325 1.5325 9.0325 1.5325 24 P 0 ;1
L 9.0325 1.5825 9.0325 1.5825 24 P 0 ;1
L 9.0325 1.6325 9.0325 1.6325 24 P 0 ;1
L 9.0325 1.6825 9.0325 1.6825 24 P 0 ;1
L 9.0325 1.7325 9.0325 1.7325 24 P 0 ;1
L 9.0325 1.7825 9.0325 1.7825 24 P 0 ;1
L 9.0325 1.8325 9.0325 1.8325 24 P 0 ;1
L 9.0325 1.8825 9.0325 1.8825 24 P 0 ;1
L 9.0325 1.9325 9.0325 1.9325 24 P 0 ;1
L 9.0325 1.9825 9.0325 1.9825 24 P 0 ;1
L 9.0325 2.0325 9.0325 2.0325 24 P 0 ;1
L 9.0325 2.0825 9.0325 2.0825 24 P 0 ;1
L 9.0325 2.1325 9.0325 2.1325 24 P 0 ;1
L 9.0325 2.1825 9.0325 2.1825 24 P 0 ;1
L 9.0325 2.2325 9.0325 2.2325 24 P 0 ;1
L 9.0325 2.2825 9.0325 2.2825 24 P 0 ;1
L 9.0325 2.3325 9.0325 2.3325 24 P 0 ;1
L 9.0325 2.3825 9.0325 2.3825 24 P 0 ;1
L 9.0325 2.4325 9.0325 2.4325 24 P 0 ;1
L 9.0325 2.4825 9.0325 2.4825 24 P 0 ;1
L 9.0325 2.5325 9.0325 2.5325 24 P 0 ;1
L 9.0325 2.5825 9.0325 2.5825 24 P 0 ;1
L 9.0325 2.6325 9.0325 2.6325 24 P 0 ;1
L 9.0325 2.6825 9.0325 2.6825 24 P 0 ;1
L 9.0325 2.9825 9.0325 2.9825 24 P 0 ;1
L 9.0325 3.0325 9.0325 3.0325 24 P 0 ;1
L 9.0325 3.0825 9.0325 3.0825 24 P 0 ;1
L 9.0325 3.1325 9.0325 3.1325 24 P 0 ;1
L 9.0325 3.1825 9.0325 3.1825 24 P 0 ;1
L 9.0325 3.2325 9.0325 3.2325 24 P 0 ;1
L 9.0325 3.2825 9.0325 3.2825 24 P 0 ;1
L 9.0325 3.3325 9.0325 3.3325 24 P 0 ;1
L 9.0325 3.3825 9.0325 3.3825 24 P 0 ;1
L 9.0325 3.4325 9.0325 3.4325 24 P 0 ;1
L 9.0325 3.4825 9.0325 3.4825 24 P 0 ;1
L 9.0325 3.5325 9.0325 3.5325 24 P 0 ;1
L 9.0325 3.5825 9.0325 3.5825 24 P 0 ;1
L 9.0325 3.6325 9.0325 3.6325 24 P 0 ;1
L 9.0325 3.6825 9.0325 3.6825 24 P 0 ;1
L 9.0325 3.7325 9.0325 3.7325 24 P 0 ;1
L 9.0325 3.7825 9.0325 3.7825 24 P 0 ;1
L 9.0325 3.8325 9.0325 3.8325 24 P 0 ;1
L 9.0325 3.8825 9.0325 3.8825 24 P 0 ;1
L 9.0325 3.9325 9.0325 3.9325 24 P 0 ;1
L 9.0325 3.9825 9.0325 3.9825 24 P 0 ;1
L 9.0325 4.0325 9.0325 4.0325 24 P 0 ;1
L 9.0325 4.0825 9.0325 4.0825 24 P 0 ;1
L 9.0325 4.1325 9.0325 4.1325 24 P 0 ;1
L 9.0325 4.1825 9.0325 4.1825 24 P 0 ;1
L 9.0325 4.2325 9.0325 4.2325 24 P 0 ;1
L 9.0325 4.2825 9.0325 4.2825 24 P 0 ;1
L 9.0325 4.3325 9.0325 4.3325 24 P 0 ;1
L 9.0325 5.4825 9.0325 5.4825 24 P 0 ;1
L 9.0325 5.5325 9.0325 5.5325 24 P 0 ;1
L 9.0325 5.5825 9.0325 5.5825 24 P 0 ;1
L 9.0325 5.6325 9.0325 5.6325 24 P 0 ;1
L 9.0325 5.6825 9.0325 5.6825 24 P 0 ;1
L 9.0325 5.7325 9.0325 5.7325 24 P 0 ;1
L 9.0325 5.7825 9.0325 5.7825 24 P 0 ;1
L 9.0325 5.8325 9.0325 5.8325 24 P 0 ;1
L 9.0325 5.8825 9.0325 5.8825 24 P 0 ;1
L 9.0825 0.1325 9.0825 0.1325 24 P 0 ;1
L 9.0825 0.1825 9.0825 0.1825 24 P 0 ;1
L 9.0825 0.2325 9.0825 0.2325 24 P 0 ;1
L 9.0825 0.2825 9.0825 0.2825 24 P 0 ;1
L 9.0825 0.3325 9.0825 0.3325 24 P 0 ;1
L 9.0825 0.3825 9.0825 0.3825 24 P 0 ;1
L 9.0825 0.4325 9.0825 0.4325 24 P 0 ;1
L 9.0825 0.6825 9.0825 0.6825 24 P 0 ;1
L 9.0825 0.7325 9.0825 0.7325 24 P 0 ;1
L 9.0825 0.7825 9.0825 0.7825 24 P 0 ;1
L 9.0825 0.8325 9.0825 0.8325 24 P 0 ;1
L 9.0825 0.8825 9.0825 0.8825 24 P 0 ;1
L 9.0825 0.9325 9.0825 0.9325 24 P 0 ;1
L 9.0825 0.9825 9.0825 0.9825 24 P 0 ;1
L 9.0825 1.0325 9.0825 1.0325 24 P 0 ;1
L 9.0825 1.0825 9.0825 1.0825 24 P 0 ;1
L 9.0825 1.1325 9.0825 1.1325 24 P 0 ;1
L 9.0825 1.1825 9.0825 1.1825 24 P 0 ;1
L 9.0825 1.2325 9.0825 1.2325 24 P 0 ;1
L 9.0825 1.2825 9.0825 1.2825 24 P 0 ;1
L 9.0825 1.3325 9.0825 1.3325 24 P 0 ;1
L 9.0825 1.3825 9.0825 1.3825 24 P 0 ;1
L 9.0825 1.4325 9.0825 1.4325 24 P 0 ;1
L 9.0825 1.4825 9.0825 1.4825 24 P 0 ;1
L 9.0825 1.5325 9.0825 1.5325 24 P 0 ;1
L 9.0825 1.5825 9.0825 1.5825 24 P 0 ;1
L 9.0825 1.6325 9.0825 1.6325 24 P 0 ;1
L 9.0825 1.6825 9.0825 1.6825 24 P 0 ;1
L 9.0825 1.7325 9.0825 1.7325 24 P 0 ;1
L 9.0825 1.7825 9.0825 1.7825 24 P 0 ;1
L 9.0825 1.8325 9.0825 1.8325 24 P 0 ;1
L 9.0825 1.8825 9.0825 1.8825 24 P 0 ;1
L 9.0825 1.9325 9.0825 1.9325 24 P 0 ;1
L 9.0825 1.9825 9.0825 1.9825 24 P 0 ;1
L 9.0825 2.0325 9.0825 2.0325 24 P 0 ;1
L 9.0825 2.0825 9.0825 2.0825 24 P 0 ;1
L 9.0825 2.1325 9.0825 2.1325 24 P 0 ;1
L 9.0825 2.1825 9.0825 2.1825 24 P 0 ;1
L 9.0825 2.2325 9.0825 2.2325 24 P 0 ;1
L 9.0825 2.2825 9.0825 2.2825 24 P 0 ;1
L 9.0825 2.3325 9.0825 2.3325 24 P 0 ;1
L 9.0825 2.3825 9.0825 2.3825 24 P 0 ;1
L 9.0825 2.4325 9.0825 2.4325 24 P 0 ;1
L 9.0825 2.4825 9.0825 2.4825 24 P 0 ;1
L 9.0825 2.5325 9.0825 2.5325 24 P 0 ;1
L 9.0825 2.5825 9.0825 2.5825 24 P 0 ;1
L 9.0825 2.6325 9.0825 2.6325 24 P 0 ;1
L 9.0825 2.6825 9.0825 2.6825 24 P 0 ;1
L 9.0825 2.7325 9.0825 2.7325 24 P 0 ;1
L 9.0825 2.7825 9.0825 2.7825 24 P 0 ;1
L 9.0825 2.8325 9.0825 2.8325 24 P 0 ;1
L 9.0825 2.8825 9.0825 2.8825 24 P 0 ;1
L 9.0825 2.9325 9.0825 2.9325 24 P 0 ;1
L 9.0825 2.9825 9.0825 2.9825 24 P 0 ;1
L 9.0825 3.0325 9.0825 3.0325 24 P 0 ;1
L 9.0825 3.0825 9.0825 3.0825 24 P 0 ;1
L 9.0825 3.1325 9.0825 3.1325 24 P 0 ;1
L 9.0825 3.1825 9.0825 3.1825 24 P 0 ;1
L 9.0825 3.2325 9.0825 3.2325 24 P 0 ;1
L 9.0825 3.2825 9.0825 3.2825 24 P 0 ;1
L 9.0825 3.3325 9.0825 3.3325 24 P 0 ;1
L 9.0825 3.3825 9.0825 3.3825 24 P 0 ;1
L 9.0825 3.4325 9.0825 3.4325 24 P 0 ;1
L 9.0825 3.4825 9.0825 3.4825 24 P 0 ;1
L 9.0825 3.5325 9.0825 3.5325 24 P 0 ;1
L 9.0825 3.5825 9.0825 3.5825 24 P 0 ;1
L 9.0825 3.6325 9.0825 3.6325 24 P 0 ;1
L 9.0825 3.6825 9.0825 3.6825 24 P 0 ;1
L 9.0825 3.7325 9.0825 3.7325 24 P 0 ;1
L 9.0825 3.7825 9.0825 3.7825 24 P 0 ;1
L 9.0825 3.8325 9.0825 3.8325 24 P 0 ;1
L 9.0825 3.8825 9.0825 3.8825 24 P 0 ;1
L 9.0825 3.9325 9.0825 3.9325 24 P 0 ;1
L 9.0825 3.9825 9.0825 3.9825 24 P 0 ;1
L 9.0825 4.0325 9.0825 4.0325 24 P 0 ;1
L 9.0825 4.0825 9.0825 4.0825 24 P 0 ;1
L 9.0825 4.1325 9.0825 4.1325 24 P 0 ;1
L 9.0825 4.1825 9.0825 4.1825 24 P 0 ;1
L 9.0825 4.2325 9.0825 4.2325 24 P 0 ;1
L 9.0825 4.2825 9.0825 4.2825 24 P 0 ;1
L 9.0825 5.4825 9.0825 5.4825 24 P 0 ;1
L 9.0825 5.5325 9.0825 5.5325 24 P 0 ;1
L 9.0825 5.5825 9.0825 5.5825 24 P 0 ;1
L 9.0825 5.6325 9.0825 5.6325 24 P 0 ;1
L 9.0825 5.6825 9.0825 5.6825 24 P 0 ;1
L 9.0825 5.7325 9.0825 5.7325 24 P 0 ;1
L 9.0825 5.7825 9.0825 5.7825 24 P 0 ;1
L 9.0825 5.8325 9.0825 5.8325 24 P 0 ;1
L 9.0825 5.8825 9.0825 5.8825 24 P 0 ;1
L 9.1325 0.1325 9.1325 0.1325 24 P 0 ;1
L 9.1325 0.1825 9.1325 0.1825 24 P 0 ;1
L 9.1325 0.2325 9.1325 0.2325 24 P 0 ;1
L 9.1325 0.2825 9.1325 0.2825 24 P 0 ;1
L 9.1325 0.3325 9.1325 0.3325 24 P 0 ;1
L 9.1325 0.3825 9.1325 0.3825 24 P 0 ;1
L 9.1325 0.4325 9.1325 0.4325 24 P 0 ;1
L 9.1325 0.6825 9.1325 0.6825 24 P 0 ;1
L 9.1325 0.7325 9.1325 0.7325 24 P 0 ;1
L 9.1325 0.7825 9.1325 0.7825 24 P 0 ;1
L 9.1325 0.8325 9.1325 0.8325 24 P 0 ;1
L 9.1325 0.8825 9.1325 0.8825 24 P 0 ;1
L 9.1325 0.9325 9.1325 0.9325 24 P 0 ;1
L 9.1325 0.9825 9.1325 0.9825 24 P 0 ;1
L 9.1325 1.0325 9.1325 1.0325 24 P 0 ;1
L 9.1325 1.0825 9.1325 1.0825 24 P 0 ;1
L 9.1325 1.1325 9.1325 1.1325 24 P 0 ;1
L 9.1325 1.1825 9.1325 1.1825 24 P 0 ;1
L 9.1325 1.2325 9.1325 1.2325 24 P 0 ;1
L 9.1325 1.2825 9.1325 1.2825 24 P 0 ;1
L 9.1325 1.3325 9.1325 1.3325 24 P 0 ;1
L 9.1325 1.3825 9.1325 1.3825 24 P 0 ;1
L 9.1325 1.4325 9.1325 1.4325 24 P 0 ;1
L 9.1325 1.4825 9.1325 1.4825 24 P 0 ;1
L 9.1325 1.5325 9.1325 1.5325 24 P 0 ;1
L 9.1325 1.5825 9.1325 1.5825 24 P 0 ;1
L 9.1325 1.6325 9.1325 1.6325 24 P 0 ;1
L 9.1325 1.6825 9.1325 1.6825 24 P 0 ;1
L 9.1325 1.7325 9.1325 1.7325 24 P 0 ;1
L 9.1325 1.7825 9.1325 1.7825 24 P 0 ;1
L 9.1325 1.8325 9.1325 1.8325 24 P 0 ;1
L 9.1325 1.8825 9.1325 1.8825 24 P 0 ;1
L 9.1325 1.9325 9.1325 1.9325 24 P 0 ;1
L 9.1325 1.9825 9.1325 1.9825 24 P 0 ;1
L 9.1325 2.0325 9.1325 2.0325 24 P 0 ;1
L 9.1325 2.0825 9.1325 2.0825 24 P 0 ;1
L 9.1325 2.1325 9.1325 2.1325 24 P 0 ;1
L 9.1325 2.1825 9.1325 2.1825 24 P 0 ;1
L 9.1325 2.2325 9.1325 2.2325 24 P 0 ;1
L 9.1325 2.2825 9.1325 2.2825 24 P 0 ;1
L 9.1325 2.3325 9.1325 2.3325 24 P 0 ;1
L 9.1325 2.3825 9.1325 2.3825 24 P 0 ;1
L 9.1325 2.4325 9.1325 2.4325 24 P 0 ;1
L 9.1325 2.4825 9.1325 2.4825 24 P 0 ;1
L 9.1325 2.5325 9.1325 2.5325 24 P 0 ;1
L 9.1325 2.5825 9.1325 2.5825 24 P 0 ;1
L 9.1325 2.6325 9.1325 2.6325 24 P 0 ;1
L 9.1325 2.6825 9.1325 2.6825 24 P 0 ;1
L 9.1325 2.7325 9.1325 2.7325 24 P 0 ;1
L 9.1325 2.7825 9.1325 2.7825 24 P 0 ;1
L 9.1325 2.8325 9.1325 2.8325 24 P 0 ;1
L 9.1325 2.8825 9.1325 2.8825 24 P 0 ;1
L 9.1325 2.9325 9.1325 2.9325 24 P 0 ;1
L 9.1325 2.9825 9.1325 2.9825 24 P 0 ;1
L 9.1325 3.0325 9.1325 3.0325 24 P 0 ;1
L 9.1325 3.0825 9.1325 3.0825 24 P 0 ;1
L 9.1325 3.1325 9.1325 3.1325 24 P 0 ;1
L 9.1325 3.1825 9.1325 3.1825 24 P 0 ;1
L 9.1325 3.2325 9.1325 3.2325 24 P 0 ;1
L 9.1325 3.2825 9.1325 3.2825 24 P 0 ;1
L 9.1325 3.3325 9.1325 3.3325 24 P 0 ;1
L 9.1325 3.3825 9.1325 3.3825 24 P 0 ;1
L 9.1325 3.4325 9.1325 3.4325 24 P 0 ;1
L 9.1325 3.4825 9.1325 3.4825 24 P 0 ;1
L 9.1325 3.5325 9.1325 3.5325 24 P 0 ;1
L 9.1325 3.5825 9.1325 3.5825 24 P 0 ;1
L 9.1325 3.6325 9.1325 3.6325 24 P 0 ;1
L 9.1325 3.6825 9.1325 3.6825 24 P 0 ;1
L 9.1325 3.7325 9.1325 3.7325 24 P 0 ;1
L 9.1325 3.7825 9.1325 3.7825 24 P 0 ;1
L 9.1325 3.8325 9.1325 3.8325 24 P 0 ;1
L 9.1325 3.8825 9.1325 3.8825 24 P 0 ;1
L 9.1325 3.9325 9.1325 3.9325 24 P 0 ;1
L 9.1325 3.9825 9.1325 3.9825 24 P 0 ;1
L 9.1325 4.0325 9.1325 4.0325 24 P 0 ;1
L 9.1325 4.0825 9.1325 4.0825 24 P 0 ;1
L 9.1325 4.1325 9.1325 4.1325 24 P 0 ;1
L 9.1325 4.1825 9.1325 4.1825 24 P 0 ;1
L 9.1325 4.2325 9.1325 4.2325 24 P 0 ;1
L 9.1325 4.2825 9.1325 4.2825 24 P 0 ;1
L 9.1325 4.3325 9.1325 4.3325 24 P 0 ;1
L 9.1325 5.4825 9.1325 5.4825 24 P 0 ;1
L 9.1325 5.5325 9.1325 5.5325 24 P 0 ;1
L 9.1325 5.5825 9.1325 5.5825 24 P 0 ;1
L 9.1325 5.6325 9.1325 5.6325 24 P 0 ;1
L 9.1325 5.6825 9.1325 5.6825 24 P 0 ;1
L 9.1325 5.7325 9.1325 5.7325 24 P 0 ;1
L 9.1325 5.7825 9.1325 5.7825 24 P 0 ;1
L 9.1325 5.8325 9.1325 5.8325 24 P 0 ;1
L 9.1325 5.8825 9.1325 5.8825 24 P 0 ;1
L 9.1825 0.1325 9.1825 0.1325 24 P 0 ;1
L 9.1825 0.1825 9.1825 0.1825 24 P 0 ;1
L 9.1825 0.2325 9.1825 0.2325 24 P 0 ;1
L 9.1825 0.2825 9.1825 0.2825 24 P 0 ;1
L 9.1825 0.3325 9.1825 0.3325 24 P 0 ;1
L 9.1825 0.3825 9.1825 0.3825 24 P 0 ;1
L 9.1825 0.6825 9.1825 0.6825 24 P 0 ;1
L 9.1825 0.7325 9.1825 0.7325 24 P 0 ;1
L 9.1825 0.7825 9.1825 0.7825 24 P 0 ;1
L 9.1825 0.8325 9.1825 0.8325 24 P 0 ;1
L 9.1825 0.8825 9.1825 0.8825 24 P 0 ;1
L 9.1825 0.9325 9.1825 0.9325 24 P 0 ;1
L 9.1825 0.9825 9.1825 0.9825 24 P 0 ;1
L 9.1825 1.0325 9.1825 1.0325 24 P 0 ;1
L 9.1825 1.0825 9.1825 1.0825 24 P 0 ;1
L 9.1825 1.1325 9.1825 1.1325 24 P 0 ;1
L 9.1825 1.1825 9.1825 1.1825 24 P 0 ;1
L 9.1825 1.2325 9.1825 1.2325 24 P 0 ;1
L 9.1825 1.2825 9.1825 1.2825 24 P 0 ;1
L 9.1825 1.3325 9.1825 1.3325 24 P 0 ;1
L 9.1825 1.3825 9.1825 1.3825 24 P 0 ;1
L 9.1825 1.4325 9.1825 1.4325 24 P 0 ;1
L 9.1825 1.4825 9.1825 1.4825 24 P 0 ;1
L 9.1825 1.5325 9.1825 1.5325 24 P 0 ;1
L 9.1825 1.5825 9.1825 1.5825 24 P 0 ;1
L 9.1825 1.6325 9.1825 1.6325 24 P 0 ;1
L 9.1825 1.6825 9.1825 1.6825 24 P 0 ;1
L 9.1825 1.7325 9.1825 1.7325 24 P 0 ;1
L 9.1825 1.7825 9.1825 1.7825 24 P 0 ;1
L 9.1825 1.8325 9.1825 1.8325 24 P 0 ;1
L 9.1825 1.8825 9.1825 1.8825 24 P 0 ;1
L 9.1825 1.9325 9.1825 1.9325 24 P 0 ;1
L 9.1825 1.9825 9.1825 1.9825 24 P 0 ;1
L 9.1825 2.0325 9.1825 2.0325 24 P 0 ;1
L 9.1825 2.0825 9.1825 2.0825 24 P 0 ;1
L 9.1825 2.1325 9.1825 2.1325 24 P 0 ;1
L 9.1825 2.1825 9.1825 2.1825 24 P 0 ;1
L 9.1825 2.2325 9.1825 2.2325 24 P 0 ;1
L 9.1825 2.2825 9.1825 2.2825 24 P 0 ;1
L 9.1825 2.3325 9.1825 2.3325 24 P 0 ;1
L 9.1825 2.3825 9.1825 2.3825 24 P 0 ;1
L 9.1825 2.4325 9.1825 2.4325 24 P 0 ;1
L 9.1825 2.4825 9.1825 2.4825 24 P 0 ;1
L 9.1825 2.5325 9.1825 2.5325 24 P 0 ;1
L 9.1825 2.5825 9.1825 2.5825 24 P 0 ;1
L 9.1825 2.6325 9.1825 2.6325 24 P 0 ;1
L 9.1825 2.6825 9.1825 2.6825 24 P 0 ;1
L 9.1825 2.7325 9.1825 2.7325 24 P 0 ;1
L 9.1825 2.7825 9.1825 2.7825 24 P 0 ;1
L 9.1825 2.8325 9.1825 2.8325 24 P 0 ;1
L 9.1825 2.8825 9.1825 2.8825 24 P 0 ;1
L 9.1825 2.9325 9.1825 2.9325 24 P 0 ;1
L 9.1825 2.9825 9.1825 2.9825 24 P 0 ;1
L 9.1825 3.0325 9.1825 3.0325 24 P 0 ;1
L 9.1825 3.0825 9.1825 3.0825 24 P 0 ;1
L 9.1825 3.1325 9.1825 3.1325 24 P 0 ;1
L 9.1825 3.1825 9.1825 3.1825 24 P 0 ;1
L 9.1825 3.2325 9.1825 3.2325 24 P 0 ;1
L 9.1825 3.2825 9.1825 3.2825 24 P 0 ;1
L 9.1825 3.3325 9.1825 3.3325 24 P 0 ;1
L 9.1825 3.3825 9.1825 3.3825 24 P 0 ;1
L 9.1825 3.4325 9.1825 3.4325 24 P 0 ;1
L 9.1825 3.4825 9.1825 3.4825 24 P 0 ;1
L 9.1825 3.5325 9.1825 3.5325 24 P 0 ;1
L 9.1825 3.5825 9.1825 3.5825 24 P 0 ;1
L 9.1825 3.6325 9.1825 3.6325 24 P 0 ;1
L 9.1825 3.6825 9.1825 3.6825 24 P 0 ;1
L 9.1825 3.7325 9.1825 3.7325 24 P 0 ;1
L 9.1825 3.7825 9.1825 3.7825 24 P 0 ;1
L 9.1825 3.8325 9.1825 3.8325 24 P 0 ;1
L 9.1825 3.8825 9.1825 3.8825 24 P 0 ;1
L 9.1825 3.9325 9.1825 3.9325 24 P 0 ;1
L 9.1825 3.9825 9.1825 3.9825 24 P 0 ;1
L 9.1825 4.0325 9.1825 4.0325 24 P 0 ;1
L 9.1825 4.0825 9.1825 4.0825 24 P 0 ;1
L 9.1825 4.1325 9.1825 4.1325 24 P 0 ;1
L 9.1825 4.1825 9.1825 4.1825 24 P 0 ;1
L 9.1825 4.2325 9.1825 4.2325 24 P 0 ;1
L 9.1825 4.2825 9.1825 4.2825 24 P 0 ;1
L 9.1825 4.3325 9.1825 4.3325 24 P 0 ;1
L 9.1825 5.4825 9.1825 5.4825 24 P 0 ;1
L 9.1825 5.5325 9.1825 5.5325 24 P 0 ;1
L 9.1825 5.5825 9.1825 5.5825 24 P 0 ;1
L 9.1825 5.6325 9.1825 5.6325 24 P 0 ;1
L 9.1825 5.6825 9.1825 5.6825 24 P 0 ;1
L 9.1825 5.7325 9.1825 5.7325 24 P 0 ;1
L 9.1825 5.7825 9.1825 5.7825 24 P 0 ;1
L 9.1825 5.8325 9.1825 5.8325 24 P 0 ;1
L 9.1825 5.8825 9.1825 5.8825 24 P 0 ;1
L 9.2325 0.1325 9.2325 0.1325 24 P 0 ;1
L 9.2325 0.1825 9.2325 0.1825 24 P 0 ;1
L 9.2325 0.2325 9.2325 0.2325 24 P 0 ;1
L 9.2325 0.2825 9.2325 0.2825 24 P 0 ;1
L 9.2325 0.3325 9.2325 0.3325 24 P 0 ;1
L 9.2325 0.6325 9.2325 0.6325 24 P 0 ;1
L 9.2325 0.6825 9.2325 0.6825 24 P 0 ;1
L 9.2325 0.7325 9.2325 0.7325 24 P 0 ;1
L 9.2325 0.7825 9.2325 0.7825 24 P 0 ;1
L 9.2325 0.8325 9.2325 0.8325 24 P 0 ;1
L 9.2325 0.8825 9.2325 0.8825 24 P 0 ;1
L 9.2325 0.9325 9.2325 0.9325 24 P 0 ;1
L 9.2325 0.9825 9.2325 0.9825 24 P 0 ;1
L 9.2325 1.0325 9.2325 1.0325 24 P 0 ;1
L 9.2325 1.0825 9.2325 1.0825 24 P 0 ;1
L 9.2325 1.1325 9.2325 1.1325 24 P 0 ;1
L 9.2325 1.1825 9.2325 1.1825 24 P 0 ;1
L 9.2325 1.2325 9.2325 1.2325 24 P 0 ;1
L 9.2325 1.2825 9.2325 1.2825 24 P 0 ;1
L 9.2325 1.3325 9.2325 1.3325 24 P 0 ;1
L 9.2325 1.3825 9.2325 1.3825 24 P 0 ;1
L 9.2325 1.4325 9.2325 1.4325 24 P 0 ;1
L 9.2325 1.4825 9.2325 1.4825 24 P 0 ;1
L 9.2325 1.5325 9.2325 1.5325 24 P 0 ;1
L 9.2325 1.5825 9.2325 1.5825 24 P 0 ;1
L 9.2325 1.6325 9.2325 1.6325 24 P 0 ;1
L 9.2325 1.6825 9.2325 1.6825 24 P 0 ;1
L 9.2325 1.7325 9.2325 1.7325 24 P 0 ;1
L 9.2325 1.7825 9.2325 1.7825 24 P 0 ;1
L 9.2325 1.8325 9.2325 1.8325 24 P 0 ;1
L 9.2325 1.8825 9.2325 1.8825 24 P 0 ;1
L 9.2325 1.9325 9.2325 1.9325 24 P 0 ;1
L 9.2325 1.9825 9.2325 1.9825 24 P 0 ;1
L 9.2325 2.0325 9.2325 2.0325 24 P 0 ;1
L 9.2325 2.0825 9.2325 2.0825 24 P 0 ;1
L 9.2325 2.1325 9.2325 2.1325 24 P 0 ;1
L 9.2325 2.1825 9.2325 2.1825 24 P 0 ;1
L 9.2325 2.2325 9.2325 2.2325 24 P 0 ;1
L 9.2325 2.2825 9.2325 2.2825 24 P 0 ;1
L 9.2325 2.3325 9.2325 2.3325 24 P 0 ;1
L 9.2325 2.3825 9.2325 2.3825 24 P 0 ;1
L 9.2325 2.4325 9.2325 2.4325 24 P 0 ;1
L 9.2325 2.4825 9.2325 2.4825 24 P 0 ;1
L 9.2325 2.5325 9.2325 2.5325 24 P 0 ;1
L 9.2325 2.5825 9.2325 2.5825 24 P 0 ;1
L 9.2325 2.6325 9.2325 2.6325 24 P 0 ;1
L 9.2325 2.6825 9.2325 2.6825 24 P 0 ;1
L 9.2325 2.7325 9.2325 2.7325 24 P 0 ;1
L 9.2325 2.7825 9.2325 2.7825 24 P 0 ;1
L 9.2325 2.8325 9.2325 2.8325 24 P 0 ;1
L 9.2325 2.8825 9.2325 2.8825 24 P 0 ;1
L 9.2325 2.9325 9.2325 2.9325 24 P 0 ;1
L 9.2325 2.9825 9.2325 2.9825 24 P 0 ;1
L 9.2325 3.0325 9.2325 3.0325 24 P 0 ;1
L 9.2325 3.0825 9.2325 3.0825 24 P 0 ;1
L 9.2325 3.1325 9.2325 3.1325 24 P 0 ;1
L 9.2325 3.1825 9.2325 3.1825 24 P 0 ;1
L 9.2325 3.2325 9.2325 3.2325 24 P 0 ;1
L 9.2325 3.2825 9.2325 3.2825 24 P 0 ;1
L 9.2325 3.3325 9.2325 3.3325 24 P 0 ;1
L 9.2325 3.3825 9.2325 3.3825 24 P 0 ;1
L 9.2325 3.4325 9.2325 3.4325 24 P 0 ;1
L 9.2325 3.4825 9.2325 3.4825 24 P 0 ;1
L 9.2325 3.5325 9.2325 3.5325 24 P 0 ;1
L 9.2325 3.5825 9.2325 3.5825 24 P 0 ;1
L 9.2325 3.6325 9.2325 3.6325 24 P 0 ;1
L 9.2325 3.6825 9.2325 3.6825 24 P 0 ;1
L 9.2325 3.7325 9.2325 3.7325 24 P 0 ;1
L 9.2325 3.7825 9.2325 3.7825 24 P 0 ;1
L 9.2325 3.8325 9.2325 3.8325 24 P 0 ;1
L 9.2325 3.8825 9.2325 3.8825 24 P 0 ;1
L 9.2325 3.9325 9.2325 3.9325 24 P 0 ;1
L 9.2325 3.9825 9.2325 3.9825 24 P 0 ;1
L 9.2325 4.0325 9.2325 4.0325 24 P 0 ;1
L 9.2325 4.0825 9.2325 4.0825 24 P 0 ;1
L 9.2325 4.1325 9.2325 4.1325 24 P 0 ;1
L 9.2325 4.1825 9.2325 4.1825 24 P 0 ;1
L 9.2325 4.2325 9.2325 4.2325 24 P 0 ;1
L 9.2325 4.2825 9.2325 4.2825 24 P 0 ;1
L 9.2325 4.3325 9.2325 4.3325 24 P 0 ;1
L 9.2325 4.3825 9.2325 4.3825 24 P 0 ;1
L 9.2325 5.4825 9.2325 5.4825 24 P 0 ;1
L 9.2325 5.5325 9.2325 5.5325 24 P 0 ;1
L 9.2325 5.5825 9.2325 5.5825 24 P 0 ;1
L 9.2325 5.6325 9.2325 5.6325 24 P 0 ;1
L 9.2325 5.6825 9.2325 5.6825 24 P 0 ;1
L 9.2325 5.7325 9.2325 5.7325 24 P 0 ;1
L 9.2325 5.7825 9.2325 5.7825 24 P 0 ;1
L 9.2325 5.8325 9.2325 5.8325 24 P 0 ;1
L 9.2325 5.8825 9.2325 5.8825 24 P 0 ;1
L 9.2825 0.1325 9.2825 0.1325 24 P 0 ;1
L 9.2825 0.1825 9.2825 0.1825 24 P 0 ;1
L 9.2825 0.2325 9.2825 0.2325 24 P 0 ;1
L 9.2825 0.2825 9.2825 0.2825 24 P 0 ;1
L 9.2825 2.6325 9.2825 2.6325 24 P 0 ;1
L 9.2825 2.6825 9.2825 2.6825 24 P 0 ;1
L 9.2825 2.7325 9.2825 2.7325 24 P 0 ;1
L 9.2825 2.7825 9.2825 2.7825 24 P 0 ;1
L 9.2825 2.8325 9.2825 2.8325 24 P 0 ;1
L 9.2825 2.8825 9.2825 2.8825 24 P 0 ;1
L 9.2825 2.9325 9.2825 2.9325 24 P 0 ;1
L 9.2825 2.9825 9.2825 2.9825 24 P 0 ;1
L 9.2825 3.0325 9.2825 3.0325 24 P 0 ;1
L 9.2825 3.0825 9.2825 3.0825 24 P 0 ;1
L 9.2825 3.1325 9.2825 3.1325 24 P 0 ;1
L 9.2825 3.1825 9.2825 3.1825 24 P 0 ;1
L 9.2825 3.2325 9.2825 3.2325 24 P 0 ;1
L 9.2825 3.2825 9.2825 3.2825 24 P 0 ;1
L 9.2825 3.3325 9.2825 3.3325 24 P 0 ;1
L 9.2825 3.3825 9.2825 3.3825 24 P 0 ;1
L 9.2825 3.4325 9.2825 3.4325 24 P 0 ;1
L 9.2825 3.4825 9.2825 3.4825 24 P 0 ;1
L 9.2825 3.5325 9.2825 3.5325 24 P 0 ;1
L 9.2825 3.5825 9.2825 3.5825 24 P 0 ;1
L 9.2825 3.6325 9.2825 3.6325 24 P 0 ;1
L 9.2825 3.6825 9.2825 3.6825 24 P 0 ;1
L 9.2825 3.7325 9.2825 3.7325 24 P 0 ;1
L 9.2825 3.7825 9.2825 3.7825 24 P 0 ;1
L 9.2825 3.8325 9.2825 3.8325 24 P 0 ;1
L 9.2825 3.8825 9.2825 3.8825 24 P 0 ;1
L 9.2825 3.9325 9.2825 3.9325 24 P 0 ;1
L 9.2825 3.9825 9.2825 3.9825 24 P 0 ;1
L 9.2825 4.0325 9.2825 4.0325 24 P 0 ;1
L 9.2825 4.0825 9.2825 4.0825 24 P 0 ;1
L 9.2825 4.1325 9.2825 4.1325 24 P 0 ;1
L 9.2825 4.1825 9.2825 4.1825 24 P 0 ;1
L 9.2825 4.2325 9.2825 4.2325 24 P 0 ;1
L 9.2825 4.2825 9.2825 4.2825 24 P 0 ;1
L 9.2825 4.3325 9.2825 4.3325 24 P 0 ;1
L 9.2825 4.3825 9.2825 4.3825 24 P 0 ;1
L 9.2825 4.4325 9.2825 4.4325 24 P 0 ;1
L 9.2825 4.4825 9.2825 4.4825 24 P 0 ;1
L 9.2825 4.5325 9.2825 4.5325 24 P 0 ;1
L 9.3325 0.1325 9.3325 0.1325 24 P 0 ;1
L 9.3325 0.1825 9.3325 0.1825 24 P 0 ;1
L 9.3325 2.6825 9.3325 2.6825 24 P 0 ;1
L 9.3325 2.7325 9.3325 2.7325 24 P 0 ;1
L 9.3325 2.7825 9.3325 2.7825 24 P 0 ;1
L 9.3325 2.8325 9.3325 2.8325 24 P 0 ;1
L 9.3325 2.8825 9.3325 2.8825 24 P 0 ;1
L 9.3325 2.9325 9.3325 2.9325 24 P 0 ;1
L 9.3325 2.9825 9.3325 2.9825 24 P 0 ;1
L 9.3325 3.0325 9.3325 3.0325 24 P 0 ;1
L 9.3325 3.0825 9.3325 3.0825 24 P 0 ;1
L 9.3325 3.1325 9.3325 3.1325 24 P 0 ;1
L 9.3325 3.1825 9.3325 3.1825 24 P 0 ;1
L 9.3325 3.2325 9.3325 3.2325 24 P 0 ;1
L 9.3325 3.2825 9.3325 3.2825 24 P 0 ;1
L 9.3325 3.3325 9.3325 3.3325 24 P 0 ;1
L 9.3325 3.3825 9.3325 3.3825 24 P 0 ;1
L 9.3325 3.4325 9.3325 3.4325 24 P 0 ;1
L 9.3325 3.4825 9.3325 3.4825 24 P 0 ;1
L 9.3325 3.5325 9.3325 3.5325 24 P 0 ;1
L 9.3325 3.5825 9.3325 3.5825 24 P 0 ;1
L 9.3325 3.6325 9.3325 3.6325 24 P 0 ;1
L 9.3325 3.6825 9.3325 3.6825 24 P 0 ;1
L 9.3325 3.7325 9.3325 3.7325 24 P 0 ;1
L 9.3325 3.7825 9.3325 3.7825 24 P 0 ;1
L 9.3325 3.8325 9.3325 3.8325 24 P 0 ;1
L 9.3325 3.8825 9.3325 3.8825 24 P 0 ;1
L 9.3325 3.9325 9.3325 3.9325 24 P 0 ;1
L 9.3325 3.9825 9.3325 3.9825 24 P 0 ;1
L 9.3325 4.0325 9.3325 4.0325 24 P 0 ;1
L 9.3325 4.0825 9.3325 4.0825 24 P 0 ;1
L 9.3325 4.1325 9.3325 4.1325 24 P 0 ;1
L 9.3325 4.1825 9.3325 4.1825 24 P 0 ;1
L 9.3325 4.2325 9.3325 4.2325 24 P 0 ;1
L 9.3325 4.2825 9.3325 4.2825 24 P 0 ;1
L 9.3325 4.3325 9.3325 4.3325 24 P 0 ;1
L 9.3325 4.3825 9.3325 4.3825 24 P 0 ;1
L 9.3325 4.4325 9.3325 4.4325 24 P 0 ;1
L 9.3325 4.4825 9.3325 4.4825 24 P 0 ;1
L 9.3325 4.5325 9.3325 4.5325 24 P 0 ;1
L 9.3825 0.1325 9.3825 0.1325 24 P 0 ;1
L 9.3825 2.7325 9.3825 2.7325 24 P 0 ;1
L 9.3825 2.7825 9.3825 2.7825 24 P 0 ;1
L 9.3825 2.8325 9.3825 2.8325 24 P 0 ;1
L 9.3825 2.8825 9.3825 2.8825 24 P 0 ;1
L 9.3825 2.9325 9.3825 2.9325 24 P 0 ;1
L 9.3825 2.9825 9.3825 2.9825 24 P 0 ;1
L 9.3825 3.0325 9.3825 3.0325 24 P 0 ;1
L 9.3825 3.0825 9.3825 3.0825 24 P 0 ;1
L 9.3825 3.1325 9.3825 3.1325 24 P 0 ;1
L 9.3825 3.1825 9.3825 3.1825 24 P 0 ;1
L 9.3825 3.2325 9.3825 3.2325 24 P 0 ;1
L 9.3825 3.2825 9.3825 3.2825 24 P 0 ;1
L 9.3825 3.3325 9.3825 3.3325 24 P 0 ;1
L 9.3825 3.3825 9.3825 3.3825 24 P 0 ;1
L 9.3825 3.4325 9.3825 3.4325 24 P 0 ;1
L 9.3825 3.4825 9.3825 3.4825 24 P 0 ;1
L 9.3825 3.5325 9.3825 3.5325 24 P 0 ;1
L 9.3825 3.5825 9.3825 3.5825 24 P 0 ;1
L 9.3825 3.6325 9.3825 3.6325 24 P 0 ;1
L 9.3825 3.6825 9.3825 3.6825 24 P 0 ;1
L 9.3825 3.7325 9.3825 3.7325 24 P 0 ;1
L 9.3825 3.7825 9.3825 3.7825 24 P 0 ;1
L 9.3825 3.8325 9.3825 3.8325 24 P 0 ;1
L 9.3825 3.8825 9.3825 3.8825 24 P 0 ;1
L 9.3825 3.9325 9.3825 3.9325 24 P 0 ;1
L 9.3825 3.9825 9.3825 3.9825 24 P 0 ;1
L 9.3825 4.0325 9.3825 4.0325 24 P 0 ;1
L 9.3825 4.0825 9.3825 4.0825 24 P 0 ;1
L 9.3825 4.1325 9.3825 4.1325 24 P 0 ;1
L 9.3825 4.1825 9.3825 4.1825 24 P 0 ;1
L 9.3825 4.2325 9.3825 4.2325 24 P 0 ;1
L 9.3825 4.2825 9.3825 4.2825 24 P 0 ;1
L 9.3825 4.3325 9.3825 4.3325 24 P 0 ;1
L 9.3825 4.3825 9.3825 4.3825 24 P 0 ;1
L 9.3825 4.4325 9.3825 4.4325 24 P 0 ;1
L 9.3825 4.4825 9.3825 4.4825 24 P 0 ;1
L 9.4325 0.1325 9.4325 0.1325 24 P 0 ;1
L 9.4325 2.7825 9.4325 2.7825 24 P 0 ;1
L 9.4325 2.8325 9.4325 2.8325 24 P 0 ;1
L 9.4325 2.8825 9.4325 2.8825 24 P 0 ;1
L 9.4325 2.9325 9.4325 2.9325 24 P 0 ;1
L 9.4325 2.9825 9.4325 2.9825 24 P 0 ;1
L 9.4325 3.0325 9.4325 3.0325 24 P 0 ;1
L 9.4325 3.0825 9.4325 3.0825 24 P 0 ;1
L 9.4325 3.1325 9.4325 3.1325 24 P 0 ;1
L 9.4325 3.1825 9.4325 3.1825 24 P 0 ;1
L 9.4325 3.2325 9.4325 3.2325 24 P 0 ;1
L 9.4325 3.2825 9.4325 3.2825 24 P 0 ;1
L 9.4325 3.3325 9.4325 3.3325 24 P 0 ;1
L 9.4325 3.3825 9.4325 3.3825 24 P 0 ;1
L 9.4325 3.4325 9.4325 3.4325 24 P 0 ;1
L 9.4325 3.4825 9.4325 3.4825 24 P 0 ;1
L 9.4325 3.5325 9.4325 3.5325 24 P 0 ;1
L 9.4325 3.5825 9.4325 3.5825 24 P 0 ;1
L 9.4325 3.6325 9.4325 3.6325 24 P 0 ;1
L 9.4325 3.6825 9.4325 3.6825 24 P 0 ;1
L 9.4325 3.7325 9.4325 3.7325 24 P 0 ;1
L 9.4325 3.7825 9.4325 3.7825 24 P 0 ;1
L 9.4325 3.8325 9.4325 3.8325 24 P 0 ;1
L 9.4325 3.8825 9.4325 3.8825 24 P 0 ;1
L 9.4325 3.9325 9.4325 3.9325 24 P 0 ;1
L 9.4325 3.9825 9.4325 3.9825 24 P 0 ;1
L 9.4325 4.0325 9.4325 4.0325 24 P 0 ;1
L 9.4325 4.0825 9.4325 4.0825 24 P 0 ;1
L 9.4325 4.1325 9.4325 4.1325 24 P 0 ;1
L 9.4325 4.1825 9.4325 4.1825 24 P 0 ;1
L 9.4325 4.2325 9.4325 4.2325 24 P 0 ;1
L 9.4325 4.2825 9.4325 4.2825 24 P 0 ;1
L 9.4325 4.3325 9.4325 4.3325 24 P 0 ;1
L 9.4325 4.3825 9.4325 4.3825 24 P 0 ;1
L 9.4325 4.4325 9.4325 4.4325 24 P 0 ;1
L 9.4325 4.4825 9.4325 4.4825 24 P 0 ;1
L 9.4825 0.1325 9.4825 0.1325 24 P 0 ;1
L 9.4825 0.1825 9.4825 0.1825 24 P 0 ;1
L 9.4825 2.8325 9.4825 2.8325 24 P 0 ;1
L 9.4825 2.8825 9.4825 2.8825 24 P 0 ;1
L 9.4825 2.9325 9.4825 2.9325 24 P 0 ;1
L 9.4825 2.9825 9.4825 2.9825 24 P 0 ;1
L 9.4825 3.0325 9.4825 3.0325 24 P 0 ;1
L 9.4825 3.0825 9.4825 3.0825 24 P 0 ;1
L 9.4825 3.1325 9.4825 3.1325 24 P 0 ;1
L 9.4825 3.1825 9.4825 3.1825 24 P 0 ;1
L 9.4825 3.2325 9.4825 3.2325 24 P 0 ;1
L 9.4825 3.2825 9.4825 3.2825 24 P 0 ;1
L 9.4825 3.3325 9.4825 3.3325 24 P 0 ;1
L 9.4825 3.3825 9.4825 3.3825 24 P 0 ;1
L 9.4825 3.4325 9.4825 3.4325 24 P 0 ;1
L 9.4825 3.4825 9.4825 3.4825 24 P 0 ;1
L 9.4825 3.5325 9.4825 3.5325 24 P 0 ;1
L 9.4825 3.5825 9.4825 3.5825 24 P 0 ;1
L 9.4825 3.6325 9.4825 3.6325 24 P 0 ;1
L 9.4825 3.6825 9.4825 3.6825 24 P 0 ;1
L 9.4825 3.7325 9.4825 3.7325 24 P 0 ;1
L 9.4825 3.7825 9.4825 3.7825 24 P 0 ;1
L 9.4825 3.8325 9.4825 3.8325 24 P 0 ;1
L 9.4825 3.8825 9.4825 3.8825 24 P 0 ;1
L 9.4825 3.9325 9.4825 3.9325 24 P 0 ;1
L 9.4825 3.9825 9.4825 3.9825 24 P 0 ;1
L 9.4825 4.0325 9.4825 4.0325 24 P 0 ;1
L 9.4825 4.0825 9.4825 4.0825 24 P 0 ;1
L 9.4825 4.1325 9.4825 4.1325 24 P 0 ;1
L 9.4825 4.1825 9.4825 4.1825 24 P 0 ;1
L 9.4825 4.2325 9.4825 4.2325 24 P 0 ;1
L 9.4825 4.2825 9.4825 4.2825 24 P 0 ;1
L 9.4825 4.3325 9.4825 4.3325 24 P 0 ;1
L 9.4825 4.3825 9.4825 4.3825 24 P 0 ;1
L 9.4825 4.4325 9.4825 4.4325 24 P 0 ;1
L 9.4825 4.4825 9.4825 4.4825 24 P 0 ;1
L 9.4825 5.4325 9.4825 5.4325 24 P 0 ;1
L 9.4825 5.4825 9.4825 5.4825 24 P 0 ;1
L 9.4825 5.5325 9.4825 5.5325 24 P 0 ;1
L 9.4825 5.5825 9.4825 5.5825 24 P 0 ;1
L 9.4825 5.6325 9.4825 5.6325 24 P 0 ;1
L 9.4825 5.6825 9.4825 5.6825 24 P 0 ;1
L 9.4825 5.7325 9.4825 5.7325 24 P 0 ;1
L 9.4825 5.7825 9.4825 5.7825 24 P 0 ;1
L 9.5325 0.1325 9.5325 0.1325 24 P 0 ;1
L 9.5325 2.8825 9.5325 2.8825 24 P 0 ;1
L 9.5325 2.9325 9.5325 2.9325 24 P 0 ;1
L 9.5325 2.9825 9.5325 2.9825 24 P 0 ;1
L 9.5325 3.0325 9.5325 3.0325 24 P 0 ;1
L 9.5325 3.0825 9.5325 3.0825 24 P 0 ;1
L 9.5325 3.1325 9.5325 3.1325 24 P 0 ;1
L 9.5325 3.1825 9.5325 3.1825 24 P 0 ;1
L 9.5325 3.2325 9.5325 3.2325 24 P 0 ;1
L 9.5325 3.2825 9.5325 3.2825 24 P 0 ;1
L 9.5325 3.3325 9.5325 3.3325 24 P 0 ;1
L 9.5325 3.3825 9.5325 3.3825 24 P 0 ;1
L 9.5325 3.4325 9.5325 3.4325 24 P 0 ;1
L 9.5325 3.4825 9.5325 3.4825 24 P 0 ;1
L 9.5325 3.5325 9.5325 3.5325 24 P 0 ;1
L 9.5325 3.5825 9.5325 3.5825 24 P 0 ;1
L 9.5325 3.6325 9.5325 3.6325 24 P 0 ;1
L 9.5325 3.6825 9.5325 3.6825 24 P 0 ;1
L 9.5325 3.7325 9.5325 3.7325 24 P 0 ;1
L 9.5325 3.7825 9.5325 3.7825 24 P 0 ;1
L 9.5325 3.8325 9.5325 3.8325 24 P 0 ;1
L 9.5325 3.8825 9.5325 3.8825 24 P 0 ;1
L 9.5325 3.9325 9.5325 3.9325 24 P 0 ;1
L 9.5325 3.9825 9.5325 3.9825 24 P 0 ;1
L 9.5325 4.0325 9.5325 4.0325 24 P 0 ;1
L 9.5325 4.0825 9.5325 4.0825 24 P 0 ;1
L 9.5325 4.1325 9.5325 4.1325 24 P 0 ;1
L 9.5325 4.1825 9.5325 4.1825 24 P 0 ;1
L 9.5325 4.2325 9.5325 4.2325 24 P 0 ;1
L 9.5325 4.2825 9.5325 4.2825 24 P 0 ;1
L 9.5325 4.3325 9.5325 4.3325 24 P 0 ;1
L 9.5325 4.3825 9.5325 4.3825 24 P 0 ;1
L 9.5325 4.4325 9.5325 4.4325 24 P 0 ;1
L 9.5325 4.4825 9.5325 4.4825 24 P 0 ;1
L 9.5325 5.3825 9.5325 5.3825 24 P 0 ;1
L 9.5325 5.4325 9.5325 5.4325 24 P 0 ;1
L 9.5325 5.4825 9.5325 5.4825 24 P 0 ;1
L 9.5325 5.5325 9.5325 5.5325 24 P 0 ;1
L 9.5325 5.5825 9.5325 5.5825 24 P 0 ;1
L 9.5325 5.6325 9.5325 5.6325 24 P 0 ;1
L 9.5325 5.6825 9.5325 5.6825 24 P 0 ;1
L 9.5325 5.7325 9.5325 5.7325 24 P 0 ;1
L 9.5325 5.7825 9.5325 5.7825 24 P 0 ;1
L 9.5325 5.8325 9.5325 5.8325 24 P 0 ;1
L 9.5825 0.1325 9.5825 0.1325 24 P 0 ;1
L 9.5825 0.4825 9.5825 0.4825 24 P 0 ;1
L 9.5825 2.9325 9.5825 2.9325 24 P 0 ;1
L 9.5825 2.9825 9.5825 2.9825 24 P 0 ;1
L 9.5825 3.0325 9.5825 3.0325 24 P 0 ;1
L 9.5825 3.0825 9.5825 3.0825 24 P 0 ;1
L 9.5825 3.1325 9.5825 3.1325 24 P 0 ;1
L 9.5825 3.1825 9.5825 3.1825 24 P 0 ;1
L 9.5825 3.2325 9.5825 3.2325 24 P 0 ;1
L 9.5825 3.2825 9.5825 3.2825 24 P 0 ;1
L 9.5825 3.3325 9.5825 3.3325 24 P 0 ;1
L 9.5825 3.3825 9.5825 3.3825 24 P 0 ;1
L 9.5825 3.4325 9.5825 3.4325 24 P 0 ;1
L 9.5825 3.4825 9.5825 3.4825 24 P 0 ;1
L 9.5825 3.5325 9.5825 3.5325 24 P 0 ;1
L 9.5825 3.5825 9.5825 3.5825 24 P 0 ;1
L 9.5825 3.6325 9.5825 3.6325 24 P 0 ;1
L 9.5825 3.6825 9.5825 3.6825 24 P 0 ;1
L 9.5825 3.7325 9.5825 3.7325 24 P 0 ;1
L 9.5825 3.7825 9.5825 3.7825 24 P 0 ;1
L 9.5825 3.8325 9.5825 3.8325 24 P 0 ;1
L 9.5825 3.8825 9.5825 3.8825 24 P 0 ;1
L 9.5825 3.9325 9.5825 3.9325 24 P 0 ;1
L 9.5825 3.9825 9.5825 3.9825 24 P 0 ;1
L 9.5825 4.0325 9.5825 4.0325 24 P 0 ;1
L 9.5825 4.0825 9.5825 4.0825 24 P 0 ;1
L 9.5825 4.1325 9.5825 4.1325 24 P 0 ;1
L 9.5825 4.1825 9.5825 4.1825 24 P 0 ;1
L 9.5825 4.2325 9.5825 4.2325 24 P 0 ;1
L 9.5825 4.2825 9.5825 4.2825 24 P 0 ;1
L 9.5825 4.3325 9.5825 4.3325 24 P 0 ;1
L 9.5825 4.3825 9.5825 4.3825 24 P 0 ;1
L 9.5825 4.4325 9.5825 4.4325 24 P 0 ;1
L 9.5825 4.4825 9.5825 4.4825 24 P 0 ;1
L 9.5825 4.5325 9.5825 4.5325 24 P 0 ;1
L 9.5825 5.2825 9.5825 5.2825 24 P 0 ;1
L 9.5825 5.3325 9.5825 5.3325 24 P 0 ;1
L 9.5825 5.3825 9.5825 5.3825 24 P 0 ;1
L 9.5825 5.4325 9.5825 5.4325 24 P 0 ;1
L 9.5825 5.4825 9.5825 5.4825 24 P 0 ;1
L 9.5825 5.5325 9.5825 5.5325 24 P 0 ;1
L 9.5825 5.5825 9.5825 5.5825 24 P 0 ;1
L 9.5825 5.6325 9.5825 5.6325 24 P 0 ;1
L 9.5825 5.6825 9.5825 5.6825 24 P 0 ;1
L 9.5825 5.7325 9.5825 5.7325 24 P 0 ;1
L 9.5825 5.7825 9.5825 5.7825 24 P 0 ;1
L 9.5825 5.8325 9.5825 5.8325 24 P 0 ;1
L 9.6325 0.1325 9.6325 0.1325 24 P 0 ;1
L 9.6325 0.1825 9.6325 0.1825 24 P 0 ;1
L 9.6325 2.9825 9.6325 2.9825 24 P 0 ;1
L 9.6325 3.0325 9.6325 3.0325 24 P 0 ;1
L 9.6325 3.0825 9.6325 3.0825 24 P 0 ;1
L 9.6325 3.1325 9.6325 3.1325 24 P 0 ;1
L 9.6325 3.1825 9.6325 3.1825 24 P 0 ;1
L 9.6325 3.2325 9.6325 3.2325 24 P 0 ;1
L 9.6325 3.2825 9.6325 3.2825 24 P 0 ;1
L 9.6325 3.3325 9.6325 3.3325 24 P 0 ;1
L 9.6325 3.3825 9.6325 3.3825 24 P 0 ;1
L 9.6325 3.4325 9.6325 3.4325 24 P 0 ;1
L 9.6325 3.4825 9.6325 3.4825 24 P 0 ;1
L 9.6325 3.5325 9.6325 3.5325 24 P 0 ;1
L 9.6325 3.5825 9.6325 3.5825 24 P 0 ;1
L 9.6325 3.6325 9.6325 3.6325 24 P 0 ;1
L 9.6325 3.6825 9.6325 3.6825 24 P 0 ;1
L 9.6325 3.7325 9.6325 3.7325 24 P 0 ;1
L 9.6325 3.7825 9.6325 3.7825 24 P 0 ;1
L 9.6325 3.8325 9.6325 3.8325 24 P 0 ;1
L 9.6325 3.8825 9.6325 3.8825 24 P 0 ;1
L 9.6325 3.9325 9.6325 3.9325 24 P 0 ;1
L 9.6325 3.9825 9.6325 3.9825 24 P 0 ;1
L 9.6325 4.0325 9.6325 4.0325 24 P 0 ;1
L 9.6325 4.0825 9.6325 4.0825 24 P 0 ;1
L 9.6325 4.1325 9.6325 4.1325 24 P 0 ;1
L 9.6325 4.1825 9.6325 4.1825 24 P 0 ;1
L 9.6325 4.2325 9.6325 4.2325 24 P 0 ;1
L 9.6325 4.2825 9.6325 4.2825 24 P 0 ;1
L 9.6325 4.3325 9.6325 4.3325 24 P 0 ;1
L 9.6325 4.3825 9.6325 4.3825 24 P 0 ;1
L 9.6325 4.4325 9.6325 4.4325 24 P 0 ;1
L 9.6325 4.4825 9.6325 4.4825 24 P 0 ;1
L 9.6325 4.5325 9.6325 4.5325 24 P 0 ;1
L 9.6325 4.5825 9.6325 4.5825 24 P 0 ;1
L 9.6325 5.2825 9.6325 5.2825 24 P 0 ;1
L 9.6325 5.3325 9.6325 5.3325 24 P 0 ;1
L 9.6325 5.3825 9.6325 5.3825 24 P 0 ;1
L 9.6325 5.4325 9.6325 5.4325 24 P 0 ;1
L 9.6325 5.4825 9.6325 5.4825 24 P 0 ;1
L 9.6325 5.5325 9.6325 5.5325 24 P 0 ;1
L 9.6325 5.5825 9.6325 5.5825 24 P 0 ;1
L 9.6325 5.6325 9.6325 5.6325 24 P 0 ;1
L 9.6325 5.6825 9.6325 5.6825 24 P 0 ;1
L 9.6325 5.7325 9.6325 5.7325 24 P 0 ;1
L 9.6325 5.7825 9.6325 5.7825 24 P 0 ;1
L 9.6325 5.8325 9.6325 5.8325 24 P 0 ;1
L 9.6825 0.1325 9.6825 0.1325 24 P 0 ;1
L 9.6825 0.1825 9.6825 0.1825 24 P 0 ;1
L 9.6825 0.2325 9.6825 0.2325 24 P 0 ;1
L 9.6825 0.2825 9.6825 0.2825 24 P 0 ;1
L 9.6825 3.0325 9.6825 3.0325 24 P 0 ;1
L 9.6825 3.0825 9.6825 3.0825 24 P 0 ;1
L 9.6825 3.1325 9.6825 3.1325 24 P 0 ;1
L 9.6825 3.1825 9.6825 3.1825 24 P 0 ;1
L 9.6825 3.2325 9.6825 3.2325 24 P 0 ;1
L 9.6825 3.2825 9.6825 3.2825 24 P 0 ;1
L 9.6825 3.3325 9.6825 3.3325 24 P 0 ;1
L 9.6825 3.3825 9.6825 3.3825 24 P 0 ;1
L 9.6825 3.4325 9.6825 3.4325 24 P 0 ;1
L 9.6825 3.4825 9.6825 3.4825 24 P 0 ;1
L 9.6825 3.5325 9.6825 3.5325 24 P 0 ;1
L 9.6825 3.5825 9.6825 3.5825 24 P 0 ;1
L 9.6825 3.6325 9.6825 3.6325 24 P 0 ;1
L 9.6825 3.6825 9.6825 3.6825 24 P 0 ;1
L 9.6825 3.7325 9.6825 3.7325 24 P 0 ;1
L 9.6825 3.7825 9.6825 3.7825 24 P 0 ;1
L 9.6825 3.8325 9.6825 3.8325 24 P 0 ;1
L 9.6825 3.8825 9.6825 3.8825 24 P 0 ;1
L 9.6825 3.9325 9.6825 3.9325 24 P 0 ;1
L 9.6825 3.9825 9.6825 3.9825 24 P 0 ;1
L 9.6825 4.0325 9.6825 4.0325 24 P 0 ;1
L 9.6825 4.0825 9.6825 4.0825 24 P 0 ;1
L 9.6825 4.1325 9.6825 4.1325 24 P 0 ;1
L 9.6825 4.1825 9.6825 4.1825 24 P 0 ;1
L 9.6825 4.2325 9.6825 4.2325 24 P 0 ;1
L 9.6825 4.2825 9.6825 4.2825 24 P 0 ;1
L 9.6825 4.3325 9.6825 4.3325 24 P 0 ;1
L 9.6825 4.3825 9.6825 4.3825 24 P 0 ;1
L 9.6825 4.4325 9.6825 4.4325 24 P 0 ;1
L 9.6825 4.4825 9.6825 4.4825 24 P 0 ;1
L 9.6825 4.5325 9.6825 4.5325 24 P 0 ;1
L 9.6825 4.5825 9.6825 4.5825 24 P 0 ;1
L 9.6825 4.6325 9.6825 4.6325 24 P 0 ;1
L 9.6825 4.6825 9.6825 4.6825 24 P 0 ;1
L 9.6825 5.1825 9.6825 5.1825 24 P 0 ;1
L 9.6825 5.2325 9.6825 5.2325 24 P 0 ;1
L 9.6825 5.2825 9.6825 5.2825 24 P 0 ;1
L 9.6825 5.3325 9.6825 5.3325 24 P 0 ;1
L 9.6825 5.3825 9.6825 5.3825 24 P 0 ;1
L 9.6825 5.4325 9.6825 5.4325 24 P 0 ;1
L 9.6825 5.4825 9.6825 5.4825 24 P 0 ;1
L 9.6825 5.5325 9.6825 5.5325 24 P 0 ;1
L 9.6825 5.5825 9.6825 5.5825 24 P 0 ;1
L 9.6825 5.6325 9.6825 5.6325 24 P 0 ;1
L 9.6825 5.6825 9.6825 5.6825 24 P 0 ;1
L 9.6825 5.7325 9.6825 5.7325 24 P 0 ;1
L 9.6825 5.7825 9.6825 5.7825 24 P 0 ;1
L 9.6825 5.8325 9.6825 5.8325 24 P 0 ;1
L 9.7325 0.1325 9.7325 0.1325 24 P 0 ;1
L 9.7325 0.1825 9.7325 0.1825 24 P 0 ;1
L 9.7325 0.2325 9.7325 0.2325 24 P 0 ;1
L 9.7325 0.2825 9.7325 0.2825 24 P 0 ;1
L 9.7325 0.3325 9.7325 0.3325 24 P 0 ;1
L 9.7325 3.0825 9.7325 3.0825 24 P 0 ;1
L 9.7325 3.1325 9.7325 3.1325 24 P 0 ;1
L 9.7325 3.1825 9.7325 3.1825 24 P 0 ;1
L 9.7325 3.2325 9.7325 3.2325 24 P 0 ;1
L 9.7325 3.2825 9.7325 3.2825 24 P 0 ;1
L 9.7325 3.3325 9.7325 3.3325 24 P 0 ;1
L 9.7325 3.3825 9.7325 3.3825 24 P 0 ;1
L 9.7325 3.4325 9.7325 3.4325 24 P 0 ;1
L 9.7325 3.4825 9.7325 3.4825 24 P 0 ;1
L 9.7325 3.5325 9.7325 3.5325 24 P 0 ;1
L 9.7325 3.5825 9.7325 3.5825 24 P 0 ;1
L 9.7325 3.6325 9.7325 3.6325 24 P 0 ;1
L 9.7325 3.6825 9.7325 3.6825 24 P 0 ;1
L 9.7325 3.7325 9.7325 3.7325 24 P 0 ;1
L 9.7325 3.7825 9.7325 3.7825 24 P 0 ;1
L 9.7325 3.8325 9.7325 3.8325 24 P 0 ;1
L 9.7325 3.8825 9.7325 3.8825 24 P 0 ;1
L 9.7325 3.9325 9.7325 3.9325 24 P 0 ;1
L 9.7325 3.9825 9.7325 3.9825 24 P 0 ;1
L 9.7325 4.0325 9.7325 4.0325 24 P 0 ;1
L 9.7325 4.0825 9.7325 4.0825 24 P 0 ;1
L 9.7325 4.1325 9.7325 4.1325 24 P 0 ;1
L 9.7325 4.1825 9.7325 4.1825 24 P 0 ;1
L 9.7325 4.2325 9.7325 4.2325 24 P 0 ;1
L 9.7325 4.2825 9.7325 4.2825 24 P 0 ;1
L 9.7325 4.3325 9.7325 4.3325 24 P 0 ;1
L 9.7325 4.3825 9.7325 4.3825 24 P 0 ;1
L 9.7325 4.4325 9.7325 4.4325 24 P 0 ;1
L 9.7325 4.4825 9.7325 4.4825 24 P 0 ;1
L 9.7325 4.5325 9.7325 4.5325 24 P 0 ;1
L 9.7325 4.5825 9.7325 4.5825 24 P 0 ;1
L 9.7325 4.6325 9.7325 4.6325 24 P 0 ;1
L 9.7325 4.6825 9.7325 4.6825 24 P 0 ;1
L 9.7325 4.7325 9.7325 4.7325 24 P 0 ;1
L 9.7325 4.7825 9.7325 4.7825 24 P 0 ;1
L 9.7325 4.8325 9.7325 4.8325 24 P 0 ;1
L 9.7325 4.8825 9.7325 4.8825 24 P 0 ;1
L 9.7325 4.9325 9.7325 4.9325 24 P 0 ;1
L 9.7325 4.9825 9.7325 4.9825 24 P 0 ;1
L 9.7325 5.0325 9.7325 5.0325 24 P 0 ;1
L 9.7325 5.0825 9.7325 5.0825 24 P 0 ;1
L 9.7325 5.1325 9.7325 5.1325 24 P 0 ;1
L 9.7325 5.1825 9.7325 5.1825 24 P 0 ;1
L 9.7325 5.2325 9.7325 5.2325 24 P 0 ;1
L 9.7325 5.2825 9.7325 5.2825 24 P 0 ;1
L 9.7325 5.3325 9.7325 5.3325 24 P 0 ;1
L 9.7325 5.3825 9.7325 5.3825 24 P 0 ;1
L 9.7325 5.4325 9.7325 5.4325 24 P 0 ;1
L 9.7325 5.4825 9.7325 5.4825 24 P 0 ;1
L 9.7325 5.5325 9.7325 5.5325 24 P 0 ;1
L 9.7325 5.5825 9.7325 5.5825 24 P 0 ;1
L 9.7325 5.6325 9.7325 5.6325 24 P 0 ;1
L 9.7325 5.6825 9.7325 5.6825 24 P 0 ;1
L 9.7325 5.7325 9.7325 5.7325 24 P 0 ;1
L 9.7325 5.7825 9.7325 5.7825 24 P 0 ;1
L 9.7325 5.8325 9.7325 5.8325 24 P 0 ;1
L 9.7825 0.1325 9.7825 0.1325 24 P 0 ;1
L 9.7825 0.1825 9.7825 0.1825 24 P 0 ;1
L 9.7825 0.2325 9.7825 0.2325 24 P 0 ;1
L 9.7825 0.2825 9.7825 0.2825 24 P 0 ;1
L 9.7825 0.3325 9.7825 0.3325 24 P 0 ;1
L 9.7825 0.3825 9.7825 0.3825 24 P 0 ;1
L 9.7825 3.1325 9.7825 3.1325 24 P 0 ;1
L 9.7825 3.1825 9.7825 3.1825 24 P 0 ;1
L 9.7825 3.2325 9.7825 3.2325 24 P 0 ;1
L 9.7825 3.2825 9.7825 3.2825 24 P 0 ;1
L 9.7825 3.3325 9.7825 3.3325 24 P 0 ;1
L 9.7825 3.3825 9.7825 3.3825 24 P 0 ;1
L 9.7825 3.4325 9.7825 3.4325 24 P 0 ;1
L 9.7825 3.4825 9.7825 3.4825 24 P 0 ;1
L 9.7825 3.5325 9.7825 3.5325 24 P 0 ;1
L 9.7825 3.5825 9.7825 3.5825 24 P 0 ;1
L 9.7825 3.6325 9.7825 3.6325 24 P 0 ;1
L 9.7825 3.6825 9.7825 3.6825 24 P 0 ;1
L 9.7825 3.7325 9.7825 3.7325 24 P 0 ;1
L 9.7825 3.7825 9.7825 3.7825 24 P 0 ;1
L 9.7825 3.8325 9.7825 3.8325 24 P 0 ;1
L 9.7825 3.8825 9.7825 3.8825 24 P 0 ;1
L 9.7825 3.9325 9.7825 3.9325 24 P 0 ;1
L 9.7825 3.9825 9.7825 3.9825 24 P 0 ;1
L 9.7825 4.0325 9.7825 4.0325 24 P 0 ;1
L 9.7825 4.0825 9.7825 4.0825 24 P 0 ;1
L 9.7825 4.1325 9.7825 4.1325 24 P 0 ;1
L 9.7825 4.1825 9.7825 4.1825 24 P 0 ;1
L 9.7825 4.2325 9.7825 4.2325 24 P 0 ;1
L 9.7825 4.2825 9.7825 4.2825 24 P 0 ;1
L 9.7825 4.3325 9.7825 4.3325 24 P 0 ;1
L 9.7825 4.3825 9.7825 4.3825 24 P 0 ;1
L 9.7825 4.4325 9.7825 4.4325 24 P 0 ;1
L 9.7825 4.4825 9.7825 4.4825 24 P 0 ;1
L 9.7825 4.5325 9.7825 4.5325 24 P 0 ;1
L 9.7825 4.5825 9.7825 4.5825 24 P 0 ;1
L 9.7825 4.6325 9.7825 4.6325 24 P 0 ;1
L 9.7825 4.6825 9.7825 4.6825 24 P 0 ;1
L 9.7825 4.7325 9.7825 4.7325 24 P 0 ;1
L 9.7825 4.7825 9.7825 4.7825 24 P 0 ;1
L 9.7825 4.8325 9.7825 4.8325 24 P 0 ;1
L 9.7825 4.8825 9.7825 4.8825 24 P 0 ;1
L 9.7825 4.9325 9.7825 4.9325 24 P 0 ;1
L 9.7825 4.9825 9.7825 4.9825 24 P 0 ;1
L 9.7825 5.0325 9.7825 5.0325 24 P 0 ;1
L 9.7825 5.0825 9.7825 5.0825 24 P 0 ;1
L 9.7825 5.1325 9.7825 5.1325 24 P 0 ;1
L 9.7825 5.1825 9.7825 5.1825 24 P 0 ;1
L 9.7825 5.2325 9.7825 5.2325 24 P 0 ;1
L 9.7825 5.2825 9.7825 5.2825 24 P 0 ;1
L 9.7825 5.3325 9.7825 5.3325 24 P 0 ;1
L 9.7825 5.3825 9.7825 5.3825 24 P 0 ;1
L 9.7825 5.4325 9.7825 5.4325 24 P 0 ;1
L 9.7825 5.4825 9.7825 5.4825 24 P 0 ;1
L 9.7825 5.5325 9.7825 5.5325 24 P 0 ;1
L 9.7825 5.5825 9.7825 5.5825 24 P 0 ;1
L 9.7825 5.6325 9.7825 5.6325 24 P 0 ;1
L 9.7825 5.6825 9.7825 5.6825 24 P 0 ;1
L 9.7825 5.7325 9.7825 5.7325 24 P 0 ;1
L 9.7825 5.7825 9.7825 5.7825 24 P 0 ;1
L 9.7825 5.8325 9.7825 5.8325 24 P 0 ;1
L 9.8325 0.1325 9.8325 0.1325 24 P 0 ;1
L 9.8325 0.1825 9.8325 0.1825 24 P 0 ;1
L 9.8325 0.2325 9.8325 0.2325 24 P 0 ;1
L 9.8325 0.2825 9.8325 0.2825 24 P 0 ;1
L 9.8325 0.3325 9.8325 0.3325 24 P 0 ;1
L 9.8325 0.3825 9.8325 0.3825 24 P 0 ;1
L 9.8325 0.4325 9.8325 0.4325 24 P 0 ;1
L 9.8325 0.4825 9.8325 0.4825 24 P 0 ;1
L 9.8325 0.5325 9.8325 0.5325 24 P 0 ;1
L 9.8325 0.5825 9.8325 0.5825 24 P 0 ;1
L 9.8325 0.6325 9.8325 0.6325 24 P 0 ;1
L 9.8325 0.6825 9.8325 0.6825 24 P 0 ;1
L 9.8325 0.7325 9.8325 0.7325 24 P 0 ;1
L 9.8325 0.7825 9.8325 0.7825 24 P 0 ;1
L 9.8325 0.8325 9.8325 0.8325 24 P 0 ;1
L 9.8325 0.8825 9.8325 0.8825 24 P 0 ;1
L 9.8325 0.9325 9.8325 0.9325 24 P 0 ;1
L 9.8325 0.9825 9.8325 0.9825 24 P 0 ;1
L 9.8325 1.0325 9.8325 1.0325 24 P 0 ;1
L 9.8325 1.0825 9.8325 1.0825 24 P 0 ;1
L 9.8325 1.1325 9.8325 1.1325 24 P 0 ;1
L 9.8325 1.1825 9.8325 1.1825 24 P 0 ;1
L 9.8325 1.2325 9.8325 1.2325 24 P 0 ;1
L 9.8325 1.2825 9.8325 1.2825 24 P 0 ;1
L 9.8325 1.3325 9.8325 1.3325 24 P 0 ;1
L 9.8325 1.3825 9.8325 1.3825 24 P 0 ;1
L 9.8325 1.4325 9.8325 1.4325 24 P 0 ;1
L 9.8325 1.4825 9.8325 1.4825 24 P 0 ;1
L 9.8325 1.5325 9.8325 1.5325 24 P 0 ;1
L 9.8325 1.5825 9.8325 1.5825 24 P 0 ;1
L 9.8325 1.6325 9.8325 1.6325 24 P 0 ;1
L 9.8325 1.6825 9.8325 1.6825 24 P 0 ;1
L 9.8325 1.7325 9.8325 1.7325 24 P 0 ;1
L 9.8325 1.7825 9.8325 1.7825 24 P 0 ;1
L 9.8325 1.8325 9.8325 1.8325 24 P 0 ;1
L 9.8325 1.8825 9.8325 1.8825 24 P 0 ;1
L 9.8325 1.9325 9.8325 1.9325 24 P 0 ;1
L 9.8325 1.9825 9.8325 1.9825 24 P 0 ;1
L 9.8325 2.0325 9.8325 2.0325 24 P 0 ;1
L 9.8325 2.0825 9.8325 2.0825 24 P 0 ;1
L 9.8325 2.1325 9.8325 2.1325 24 P 0 ;1
L 9.8325 2.1825 9.8325 2.1825 24 P 0 ;1
L 9.8325 2.2325 9.8325 2.2325 24 P 0 ;1
L 9.8325 2.2825 9.8325 2.2825 24 P 0 ;1
L 9.8325 2.3325 9.8325 2.3325 24 P 0 ;1
L 9.8325 2.3825 9.8325 2.3825 24 P 0 ;1
L 9.8325 2.4325 9.8325 2.4325 24 P 0 ;1
L 9.8325 2.4825 9.8325 2.4825 24 P 0 ;1
L 9.8325 2.5325 9.8325 2.5325 24 P 0 ;1
L 9.8325 2.5825 9.8325 2.5825 24 P 0 ;1
L 9.8325 2.6325 9.8325 2.6325 24 P 0 ;1
L 9.8325 3.1825 9.8325 3.1825 24 P 0 ;1
L 9.8325 3.2325 9.8325 3.2325 24 P 0 ;1
L 9.8325 3.2825 9.8325 3.2825 24 P 0 ;1
L 9.8325 3.3325 9.8325 3.3325 24 P 0 ;1
L 9.8325 3.3825 9.8325 3.3825 24 P 0 ;1
L 9.8325 3.4325 9.8325 3.4325 24 P 0 ;1
L 9.8325 3.4825 9.8325 3.4825 24 P 0 ;1
L 9.8325 3.5325 9.8325 3.5325 24 P 0 ;1
L 9.8325 3.5825 9.8325 3.5825 24 P 0 ;1
L 9.8325 3.6325 9.8325 3.6325 24 P 0 ;1
L 9.8325 3.6825 9.8325 3.6825 24 P 0 ;1
L 9.8325 3.7325 9.8325 3.7325 24 P 0 ;1
L 9.8325 3.7825 9.8325 3.7825 24 P 0 ;1
L 9.8325 3.8325 9.8325 3.8325 24 P 0 ;1
L 9.8325 3.8825 9.8325 3.8825 24 P 0 ;1
L 9.8325 3.9325 9.8325 3.9325 24 P 0 ;1
L 9.8325 3.9825 9.8325 3.9825 24 P 0 ;1
L 9.8325 4.0325 9.8325 4.0325 24 P 0 ;1
L 9.8325 4.0825 9.8325 4.0825 24 P 0 ;1
L 9.8325 4.1325 9.8325 4.1325 24 P 0 ;1
L 9.8325 4.1825 9.8325 4.1825 24 P 0 ;1
L 9.8325 4.2325 9.8325 4.2325 24 P 0 ;1
L 9.8325 4.2825 9.8325 4.2825 24 P 0 ;1
L 9.8325 4.3325 9.8325 4.3325 24 P 0 ;1
L 9.8325 4.5325 9.8325 4.5325 24 P 0 ;1
L 9.8325 4.5825 9.8325 4.5825 24 P 0 ;1
L 9.8325 4.6325 9.8325 4.6325 24 P 0 ;1
L 9.8325 4.7825 9.8325 4.7825 24 P 0 ;1
L 9.8325 4.8325 9.8325 4.8325 24 P 0 ;1
L 9.8325 4.8825 9.8325 4.8825 24 P 0 ;1
L 9.8325 4.9325 9.8325 4.9325 24 P 0 ;1
L 9.8325 4.9825 9.8325 4.9825 24 P 0 ;1
L 9.8325 5.0325 9.8325 5.0325 24 P 0 ;1
L 9.8325 5.0825 9.8325 5.0825 24 P 0 ;1
L 9.8325 5.1325 9.8325 5.1325 24 P 0 ;1
L 9.8325 5.1825 9.8325 5.1825 24 P 0 ;1
L 9.8325 5.2325 9.8325 5.2325 24 P 0 ;1
L 9.8325 5.2825 9.8325 5.2825 24 P 0 ;1
L 9.8325 5.3325 9.8325 5.3325 24 P 0 ;1
L 9.8325 5.3825 9.8325 5.3825 24 P 0 ;1
L 9.8325 5.4325 9.8325 5.4325 24 P 0 ;1
L 9.8325 5.4825 9.8325 5.4825 24 P 0 ;1
L 9.8325 5.5325 9.8325 5.5325 24 P 0 ;1
L 9.8325 5.5825 9.8325 5.5825 24 P 0 ;1
L 9.8325 5.6325 9.8325 5.6325 24 P 0 ;1
L 9.8325 5.6825 9.8325 5.6825 24 P 0 ;1
L 9.8325 5.7325 9.8325 5.7325 24 P 0 ;1
L 9.8325 5.7825 9.8325 5.7825 24 P 0 ;1
L 9.8325 5.8325 9.8325 5.8325 24 P 0 ;1
L 9.8825 0.1325 9.8825 0.1325 24 P 0 ;1
L 9.8825 0.1825 9.8825 0.1825 24 P 0 ;1
L 9.8825 0.2325 9.8825 0.2325 24 P 0 ;1
L 9.8825 0.2825 9.8825 0.2825 24 P 0 ;1
L 9.8825 0.3325 9.8825 0.3325 24 P 0 ;1
L 9.8825 0.3825 9.8825 0.3825 24 P 0 ;1
L 9.8825 0.4325 9.8825 0.4325 24 P 0 ;1
L 9.8825 0.4825 9.8825 0.4825 24 P 0 ;1
L 9.8825 0.5325 9.8825 0.5325 24 P 0 ;1
L 9.8825 0.5825 9.8825 0.5825 24 P 0 ;1
L 9.8825 0.6325 9.8825 0.6325 24 P 0 ;1
L 9.8825 0.6825 9.8825 0.6825 24 P 0 ;1
L 9.8825 0.7325 9.8825 0.7325 24 P 0 ;1
L 9.8825 0.7825 9.8825 0.7825 24 P 0 ;1
L 9.8825 0.8325 9.8825 0.8325 24 P 0 ;1
L 9.8825 0.8825 9.8825 0.8825 24 P 0 ;1
L 9.8825 0.9325 9.8825 0.9325 24 P 0 ;1
L 9.8825 0.9825 9.8825 0.9825 24 P 0 ;1
L 9.8825 1.0325 9.8825 1.0325 24 P 0 ;1
L 9.8825 1.0825 9.8825 1.0825 24 P 0 ;1
L 9.8825 1.1325 9.8825 1.1325 24 P 0 ;1
L 9.8825 1.1825 9.8825 1.1825 24 P 0 ;1
L 9.8825 1.2325 9.8825 1.2325 24 P 0 ;1
L 9.8825 1.2825 9.8825 1.2825 24 P 0 ;1
L 9.8825 1.3325 9.8825 1.3325 24 P 0 ;1
L 9.8825 1.3825 9.8825 1.3825 24 P 0 ;1
L 9.8825 1.4325 9.8825 1.4325 24 P 0 ;1
L 9.8825 1.4825 9.8825 1.4825 24 P 0 ;1
L 9.8825 1.5325 9.8825 1.5325 24 P 0 ;1
L 9.8825 1.5825 9.8825 1.5825 24 P 0 ;1
L 9.8825 1.6325 9.8825 1.6325 24 P 0 ;1
L 9.8825 1.6825 9.8825 1.6825 24 P 0 ;1
L 9.8825 1.7325 9.8825 1.7325 24 P 0 ;1
L 9.8825 1.7825 9.8825 1.7825 24 P 0 ;1
L 9.8825 1.8325 9.8825 1.8325 24 P 0 ;1
L 9.8825 1.8825 9.8825 1.8825 24 P 0 ;1
L 9.8825 1.9325 9.8825 1.9325 24 P 0 ;1
L 9.8825 1.9825 9.8825 1.9825 24 P 0 ;1
L 9.8825 2.0325 9.8825 2.0325 24 P 0 ;1
L 9.8825 2.0825 9.8825 2.0825 24 P 0 ;1
L 9.8825 2.1325 9.8825 2.1325 24 P 0 ;1
L 9.8825 2.1825 9.8825 2.1825 24 P 0 ;1
L 9.8825 2.2325 9.8825 2.2325 24 P 0 ;1
L 9.8825 2.2825 9.8825 2.2825 24 P 0 ;1
L 9.8825 2.3325 9.8825 2.3325 24 P 0 ;1
L 9.8825 2.3825 9.8825 2.3825 24 P 0 ;1
L 9.8825 2.4325 9.8825 2.4325 24 P 0 ;1
L 9.8825 2.4825 9.8825 2.4825 24 P 0 ;1
L 9.8825 2.5325 9.8825 2.5325 24 P 0 ;1
L 9.8825 2.5825 9.8825 2.5825 24 P 0 ;1
L 9.8825 2.6325 9.8825 2.6325 24 P 0 ;1
L 9.8825 2.6825 9.8825 2.6825 24 P 0 ;1
L 9.8825 3.2325 9.8825 3.2325 24 P 0 ;1
L 9.8825 3.2825 9.8825 3.2825 24 P 0 ;1
L 9.8825 3.3325 9.8825 3.3325 24 P 0 ;1
L 9.8825 3.3825 9.8825 3.3825 24 P 0 ;1
L 9.8825 3.4325 9.8825 3.4325 24 P 0 ;1
L 9.8825 3.4825 9.8825 3.4825 24 P 0 ;1
L 9.8825 3.5325 9.8825 3.5325 24 P 0 ;1
L 9.8825 3.5825 9.8825 3.5825 24 P 0 ;1
L 9.8825 3.6325 9.8825 3.6325 24 P 0 ;1
L 9.8825 3.6825 9.8825 3.6825 24 P 0 ;1
L 9.8825 3.7325 9.8825 3.7325 24 P 0 ;1
L 9.8825 3.7825 9.8825 3.7825 24 P 0 ;1
L 9.8825 3.8325 9.8825 3.8325 24 P 0 ;1
L 9.8825 3.8825 9.8825 3.8825 24 P 0 ;1
L 9.8825 3.9325 9.8825 3.9325 24 P 0 ;1
L 9.8825 3.9825 9.8825 3.9825 24 P 0 ;1
L 9.8825 4.0325 9.8825 4.0325 24 P 0 ;1
L 9.8825 4.0825 9.8825 4.0825 24 P 0 ;1
L 9.8825 4.1325 9.8825 4.1325 24 P 0 ;1
L 9.8825 4.1825 9.8825 4.1825 24 P 0 ;1
L 9.8825 4.2325 9.8825 4.2325 24 P 0 ;1
L 9.8825 4.2825 9.8825 4.2825 24 P 0 ;1
L 9.8825 4.3325 9.8825 4.3325 24 P 0 ;1
L 9.8825 4.5325 9.8825 4.5325 24 P 0 ;1
L 9.8825 4.5825 9.8825 4.5825 24 P 0 ;1
L 9.8825 4.8325 9.8825 4.8325 24 P 0 ;1
L 9.8825 4.8825 9.8825 4.8825 24 P 0 ;1
L 9.8825 4.9325 9.8825 4.9325 24 P 0 ;1
L 9.8825 4.9825 9.8825 4.9825 24 P 0 ;1
L 9.8825 5.0325 9.8825 5.0325 24 P 0 ;1
L 9.8825 5.0825 9.8825 5.0825 24 P 0 ;1
L 9.8825 5.1325 9.8825 5.1325 24 P 0 ;1
L 9.8825 5.1825 9.8825 5.1825 24 P 0 ;1
L 9.8825 5.2325 9.8825 5.2325 24 P 0 ;1
L 9.8825 5.2825 9.8825 5.2825 24 P 0 ;1
L 9.8825 5.3325 9.8825 5.3325 24 P 0 ;1
L 9.8825 5.3825 9.8825 5.3825 24 P 0 ;1
L 9.8825 5.4325 9.8825 5.4325 24 P 0 ;1
L 9.8825 5.4825 9.8825 5.4825 24 P 0 ;1
L 9.8825 5.5325 9.8825 5.5325 24 P 0 ;1
L 9.8825 5.5825 9.8825 5.5825 24 P 0 ;1
L 9.8825 5.6325 9.8825 5.6325 24 P 0 ;1
L 9.8825 5.6825 9.8825 5.6825 24 P 0 ;1
L 9.8825 5.7325 9.8825 5.7325 24 P 0 ;1
L 9.8825 5.7825 9.8825 5.7825 24 P 0 ;1
L 9.8825 5.8325 9.8825 5.8325 24 P 0 ;1
L 9.9325 0.1325 9.9325 0.1325 24 P 0 ;1
L 9.9325 0.1825 9.9325 0.1825 24 P 0 ;1
L 9.9325 0.2325 9.9325 0.2325 24 P 0 ;1
L 9.9325 0.2825 9.9325 0.2825 24 P 0 ;1
L 9.9325 0.3325 9.9325 0.3325 24 P 0 ;1
L 9.9325 0.3825 9.9325 0.3825 24 P 0 ;1
L 9.9325 0.4325 9.9325 0.4325 24 P 0 ;1
L 9.9325 0.4825 9.9325 0.4825 24 P 0 ;1
L 9.9325 0.5325 9.9325 0.5325 24 P 0 ;1
L 9.9325 0.5825 9.9325 0.5825 24 P 0 ;1
L 9.9325 0.6325 9.9325 0.6325 24 P 0 ;1
L 9.9325 0.6825 9.9325 0.6825 24 P 0 ;1
L 9.9325 0.7325 9.9325 0.7325 24 P 0 ;1
L 9.9325 0.7825 9.9325 0.7825 24 P 0 ;1
L 9.9325 0.8325 9.9325 0.8325 24 P 0 ;1
L 9.9325 0.8825 9.9325 0.8825 24 P 0 ;1
L 9.9325 0.9325 9.9325 0.9325 24 P 0 ;1
L 9.9325 0.9825 9.9325 0.9825 24 P 0 ;1
L 9.9325 1.0325 9.9325 1.0325 24 P 0 ;1
L 9.9325 1.0825 9.9325 1.0825 24 P 0 ;1
L 9.9325 1.1325 9.9325 1.1325 24 P 0 ;1
L 9.9325 1.1825 9.9325 1.1825 24 P 0 ;1
L 9.9325 1.2325 9.9325 1.2325 24 P 0 ;1
L 9.9325 1.2825 9.9325 1.2825 24 P 0 ;1
L 9.9325 1.3325 9.9325 1.3325 24 P 0 ;1
L 9.9325 1.3825 9.9325 1.3825 24 P 0 ;1
L 9.9325 1.4325 9.9325 1.4325 24 P 0 ;1
L 9.9325 1.4825 9.9325 1.4825 24 P 0 ;1
L 9.9325 1.5325 9.9325 1.5325 24 P 0 ;1
L 9.9325 1.5825 9.9325 1.5825 24 P 0 ;1
L 9.9325 1.6325 9.9325 1.6325 24 P 0 ;1
L 9.9325 1.6825 9.9325 1.6825 24 P 0 ;1
L 9.9325 1.7325 9.9325 1.7325 24 P 0 ;1
L 9.9325 1.7825 9.9325 1.7825 24 P 0 ;1
L 9.9325 1.8325 9.9325 1.8325 24 P 0 ;1
L 9.9325 1.8825 9.9325 1.8825 24 P 0 ;1
L 9.9325 1.9325 9.9325 1.9325 24 P 0 ;1
L 9.9325 1.9825 9.9325 1.9825 24 P 0 ;1
L 9.9325 2.0325 9.9325 2.0325 24 P 0 ;1
L 9.9325 2.0825 9.9325 2.0825 24 P 0 ;1
L 9.9325 3.2825 9.9325 3.2825 24 P 0 ;1
L 9.9325 3.3325 9.9325 3.3325 24 P 0 ;1
L 9.9325 3.3825 9.9325 3.3825 24 P 0 ;1
L 9.9325 3.4325 9.9325 3.4325 24 P 0 ;1
L 9.9325 3.4825 9.9325 3.4825 24 P 0 ;1
L 9.9325 3.5325 9.9325 3.5325 24 P 0 ;1
L 9.9325 3.5825 9.9325 3.5825 24 P 0 ;1
L 9.9325 3.6325 9.9325 3.6325 24 P 0 ;1
L 9.9325 3.6825 9.9325 3.6825 24 P 0 ;1
L 9.9325 3.7325 9.9325 3.7325 24 P 0 ;1
L 9.9325 3.7825 9.9325 3.7825 24 P 0 ;1
L 9.9325 3.8325 9.9325 3.8325 24 P 0 ;1
L 9.9325 3.8825 9.9325 3.8825 24 P 0 ;1
L 9.9325 3.9325 9.9325 3.9325 24 P 0 ;1
L 9.9325 3.9825 9.9325 3.9825 24 P 0 ;1
L 9.9325 4.0325 9.9325 4.0325 24 P 0 ;1
L 9.9325 4.0825 9.9325 4.0825 24 P 0 ;1
L 9.9325 4.1325 9.9325 4.1325 24 P 0 ;1
L 9.9325 4.1825 9.9325 4.1825 24 P 0 ;1
L 9.9325 4.2325 9.9325 4.2325 24 P 0 ;1
L 9.9325 4.2825 9.9325 4.2825 24 P 0 ;1
L 9.9325 4.3325 9.9325 4.3325 24 P 0 ;1
L 9.9325 4.8325 9.9325 4.8325 24 P 0 ;1
L 9.9325 4.8825 9.9325 4.8825 24 P 0 ;1
L 9.9325 4.9325 9.9325 4.9325 24 P 0 ;1
L 9.9325 4.9825 9.9325 4.9825 24 P 0 ;1
L 9.9325 5.0325 9.9325 5.0325 24 P 0 ;1
L 9.9325 5.0825 9.9325 5.0825 24 P 0 ;1
L 9.9325 5.1325 9.9325 5.1325 24 P 0 ;1
L 9.9325 5.1825 9.9325 5.1825 24 P 0 ;1
L 9.9325 5.2325 9.9325 5.2325 24 P 0 ;1
L 9.9325 5.2825 9.9325 5.2825 24 P 0 ;1
L 9.9325 5.3325 9.9325 5.3325 24 P 0 ;1
L 9.9325 5.3825 9.9325 5.3825 24 P 0 ;1
L 9.9325 5.5325 9.9325 5.5325 24 P 0 ;1
L 9.9325 5.5825 9.9325 5.5825 24 P 0 ;1
L 9.9325 5.6325 9.9325 5.6325 24 P 0 ;1
L 9.9325 5.6825 9.9325 5.6825 24 P 0 ;1
L 9.9325 5.7325 9.9325 5.7325 24 P 0 ;1
L 9.9325 5.7825 9.9325 5.7825 24 P 0 ;1
L 9.9325 5.8325 9.9325 5.8325 24 P 0 ;1
L 9.9825 0.1325 9.9825 0.1325 24 P 0 ;1
L 9.9825 0.1825 9.9825 0.1825 24 P 0 ;1
L 9.9825 0.2325 9.9825 0.2325 24 P 0 ;1
L 9.9825 0.2825 9.9825 0.2825 24 P 0 ;1
L 9.9825 0.3325 9.9825 0.3325 24 P 0 ;1
L 9.9825 0.3825 9.9825 0.3825 24 P 0 ;1
L 9.9825 0.4325 9.9825 0.4325 24 P 0 ;1
L 9.9825 0.4825 9.9825 0.4825 24 P 0 ;1
L 9.9825 0.5325 9.9825 0.5325 24 P 0 ;1
L 9.9825 0.5825 9.9825 0.5825 24 P 0 ;1
L 9.9825 0.6325 9.9825 0.6325 24 P 0 ;1
L 9.9825 0.6825 9.9825 0.6825 24 P 0 ;1
L 9.9825 0.7325 9.9825 0.7325 24 P 0 ;1
L 9.9825 0.7825 9.9825 0.7825 24 P 0 ;1
L 9.9825 0.8325 9.9825 0.8325 24 P 0 ;1
L 9.9825 0.8825 9.9825 0.8825 24 P 0 ;1
L 9.9825 0.9325 9.9825 0.9325 24 P 0 ;1
L 9.9825 0.9825 9.9825 0.9825 24 P 0 ;1
L 9.9825 1.0325 9.9825 1.0325 24 P 0 ;1
L 9.9825 1.0825 9.9825 1.0825 24 P 0 ;1
L 9.9825 1.1325 9.9825 1.1325 24 P 0 ;1
L 9.9825 1.1825 9.9825 1.1825 24 P 0 ;1
L 9.9825 1.2325 9.9825 1.2325 24 P 0 ;1
L 9.9825 1.2825 9.9825 1.2825 24 P 0 ;1
L 9.9825 1.3325 9.9825 1.3325 24 P 0 ;1
L 9.9825 1.3825 9.9825 1.3825 24 P 0 ;1
L 9.9825 1.4325 9.9825 1.4325 24 P 0 ;1
L 9.9825 1.4825 9.9825 1.4825 24 P 0 ;1
L 9.9825 1.5325 9.9825 1.5325 24 P 0 ;1
L 9.9825 1.5825 9.9825 1.5825 24 P 0 ;1
L 9.9825 1.6325 9.9825 1.6325 24 P 0 ;1
L 9.9825 1.6825 9.9825 1.6825 24 P 0 ;1
L 9.9825 1.7325 9.9825 1.7325 24 P 0 ;1
L 9.9825 1.7825 9.9825 1.7825 24 P 0 ;1
L 9.9825 1.8325 9.9825 1.8325 24 P 0 ;1
L 9.9825 1.8825 9.9825 1.8825 24 P 0 ;1
L 9.9825 1.9325 9.9825 1.9325 24 P 0 ;1
L 9.9825 1.9825 9.9825 1.9825 24 P 0 ;1
L 9.9825 2.0325 9.9825 2.0325 24 P 0 ;1
L 9.9825 2.0825 9.9825 2.0825 24 P 0 ;1
L 9.9825 3.2825 9.9825 3.2825 24 P 0 ;1
L 9.9825 3.3325 9.9825 3.3325 24 P 0 ;1
L 9.9825 3.3825 9.9825 3.3825 24 P 0 ;1
L 9.9825 3.4325 9.9825 3.4325 24 P 0 ;1
L 9.9825 3.4825 9.9825 3.4825 24 P 0 ;1
L 9.9825 3.5325 9.9825 3.5325 24 P 0 ;1
L 9.9825 3.5825 9.9825 3.5825 24 P 0 ;1
L 9.9825 3.6325 9.9825 3.6325 24 P 0 ;1
L 9.9825 3.6825 9.9825 3.6825 24 P 0 ;1
L 9.9825 3.7325 9.9825 3.7325 24 P 0 ;1
L 9.9825 3.7825 9.9825 3.7825 24 P 0 ;1
L 9.9825 3.8325 9.9825 3.8325 24 P 0 ;1
L 9.9825 3.8825 9.9825 3.8825 24 P 0 ;1
L 9.9825 3.9325 9.9825 3.9325 24 P 0 ;1
L 9.9825 3.9825 9.9825 3.9825 24 P 0 ;1
L 9.9825 4.0325 9.9825 4.0325 24 P 0 ;1
L 9.9825 4.0825 9.9825 4.0825 24 P 0 ;1
L 9.9825 4.1325 9.9825 4.1325 24 P 0 ;1
L 9.9825 4.1825 9.9825 4.1825 24 P 0 ;1
L 9.9825 4.2325 9.9825 4.2325 24 P 0 ;1
L 9.9825 4.2825 9.9825 4.2825 24 P 0 ;1
L 9.9825 4.3325 9.9825 4.3325 24 P 0 ;1
L 9.9825 4.7825 9.9825 4.7825 24 P 0 ;1
L 9.9825 4.8325 9.9825 4.8325 24 P 0 ;1
L 9.9825 4.8825 9.9825 4.8825 24 P 0 ;1
L 9.9825 4.9325 9.9825 4.9325 24 P 0 ;1
L 9.9825 4.9825 9.9825 4.9825 24 P 0 ;1
L 9.9825 5.0325 9.9825 5.0325 24 P 0 ;1
L 9.9825 5.0825 9.9825 5.0825 24 P 0 ;1
L 9.9825 5.1325 9.9825 5.1325 24 P 0 ;1
L 9.9825 5.1825 9.9825 5.1825 24 P 0 ;1
L 9.9825 5.2325 9.9825 5.2325 24 P 0 ;1
L 9.9825 5.6325 9.9825 5.6325 24 P 0 ;1
L 9.9825 5.6825 9.9825 5.6825 24 P 0 ;1
L 9.9825 5.7325 9.9825 5.7325 24 P 0 ;1
L 9.9825 5.7825 9.9825 5.7825 24 P 0 ;1
L 9.9825 5.8325 9.9825 5.8325 24 P 0 ;1
L 10.0325 0.1325 10.0325 0.1325 24 P 0 ;1
L 10.0325 0.1825 10.0325 0.1825 24 P 0 ;1
L 10.0325 0.2325 10.0325 0.2325 24 P 0 ;1
L 10.0325 0.2825 10.0325 0.2825 24 P 0 ;1
L 10.0325 0.3325 10.0325 0.3325 24 P 0 ;1
L 10.0325 0.3825 10.0325 0.3825 24 P 0 ;1
L 10.0325 0.4325 10.0325 0.4325 24 P 0 ;1
L 10.0325 0.4825 10.0325 0.4825 24 P 0 ;1
L 10.0325 0.5325 10.0325 0.5325 24 P 0 ;1
L 10.0325 0.5825 10.0325 0.5825 24 P 0 ;1
L 10.0325 0.6325 10.0325 0.6325 24 P 0 ;1
L 10.0325 0.6825 10.0325 0.6825 24 P 0 ;1
L 10.0325 0.7325 10.0325 0.7325 24 P 0 ;1
L 10.0325 0.7825 10.0325 0.7825 24 P 0 ;1
L 10.0325 0.8325 10.0325 0.8325 24 P 0 ;1
L 10.0325 0.8825 10.0325 0.8825 24 P 0 ;1
L 10.0325 0.9325 10.0325 0.9325 24 P 0 ;1
L 10.0325 0.9825 10.0325 0.9825 24 P 0 ;1
L 10.0325 1.0325 10.0325 1.0325 24 P 0 ;1
L 10.0325 1.0825 10.0325 1.0825 24 P 0 ;1
L 10.0325 1.1325 10.0325 1.1325 24 P 0 ;1
L 10.0325 1.1825 10.0325 1.1825 24 P 0 ;1
L 10.0325 1.2325 10.0325 1.2325 24 P 0 ;1
L 10.0325 1.2825 10.0325 1.2825 24 P 0 ;1
L 10.0325 1.3325 10.0325 1.3325 24 P 0 ;1
L 10.0325 1.3825 10.0325 1.3825 24 P 0 ;1
L 10.0325 1.4325 10.0325 1.4325 24 P 0 ;1
L 10.0325 1.4825 10.0325 1.4825 24 P 0 ;1
L 10.0325 1.5325 10.0325 1.5325 24 P 0 ;1
L 10.0325 1.5825 10.0325 1.5825 24 P 0 ;1
L 10.0325 1.6325 10.0325 1.6325 24 P 0 ;1
L 10.0325 1.6825 10.0325 1.6825 24 P 0 ;1
L 10.0325 1.7325 10.0325 1.7325 24 P 0 ;1
L 10.0325 1.7825 10.0325 1.7825 24 P 0 ;1
L 10.0325 1.8325 10.0325 1.8325 24 P 0 ;1
L 10.0325 1.8825 10.0325 1.8825 24 P 0 ;1
L 10.0325 1.9325 10.0325 1.9325 24 P 0 ;1
L 10.0325 3.2825 10.0325 3.2825 24 P 0 ;1
L 10.0325 3.3325 10.0325 3.3325 24 P 0 ;1
L 10.0325 3.3825 10.0325 3.3825 24 P 0 ;1
L 10.0325 3.4325 10.0325 3.4325 24 P 0 ;1
L 10.0325 3.4825 10.0325 3.4825 24 P 0 ;1
L 10.0325 3.5325 10.0325 3.5325 24 P 0 ;1
L 10.0325 3.5825 10.0325 3.5825 24 P 0 ;1
L 10.0325 3.6325 10.0325 3.6325 24 P 0 ;1
L 10.0325 3.6825 10.0325 3.6825 24 P 0 ;1
L 10.0325 3.7325 10.0325 3.7325 24 P 0 ;1
L 10.0325 3.7825 10.0325 3.7825 24 P 0 ;1
L 10.0325 3.8325 10.0325 3.8325 24 P 0 ;1
L 10.0325 3.8825 10.0325 3.8825 24 P 0 ;1
L 10.0325 3.9325 10.0325 3.9325 24 P 0 ;1
L 10.0325 3.9825 10.0325 3.9825 24 P 0 ;1
L 10.0325 4.0325 10.0325 4.0325 24 P 0 ;1
L 10.0325 4.0825 10.0325 4.0825 24 P 0 ;1
L 10.0325 4.1325 10.0325 4.1325 24 P 0 ;1
L 10.0325 4.1825 10.0325 4.1825 24 P 0 ;1
L 10.0325 4.2325 10.0325 4.2325 24 P 0 ;1
L 10.0325 4.2825 10.0325 4.2825 24 P 0 ;1
L 10.0325 4.3325 10.0325 4.3325 24 P 0 ;1
L 10.0325 4.3825 10.0325 4.3825 24 P 0 ;1
L 10.0325 4.7825 10.0325 4.7825 24 P 0 ;1
L 10.0325 4.8325 10.0325 4.8325 24 P 0 ;1
L 10.0325 4.8825 10.0325 4.8825 24 P 0 ;1
L 10.0325 4.9325 10.0325 4.9325 24 P 0 ;1
L 10.0325 4.9825 10.0325 4.9825 24 P 0 ;1
L 10.0325 5.0325 10.0325 5.0325 24 P 0 ;1
L 10.0325 5.0825 10.0325 5.0825 24 P 0 ;1
L 10.0325 5.1325 10.0325 5.1325 24 P 0 ;1
L 10.0325 5.1825 10.0325 5.1825 24 P 0 ;1
L 10.0325 5.6825 10.0325 5.6825 24 P 0 ;1
L 10.0325 5.7325 10.0325 5.7325 24 P 0 ;1
L 10.0325 5.7825 10.0325 5.7825 24 P 0 ;1
L 10.0325 5.8325 10.0325 5.8325 24 P 0 ;1
L 10.0825 0.1325 10.0825 0.1325 24 P 0 ;1
L 10.0825 0.1825 10.0825 0.1825 24 P 0 ;1
L 10.0825 0.2325 10.0825 0.2325 24 P 0 ;1
L 10.0825 0.2825 10.0825 0.2825 24 P 0 ;1
L 10.0825 0.3325 10.0825 0.3325 24 P 0 ;1
L 10.0825 0.3825 10.0825 0.3825 24 P 0 ;1
L 10.0825 0.4325 10.0825 0.4325 24 P 0 ;1
L 10.0825 0.4825 10.0825 0.4825 24 P 0 ;1
L 10.0825 0.5325 10.0825 0.5325 24 P 0 ;1
L 10.0825 0.5825 10.0825 0.5825 24 P 0 ;1
L 10.0825 0.6325 10.0825 0.6325 24 P 0 ;1
L 10.0825 0.6825 10.0825 0.6825 24 P 0 ;1
L 10.0825 0.7325 10.0825 0.7325 24 P 0 ;1
L 10.0825 0.7825 10.0825 0.7825 24 P 0 ;1
L 10.0825 0.8325 10.0825 0.8325 24 P 0 ;1
L 10.0825 0.8825 10.0825 0.8825 24 P 0 ;1
L 10.0825 0.9325 10.0825 0.9325 24 P 0 ;1
L 10.0825 0.9825 10.0825 0.9825 24 P 0 ;1
L 10.0825 1.0325 10.0825 1.0325 24 P 0 ;1
L 10.0825 1.0825 10.0825 1.0825 24 P 0 ;1
L 10.0825 1.1325 10.0825 1.1325 24 P 0 ;1
L 10.0825 1.1825 10.0825 1.1825 24 P 0 ;1
L 10.0825 1.2325 10.0825 1.2325 24 P 0 ;1
L 10.0825 1.2825 10.0825 1.2825 24 P 0 ;1
L 10.0825 1.3325 10.0825 1.3325 24 P 0 ;1
L 10.0825 1.3825 10.0825 1.3825 24 P 0 ;1
L 10.0825 1.4325 10.0825 1.4325 24 P 0 ;1
L 10.0825 1.4825 10.0825 1.4825 24 P 0 ;1
L 10.0825 1.5325 10.0825 1.5325 24 P 0 ;1
L 10.0825 1.5825 10.0825 1.5825 24 P 0 ;1
L 10.0825 1.6325 10.0825 1.6325 24 P 0 ;1
L 10.0825 1.6825 10.0825 1.6825 24 P 0 ;1
L 10.0825 1.7325 10.0825 1.7325 24 P 0 ;1
L 10.0825 1.7825 10.0825 1.7825 24 P 0 ;1
L 10.0825 1.8325 10.0825 1.8325 24 P 0 ;1
L 10.0825 1.8825 10.0825 1.8825 24 P 0 ;1
L 10.0825 3.2825 10.0825 3.2825 24 P 0 ;1
L 10.0825 3.3325 10.0825 3.3325 24 P 0 ;1
L 10.0825 3.3825 10.0825 3.3825 24 P 0 ;1
L 10.0825 3.4325 10.0825 3.4325 24 P 0 ;1
L 10.0825 3.4825 10.0825 3.4825 24 P 0 ;1
L 10.0825 3.5325 10.0825 3.5325 24 P 0 ;1
L 10.0825 3.5825 10.0825 3.5825 24 P 0 ;1
L 10.0825 3.6325 10.0825 3.6325 24 P 0 ;1
L 10.0825 3.6825 10.0825 3.6825 24 P 0 ;1
L 10.0825 3.7325 10.0825 3.7325 24 P 0 ;1
L 10.0825 3.7825 10.0825 3.7825 24 P 0 ;1
L 10.0825 3.8325 10.0825 3.8325 24 P 0 ;1
L 10.0825 3.8825 10.0825 3.8825 24 P 0 ;1
L 10.0825 3.9325 10.0825 3.9325 24 P 0 ;1
L 10.0825 3.9825 10.0825 3.9825 24 P 0 ;1
L 10.0825 4.0325 10.0825 4.0325 24 P 0 ;1
L 10.0825 4.0825 10.0825 4.0825 24 P 0 ;1
L 10.0825 4.1325 10.0825 4.1325 24 P 0 ;1
L 10.0825 4.1825 10.0825 4.1825 24 P 0 ;1
L 10.0825 4.2325 10.0825 4.2325 24 P 0 ;1
L 10.0825 4.2825 10.0825 4.2825 24 P 0 ;1
L 10.0825 4.3325 10.0825 4.3325 24 P 0 ;1
L 10.0825 4.3825 10.0825 4.3825 24 P 0 ;1
L 10.0825 4.7325 10.0825 4.7325 24 P 0 ;1
L 10.0825 4.7825 10.0825 4.7825 24 P 0 ;1
L 10.0825 4.8325 10.0825 4.8325 24 P 0 ;1
L 10.0825 4.8825 10.0825 4.8825 24 P 0 ;1
L 10.0825 4.9325 10.0825 4.9325 24 P 0 ;1
L 10.0825 4.9825 10.0825 4.9825 24 P 0 ;1
L 10.0825 5.0325 10.0825 5.0325 24 P 0 ;1
L 10.0825 5.0825 10.0825 5.0825 24 P 0 ;1
L 10.0825 5.1325 10.0825 5.1325 24 P 0 ;1
L 10.0825 5.1825 10.0825 5.1825 24 P 0 ;1
L 10.0825 5.7325 10.0825 5.7325 24 P 0 ;1
L 10.0825 5.7825 10.0825 5.7825 24 P 0 ;1
L 10.0825 5.8325 10.0825 5.8325 24 P 0 ;1
L 10.1325 0.1325 10.1325 0.1325 24 P 0 ;1
L 10.1325 0.1825 10.1325 0.1825 24 P 0 ;1
L 10.1325 0.2325 10.1325 0.2325 24 P 0 ;1
L 10.1325 0.2825 10.1325 0.2825 24 P 0 ;1
L 10.1325 0.3325 10.1325 0.3325 24 P 0 ;1
L 10.1325 0.3825 10.1325 0.3825 24 P 0 ;1
L 10.1325 0.4325 10.1325 0.4325 24 P 0 ;1
L 10.1325 0.4825 10.1325 0.4825 24 P 0 ;1
L 10.1325 0.5325 10.1325 0.5325 24 P 0 ;1
L 10.1325 0.5825 10.1325 0.5825 24 P 0 ;1
L 10.1325 0.6325 10.1325 0.6325 24 P 0 ;1
L 10.1325 0.6825 10.1325 0.6825 24 P 0 ;1
L 10.1325 0.7325 10.1325 0.7325 24 P 0 ;1
L 10.1325 0.7825 10.1325 0.7825 24 P 0 ;1
L 10.1325 0.8325 10.1325 0.8325 24 P 0 ;1
L 10.1325 0.8825 10.1325 0.8825 24 P 0 ;1
L 10.1325 0.9325 10.1325 0.9325 24 P 0 ;1
L 10.1325 0.9825 10.1325 0.9825 24 P 0 ;1
L 10.1325 1.0325 10.1325 1.0325 24 P 0 ;1
L 10.1325 1.0825 10.1325 1.0825 24 P 0 ;1
L 10.1325 1.1325 10.1325 1.1325 24 P 0 ;1
L 10.1325 1.1825 10.1325 1.1825 24 P 0 ;1
L 10.1325 1.2325 10.1325 1.2325 24 P 0 ;1
L 10.1325 1.2825 10.1325 1.2825 24 P 0 ;1
L 10.1325 1.3325 10.1325 1.3325 24 P 0 ;1
L 10.1325 1.3825 10.1325 1.3825 24 P 0 ;1
L 10.1325 1.4325 10.1325 1.4325 24 P 0 ;1
L 10.1325 1.4825 10.1325 1.4825 24 P 0 ;1
L 10.1325 1.5325 10.1325 1.5325 24 P 0 ;1
L 10.1325 1.5825 10.1325 1.5825 24 P 0 ;1
L 10.1325 1.6325 10.1325 1.6325 24 P 0 ;1
L 10.1325 1.6825 10.1325 1.6825 24 P 0 ;1
L 10.1325 1.7325 10.1325 1.7325 24 P 0 ;1
L 10.1325 1.7825 10.1325 1.7825 24 P 0 ;1
L 10.1325 1.8325 10.1325 1.8325 24 P 0 ;1
L 10.1325 1.8825 10.1325 1.8825 24 P 0 ;1
L 10.1325 3.2825 10.1325 3.2825 24 P 0 ;1
L 10.1325 3.3325 10.1325 3.3325 24 P 0 ;1
L 10.1325 3.3825 10.1325 3.3825 24 P 0 ;1
L 10.1325 3.4325 10.1325 3.4325 24 P 0 ;1
L 10.1325 3.4825 10.1325 3.4825 24 P 0 ;1
L 10.1325 3.5325 10.1325 3.5325 24 P 0 ;1
L 10.1325 3.5825 10.1325 3.5825 24 P 0 ;1
L 10.1325 3.6325 10.1325 3.6325 24 P 0 ;1
L 10.1325 3.6825 10.1325 3.6825 24 P 0 ;1
L 10.1325 3.7325 10.1325 3.7325 24 P 0 ;1
L 10.1325 3.7825 10.1325 3.7825 24 P 0 ;1
L 10.1325 3.8325 10.1325 3.8325 24 P 0 ;1
L 10.1325 3.8825 10.1325 3.8825 24 P 0 ;1
L 10.1325 3.9325 10.1325 3.9325 24 P 0 ;1
L 10.1325 3.9825 10.1325 3.9825 24 P 0 ;1
L 10.1325 4.0325 10.1325 4.0325 24 P 0 ;1
L 10.1325 4.0825 10.1325 4.0825 24 P 0 ;1
L 10.1325 4.1325 10.1325 4.1325 24 P 0 ;1
L 10.1325 4.1825 10.1325 4.1825 24 P 0 ;1
L 10.1325 4.2325 10.1325 4.2325 24 P 0 ;1
L 10.1325 4.2825 10.1325 4.2825 24 P 0 ;1
L 10.1325 4.3325 10.1325 4.3325 24 P 0 ;1
L 10.1325 4.3825 10.1325 4.3825 24 P 0 ;1
L 10.1325 4.4325 10.1325 4.4325 24 P 0 ;1
L 10.1325 4.4825 10.1325 4.4825 24 P 0 ;1
L 10.1325 4.5325 10.1325 4.5325 24 P 0 ;1
L 10.1325 4.5825 10.1325 4.5825 24 P 0 ;1
L 10.1325 4.6325 10.1325 4.6325 24 P 0 ;1
L 10.1325 4.6825 10.1325 4.6825 24 P 0 ;1
L 10.1325 4.7325 10.1325 4.7325 24 P 0 ;1
L 10.1325 4.7825 10.1325 4.7825 24 P 0 ;1
L 10.1325 4.8325 10.1325 4.8325 24 P 0 ;1
L 10.1325 4.8825 10.1325 4.8825 24 P 0 ;1
L 10.1325 4.9325 10.1325 4.9325 24 P 0 ;1
L 10.1325 4.9825 10.1325 4.9825 24 P 0 ;1
L 10.1325 5.0325 10.1325 5.0325 24 P 0 ;1
L 10.1325 5.0825 10.1325 5.0825 24 P 0 ;1
L 10.1325 5.1325 10.1325 5.1325 24 P 0 ;1
L 10.1325 5.7325 10.1325 5.7325 24 P 0 ;1
L 10.1325 5.7825 10.1325 5.7825 24 P 0 ;1
L 10.1325 5.8325 10.1325 5.8325 24 P 0 ;1
L 10.1825 0.1325 10.1825 0.1325 24 P 0 ;1
L 10.1825 0.1825 10.1825 0.1825 24 P 0 ;1
L 10.1825 0.2325 10.1825 0.2325 24 P 0 ;1
L 10.1825 0.2825 10.1825 0.2825 24 P 0 ;1
L 10.1825 0.3325 10.1825 0.3325 24 P 0 ;1
L 10.1825 0.3825 10.1825 0.3825 24 P 0 ;1
L 10.1825 0.4325 10.1825 0.4325 24 P 0 ;1
L 10.1825 0.4825 10.1825 0.4825 24 P 0 ;1
L 10.1825 0.5325 10.1825 0.5325 24 P 0 ;1
L 10.1825 0.5825 10.1825 0.5825 24 P 0 ;1
L 10.1825 0.6325 10.1825 0.6325 24 P 0 ;1
L 10.1825 0.6825 10.1825 0.6825 24 P 0 ;1
L 10.1825 0.7325 10.1825 0.7325 24 P 0 ;1
L 10.1825 0.7825 10.1825 0.7825 24 P 0 ;1
L 10.1825 0.8325 10.1825 0.8325 24 P 0 ;1
L 10.1825 0.8825 10.1825 0.8825 24 P 0 ;1
L 10.1825 0.9325 10.1825 0.9325 24 P 0 ;1
L 10.1825 0.9825 10.1825 0.9825 24 P 0 ;1
L 10.1825 1.0325 10.1825 1.0325 24 P 0 ;1
L 10.1825 1.0825 10.1825 1.0825 24 P 0 ;1
L 10.1825 1.1325 10.1825 1.1325 24 P 0 ;1
L 10.1825 1.1825 10.1825 1.1825 24 P 0 ;1
L 10.1825 1.2325 10.1825 1.2325 24 P 0 ;1
L 10.1825 1.2825 10.1825 1.2825 24 P 0 ;1
L 10.1825 1.3325 10.1825 1.3325 24 P 0 ;1
L 10.1825 1.3825 10.1825 1.3825 24 P 0 ;1
L 10.1825 1.4325 10.1825 1.4325 24 P 0 ;1
L 10.1825 1.4825 10.1825 1.4825 24 P 0 ;1
L 10.1825 1.5325 10.1825 1.5325 24 P 0 ;1
L 10.1825 1.5825 10.1825 1.5825 24 P 0 ;1
L 10.1825 4.8825 10.1825 4.8825 24 P 0 ;1
L 10.1825 5.7325 10.1825 5.7325 24 P 0 ;1
L 10.1825 5.7825 10.1825 5.7825 24 P 0 ;1
L 10.1825 5.8325 10.1825 5.8325 24 P 0 ;1
L 10.2325 0.1325 10.2325 0.1325 24 P 0 ;1
L 10.2325 0.1825 10.2325 0.1825 24 P 0 ;1
L 10.2325 0.2325 10.2325 0.2325 24 P 0 ;1
L 10.2325 0.2825 10.2325 0.2825 24 P 0 ;1
L 10.2325 0.3325 10.2325 0.3325 24 P 0 ;1
L 10.2325 0.3825 10.2325 0.3825 24 P 0 ;1
L 10.2325 0.4325 10.2325 0.4325 24 P 0 ;1
L 10.2325 0.4825 10.2325 0.4825 24 P 0 ;1
L 10.2325 0.5325 10.2325 0.5325 24 P 0 ;1
L 10.2325 0.5825 10.2325 0.5825 24 P 0 ;1
L 10.2325 0.6325 10.2325 0.6325 24 P 0 ;1
L 10.2325 0.6825 10.2325 0.6825 24 P 0 ;1
L 10.2325 0.7325 10.2325 0.7325 24 P 0 ;1
L 10.2325 0.7825 10.2325 0.7825 24 P 0 ;1
L 10.2325 0.8325 10.2325 0.8325 24 P 0 ;1
L 10.2325 0.8825 10.2325 0.8825 24 P 0 ;1
L 10.2325 0.9325 10.2325 0.9325 24 P 0 ;1
L 10.2325 0.9825 10.2325 0.9825 24 P 0 ;1
L 10.2325 1.0325 10.2325 1.0325 24 P 0 ;1
L 10.2325 1.0825 10.2325 1.0825 24 P 0 ;1
L 10.2325 1.1325 10.2325 1.1325 24 P 0 ;1
L 10.2325 1.1825 10.2325 1.1825 24 P 0 ;1
L 10.2325 1.2325 10.2325 1.2325 24 P 0 ;1
L 10.2325 1.2825 10.2325 1.2825 24 P 0 ;1
L 10.2325 1.3325 10.2325 1.3325 24 P 0 ;1
L 10.2325 1.3825 10.2325 1.3825 24 P 0 ;1
L 10.2325 1.4325 10.2325 1.4325 24 P 0 ;1
L 10.2325 1.4825 10.2325 1.4825 24 P 0 ;1
L 10.2325 1.5325 10.2325 1.5325 24 P 0 ;1
L 10.2325 5.7325 10.2325 5.7325 24 P 0 ;1
L 10.2325 5.7825 10.2325 5.7825 24 P 0 ;1
L 10.2325 5.8325 10.2325 5.8325 24 P 0 ;1
L 10.2825 0.1325 10.2825 0.1325 24 P 0 ;1
L 10.2825 0.1825 10.2825 0.1825 24 P 0 ;1
L 10.2825 0.2325 10.2825 0.2325 24 P 0 ;1
L 10.2825 0.2825 10.2825 0.2825 24 P 0 ;1
L 10.2825 0.3325 10.2825 0.3325 24 P 0 ;1
L 10.2825 0.3825 10.2825 0.3825 24 P 0 ;1
L 10.2825 0.4325 10.2825 0.4325 24 P 0 ;1
L 10.2825 0.4825 10.2825 0.4825 24 P 0 ;1
L 10.2825 0.5325 10.2825 0.5325 24 P 0 ;1
L 10.2825 0.5825 10.2825 0.5825 24 P 0 ;1
L 10.2825 0.6325 10.2825 0.6325 24 P 0 ;1
L 10.2825 0.6825 10.2825 0.6825 24 P 0 ;1
L 10.2825 0.7325 10.2825 0.7325 24 P 0 ;1
L 10.2825 0.7825 10.2825 0.7825 24 P 0 ;1
L 10.2825 0.8325 10.2825 0.8325 24 P 0 ;1
L 10.2825 0.8825 10.2825 0.8825 24 P 0 ;1
L 10.2825 0.9325 10.2825 0.9325 24 P 0 ;1
L 10.2825 0.9825 10.2825 0.9825 24 P 0 ;1
L 10.2825 1.0325 10.2825 1.0325 24 P 0 ;1
L 10.2825 1.0825 10.2825 1.0825 24 P 0 ;1
L 10.2825 1.1325 10.2825 1.1325 24 P 0 ;1
L 10.2825 1.1825 10.2825 1.1825 24 P 0 ;1
L 10.2825 1.2325 10.2825 1.2325 24 P 0 ;1
L 10.2825 1.2825 10.2825 1.2825 24 P 0 ;1
L 10.2825 1.3325 10.2825 1.3325 24 P 0 ;1
L 10.2825 1.3825 10.2825 1.3825 24 P 0 ;1
L 10.2825 1.4325 10.2825 1.4325 24 P 0 ;1
L 10.2825 5.7325 10.2825 5.7325 24 P 0 ;1
L 10.2825 5.7825 10.2825 5.7825 24 P 0 ;1
L 10.2825 5.8325 10.2825 5.8325 24 P 0 ;1
L 10.3325 0.1325 10.3325 0.1325 24 P 0 ;1
L 10.3325 0.1825 10.3325 0.1825 24 P 0 ;1
L 10.3325 0.2325 10.3325 0.2325 24 P 0 ;1
L 10.3325 0.2825 10.3325 0.2825 24 P 0 ;1
L 10.3325 0.3325 10.3325 0.3325 24 P 0 ;1
L 10.3325 0.3825 10.3325 0.3825 24 P 0 ;1
L 10.3325 0.4325 10.3325 0.4325 24 P 0 ;1
L 10.3325 0.4825 10.3325 0.4825 24 P 0 ;1
L 10.3325 0.5325 10.3325 0.5325 24 P 0 ;1
L 10.3325 0.5825 10.3325 0.5825 24 P 0 ;1
L 10.3325 0.6325 10.3325 0.6325 24 P 0 ;1
L 10.3325 0.6825 10.3325 0.6825 24 P 0 ;1
L 10.3325 0.7325 10.3325 0.7325 24 P 0 ;1
L 10.3325 0.7825 10.3325 0.7825 24 P 0 ;1
L 10.3325 0.8325 10.3325 0.8325 24 P 0 ;1
L 10.3325 0.8825 10.3325 0.8825 24 P 0 ;1
L 10.3325 0.9325 10.3325 0.9325 24 P 0 ;1
L 10.3325 0.9825 10.3325 0.9825 24 P 0 ;1
L 10.3325 1.0325 10.3325 1.0325 24 P 0 ;1
L 10.3325 1.0825 10.3325 1.0825 24 P 0 ;1
L 10.3325 1.1325 10.3325 1.1325 24 P 0 ;1
L 10.3325 1.1825 10.3325 1.1825 24 P 0 ;1
L 10.3325 5.7325 10.3325 5.7325 24 P 0 ;1
L 10.3325 5.7825 10.3325 5.7825 24 P 0 ;1
L 10.3325 5.8325 10.3325 5.8325 24 P 0 ;1
L 10.3825 0.1325 10.3825 0.1325 24 P 0 ;1
L 10.3825 0.1825 10.3825 0.1825 24 P 0 ;1
L 10.3825 0.2325 10.3825 0.2325 24 P 0 ;1
L 10.3825 0.2825 10.3825 0.2825 24 P 0 ;1
L 10.3825 0.3325 10.3825 0.3325 24 P 0 ;1
L 10.3825 0.3825 10.3825 0.3825 24 P 0 ;1
L 10.3825 0.4325 10.3825 0.4325 24 P 0 ;1
L 10.3825 0.4825 10.3825 0.4825 24 P 0 ;1
L 10.3825 0.5325 10.3825 0.5325 24 P 0 ;1
L 10.3825 0.5825 10.3825 0.5825 24 P 0 ;1
L 10.3825 0.6325 10.3825 0.6325 24 P 0 ;1
L 10.3825 0.6825 10.3825 0.6825 24 P 0 ;1
L 10.3825 0.7325 10.3825 0.7325 24 P 0 ;1
L 10.3825 0.7825 10.3825 0.7825 24 P 0 ;1
L 10.3825 0.8325 10.3825 0.8325 24 P 0 ;1
L 10.3825 0.8825 10.3825 0.8825 24 P 0 ;1
L 10.3825 0.9325 10.3825 0.9325 24 P 0 ;1
L 10.3825 0.9825 10.3825 0.9825 24 P 0 ;1
L 10.3825 1.0325 10.3825 1.0325 24 P 0 ;1
L 10.3825 1.0825 10.3825 1.0825 24 P 0 ;1
L 10.3825 1.1325 10.3825 1.1325 24 P 0 ;1
L 10.3825 1.1825 10.3825 1.1825 24 P 0 ;1
L 10.3825 5.6825 10.3825 5.6825 24 P 0 ;1
L 10.3825 5.7325 10.3825 5.7325 24 P 0 ;1
L 10.3825 5.7825 10.3825 5.7825 24 P 0 ;1
L 10.3825 5.8325 10.3825 5.8325 24 P 0 ;1
L 10.4325 0.1325 10.4325 0.1325 24 P 0 ;1
L 10.4325 0.1825 10.4325 0.1825 24 P 0 ;1
L 10.4325 0.2325 10.4325 0.2325 24 P 0 ;1
L 10.4325 0.2825 10.4325 0.2825 24 P 0 ;1
L 10.4325 0.3325 10.4325 0.3325 24 P 0 ;1
L 10.4325 0.3825 10.4325 0.3825 24 P 0 ;1
L 10.4325 0.4325 10.4325 0.4325 24 P 0 ;1
L 10.4325 0.4825 10.4325 0.4825 24 P 0 ;1
L 10.4325 0.5325 10.4325 0.5325 24 P 0 ;1
L 10.4325 0.5825 10.4325 0.5825 24 P 0 ;1
L 10.4325 0.6325 10.4325 0.6325 24 P 0 ;1
L 10.4325 0.6825 10.4325 0.6825 24 P 0 ;1
L 10.4325 0.7325 10.4325 0.7325 24 P 0 ;1
L 10.4325 0.7825 10.4325 0.7825 24 P 0 ;1
L 10.4325 0.8325 10.4325 0.8325 24 P 0 ;1
L 10.4325 0.8825 10.4325 0.8825 24 P 0 ;1
L 10.4325 0.9325 10.4325 0.9325 24 P 0 ;1
L 10.4325 0.9825 10.4325 0.9825 24 P 0 ;1
L 10.4325 1.0325 10.4325 1.0325 24 P 0 ;1
L 10.4325 1.0825 10.4325 1.0825 24 P 0 ;1
L 10.4325 1.1325 10.4325 1.1325 24 P 0 ;1
L 10.4325 1.1825 10.4325 1.1825 24 P 0 ;1
L 10.4325 5.6325 10.4325 5.6325 24 P 0 ;1
L 10.4325 5.6825 10.4325 5.6825 24 P 0 ;1
L 10.4325 5.7325 10.4325 5.7325 24 P 0 ;1
L 10.4325 5.7825 10.4325 5.7825 24 P 0 ;1
L 10.4325 5.8325 10.4325 5.8325 24 P 0 ;1
L 10.4825 0.1325 10.4825 0.1325 24 P 0 ;1
L 10.4825 0.1825 10.4825 0.1825 24 P 0 ;1
L 10.4825 0.2325 10.4825 0.2325 24 P 0 ;1
L 10.4825 0.2825 10.4825 0.2825 24 P 0 ;1
L 10.4825 0.3325 10.4825 0.3325 24 P 0 ;1
L 10.4825 0.3825 10.4825 0.3825 24 P 0 ;1
L 10.4825 0.4325 10.4825 0.4325 24 P 0 ;1
L 10.4825 0.4825 10.4825 0.4825 24 P 0 ;1
L 10.4825 0.5325 10.4825 0.5325 24 P 0 ;1
L 10.4825 0.5825 10.4825 0.5825 24 P 0 ;1
L 10.4825 0.6325 10.4825 0.6325 24 P 0 ;1
L 10.4825 0.6825 10.4825 0.6825 24 P 0 ;1
L 10.4825 0.7325 10.4825 0.7325 24 P 0 ;1
L 10.4825 0.7825 10.4825 0.7825 24 P 0 ;1
L 10.4825 0.8325 10.4825 0.8325 24 P 0 ;1
L 10.4825 0.8825 10.4825 0.8825 24 P 0 ;1
L 10.4825 0.9325 10.4825 0.9325 24 P 0 ;1
L 10.4825 0.9825 10.4825 0.9825 24 P 0 ;1
L 10.4825 1.0325 10.4825 1.0325 24 P 0 ;1
L 10.4825 1.0825 10.4825 1.0825 24 P 0 ;1
L 10.4825 1.1325 10.4825 1.1325 24 P 0 ;1
L 10.4825 1.1825 10.4825 1.1825 24 P 0 ;1
L 10.4825 5.5325 10.4825 5.5325 24 P 0 ;1
L 10.4825 5.5825 10.4825 5.5825 24 P 0 ;1
L 10.4825 5.6325 10.4825 5.6325 24 P 0 ;1
L 10.4825 5.6825 10.4825 5.6825 24 P 0 ;1
L 10.4825 5.7325 10.4825 5.7325 24 P 0 ;1
L 10.4825 5.7825 10.4825 5.7825 24 P 0 ;1
L 10.4825 5.8325 10.4825 5.8325 24 P 0 ;1
L 10.5325 0.1325 10.5325 0.1325 24 P 0 ;1
L 10.5325 0.1825 10.5325 0.1825 24 P 0 ;1
L 10.5325 0.2325 10.5325 0.2325 24 P 0 ;1
L 10.5325 0.2825 10.5325 0.2825 24 P 0 ;1
L 10.5325 0.3325 10.5325 0.3325 24 P 0 ;1
L 10.5325 0.3825 10.5325 0.3825 24 P 0 ;1
L 10.5325 0.4325 10.5325 0.4325 24 P 0 ;1
L 10.5325 0.4825 10.5325 0.4825 24 P 0 ;1
L 10.5325 0.5325 10.5325 0.5325 24 P 0 ;1
L 10.5325 0.5825 10.5325 0.5825 24 P 0 ;1
L 10.5325 0.6325 10.5325 0.6325 24 P 0 ;1
L 10.5325 0.6825 10.5325 0.6825 24 P 0 ;1
L 10.5325 0.7325 10.5325 0.7325 24 P 0 ;1
L 10.5325 0.7825 10.5325 0.7825 24 P 0 ;1
L 10.5325 0.8325 10.5325 0.8325 24 P 0 ;1
L 10.5325 0.8825 10.5325 0.8825 24 P 0 ;1
L 10.5325 0.9325 10.5325 0.9325 24 P 0 ;1
L 10.5325 0.9825 10.5325 0.9825 24 P 0 ;1
L 10.5325 1.0325 10.5325 1.0325 24 P 0 ;1
L 10.5325 1.0825 10.5325 1.0825 24 P 0 ;1
L 10.5325 1.1325 10.5325 1.1325 24 P 0 ;1
L 10.5325 1.1825 10.5325 1.1825 24 P 0 ;1
L 10.5825 0.1325 10.5825 0.1325 24 P 0 ;1
L 10.5825 0.1825 10.5825 0.1825 24 P 0 ;1
L 10.5825 0.2325 10.5825 0.2325 24 P 0 ;1
L 10.5825 0.2825 10.5825 0.2825 24 P 0 ;1
L 10.5825 0.3325 10.5825 0.3325 24 P 0 ;1
L 10.5825 0.3825 10.5825 0.3825 24 P 0 ;1
L 10.5825 0.4325 10.5825 0.4325 24 P 0 ;1
L 10.5825 0.4825 10.5825 0.4825 24 P 0 ;1
L 10.5825 0.5325 10.5825 0.5325 24 P 0 ;1
L 10.5825 0.5825 10.5825 0.5825 24 P 0 ;1
L 10.5825 0.6325 10.5825 0.6325 24 P 0 ;1
L 10.5825 0.6825 10.5825 0.6825 24 P 0 ;1
L 10.5825 0.7325 10.5825 0.7325 24 P 0 ;1
L 10.5825 0.7825 10.5825 0.7825 24 P 0 ;1
L 10.5825 0.8325 10.5825 0.8325 24 P 0 ;1
L 10.5825 0.8825 10.5825 0.8825 24 P 0 ;1
L 10.5825 0.9325 10.5825 0.9325 24 P 0 ;1
L 10.5825 0.9825 10.5825 0.9825 24 P 0 ;1
L 10.5825 1.0325 10.5825 1.0325 24 P 0 ;1
L 10.5825 1.0825 10.5825 1.0825 24 P 0 ;1
L 10.5825 1.1325 10.5825 1.1325 24 P 0 ;1
L 10.5825 1.1825 10.5825 1.1825 24 P 0 ;1
L 10.6325 0.1325 10.6325 0.1325 24 P 0 ;1
L 10.6325 0.1825 10.6325 0.1825 24 P 0 ;1
L 10.6325 0.2325 10.6325 0.2325 24 P 0 ;1
L 10.6325 0.2825 10.6325 0.2825 24 P 0 ;1
L 10.6325 0.3325 10.6325 0.3325 24 P 0 ;1
L 10.6325 0.3825 10.6325 0.3825 24 P 0 ;1
L 10.6325 0.4325 10.6325 0.4325 24 P 0 ;1
L 10.6325 0.4825 10.6325 0.4825 24 P 0 ;1
L 10.6325 0.5325 10.6325 0.5325 24 P 0 ;1
L 10.6325 0.5825 10.6325 0.5825 24 P 0 ;1
L 10.6325 0.6325 10.6325 0.6325 24 P 0 ;1
L 10.6325 0.6825 10.6325 0.6825 24 P 0 ;1
L 10.6325 0.7325 10.6325 0.7325 24 P 0 ;1
L 10.6325 0.7825 10.6325 0.7825 24 P 0 ;1
L 10.6325 0.8325 10.6325 0.8325 24 P 0 ;1
L 10.6325 0.8825 10.6325 0.8825 24 P 0 ;1
L 10.6325 0.9325 10.6325 0.9325 24 P 0 ;1
L 10.6325 0.9825 10.6325 0.9825 24 P 0 ;1
L 10.6325 1.0325 10.6325 1.0325 24 P 0 ;1
L 10.6325 1.0825 10.6325 1.0825 24 P 0 ;1
L 10.6325 1.1325 10.6325 1.1325 24 P 0 ;1
L 10.6325 1.1825 10.6325 1.1825 24 P 0 ;1
L 10.6325 1.2325 10.6325 1.2325 24 P 0 ;1
L 10.6825 0.1325 10.6825 0.1325 24 P 0 ;1
L 10.6825 0.1825 10.6825 0.1825 24 P 0 ;1
L 10.6825 0.2325 10.6825 0.2325 24 P 0 ;1
L 10.6825 0.2825 10.6825 0.2825 24 P 0 ;1
L 10.6825 0.3325 10.6825 0.3325 24 P 0 ;1
L 10.6825 0.3825 10.6825 0.3825 24 P 0 ;1
L 10.6825 0.4325 10.6825 0.4325 24 P 0 ;1
L 10.6825 0.4825 10.6825 0.4825 24 P 0 ;1
L 10.6825 0.5325 10.6825 0.5325 24 P 0 ;1
L 10.6825 0.5825 10.6825 0.5825 24 P 0 ;1
L 10.6825 0.6325 10.6825 0.6325 24 P 0 ;1
L 10.6825 0.6825 10.6825 0.6825 24 P 0 ;1
L 10.6825 0.7325 10.6825 0.7325 24 P 0 ;1
L 10.6825 0.7825 10.6825 0.7825 24 P 0 ;1
L 10.6825 0.8325 10.6825 0.8325 24 P 0 ;1
L 10.6825 0.8825 10.6825 0.8825 24 P 0 ;1
L 10.6825 0.9325 10.6825 0.9325 24 P 0 ;1
L 10.6825 0.9825 10.6825 0.9825 24 P 0 ;1
L 10.6825 1.0325 10.6825 1.0325 24 P 0 ;1
L 10.6825 1.0825 10.6825 1.0825 24 P 0 ;1
L 10.6825 1.1325 10.6825 1.1325 24 P 0 ;1
L 10.6825 1.1825 10.6825 1.1825 24 P 0 ;1
L 10.6825 1.2325 10.6825 1.2325 24 P 0 ;1
L 10.6825 1.2825 10.6825 1.2825 24 P 0 ;1
L 10.7325 0.1325 10.7325 0.1325 24 P 0 ;1
L 10.7325 0.1825 10.7325 0.1825 24 P 0 ;1
L 10.7325 0.2325 10.7325 0.2325 24 P 0 ;1
L 10.7325 0.2825 10.7325 0.2825 24 P 0 ;1
L 10.7325 0.3325 10.7325 0.3325 24 P 0 ;1
L 10.7325 0.3825 10.7325 0.3825 24 P 0 ;1
L 10.7325 0.4325 10.7325 0.4325 24 P 0 ;1
L 10.7325 0.4825 10.7325 0.4825 24 P 0 ;1
L 10.7325 0.5325 10.7325 0.5325 24 P 0 ;1
L 10.7325 0.5825 10.7325 0.5825 24 P 0 ;1
L 10.7325 0.6325 10.7325 0.6325 24 P 0 ;1
L 10.7325 0.6825 10.7325 0.6825 24 P 0 ;1
L 10.7325 0.7325 10.7325 0.7325 24 P 0 ;1
L 10.7325 0.7825 10.7325 0.7825 24 P 0 ;1
L 10.7325 0.8325 10.7325 0.8325 24 P 0 ;1
L 10.7325 0.8825 10.7325 0.8825 24 P 0 ;1
L 10.7325 0.9325 10.7325 0.9325 24 P 0 ;1
L 10.7325 0.9825 10.7325 0.9825 24 P 0 ;1
L 10.7325 1.0325 10.7325 1.0325 24 P 0 ;1
L 10.7325 1.0825 10.7325 1.0825 24 P 0 ;1
L 10.7325 1.1325 10.7325 1.1325 24 P 0 ;1
L 10.7325 1.1825 10.7325 1.1825 24 P 0 ;1
L 10.7325 1.2325 10.7325 1.2325 24 P 0 ;1
L 10.7325 1.2825 10.7325 1.2825 24 P 0 ;1
L 10.7825 0.1325 10.7825 0.1325 24 P 0 ;1
L 10.7825 0.1825 10.7825 0.1825 24 P 0 ;1
L 10.7825 0.2325 10.7825 0.2325 24 P 0 ;1
L 10.7825 0.2825 10.7825 0.2825 24 P 0 ;1
L 10.7825 0.3325 10.7825 0.3325 24 P 0 ;1
L 10.7825 0.3825 10.7825 0.3825 24 P 0 ;1
L 10.7825 0.4325 10.7825 0.4325 24 P 0 ;1
L 10.7825 0.4825 10.7825 0.4825 24 P 0 ;1
L 10.7825 0.5325 10.7825 0.5325 24 P 0 ;1
L 10.7825 0.5825 10.7825 0.5825 24 P 0 ;1
L 10.7825 0.6325 10.7825 0.6325 24 P 0 ;1
L 10.7825 0.6825 10.7825 0.6825 24 P 0 ;1
L 10.7825 0.7325 10.7825 0.7325 24 P 0 ;1
L 10.7825 0.7825 10.7825 0.7825 24 P 0 ;1
L 10.7825 0.8325 10.7825 0.8325 24 P 0 ;1
L 10.7825 0.8825 10.7825 0.8825 24 P 0 ;1
L 10.7825 0.9325 10.7825 0.9325 24 P 0 ;1
L 10.7825 0.9825 10.7825 0.9825 24 P 0 ;1
L 10.7825 1.0325 10.7825 1.0325 24 P 0 ;1
L 10.7825 1.0825 10.7825 1.0825 24 P 0 ;1
L 10.7825 1.1325 10.7825 1.1325 24 P 0 ;1
L 10.7825 1.1825 10.7825 1.1825 24 P 0 ;1
L 10.7825 1.2325 10.7825 1.2325 24 P 0 ;1
L 10.8325 0.1325 10.8325 0.1325 24 P 0 ;1
L 10.8325 0.1825 10.8325 0.1825 24 P 0 ;1
L 10.8325 0.2325 10.8325 0.2325 24 P 0 ;1
L 10.8325 0.2825 10.8325 0.2825 24 P 0 ;1
L 10.8325 0.3325 10.8325 0.3325 24 P 0 ;1
L 10.8325 0.3825 10.8325 0.3825 24 P 0 ;1
L 10.8325 0.4325 10.8325 0.4325 24 P 0 ;1
L 10.8325 0.4825 10.8325 0.4825 24 P 0 ;1
L 10.8325 0.5325 10.8325 0.5325 24 P 0 ;1
L 10.8325 0.5825 10.8325 0.5825 24 P 0 ;1
L 10.8325 0.6325 10.8325 0.6325 24 P 0 ;1
L 10.8325 0.6825 10.8325 0.6825 24 P 0 ;1
L 10.8325 0.7325 10.8325 0.7325 24 P 0 ;1
L 10.8325 0.7825 10.8325 0.7825 24 P 0 ;1
L 10.8325 0.8325 10.8325 0.8325 24 P 0 ;1
L 10.8325 0.8825 10.8325 0.8825 24 P 0 ;1
L 10.8325 0.9325 10.8325 0.9325 24 P 0 ;1
L 10.8325 0.9825 10.8325 0.9825 24 P 0 ;1
L 10.8325 1.0325 10.8325 1.0325 24 P 0 ;1
L 10.8325 1.0825 10.8325 1.0825 24 P 0 ;1
L 10.8325 1.1325 10.8325 1.1325 24 P 0 ;1
L 10.8325 1.1825 10.8325 1.1825 24 P 0 ;1
L 10.8325 1.2325 10.8325 1.2325 24 P 0 ;1
L 10.8825 0.1325 10.8825 0.1325 24 P 0 ;1
L 10.8825 0.1825 10.8825 0.1825 24 P 0 ;1
L 10.8825 0.2325 10.8825 0.2325 24 P 0 ;1
L 10.8825 0.2825 10.8825 0.2825 24 P 0 ;1
L 10.8825 0.3325 10.8825 0.3325 24 P 0 ;1
L 10.8825 0.3825 10.8825 0.3825 24 P 0 ;1
L 10.8825 0.4325 10.8825 0.4325 24 P 0 ;1
L 10.8825 0.4825 10.8825 0.4825 24 P 0 ;1
L 10.8825 0.5325 10.8825 0.5325 24 P 0 ;1
L 10.8825 0.5825 10.8825 0.5825 24 P 0 ;1
L 10.8825 0.6325 10.8825 0.6325 24 P 0 ;1
L 10.8825 0.6825 10.8825 0.6825 24 P 0 ;1
L 10.8825 0.7325 10.8825 0.7325 24 P 0 ;1
L 10.8825 0.7825 10.8825 0.7825 24 P 0 ;1
L 10.8825 0.8325 10.8825 0.8325 24 P 0 ;1
L 10.8825 0.8825 10.8825 0.8825 24 P 0 ;1
L 10.8825 0.9325 10.8825 0.9325 24 P 0 ;1
L 10.8825 0.9825 10.8825 0.9825 24 P 0 ;1
L 10.8825 1.0325 10.8825 1.0325 24 P 0 ;1
L 10.8825 1.0825 10.8825 1.0825 24 P 0 ;1
L 10.8825 1.1325 10.8825 1.1325 24 P 0 ;1
L 10.8825 1.1825 10.8825 1.1825 24 P 0 ;1
L 10.8825 1.2325 10.8825 1.2325 24 P 0 ;1
L 10.9325 0.1325 10.9325 0.1325 24 P 0 ;1
L 10.9325 0.1825 10.9325 0.1825 24 P 0 ;1
L 10.9325 0.2325 10.9325 0.2325 24 P 0 ;1
L 10.9325 0.2825 10.9325 0.2825 24 P 0 ;1
L 10.9325 0.3325 10.9325 0.3325 24 P 0 ;1
L 10.9325 0.3825 10.9325 0.3825 24 P 0 ;1
L 10.9325 0.4325 10.9325 0.4325 24 P 0 ;1
L 10.9325 0.4825 10.9325 0.4825 24 P 0 ;1
L 10.9325 0.5325 10.9325 0.5325 24 P 0 ;1
L 10.9325 0.5825 10.9325 0.5825 24 P 0 ;1
L 10.9325 0.6325 10.9325 0.6325 24 P 0 ;1
L 10.9325 0.6825 10.9325 0.6825 24 P 0 ;1
L 10.9325 0.7325 10.9325 0.7325 24 P 0 ;1
L 10.9325 0.7825 10.9325 0.7825 24 P 0 ;1
L 10.9325 0.8325 10.9325 0.8325 24 P 0 ;1
L 10.9325 0.8825 10.9325 0.8825 24 P 0 ;1
L 10.9325 0.9325 10.9325 0.9325 24 P 0 ;1
L 10.9325 0.9825 10.9325 0.9825 24 P 0 ;1
L 10.9325 1.0325 10.9325 1.0325 24 P 0 ;1
L 10.9325 1.0825 10.9325 1.0825 24 P 0 ;1
L 10.9325 1.1325 10.9325 1.1325 24 P 0 ;1
L 10.9325 1.1825 10.9325 1.1825 24 P 0 ;1
L 10.9325 1.2325 10.9325 1.2325 24 P 0 ;1
L 10.9325 1.2825 10.9325 1.2825 24 P 0 ;1
L 10.9825 0.1325 10.9825 0.1325 24 P 0 ;1
L 10.9825 0.1825 10.9825 0.1825 24 P 0 ;1
L 10.9825 0.2325 10.9825 0.2325 24 P 0 ;1
L 10.9825 0.2825 10.9825 0.2825 24 P 0 ;1
L 10.9825 0.3325 10.9825 0.3325 24 P 0 ;1
L 10.9825 0.3825 10.9825 0.3825 24 P 0 ;1
L 10.9825 0.4325 10.9825 0.4325 24 P 0 ;1
L 10.9825 0.4825 10.9825 0.4825 24 P 0 ;1
L 10.9825 0.5325 10.9825 0.5325 24 P 0 ;1
L 10.9825 0.5825 10.9825 0.5825 24 P 0 ;1
L 10.9825 0.6325 10.9825 0.6325 24 P 0 ;1
L 10.9825 0.6825 10.9825 0.6825 24 P 0 ;1
L 10.9825 0.7325 10.9825 0.7325 24 P 0 ;1
L 10.9825 0.7825 10.9825 0.7825 24 P 0 ;1
L 10.9825 0.8325 10.9825 0.8325 24 P 0 ;1
L 10.9825 0.8825 10.9825 0.8825 24 P 0 ;1
L 10.9825 0.9325 10.9825 0.9325 24 P 0 ;1
L 10.9825 0.9825 10.9825 0.9825 24 P 0 ;1
L 10.9825 1.0325 10.9825 1.0325 24 P 0 ;1
L 10.9825 1.0825 10.9825 1.0825 24 P 0 ;1
L 10.9825 1.1325 10.9825 1.1325 24 P 0 ;1
L 10.9825 1.1825 10.9825 1.1825 24 P 0 ;1
L 10.9825 1.2325 10.9825 1.2325 24 P 0 ;1
L 10.9825 1.2825 10.9825 1.2825 24 P 0 ;1
L 11.0325 0.1325 11.0325 0.1325 24 P 0 ;1
L 11.0325 0.1825 11.0325 0.1825 24 P 0 ;1
L 11.0325 0.2325 11.0325 0.2325 24 P 0 ;1
L 11.0325 0.2825 11.0325 0.2825 24 P 0 ;1
L 11.0325 0.3325 11.0325 0.3325 24 P 0 ;1
L 11.0325 0.3825 11.0325 0.3825 24 P 0 ;1
L 11.0325 0.4325 11.0325 0.4325 24 P 0 ;1
L 11.0325 0.4825 11.0325 0.4825 24 P 0 ;1
L 11.0325 0.5325 11.0325 0.5325 24 P 0 ;1
L 11.0325 0.5825 11.0325 0.5825 24 P 0 ;1
L 11.0325 0.6325 11.0325 0.6325 24 P 0 ;1
L 11.0325 0.6825 11.0325 0.6825 24 P 0 ;1
L 11.0325 0.7325 11.0325 0.7325 24 P 0 ;1
L 11.0325 0.7825 11.0325 0.7825 24 P 0 ;1
L 11.0325 0.8325 11.0325 0.8325 24 P 0 ;1
L 11.0325 0.8825 11.0325 0.8825 24 P 0 ;1
L 11.0325 0.9325 11.0325 0.9325 24 P 0 ;1
L 11.0325 0.9825 11.0325 0.9825 24 P 0 ;1
L 11.0325 1.0325 11.0325 1.0325 24 P 0 ;1
L 11.0325 1.0825 11.0325 1.0825 24 P 0 ;1
L 11.0325 1.1325 11.0325 1.1325 24 P 0 ;1
L 11.0325 1.1825 11.0325 1.1825 24 P 0 ;1
L 11.0325 1.2325 11.0325 1.2325 24 P 0 ;1
L 11.0325 1.2825 11.0325 1.2825 24 P 0 ;1
L 11.0325 1.3325 11.0325 1.3325 24 P 0 ;1
L 11.0825 0.1325 11.0825 0.1325 24 P 0 ;1
L 11.0825 0.1825 11.0825 0.1825 24 P 0 ;1
L 11.0825 0.2325 11.0825 0.2325 24 P 0 ;1
L 11.0825 0.2825 11.0825 0.2825 24 P 0 ;1
L 11.0825 0.3325 11.0825 0.3325 24 P 0 ;1
L 11.0825 0.3825 11.0825 0.3825 24 P 0 ;1
L 11.0825 0.4325 11.0825 0.4325 24 P 0 ;1
L 11.0825 0.4825 11.0825 0.4825 24 P 0 ;1
L 11.0825 0.5325 11.0825 0.5325 24 P 0 ;1
L 11.0825 0.5825 11.0825 0.5825 24 P 0 ;1
L 11.0825 0.6325 11.0825 0.6325 24 P 0 ;1
L 11.0825 0.6825 11.0825 0.6825 24 P 0 ;1
L 11.0825 0.7325 11.0825 0.7325 24 P 0 ;1
L 11.0825 0.7825 11.0825 0.7825 24 P 0 ;1
L 11.0825 0.8325 11.0825 0.8325 24 P 0 ;1
L 11.0825 0.8825 11.0825 0.8825 24 P 0 ;1
L 11.0825 0.9325 11.0825 0.9325 24 P 0 ;1
L 11.0825 0.9825 11.0825 0.9825 24 P 0 ;1
L 11.0825 1.0325 11.0825 1.0325 24 P 0 ;1
L 11.0825 1.0825 11.0825 1.0825 24 P 0 ;1
L 11.0825 1.1325 11.0825 1.1325 24 P 0 ;1
L 11.0825 1.1825 11.0825 1.1825 24 P 0 ;1
L 11.0825 1.2325 11.0825 1.2325 24 P 0 ;1
L 11.0825 1.2825 11.0825 1.2825 24 P 0 ;1
L 11.0825 1.3325 11.0825 1.3325 24 P 0 ;1
L 11.0825 1.3825 11.0825 1.3825 24 P 0 ;1
L 11.1325 0.1325 11.1325 0.1325 24 P 0 ;1
L 11.1325 0.1825 11.1325 0.1825 24 P 0 ;1
L 11.1325 0.2325 11.1325 0.2325 24 P 0 ;1
L 11.1325 0.2825 11.1325 0.2825 24 P 0 ;1
L 11.1325 0.3325 11.1325 0.3325 24 P 0 ;1
L 11.1325 0.3825 11.1325 0.3825 24 P 0 ;1
L 11.1325 0.4325 11.1325 0.4325 24 P 0 ;1
L 11.1325 0.4825 11.1325 0.4825 24 P 0 ;1
L 11.1325 0.5325 11.1325 0.5325 24 P 0 ;1
L 11.1325 0.5825 11.1325 0.5825 24 P 0 ;1
L 11.1325 0.6325 11.1325 0.6325 24 P 0 ;1
L 11.1325 0.6825 11.1325 0.6825 24 P 0 ;1
L 11.1325 0.7325 11.1325 0.7325 24 P 0 ;1
L 11.1325 0.7825 11.1325 0.7825 24 P 0 ;1
L 11.1325 0.8325 11.1325 0.8325 24 P 0 ;1
L 11.1325 0.8825 11.1325 0.8825 24 P 0 ;1
L 11.1325 0.9325 11.1325 0.9325 24 P 0 ;1
L 11.1325 0.9825 11.1325 0.9825 24 P 0 ;1
L 11.1325 1.0325 11.1325 1.0325 24 P 0 ;1
L 11.1325 1.0825 11.1325 1.0825 24 P 0 ;1
L 11.1325 1.1325 11.1325 1.1325 24 P 0 ;1
L 11.1325 1.1825 11.1325 1.1825 24 P 0 ;1
L 11.1325 1.2325 11.1325 1.2325 24 P 0 ;1
L 11.1325 1.2825 11.1325 1.2825 24 P 0 ;1
L 11.1325 1.3325 11.1325 1.3325 24 P 0 ;1
L 11.1325 1.3825 11.1325 1.3825 24 P 0 ;1
L 11.1825 0.1325 11.1825 0.1325 24 P 0 ;1
L 11.1825 0.1825 11.1825 0.1825 24 P 0 ;1
L 11.1825 0.2325 11.1825 0.2325 24 P 0 ;1
L 11.1825 0.2825 11.1825 0.2825 24 P 0 ;1
L 11.1825 0.3325 11.1825 0.3325 24 P 0 ;1
L 11.1825 0.3825 11.1825 0.3825 24 P 0 ;1
L 11.1825 0.4325 11.1825 0.4325 24 P 0 ;1
L 11.1825 0.4825 11.1825 0.4825 24 P 0 ;1
L 11.1825 0.5325 11.1825 0.5325 24 P 0 ;1
L 11.1825 0.5825 11.1825 0.5825 24 P 0 ;1
L 11.1825 0.6325 11.1825 0.6325 24 P 0 ;1
L 11.1825 0.6825 11.1825 0.6825 24 P 0 ;1
L 11.1825 0.7325 11.1825 0.7325 24 P 0 ;1
L 11.1825 0.7825 11.1825 0.7825 24 P 0 ;1
L 11.1825 0.8325 11.1825 0.8325 24 P 0 ;1
L 11.1825 0.8825 11.1825 0.8825 24 P 0 ;1
L 11.1825 0.9325 11.1825 0.9325 24 P 0 ;1
L 11.1825 0.9825 11.1825 0.9825 24 P 0 ;1
L 11.1825 1.0325 11.1825 1.0325 24 P 0 ;1
L 11.1825 1.0825 11.1825 1.0825 24 P 0 ;1
L 11.1825 1.1325 11.1825 1.1325 24 P 0 ;1
L 11.1825 1.1825 11.1825 1.1825 24 P 0 ;1
L 11.1825 1.2325 11.1825 1.2325 24 P 0 ;1
L 11.1825 1.2825 11.1825 1.2825 24 P 0 ;1
L 11.1825 1.3325 11.1825 1.3325 24 P 0 ;1
L 11.2325 0.1325 11.2325 0.1325 24 P 0 ;1
L 11.2325 0.1825 11.2325 0.1825 24 P 0 ;1
L 11.2325 0.2325 11.2325 0.2325 24 P 0 ;1
L 11.2325 0.2825 11.2325 0.2825 24 P 0 ;1
L 11.2325 0.3325 11.2325 0.3325 24 P 0 ;1
L 11.2325 0.3825 11.2325 0.3825 24 P 0 ;1
L 11.2325 0.4325 11.2325 0.4325 24 P 0 ;1
L 11.2325 0.4825 11.2325 0.4825 24 P 0 ;1
L 11.2325 0.5325 11.2325 0.5325 24 P 0 ;1
L 11.2325 0.5825 11.2325 0.5825 24 P 0 ;1
L 11.2325 0.6325 11.2325 0.6325 24 P 0 ;1
L 11.2325 0.6825 11.2325 0.6825 24 P 0 ;1
L 11.2325 0.7325 11.2325 0.7325 24 P 0 ;1
L 11.2325 0.7825 11.2325 0.7825 24 P 0 ;1
L 11.2325 0.8325 11.2325 0.8325 24 P 0 ;1
L 11.2325 0.8825 11.2325 0.8825 24 P 0 ;1
L 11.2325 0.9325 11.2325 0.9325 24 P 0 ;1
L 11.2325 0.9825 11.2325 0.9825 24 P 0 ;1
L 11.2325 1.0325 11.2325 1.0325 24 P 0 ;1
L 11.2325 1.0825 11.2325 1.0825 24 P 0 ;1
L 11.2325 1.1325 11.2325 1.1325 24 P 0 ;1
L 11.2325 1.1825 11.2325 1.1825 24 P 0 ;1
L 11.2325 1.2325 11.2325 1.2325 24 P 0 ;1
L 11.2325 1.2825 11.2325 1.2825 24 P 0 ;1
L 11.2825 0.1325 11.2825 0.1325 24 P 0 ;1
L 11.2825 0.1825 11.2825 0.1825 24 P 0 ;1
L 11.2825 0.2325 11.2825 0.2325 24 P 0 ;1
L 11.2825 0.2825 11.2825 0.2825 24 P 0 ;1
L 11.2825 0.3325 11.2825 0.3325 24 P 0 ;1
L 11.2825 0.3825 11.2825 0.3825 24 P 0 ;1
L 11.2825 0.4325 11.2825 0.4325 24 P 0 ;1
L 11.2825 0.4825 11.2825 0.4825 24 P 0 ;1
L 11.2825 0.5325 11.2825 0.5325 24 P 0 ;1
L 11.2825 0.5825 11.2825 0.5825 24 P 0 ;1
L 11.2825 0.6325 11.2825 0.6325 24 P 0 ;1
L 11.2825 0.6825 11.2825 0.6825 24 P 0 ;1
L 11.2825 0.7325 11.2825 0.7325 24 P 0 ;1
L 11.2825 0.7825 11.2825 0.7825 24 P 0 ;1
L 11.2825 0.8325 11.2825 0.8325 24 P 0 ;1
L 11.2825 0.8825 11.2825 0.8825 24 P 0 ;1
L 11.2825 0.9325 11.2825 0.9325 24 P 0 ;1
L 11.2825 0.9825 11.2825 0.9825 24 P 0 ;1
L 11.2825 1.0325 11.2825 1.0325 24 P 0 ;1
L 11.2825 1.0825 11.2825 1.0825 24 P 0 ;1
L 11.2825 1.1325 11.2825 1.1325 24 P 0 ;1
L 11.2825 1.1825 11.2825 1.1825 24 P 0 ;1
L 11.2825 1.2325 11.2825 1.2325 24 P 0 ;1
L 11.2825 1.2825 11.2825 1.2825 24 P 0 ;1
L 11.3325 0.1325 11.3325 0.1325 24 P 0 ;1
L 11.3325 0.1825 11.3325 0.1825 24 P 0 ;1
L 11.3325 0.2325 11.3325 0.2325 24 P 0 ;1
L 11.3325 0.2825 11.3325 0.2825 24 P 0 ;1
L 11.3325 0.3325 11.3325 0.3325 24 P 0 ;1
L 11.3325 0.3825 11.3325 0.3825 24 P 0 ;1
L 11.3325 0.4325 11.3325 0.4325 24 P 0 ;1
L 11.3325 0.4825 11.3325 0.4825 24 P 0 ;1
L 11.3325 0.5325 11.3325 0.5325 24 P 0 ;1
L 11.3325 0.5825 11.3325 0.5825 24 P 0 ;1
L 11.3325 0.6325 11.3325 0.6325 24 P 0 ;1
L 11.3325 0.6825 11.3325 0.6825 24 P 0 ;1
L 11.3325 0.7325 11.3325 0.7325 24 P 0 ;1
L 11.3325 0.7825 11.3325 0.7825 24 P 0 ;1
L 11.3325 0.8325 11.3325 0.8325 24 P 0 ;1
L 11.3325 0.8825 11.3325 0.8825 24 P 0 ;1
L 11.3325 0.9325 11.3325 0.9325 24 P 0 ;1
L 11.3325 0.9825 11.3325 0.9825 24 P 0 ;1
L 11.3325 1.0325 11.3325 1.0325 24 P 0 ;1
L 11.3325 1.0825 11.3325 1.0825 24 P 0 ;1
L 11.3325 1.1325 11.3325 1.1325 24 P 0 ;1
L 11.3325 1.1825 11.3325 1.1825 24 P 0 ;1
L 11.3325 1.2325 11.3325 1.2325 24 P 0 ;1
L 11.3325 3.4325 11.3325 3.4325 24 P 0 ;1
L 11.3325 3.4825 11.3325 3.4825 24 P 0 ;1
L 11.3325 3.5325 11.3325 3.5325 24 P 0 ;1
L 11.3325 3.5825 11.3325 3.5825 24 P 0 ;1
L 11.3325 3.6325 11.3325 3.6325 24 P 0 ;1
L 11.3325 3.6825 11.3325 3.6825 24 P 0 ;1
L 11.3325 3.7325 11.3325 3.7325 24 P 0 ;1
L 11.3325 3.7825 11.3325 3.7825 24 P 0 ;1
L 11.3325 3.8325 11.3325 3.8325 24 P 0 ;1
L 11.3325 3.8825 11.3325 3.8825 24 P 0 ;1
L 11.3325 3.9325 11.3325 3.9325 24 P 0 ;1
L 11.3325 3.9825 11.3325 3.9825 24 P 0 ;1
L 11.3325 4.0325 11.3325 4.0325 24 P 0 ;1
L 11.3325 4.0825 11.3325 4.0825 24 P 0 ;1
L 11.3325 4.1325 11.3325 4.1325 24 P 0 ;1
L 11.3325 4.1825 11.3325 4.1825 24 P 0 ;1
L 11.3325 4.2325 11.3325 4.2325 24 P 0 ;1
L 11.3325 4.2825 11.3325 4.2825 24 P 0 ;1
L 11.3325 4.3325 11.3325 4.3325 24 P 0 ;1
L 11.3325 4.3825 11.3325 4.3825 24 P 0 ;1
L 11.3325 4.4325 11.3325 4.4325 24 P 0 ;1
L 11.3325 4.4825 11.3325 4.4825 24 P 0 ;1
L 11.3325 4.5325 11.3325 4.5325 24 P 0 ;1
L 11.3325 4.5825 11.3325 4.5825 24 P 0 ;1
L 11.3325 4.6325 11.3325 4.6325 24 P 0 ;1
L 11.3325 4.6825 11.3325 4.6825 24 P 0 ;1
L 11.3825 0.1325 11.3825 0.1325 24 P 0 ;1
L 11.3825 0.1825 11.3825 0.1825 24 P 0 ;1
L 11.3825 0.2325 11.3825 0.2325 24 P 0 ;1
L 11.3825 0.2825 11.3825 0.2825 24 P 0 ;1
L 11.3825 0.3325 11.3825 0.3325 24 P 0 ;1
L 11.3825 0.3825 11.3825 0.3825 24 P 0 ;1
L 11.3825 0.4325 11.3825 0.4325 24 P 0 ;1
L 11.3825 0.4825 11.3825 0.4825 24 P 0 ;1
L 11.3825 0.5325 11.3825 0.5325 24 P 0 ;1
L 11.3825 0.5825 11.3825 0.5825 24 P 0 ;1
L 11.3825 0.6325 11.3825 0.6325 24 P 0 ;1
L 11.3825 0.6825 11.3825 0.6825 24 P 0 ;1
L 11.3825 0.7325 11.3825 0.7325 24 P 0 ;1
L 11.3825 0.7825 11.3825 0.7825 24 P 0 ;1
L 11.3825 0.8325 11.3825 0.8325 24 P 0 ;1
L 11.3825 0.8825 11.3825 0.8825 24 P 0 ;1
L 11.3825 0.9325 11.3825 0.9325 24 P 0 ;1
L 11.3825 0.9825 11.3825 0.9825 24 P 0 ;1
L 11.3825 1.0325 11.3825 1.0325 24 P 0 ;1
L 11.3825 1.0825 11.3825 1.0825 24 P 0 ;1
L 11.3825 1.1325 11.3825 1.1325 24 P 0 ;1
L 11.3825 1.1825 11.3825 1.1825 24 P 0 ;1
L 11.3825 1.2325 11.3825 1.2325 24 P 0 ;1
L 11.3825 3.4325 11.3825 3.4325 24 P 0 ;1
L 11.3825 3.4825 11.3825 3.4825 24 P 0 ;1
L 11.3825 3.5325 11.3825 3.5325 24 P 0 ;1
L 11.3825 3.5825 11.3825 3.5825 24 P 0 ;1
L 11.3825 3.6325 11.3825 3.6325 24 P 0 ;1
L 11.3825 3.6825 11.3825 3.6825 24 P 0 ;1
L 11.3825 3.7325 11.3825 3.7325 24 P 0 ;1
L 11.3825 3.7825 11.3825 3.7825 24 P 0 ;1
L 11.3825 3.8325 11.3825 3.8325 24 P 0 ;1
L 11.3825 3.8825 11.3825 3.8825 24 P 0 ;1
L 11.3825 3.9325 11.3825 3.9325 24 P 0 ;1
L 11.3825 3.9825 11.3825 3.9825 24 P 0 ;1
L 11.3825 4.0325 11.3825 4.0325 24 P 0 ;1
L 11.3825 4.0825 11.3825 4.0825 24 P 0 ;1
L 11.3825 4.1325 11.3825 4.1325 24 P 0 ;1
L 11.3825 4.1825 11.3825 4.1825 24 P 0 ;1
L 11.3825 4.2325 11.3825 4.2325 24 P 0 ;1
L 11.3825 4.2825 11.3825 4.2825 24 P 0 ;1
L 11.3825 4.3325 11.3825 4.3325 24 P 0 ;1
L 11.3825 4.3825 11.3825 4.3825 24 P 0 ;1
L 11.3825 4.4325 11.3825 4.4325 24 P 0 ;1
L 11.3825 4.4825 11.3825 4.4825 24 P 0 ;1
L 11.3825 4.5325 11.3825 4.5325 24 P 0 ;1
L 11.3825 4.5825 11.3825 4.5825 24 P 0 ;1
L 11.3825 4.6325 11.3825 4.6325 24 P 0 ;1
L 11.3825 4.6825 11.3825 4.6825 24 P 0 ;1
L 11.4325 0.1325 11.4325 0.1325 24 P 0 ;1
L 11.4325 0.1825 11.4325 0.1825 24 P 0 ;1
L 11.4325 0.2325 11.4325 0.2325 24 P 0 ;1
L 11.4325 0.2825 11.4325 0.2825 24 P 0 ;1
L 11.4325 0.3325 11.4325 0.3325 24 P 0 ;1
L 11.4325 0.3825 11.4325 0.3825 24 P 0 ;1
L 11.4325 0.4325 11.4325 0.4325 24 P 0 ;1
L 11.4325 0.4825 11.4325 0.4825 24 P 0 ;1
L 11.4325 0.5325 11.4325 0.5325 24 P 0 ;1
L 11.4325 0.5825 11.4325 0.5825 24 P 0 ;1
L 11.4325 0.6325 11.4325 0.6325 24 P 0 ;1
L 11.4325 0.6825 11.4325 0.6825 24 P 0 ;1
L 11.4325 0.7325 11.4325 0.7325 24 P 0 ;1
L 11.4325 0.7825 11.4325 0.7825 24 P 0 ;1
L 11.4325 0.8325 11.4325 0.8325 24 P 0 ;1
L 11.4325 0.8825 11.4325 0.8825 24 P 0 ;1
L 11.4325 0.9325 11.4325 0.9325 24 P 0 ;1
L 11.4325 0.9825 11.4325 0.9825 24 P 0 ;1
L 11.4325 1.0325 11.4325 1.0325 24 P 0 ;1
L 11.4325 1.0825 11.4325 1.0825 24 P 0 ;1
L 11.4325 1.1325 11.4325 1.1325 24 P 0 ;1
L 11.4325 1.1825 11.4325 1.1825 24 P 0 ;1
L 11.4325 1.2325 11.4325 1.2325 24 P 0 ;1
L 11.4325 3.4325 11.4325 3.4325 24 P 0 ;1
L 11.4325 3.4825 11.4325 3.4825 24 P 0 ;1
L 11.4325 3.5325 11.4325 3.5325 24 P 0 ;1
L 11.4325 3.5825 11.4325 3.5825 24 P 0 ;1
L 11.4325 3.6325 11.4325 3.6325 24 P 0 ;1
L 11.4325 3.6825 11.4325 3.6825 24 P 0 ;1
L 11.4325 3.7325 11.4325 3.7325 24 P 0 ;1
L 11.4325 3.7825 11.4325 3.7825 24 P 0 ;1
L 11.4325 3.8325 11.4325 3.8325 24 P 0 ;1
L 11.4325 3.8825 11.4325 3.8825 24 P 0 ;1
L 11.4325 3.9325 11.4325 3.9325 24 P 0 ;1
L 11.4325 3.9825 11.4325 3.9825 24 P 0 ;1
L 11.4325 4.0325 11.4325 4.0325 24 P 0 ;1
L 11.4325 4.0825 11.4325 4.0825 24 P 0 ;1
L 11.4325 4.1325 11.4325 4.1325 24 P 0 ;1
L 11.4325 4.1825 11.4325 4.1825 24 P 0 ;1
L 11.4325 4.2325 11.4325 4.2325 24 P 0 ;1
L 11.4325 4.2825 11.4325 4.2825 24 P 0 ;1
L 11.4325 4.3325 11.4325 4.3325 24 P 0 ;1
L 11.4325 4.3825 11.4325 4.3825 24 P 0 ;1
L 11.4325 4.4325 11.4325 4.4325 24 P 0 ;1
L 11.4325 4.4825 11.4325 4.4825 24 P 0 ;1
L 11.4325 4.5325 11.4325 4.5325 24 P 0 ;1
L 11.4325 4.5825 11.4325 4.5825 24 P 0 ;1
L 11.4325 4.6325 11.4325 4.6325 24 P 0 ;1
L 11.4325 4.6825 11.4325 4.6825 24 P 0 ;1
L 11.4825 0.1325 11.4825 0.1325 24 P 0 ;1
L 11.4825 0.1825 11.4825 0.1825 24 P 0 ;1
L 11.4825 0.2325 11.4825 0.2325 24 P 0 ;1
L 11.4825 0.2825 11.4825 0.2825 24 P 0 ;1
L 11.4825 0.3325 11.4825 0.3325 24 P 0 ;1
L 11.4825 0.3825 11.4825 0.3825 24 P 0 ;1
L 11.4825 0.4325 11.4825 0.4325 24 P 0 ;1
L 11.4825 0.4825 11.4825 0.4825 24 P 0 ;1
L 11.4825 0.5325 11.4825 0.5325 24 P 0 ;1
L 11.4825 0.5825 11.4825 0.5825 24 P 0 ;1
L 11.4825 0.6325 11.4825 0.6325 24 P 0 ;1
L 11.4825 0.6825 11.4825 0.6825 24 P 0 ;1
L 11.4825 0.7325 11.4825 0.7325 24 P 0 ;1
L 11.4825 0.7825 11.4825 0.7825 24 P 0 ;1
L 11.4825 0.8325 11.4825 0.8325 24 P 0 ;1
L 11.4825 0.8825 11.4825 0.8825 24 P 0 ;1
L 11.4825 0.9325 11.4825 0.9325 24 P 0 ;1
L 11.4825 0.9825 11.4825 0.9825 24 P 0 ;1
L 11.4825 1.0325 11.4825 1.0325 24 P 0 ;1
L 11.4825 1.0825 11.4825 1.0825 24 P 0 ;1
L 11.4825 1.1325 11.4825 1.1325 24 P 0 ;1
L 11.4825 1.1825 11.4825 1.1825 24 P 0 ;1
L 11.4825 1.2325 11.4825 1.2325 24 P 0 ;1
L 11.4825 3.4325 11.4825 3.4325 24 P 0 ;1
L 11.4825 3.4825 11.4825 3.4825 24 P 0 ;1
L 11.4825 3.5325 11.4825 3.5325 24 P 0 ;1
L 11.4825 3.5825 11.4825 3.5825 24 P 0 ;1
L 11.4825 3.6325 11.4825 3.6325 24 P 0 ;1
L 11.4825 3.6825 11.4825 3.6825 24 P 0 ;1
L 11.4825 3.7325 11.4825 3.7325 24 P 0 ;1
L 11.4825 3.7825 11.4825 3.7825 24 P 0 ;1
L 11.4825 3.8325 11.4825 3.8325 24 P 0 ;1
L 11.4825 3.8825 11.4825 3.8825 24 P 0 ;1
L 11.4825 3.9325 11.4825 3.9325 24 P 0 ;1
L 11.4825 3.9825 11.4825 3.9825 24 P 0 ;1
L 11.4825 4.0325 11.4825 4.0325 24 P 0 ;1
L 11.4825 4.0825 11.4825 4.0825 24 P 0 ;1
L 11.4825 4.1325 11.4825 4.1325 24 P 0 ;1
L 11.4825 4.1825 11.4825 4.1825 24 P 0 ;1
L 11.4825 4.2325 11.4825 4.2325 24 P 0 ;1
L 11.4825 4.2825 11.4825 4.2825 24 P 0 ;1
L 11.4825 4.3325 11.4825 4.3325 24 P 0 ;1
L 11.4825 4.3825 11.4825 4.3825 24 P 0 ;1
L 11.4825 4.4325 11.4825 4.4325 24 P 0 ;1
L 11.4825 4.4825 11.4825 4.4825 24 P 0 ;1
L 11.4825 4.5325 11.4825 4.5325 24 P 0 ;1
L 11.4825 4.5825 11.4825 4.5825 24 P 0 ;1
L 11.4825 4.6325 11.4825 4.6325 24 P 0 ;1
L 11.4825 4.6825 11.4825 4.6825 24 P 0 ;1
L 11.5325 0.1325 11.5325 0.1325 24 P 0 ;1
L 11.5325 0.1825 11.5325 0.1825 24 P 0 ;1
L 11.5325 0.2325 11.5325 0.2325 24 P 0 ;1
L 11.5325 0.2825 11.5325 0.2825 24 P 0 ;1
L 11.5325 0.3325 11.5325 0.3325 24 P 0 ;1
L 11.5325 0.3825 11.5325 0.3825 24 P 0 ;1
L 11.5325 0.4325 11.5325 0.4325 24 P 0 ;1
L 11.5325 0.4825 11.5325 0.4825 24 P 0 ;1
L 11.5325 0.5325 11.5325 0.5325 24 P 0 ;1
L 11.5325 0.5825 11.5325 0.5825 24 P 0 ;1
L 11.5325 0.6325 11.5325 0.6325 24 P 0 ;1
L 11.5325 0.6825 11.5325 0.6825 24 P 0 ;1
L 11.5325 0.7325 11.5325 0.7325 24 P 0 ;1
L 11.5325 0.7825 11.5325 0.7825 24 P 0 ;1
L 11.5325 0.8325 11.5325 0.8325 24 P 0 ;1
L 11.5325 0.8825 11.5325 0.8825 24 P 0 ;1
L 11.5325 0.9325 11.5325 0.9325 24 P 0 ;1
L 11.5325 0.9825 11.5325 0.9825 24 P 0 ;1
L 11.5325 1.0325 11.5325 1.0325 24 P 0 ;1
L 11.5325 1.0825 11.5325 1.0825 24 P 0 ;1
L 11.5325 1.1325 11.5325 1.1325 24 P 0 ;1
L 11.5325 1.1825 11.5325 1.1825 24 P 0 ;1
L 11.5325 1.2325 11.5325 1.2325 24 P 0 ;1
L 11.5325 3.4325 11.5325 3.4325 24 P 0 ;1
L 11.5325 3.4825 11.5325 3.4825 24 P 0 ;1
L 11.5325 3.5325 11.5325 3.5325 24 P 0 ;1
L 11.5325 3.5825 11.5325 3.5825 24 P 0 ;1
L 11.5325 3.6325 11.5325 3.6325 24 P 0 ;1
L 11.5325 3.6825 11.5325 3.6825 24 P 0 ;1
L 11.5325 3.7325 11.5325 3.7325 24 P 0 ;1
L 11.5325 3.7825 11.5325 3.7825 24 P 0 ;1
L 11.5325 3.8325 11.5325 3.8325 24 P 0 ;1
L 11.5325 3.8825 11.5325 3.8825 24 P 0 ;1
L 11.5325 3.9325 11.5325 3.9325 24 P 0 ;1
L 11.5325 3.9825 11.5325 3.9825 24 P 0 ;1
L 11.5325 4.0325 11.5325 4.0325 24 P 0 ;1
L 11.5325 4.0825 11.5325 4.0825 24 P 0 ;1
L 11.5325 4.1325 11.5325 4.1325 24 P 0 ;1
L 11.5325 4.1825 11.5325 4.1825 24 P 0 ;1
L 11.5325 4.2325 11.5325 4.2325 24 P 0 ;1
L 11.5325 4.2825 11.5325 4.2825 24 P 0 ;1
L 11.5325 4.3325 11.5325 4.3325 24 P 0 ;1
L 11.5325 4.3825 11.5325 4.3825 24 P 0 ;1
L 11.5325 4.4325 11.5325 4.4325 24 P 0 ;1
L 11.5325 4.4825 11.5325 4.4825 24 P 0 ;1
L 11.5325 4.5325 11.5325 4.5325 24 P 0 ;1
L 11.5325 4.5825 11.5325 4.5825 24 P 0 ;1
L 11.5325 4.6325 11.5325 4.6325 24 P 0 ;1
L 11.5325 4.6825 11.5325 4.6825 24 P 0 ;1
L 11.5825 0.1325 11.5825 0.1325 24 P 0 ;1
L 11.5825 0.1825 11.5825 0.1825 24 P 0 ;1
L 11.5825 0.2325 11.5825 0.2325 24 P 0 ;1
L 11.5825 0.2825 11.5825 0.2825 24 P 0 ;1
L 11.5825 0.3325 11.5825 0.3325 24 P 0 ;1
L 11.5825 0.3825 11.5825 0.3825 24 P 0 ;1
L 11.5825 0.4325 11.5825 0.4325 24 P 0 ;1
L 11.5825 0.4825 11.5825 0.4825 24 P 0 ;1
L 11.5825 0.5325 11.5825 0.5325 24 P 0 ;1
L 11.5825 0.5825 11.5825 0.5825 24 P 0 ;1
L 11.5825 0.6325 11.5825 0.6325 24 P 0 ;1
L 11.5825 0.6825 11.5825 0.6825 24 P 0 ;1
L 11.5825 0.7325 11.5825 0.7325 24 P 0 ;1
L 11.5825 0.7825 11.5825 0.7825 24 P 0 ;1
L 11.5825 0.8325 11.5825 0.8325 24 P 0 ;1
L 11.5825 0.8825 11.5825 0.8825 24 P 0 ;1
L 11.5825 0.9325 11.5825 0.9325 24 P 0 ;1
L 11.5825 0.9825 11.5825 0.9825 24 P 0 ;1
L 11.5825 1.0325 11.5825 1.0325 24 P 0 ;1
L 11.5825 1.0825 11.5825 1.0825 24 P 0 ;1
L 11.5825 1.1325 11.5825 1.1325 24 P 0 ;1
L 11.5825 1.1825 11.5825 1.1825 24 P 0 ;1
L 11.5825 1.2325 11.5825 1.2325 24 P 0 ;1
L 11.5825 3.0825 11.5825 3.0825 24 P 0 ;1
L 11.5825 3.1325 11.5825 3.1325 24 P 0 ;1
L 11.5825 3.1825 11.5825 3.1825 24 P 0 ;1
L 11.5825 3.2325 11.5825 3.2325 24 P 0 ;1
L 11.5825 3.4325 11.5825 3.4325 24 P 0 ;1
L 11.5825 3.4825 11.5825 3.4825 24 P 0 ;1
L 11.5825 3.5325 11.5825 3.5325 24 P 0 ;1
L 11.5825 3.5825 11.5825 3.5825 24 P 0 ;1
L 11.5825 3.6325 11.5825 3.6325 24 P 0 ;1
L 11.5825 3.6825 11.5825 3.6825 24 P 0 ;1
L 11.5825 3.7325 11.5825 3.7325 24 P 0 ;1
L 11.5825 3.7825 11.5825 3.7825 24 P 0 ;1
L 11.5825 3.8325 11.5825 3.8325 24 P 0 ;1
L 11.5825 3.8825 11.5825 3.8825 24 P 0 ;1
L 11.5825 3.9325 11.5825 3.9325 24 P 0 ;1
L 11.5825 3.9825 11.5825 3.9825 24 P 0 ;1
L 11.5825 4.0325 11.5825 4.0325 24 P 0 ;1
L 11.5825 4.0825 11.5825 4.0825 24 P 0 ;1
L 11.5825 4.1325 11.5825 4.1325 24 P 0 ;1
L 11.5825 4.1825 11.5825 4.1825 24 P 0 ;1
L 11.5825 4.2325 11.5825 4.2325 24 P 0 ;1
L 11.5825 4.2825 11.5825 4.2825 24 P 0 ;1
L 11.5825 4.3325 11.5825 4.3325 24 P 0 ;1
L 11.5825 4.3825 11.5825 4.3825 24 P 0 ;1
L 11.5825 4.4325 11.5825 4.4325 24 P 0 ;1
L 11.5825 4.4825 11.5825 4.4825 24 P 0 ;1
L 11.5825 4.5325 11.5825 4.5325 24 P 0 ;1
L 11.5825 4.5825 11.5825 4.5825 24 P 0 ;1
L 11.5825 4.6325 11.5825 4.6325 24 P 0 ;1
L 11.5825 4.6825 11.5825 4.6825 24 P 0 ;1
L 11.6325 0.1325 11.6325 0.1325 24 P 0 ;1
L 11.6325 0.1825 11.6325 0.1825 24 P 0 ;1
L 11.6325 0.2325 11.6325 0.2325 24 P 0 ;1
L 11.6325 0.2825 11.6325 0.2825 24 P 0 ;1
L 11.6325 0.3325 11.6325 0.3325 24 P 0 ;1
L 11.6325 0.3825 11.6325 0.3825 24 P 0 ;1
L 11.6325 0.4325 11.6325 0.4325 24 P 0 ;1
L 11.6325 0.4825 11.6325 0.4825 24 P 0 ;1
L 11.6325 0.5325 11.6325 0.5325 24 P 0 ;1
L 11.6325 0.5825 11.6325 0.5825 24 P 0 ;1
L 11.6325 0.6325 11.6325 0.6325 24 P 0 ;1
L 11.6325 0.6825 11.6325 0.6825 24 P 0 ;1
L 11.6325 0.7325 11.6325 0.7325 24 P 0 ;1
L 11.6325 0.7825 11.6325 0.7825 24 P 0 ;1
L 11.6325 0.8325 11.6325 0.8325 24 P 0 ;1
L 11.6325 0.8825 11.6325 0.8825 24 P 0 ;1
L 11.6325 0.9325 11.6325 0.9325 24 P 0 ;1
L 11.6325 0.9825 11.6325 0.9825 24 P 0 ;1
L 11.6325 1.0325 11.6325 1.0325 24 P 0 ;1
L 11.6325 1.0825 11.6325 1.0825 24 P 0 ;1
L 11.6325 1.1325 11.6325 1.1325 24 P 0 ;1
L 11.6325 1.1825 11.6325 1.1825 24 P 0 ;1
L 11.6325 1.2325 11.6325 1.2325 24 P 0 ;1
L 11.6325 3.0325 11.6325 3.0325 24 P 0 ;1
L 11.6325 3.0825 11.6325 3.0825 24 P 0 ;1
L 11.6325 3.1325 11.6325 3.1325 24 P 0 ;1
L 11.6325 3.1825 11.6325 3.1825 24 P 0 ;1
L 11.6325 3.2325 11.6325 3.2325 24 P 0 ;1
L 11.6325 3.4325 11.6325 3.4325 24 P 0 ;1
L 11.6325 3.4825 11.6325 3.4825 24 P 0 ;1
L 11.6325 3.5325 11.6325 3.5325 24 P 0 ;1
L 11.6325 3.5825 11.6325 3.5825 24 P 0 ;1
L 11.6325 3.6325 11.6325 3.6325 24 P 0 ;1
L 11.6325 3.6825 11.6325 3.6825 24 P 0 ;1
L 11.6325 3.7325 11.6325 3.7325 24 P 0 ;1
L 11.6325 3.7825 11.6325 3.7825 24 P 0 ;1
L 11.6325 3.8325 11.6325 3.8325 24 P 0 ;1
L 11.6325 3.8825 11.6325 3.8825 24 P 0 ;1
L 11.6325 3.9325 11.6325 3.9325 24 P 0 ;1
L 11.6325 3.9825 11.6325 3.9825 24 P 0 ;1
L 11.6325 4.0325 11.6325 4.0325 24 P 0 ;1
L 11.6325 4.0825 11.6325 4.0825 24 P 0 ;1
L 11.6325 4.1325 11.6325 4.1325 24 P 0 ;1
L 11.6325 4.1825 11.6325 4.1825 24 P 0 ;1
L 11.6325 4.2325 11.6325 4.2325 24 P 0 ;1
L 11.6325 4.2825 11.6325 4.2825 24 P 0 ;1
L 11.6325 4.3325 11.6325 4.3325 24 P 0 ;1
L 11.6325 4.3825 11.6325 4.3825 24 P 0 ;1
L 11.6325 4.4325 11.6325 4.4325 24 P 0 ;1
L 11.6325 4.4825 11.6325 4.4825 24 P 0 ;1
L 11.6325 4.5325 11.6325 4.5325 24 P 0 ;1
L 11.6325 4.5825 11.6325 4.5825 24 P 0 ;1
L 11.6325 4.6325 11.6325 4.6325 24 P 0 ;1
L 11.6325 4.6825 11.6325 4.6825 24 P 0 ;1
L 11.6825 0.1325 11.6825 0.1325 24 P 0 ;1
L 11.6825 0.1825 11.6825 0.1825 24 P 0 ;1
L 11.6825 0.2325 11.6825 0.2325 24 P 0 ;1
L 11.6825 0.2825 11.6825 0.2825 24 P 0 ;1
L 11.6825 0.3325 11.6825 0.3325 24 P 0 ;1
L 11.6825 0.3825 11.6825 0.3825 24 P 0 ;1
L 11.6825 0.4325 11.6825 0.4325 24 P 0 ;1
L 11.6825 0.4825 11.6825 0.4825 24 P 0 ;1
L 11.6825 0.5325 11.6825 0.5325 24 P 0 ;1
L 11.6825 0.5825 11.6825 0.5825 24 P 0 ;1
L 11.6825 0.6325 11.6825 0.6325 24 P 0 ;1
L 11.6825 0.6825 11.6825 0.6825 24 P 0 ;1
L 11.6825 0.7325 11.6825 0.7325 24 P 0 ;1
L 11.6825 0.7825 11.6825 0.7825 24 P 0 ;1
L 11.6825 0.8325 11.6825 0.8325 24 P 0 ;1
L 11.6825 0.8825 11.6825 0.8825 24 P 0 ;1
L 11.6825 0.9325 11.6825 0.9325 24 P 0 ;1
L 11.6825 0.9825 11.6825 0.9825 24 P 0 ;1
L 11.6825 1.0325 11.6825 1.0325 24 P 0 ;1
L 11.6825 1.0825 11.6825 1.0825 24 P 0 ;1
L 11.6825 1.1325 11.6825 1.1325 24 P 0 ;1
L 11.6825 1.1825 11.6825 1.1825 24 P 0 ;1
L 11.6825 1.2325 11.6825 1.2325 24 P 0 ;1
L 11.6825 3.1325 11.6825 3.1325 24 P 0 ;1
L 11.6825 3.1825 11.6825 3.1825 24 P 0 ;1
L 11.6825 3.2325 11.6825 3.2325 24 P 0 ;1
L 11.6825 3.4325 11.6825 3.4325 24 P 0 ;1
L 11.6825 3.4825 11.6825 3.4825 24 P 0 ;1
L 11.6825 3.5325 11.6825 3.5325 24 P 0 ;1
L 11.6825 3.5825 11.6825 3.5825 24 P 0 ;1
L 11.6825 3.6325 11.6825 3.6325 24 P 0 ;1
L 11.6825 3.6825 11.6825 3.6825 24 P 0 ;1
L 11.6825 3.7325 11.6825 3.7325 24 P 0 ;1
L 11.6825 3.7825 11.6825 3.7825 24 P 0 ;1
L 11.6825 3.8325 11.6825 3.8325 24 P 0 ;1
L 11.6825 3.8825 11.6825 3.8825 24 P 0 ;1
L 11.6825 3.9325 11.6825 3.9325 24 P 0 ;1
L 11.6825 3.9825 11.6825 3.9825 24 P 0 ;1
L 11.6825 4.0325 11.6825 4.0325 24 P 0 ;1
L 11.6825 4.0825 11.6825 4.0825 24 P 0 ;1
L 11.6825 4.1325 11.6825 4.1325 24 P 0 ;1
L 11.6825 4.1825 11.6825 4.1825 24 P 0 ;1
L 11.6825 4.2325 11.6825 4.2325 24 P 0 ;1
L 11.6825 4.2825 11.6825 4.2825 24 P 0 ;1
L 11.6825 4.3325 11.6825 4.3325 24 P 0 ;1
L 11.6825 4.3825 11.6825 4.3825 24 P 0 ;1
L 11.6825 4.4325 11.6825 4.4325 24 P 0 ;1
L 11.6825 4.4825 11.6825 4.4825 24 P 0 ;1
L 11.6825 4.5325 11.6825 4.5325 24 P 0 ;1
L 11.6825 4.5825 11.6825 4.5825 24 P 0 ;1
L 11.6825 4.6325 11.6825 4.6325 24 P 0 ;1
L 11.6825 4.6825 11.6825 4.6825 24 P 0 ;1
L 11.7325 0.1325 11.7325 0.1325 24 P 0 ;1
L 11.7325 0.1825 11.7325 0.1825 24 P 0 ;1
L 11.7325 0.2325 11.7325 0.2325 24 P 0 ;1
L 11.7325 0.2825 11.7325 0.2825 24 P 0 ;1
L 11.7325 0.3325 11.7325 0.3325 24 P 0 ;1
L 11.7325 0.3825 11.7325 0.3825 24 P 0 ;1
L 11.7325 0.4325 11.7325 0.4325 24 P 0 ;1
L 11.7325 0.4825 11.7325 0.4825 24 P 0 ;1
L 11.7325 0.5325 11.7325 0.5325 24 P 0 ;1
L 11.7325 0.5825 11.7325 0.5825 24 P 0 ;1
L 11.7325 0.6325 11.7325 0.6325 24 P 0 ;1
L 11.7325 0.6825 11.7325 0.6825 24 P 0 ;1
L 11.7325 0.7325 11.7325 0.7325 24 P 0 ;1
L 11.7325 0.7825 11.7325 0.7825 24 P 0 ;1
L 11.7325 0.8325 11.7325 0.8325 24 P 0 ;1
L 11.7325 0.8825 11.7325 0.8825 24 P 0 ;1
L 11.7325 0.9325 11.7325 0.9325 24 P 0 ;1
L 11.7325 0.9825 11.7325 0.9825 24 P 0 ;1
L 11.7325 1.0325 11.7325 1.0325 24 P 0 ;1
L 11.7325 1.0825 11.7325 1.0825 24 P 0 ;1
L 11.7325 1.1325 11.7325 1.1325 24 P 0 ;1
L 11.7325 1.1825 11.7325 1.1825 24 P 0 ;1
L 11.7325 1.2325 11.7325 1.2325 24 P 0 ;1
L 11.7325 3.1825 11.7325 3.1825 24 P 0 ;1
L 11.7325 3.2325 11.7325 3.2325 24 P 0 ;1
L 11.7325 3.4325 11.7325 3.4325 24 P 0 ;1
L 11.7325 3.4825 11.7325 3.4825 24 P 0 ;1
L 11.7325 3.5325 11.7325 3.5325 24 P 0 ;1
L 11.7325 3.5825 11.7325 3.5825 24 P 0 ;1
L 11.7325 3.6325 11.7325 3.6325 24 P 0 ;1
L 11.7325 3.6825 11.7325 3.6825 24 P 0 ;1
L 11.7325 3.7325 11.7325 3.7325 24 P 0 ;1
L 11.7325 3.7825 11.7325 3.7825 24 P 0 ;1
L 11.7325 3.8325 11.7325 3.8325 24 P 0 ;1
L 11.7325 3.8825 11.7325 3.8825 24 P 0 ;1
L 11.7325 3.9325 11.7325 3.9325 24 P 0 ;1
L 11.7325 3.9825 11.7325 3.9825 24 P 0 ;1
L 11.7325 4.0325 11.7325 4.0325 24 P 0 ;1
L 11.7325 4.0825 11.7325 4.0825 24 P 0 ;1
L 11.7325 4.1325 11.7325 4.1325 24 P 0 ;1
L 11.7325 4.1825 11.7325 4.1825 24 P 0 ;1
L 11.7325 4.2325 11.7325 4.2325 24 P 0 ;1
L 11.7325 4.2825 11.7325 4.2825 24 P 0 ;1
L 11.7325 4.3325 11.7325 4.3325 24 P 0 ;1
L 11.7325 4.3825 11.7325 4.3825 24 P 0 ;1
L 11.7325 4.4325 11.7325 4.4325 24 P 0 ;1
L 11.7325 4.4825 11.7325 4.4825 24 P 0 ;1
L 11.7325 4.5325 11.7325 4.5325 24 P 0 ;1
L 11.7325 4.5825 11.7325 4.5825 24 P 0 ;1
L 11.7325 4.6325 11.7325 4.6325 24 P 0 ;1
L 11.7325 4.6825 11.7325 4.6825 24 P 0 ;1
L 11.7825 0.1325 11.7825 0.1325 24 P 0 ;1
L 11.7825 0.1825 11.7825 0.1825 24 P 0 ;1
L 11.7825 0.2325 11.7825 0.2325 24 P 0 ;1
L 11.7825 0.2825 11.7825 0.2825 24 P 0 ;1
L 11.7825 0.3325 11.7825 0.3325 24 P 0 ;1
L 11.7825 0.3825 11.7825 0.3825 24 P 0 ;1
L 11.7825 0.4325 11.7825 0.4325 24 P 0 ;1
L 11.7825 0.4825 11.7825 0.4825 24 P 0 ;1
L 11.7825 0.5325 11.7825 0.5325 24 P 0 ;1
L 11.7825 0.5825 11.7825 0.5825 24 P 0 ;1
L 11.7825 0.6325 11.7825 0.6325 24 P 0 ;1
L 11.7825 0.6825 11.7825 0.6825 24 P 0 ;1
L 11.7825 0.7325 11.7825 0.7325 24 P 0 ;1
L 11.7825 0.7825 11.7825 0.7825 24 P 0 ;1
L 11.7825 0.8325 11.7825 0.8325 24 P 0 ;1
L 11.7825 0.8825 11.7825 0.8825 24 P 0 ;1
L 11.7825 0.9325 11.7825 0.9325 24 P 0 ;1
L 11.7825 0.9825 11.7825 0.9825 24 P 0 ;1
L 11.7825 1.0325 11.7825 1.0325 24 P 0 ;1
L 11.7825 1.0825 11.7825 1.0825 24 P 0 ;1
L 11.7825 1.1325 11.7825 1.1325 24 P 0 ;1
L 11.7825 1.1825 11.7825 1.1825 24 P 0 ;1
L 11.7825 1.2325 11.7825 1.2325 24 P 0 ;1
L 11.7825 1.2825 11.7825 1.2825 24 P 0 ;1
L 11.7825 2.7325 11.7825 2.7325 24 P 0 ;1
L 11.7825 3.2325 11.7825 3.2325 24 P 0 ;1
L 11.7825 3.4325 11.7825 3.4325 24 P 0 ;1
L 11.7825 3.4825 11.7825 3.4825 24 P 0 ;1
L 11.7825 3.5325 11.7825 3.5325 24 P 0 ;1
L 11.7825 3.5825 11.7825 3.5825 24 P 0 ;1
L 11.7825 3.6325 11.7825 3.6325 24 P 0 ;1
L 11.7825 3.6825 11.7825 3.6825 24 P 0 ;1
L 11.7825 3.7325 11.7825 3.7325 24 P 0 ;1
L 11.7825 3.7825 11.7825 3.7825 24 P 0 ;1
L 11.7825 3.8325 11.7825 3.8325 24 P 0 ;1
L 11.7825 3.8825 11.7825 3.8825 24 P 0 ;1
L 11.7825 3.9325 11.7825 3.9325 24 P 0 ;1
L 11.7825 3.9825 11.7825 3.9825 24 P 0 ;1
L 11.7825 4.0325 11.7825 4.0325 24 P 0 ;1
L 11.7825 4.0825 11.7825 4.0825 24 P 0 ;1
L 11.7825 4.1325 11.7825 4.1325 24 P 0 ;1
L 11.7825 4.1825 11.7825 4.1825 24 P 0 ;1
L 11.7825 4.2325 11.7825 4.2325 24 P 0 ;1
L 11.7825 4.2825 11.7825 4.2825 24 P 0 ;1
L 11.7825 4.3325 11.7825 4.3325 24 P 0 ;1
L 11.7825 4.3825 11.7825 4.3825 24 P 0 ;1
L 11.7825 4.5325 11.7825 4.5325 24 P 0 ;1
L 11.7825 4.5825 11.7825 4.5825 24 P 0 ;1
L 11.7825 4.6325 11.7825 4.6325 24 P 0 ;1
L 11.7825 4.6825 11.7825 4.6825 24 P 0 ;1
L 11.8325 0.1325 11.8325 0.1325 24 P 0 ;1
L 11.8325 0.1825 11.8325 0.1825 24 P 0 ;1
L 11.8325 0.2325 11.8325 0.2325 24 P 0 ;1
L 11.8325 0.2825 11.8325 0.2825 24 P 0 ;1
L 11.8325 0.3325 11.8325 0.3325 24 P 0 ;1
L 11.8325 0.3825 11.8325 0.3825 24 P 0 ;1
L 11.8325 0.4325 11.8325 0.4325 24 P 0 ;1
L 11.8325 0.4825 11.8325 0.4825 24 P 0 ;1
L 11.8325 0.5325 11.8325 0.5325 24 P 0 ;1
L 11.8325 0.5825 11.8325 0.5825 24 P 0 ;1
L 11.8325 0.6325 11.8325 0.6325 24 P 0 ;1
L 11.8325 0.6825 11.8325 0.6825 24 P 0 ;1
L 11.8325 0.7325 11.8325 0.7325 24 P 0 ;1
L 11.8325 0.7825 11.8325 0.7825 24 P 0 ;1
L 11.8325 0.8325 11.8325 0.8325 24 P 0 ;1
L 11.8325 0.8825 11.8325 0.8825 24 P 0 ;1
L 11.8325 0.9325 11.8325 0.9325 24 P 0 ;1
L 11.8325 0.9825 11.8325 0.9825 24 P 0 ;1
L 11.8325 1.0325 11.8325 1.0325 24 P 0 ;1
L 11.8325 1.0825 11.8325 1.0825 24 P 0 ;1
L 11.8325 1.1325 11.8325 1.1325 24 P 0 ;1
L 11.8325 1.1825 11.8325 1.1825 24 P 0 ;1
L 11.8325 1.2325 11.8325 1.2325 24 P 0 ;1
L 11.8325 1.2825 11.8325 1.2825 24 P 0 ;1
L 11.8325 1.3325 11.8325 1.3325 24 P 0 ;1
L 11.8325 1.7825 11.8325 1.7825 24 P 0 ;1
L 11.8325 1.8325 11.8325 1.8325 24 P 0 ;1
L 11.8325 1.8825 11.8325 1.8825 24 P 0 ;1
L 11.8325 1.9325 11.8325 1.9325 24 P 0 ;1
L 11.8325 1.9825 11.8325 1.9825 24 P 0 ;1
L 11.8325 2.0325 11.8325 2.0325 24 P 0 ;1
L 11.8325 2.0825 11.8325 2.0825 24 P 0 ;1
L 11.8325 2.3825 11.8325 2.3825 24 P 0 ;1
L 11.8325 2.4325 11.8325 2.4325 24 P 0 ;1
L 11.8325 2.4825 11.8325 2.4825 24 P 0 ;1
L 11.8325 2.5325 11.8325 2.5325 24 P 0 ;1
L 11.8325 2.5825 11.8325 2.5825 24 P 0 ;1
L 11.8325 2.6325 11.8325 2.6325 24 P 0 ;1
L 11.8325 2.6825 11.8325 2.6825 24 P 0 ;1
L 11.8325 2.7325 11.8325 2.7325 24 P 0 ;1
L 11.8325 3.4325 11.8325 3.4325 24 P 0 ;1
L 11.8325 3.4825 11.8325 3.4825 24 P 0 ;1
L 11.8325 3.5325 11.8325 3.5325 24 P 0 ;1
L 11.8325 3.5825 11.8325 3.5825 24 P 0 ;1
L 11.8325 3.6325 11.8325 3.6325 24 P 0 ;1
L 11.8325 3.6825 11.8325 3.6825 24 P 0 ;1
L 11.8325 3.7325 11.8325 3.7325 24 P 0 ;1
L 11.8325 3.7825 11.8325 3.7825 24 P 0 ;1
L 11.8325 3.8325 11.8325 3.8325 24 P 0 ;1
L 11.8325 3.8825 11.8325 3.8825 24 P 0 ;1
L 11.8325 3.9325 11.8325 3.9325 24 P 0 ;1
L 11.8325 3.9825 11.8325 3.9825 24 P 0 ;1
L 11.8325 4.0325 11.8325 4.0325 24 P 0 ;1
L 11.8325 4.0825 11.8325 4.0825 24 P 0 ;1
L 11.8325 4.1325 11.8325 4.1325 24 P 0 ;1
L 11.8325 4.1825 11.8325 4.1825 24 P 0 ;1
L 11.8325 4.2325 11.8325 4.2325 24 P 0 ;1
L 11.8325 4.2825 11.8325 4.2825 24 P 0 ;1
L 11.8325 4.3325 11.8325 4.3325 24 P 0 ;1
L 11.8325 4.5825 11.8325 4.5825 24 P 0 ;1
L 11.8325 4.6325 11.8325 4.6325 24 P 0 ;1
L 11.8325 4.6825 11.8325 4.6825 24 P 0 ;1
L 11.8825 0.1325 11.8825 0.1325 24 P 0 ;1
L 11.8825 0.4325 11.8825 0.4325 24 P 0 ;1
L 11.8825 0.4825 11.8825 0.4825 24 P 0 ;1
L 11.8825 0.5325 11.8825 0.5325 24 P 0 ;1
L 11.8825 0.5825 11.8825 0.5825 24 P 0 ;1
L 11.8825 0.6325 11.8825 0.6325 24 P 0 ;1
L 11.8825 0.6825 11.8825 0.6825 24 P 0 ;1
L 11.8825 0.7325 11.8825 0.7325 24 P 0 ;1
L 11.8825 0.7825 11.8825 0.7825 24 P 0 ;1
L 11.8825 0.8325 11.8825 0.8325 24 P 0 ;1
L 11.8825 0.8825 11.8825 0.8825 24 P 0 ;1
L 11.8825 0.9325 11.8825 0.9325 24 P 0 ;1
L 11.8825 0.9825 11.8825 0.9825 24 P 0 ;1
L 11.8825 1.0325 11.8825 1.0325 24 P 0 ;1
L 11.8825 1.0825 11.8825 1.0825 24 P 0 ;1
L 11.8825 1.1325 11.8825 1.1325 24 P 0 ;1
L 11.8825 1.1825 11.8825 1.1825 24 P 0 ;1
L 11.8825 1.2325 11.8825 1.2325 24 P 0 ;1
L 11.8825 1.2825 11.8825 1.2825 24 P 0 ;1
L 11.8825 1.3325 11.8825 1.3325 24 P 0 ;1
L 11.8825 1.3825 11.8825 1.3825 24 P 0 ;1
L 11.8825 1.8325 11.8825 1.8325 24 P 0 ;1
L 11.8825 1.8825 11.8825 1.8825 24 P 0 ;1
L 11.8825 1.9325 11.8825 1.9325 24 P 0 ;1
L 11.8825 1.9825 11.8825 1.9825 24 P 0 ;1
L 11.8825 2.0325 11.8825 2.0325 24 P 0 ;1
L 11.8825 2.0825 11.8825 2.0825 24 P 0 ;1
L 11.8825 2.3325 11.8825 2.3325 24 P 0 ;1
L 11.8825 2.3825 11.8825 2.3825 24 P 0 ;1
L 11.8825 2.4325 11.8825 2.4325 24 P 0 ;1
L 11.8825 2.4825 11.8825 2.4825 24 P 0 ;1
L 11.8825 2.5325 11.8825 2.5325 24 P 0 ;1
L 11.8825 2.5825 11.8825 2.5825 24 P 0 ;1
L 11.8825 2.6325 11.8825 2.6325 24 P 0 ;1
L 11.8825 2.6825 11.8825 2.6825 24 P 0 ;1
L 11.8825 2.7325 11.8825 2.7325 24 P 0 ;1
L 11.8825 3.0325 11.8825 3.0325 24 P 0 ;1
L 11.8825 3.4325 11.8825 3.4325 24 P 0 ;1
L 11.8825 3.4825 11.8825 3.4825 24 P 0 ;1
L 11.8825 3.5325 11.8825 3.5325 24 P 0 ;1
L 11.8825 3.5825 11.8825 3.5825 24 P 0 ;1
L 11.8825 3.6325 11.8825 3.6325 24 P 0 ;1
L 11.8825 3.6825 11.8825 3.6825 24 P 0 ;1
L 11.8825 3.7325 11.8825 3.7325 24 P 0 ;1
L 11.8825 3.7825 11.8825 3.7825 24 P 0 ;1
L 11.8825 3.8325 11.8825 3.8325 24 P 0 ;1
L 11.8825 3.8825 11.8825 3.8825 24 P 0 ;1
L 11.8825 3.9325 11.8825 3.9325 24 P 0 ;1
L 11.8825 3.9825 11.8825 3.9825 24 P 0 ;1
L 11.8825 4.0325 11.8825 4.0325 24 P 0 ;1
L 11.8825 4.0825 11.8825 4.0825 24 P 0 ;1
L 11.8825 4.1325 11.8825 4.1325 24 P 0 ;1
L 11.8825 4.1825 11.8825 4.1825 24 P 0 ;1
L 11.8825 4.2325 11.8825 4.2325 24 P 0 ;1
L 11.8825 4.2825 11.8825 4.2825 24 P 0 ;1
L 11.8825 4.3325 11.8825 4.3325 24 P 0 ;1
L 11.8825 4.5825 11.8825 4.5825 24 P 0 ;1
L 11.8825 4.6325 11.8825 4.6325 24 P 0 ;1
L 11.8825 4.6825 11.8825 4.6825 24 P 0 ;1
L 11.9325 0.1325 11.9325 0.1325 24 P 0 ;1
L 11.9325 0.4825 11.9325 0.4825 24 P 0 ;1
L 11.9325 0.5325 11.9325 0.5325 24 P 0 ;1
L 11.9325 0.5825 11.9325 0.5825 24 P 0 ;1
L 11.9325 0.6325 11.9325 0.6325 24 P 0 ;1
L 11.9325 0.6825 11.9325 0.6825 24 P 0 ;1
L 11.9325 0.7325 11.9325 0.7325 24 P 0 ;1
L 11.9325 0.7825 11.9325 0.7825 24 P 0 ;1
L 11.9325 0.8325 11.9325 0.8325 24 P 0 ;1
L 11.9325 0.8825 11.9325 0.8825 24 P 0 ;1
L 11.9325 0.9325 11.9325 0.9325 24 P 0 ;1
L 11.9325 0.9825 11.9325 0.9825 24 P 0 ;1
L 11.9325 1.0325 11.9325 1.0325 24 P 0 ;1
L 11.9325 1.0825 11.9325 1.0825 24 P 0 ;1
L 11.9325 1.1325 11.9325 1.1325 24 P 0 ;1
L 11.9325 1.1825 11.9325 1.1825 24 P 0 ;1
L 11.9325 1.2325 11.9325 1.2325 24 P 0 ;1
L 11.9325 1.2825 11.9325 1.2825 24 P 0 ;1
L 11.9325 1.3325 11.9325 1.3325 24 P 0 ;1
L 11.9325 1.8825 11.9325 1.8825 24 P 0 ;1
L 11.9325 1.9325 11.9325 1.9325 24 P 0 ;1
L 11.9325 1.9825 11.9325 1.9825 24 P 0 ;1
L 11.9325 2.0325 11.9325 2.0325 24 P 0 ;1
L 11.9325 2.0825 11.9325 2.0825 24 P 0 ;1
L 11.9325 2.1325 11.9325 2.1325 24 P 0 ;1
L 11.9325 2.1825 11.9325 2.1825 24 P 0 ;1
L 11.9325 2.2325 11.9325 2.2325 24 P 0 ;1
L 11.9325 2.2825 11.9325 2.2825 24 P 0 ;1
L 11.9325 2.3325 11.9325 2.3325 24 P 0 ;1
L 11.9325 2.3825 11.9325 2.3825 24 P 0 ;1
L 11.9325 2.4325 11.9325 2.4325 24 P 0 ;1
L 11.9325 2.4825 11.9325 2.4825 24 P 0 ;1
L 11.9325 2.6825 11.9325 2.6825 24 P 0 ;1
L 11.9325 2.7325 11.9325 2.7325 24 P 0 ;1
L 11.9325 2.7825 11.9325 2.7825 24 P 0 ;1
L 11.9325 2.9825 11.9325 2.9825 24 P 0 ;1
L 11.9325 3.0325 11.9325 3.0325 24 P 0 ;1
L 11.9325 3.0825 11.9325 3.0825 24 P 0 ;1
L 11.9325 3.4325 11.9325 3.4325 24 P 0 ;1
L 11.9325 3.4825 11.9325 3.4825 24 P 0 ;1
L 11.9325 3.5325 11.9325 3.5325 24 P 0 ;1
L 11.9325 3.5825 11.9325 3.5825 24 P 0 ;1
L 11.9325 3.6325 11.9325 3.6325 24 P 0 ;1
L 11.9325 3.6825 11.9325 3.6825 24 P 0 ;1
L 11.9325 3.7325 11.9325 3.7325 24 P 0 ;1
L 11.9325 3.7825 11.9325 3.7825 24 P 0 ;1
L 11.9325 3.8325 11.9325 3.8325 24 P 0 ;1
L 11.9325 3.8825 11.9325 3.8825 24 P 0 ;1
L 11.9325 3.9325 11.9325 3.9325 24 P 0 ;1
L 11.9325 3.9825 11.9325 3.9825 24 P 0 ;1
L 11.9325 4.0325 11.9325 4.0325 24 P 0 ;1
L 11.9325 4.5825 11.9325 4.5825 24 P 0 ;1
L 11.9325 4.6325 11.9325 4.6325 24 P 0 ;1
L 11.9325 4.6825 11.9325 4.6825 24 P 0 ;1
L 11.9825 0.4825 11.9825 0.4825 24 P 0 ;1
L 11.9825 0.5325 11.9825 0.5325 24 P 0 ;1
L 11.9825 0.5825 11.9825 0.5825 24 P 0 ;1
L 11.9825 0.6325 11.9825 0.6325 24 P 0 ;1
L 11.9825 0.6825 11.9825 0.6825 24 P 0 ;1
L 11.9825 0.7325 11.9825 0.7325 24 P 0 ;1
L 11.9825 0.7825 11.9825 0.7825 24 P 0 ;1
L 11.9825 0.8325 11.9825 0.8325 24 P 0 ;1
L 11.9825 0.8825 11.9825 0.8825 24 P 0 ;1
L 11.9825 0.9325 11.9825 0.9325 24 P 0 ;1
L 11.9825 0.9825 11.9825 0.9825 24 P 0 ;1
L 11.9825 1.0325 11.9825 1.0325 24 P 0 ;1
L 11.9825 1.0825 11.9825 1.0825 24 P 0 ;1
L 11.9825 1.1325 11.9825 1.1325 24 P 0 ;1
L 11.9825 1.1825 11.9825 1.1825 24 P 0 ;1
L 11.9825 1.2325 11.9825 1.2325 24 P 0 ;1
L 11.9825 1.2825 11.9825 1.2825 24 P 0 ;1
L 11.9825 1.9825 11.9825 1.9825 24 P 0 ;1
L 11.9825 2.0325 11.9825 2.0325 24 P 0 ;1
L 11.9825 2.0825 11.9825 2.0825 24 P 0 ;1
L 11.9825 2.1325 11.9825 2.1325 24 P 0 ;1
L 11.9825 2.1825 11.9825 2.1825 24 P 0 ;1
L 11.9825 2.2325 11.9825 2.2325 24 P 0 ;1
L 11.9825 2.2825 11.9825 2.2825 24 P 0 ;1
L 11.9825 2.3325 11.9825 2.3325 24 P 0 ;1
L 11.9825 2.3825 11.9825 2.3825 24 P 0 ;1
L 11.9825 2.4325 11.9825 2.4325 24 P 0 ;1
L 11.9825 2.7325 11.9825 2.7325 24 P 0 ;1
L 11.9825 2.7825 11.9825 2.7825 24 P 0 ;1
L 11.9825 2.9825 11.9825 2.9825 24 P 0 ;1
L 11.9825 3.0325 11.9825 3.0325 24 P 0 ;1
L 11.9825 3.0825 11.9825 3.0825 24 P 0 ;1
L 11.9825 3.1325 11.9825 3.1325 24 P 0 ;1
L 11.9825 3.3825 11.9825 3.3825 24 P 0 ;1
L 11.9825 3.4325 11.9825 3.4325 24 P 0 ;1
L 11.9825 3.4825 11.9825 3.4825 24 P 0 ;1
L 11.9825 3.5325 11.9825 3.5325 24 P 0 ;1
L 11.9825 3.5825 11.9825 3.5825 24 P 0 ;1
L 11.9825 3.6325 11.9825 3.6325 24 P 0 ;1
L 11.9825 3.6825 11.9825 3.6825 24 P 0 ;1
L 11.9825 3.7325 11.9825 3.7325 24 P 0 ;1
L 11.9825 3.7825 11.9825 3.7825 24 P 0 ;1
L 11.9825 3.8325 11.9825 3.8325 24 P 0 ;1
L 11.9825 3.8825 11.9825 3.8825 24 P 0 ;1
L 11.9825 3.9325 11.9825 3.9325 24 P 0 ;1
L 11.9825 3.9825 11.9825 3.9825 24 P 0 ;1
L 11.9825 4.5825 11.9825 4.5825 24 P 0 ;1
L 11.9825 4.6325 11.9825 4.6325 24 P 0 ;1
L 11.9825 4.6825 11.9825 4.6825 24 P 0 ;1
L 12.0325 0.4825 12.0325 0.4825 24 P 0 ;1
L 12.0325 0.5325 12.0325 0.5325 24 P 0 ;1
L 12.0325 0.5825 12.0325 0.5825 24 P 0 ;1
L 12.0325 0.6325 12.0325 0.6325 24 P 0 ;1
L 12.0325 0.6825 12.0325 0.6825 24 P 0 ;1
L 12.0325 0.7325 12.0325 0.7325 24 P 0 ;1
L 12.0325 0.7825 12.0325 0.7825 24 P 0 ;1
L 12.0325 0.8325 12.0325 0.8325 24 P 0 ;1
L 12.0325 0.8825 12.0325 0.8825 24 P 0 ;1
L 12.0325 0.9325 12.0325 0.9325 24 P 0 ;1
L 12.0325 0.9825 12.0325 0.9825 24 P 0 ;1
L 12.0325 1.0325 12.0325 1.0325 24 P 0 ;1
L 12.0325 1.0825 12.0325 1.0825 24 P 0 ;1
L 12.0325 1.1325 12.0325 1.1325 24 P 0 ;1
L 12.0325 1.1825 12.0325 1.1825 24 P 0 ;1
L 12.0325 1.2325 12.0325 1.2325 24 P 0 ;1
L 12.0325 1.2825 12.0325 1.2825 24 P 0 ;1
L 12.0325 2.0325 12.0325 2.0325 24 P 0 ;1
L 12.0325 2.0825 12.0325 2.0825 24 P 0 ;1
L 12.0325 2.1325 12.0325 2.1325 24 P 0 ;1
L 12.0325 2.1825 12.0325 2.1825 24 P 0 ;1
L 12.0325 2.2325 12.0325 2.2325 24 P 0 ;1
L 12.0325 2.2825 12.0325 2.2825 24 P 0 ;1
L 12.0325 2.3325 12.0325 2.3325 24 P 0 ;1
L 12.0325 2.3825 12.0325 2.3825 24 P 0 ;1
L 12.0325 2.7825 12.0325 2.7825 24 P 0 ;1
L 12.0325 2.9825 12.0325 2.9825 24 P 0 ;1
L 12.0325 3.0325 12.0325 3.0325 24 P 0 ;1
L 12.0325 3.0825 12.0325 3.0825 24 P 0 ;1
L 12.0325 3.1325 12.0325 3.1325 24 P 0 ;1
L 12.0325 3.1825 12.0325 3.1825 24 P 0 ;1
L 12.0325 3.2325 12.0325 3.2325 24 P 0 ;1
L 12.0325 3.2825 12.0325 3.2825 24 P 0 ;1
L 12.0325 3.3325 12.0325 3.3325 24 P 0 ;1
L 12.0325 3.3825 12.0325 3.3825 24 P 0 ;1
L 12.0325 3.4325 12.0325 3.4325 24 P 0 ;1
L 12.0325 3.4825 12.0325 3.4825 24 P 0 ;1
L 12.0325 3.5325 12.0325 3.5325 24 P 0 ;1
L 12.0325 3.5825 12.0325 3.5825 24 P 0 ;1
L 12.0325 3.6325 12.0325 3.6325 24 P 0 ;1
L 12.0325 3.6825 12.0325 3.6825 24 P 0 ;1
L 12.0325 3.7325 12.0325 3.7325 24 P 0 ;1
L 12.0325 3.7825 12.0325 3.7825 24 P 0 ;1
L 12.0325 3.8325 12.0325 3.8325 24 P 0 ;1
L 12.0325 3.8825 12.0325 3.8825 24 P 0 ;1
L 12.0325 3.9325 12.0325 3.9325 24 P 0 ;1
L 12.0325 4.5825 12.0325 4.5825 24 P 0 ;1
L 12.0325 4.6325 12.0325 4.6325 24 P 0 ;1
L 12.0325 4.6825 12.0325 4.6825 24 P 0 ;1
L 12.0325 4.7325 12.0325 4.7325 24 P 0 ;1
L 12.0825 0.1325 12.0825 0.1325 24 P 0 ;1
L 12.0825 0.4325 12.0825 0.4325 24 P 0 ;1
L 12.0825 0.4825 12.0825 0.4825 24 P 0 ;1
L 12.0825 0.5325 12.0825 0.5325 24 P 0 ;1
L 12.0825 0.5825 12.0825 0.5825 24 P 0 ;1
L 12.0825 0.6325 12.0825 0.6325 24 P 0 ;1
L 12.0825 0.6825 12.0825 0.6825 24 P 0 ;1
L 12.0825 0.7325 12.0825 0.7325 24 P 0 ;1
L 12.0825 0.7825 12.0825 0.7825 24 P 0 ;1
L 12.0825 0.8325 12.0825 0.8325 24 P 0 ;1
L 12.0825 0.8825 12.0825 0.8825 24 P 0 ;1
L 12.0825 0.9325 12.0825 0.9325 24 P 0 ;1
L 12.0825 0.9825 12.0825 0.9825 24 P 0 ;1
L 12.0825 1.0325 12.0825 1.0325 24 P 0 ;1
L 12.0825 1.0825 12.0825 1.0825 24 P 0 ;1
L 12.0825 1.1325 12.0825 1.1325 24 P 0 ;1
L 12.0825 1.1825 12.0825 1.1825 24 P 0 ;1
L 12.0825 1.2325 12.0825 1.2325 24 P 0 ;1
L 12.0825 1.2825 12.0825 1.2825 24 P 0 ;1
L 12.0825 2.0325 12.0825 2.0325 24 P 0 ;1
L 12.0825 2.0825 12.0825 2.0825 24 P 0 ;1
L 12.0825 2.1325 12.0825 2.1325 24 P 0 ;1
L 12.0825 2.1825 12.0825 2.1825 24 P 0 ;1
L 12.0825 2.2325 12.0825 2.2325 24 P 0 ;1
L 12.0825 2.2825 12.0825 2.2825 24 P 0 ;1
L 12.0825 2.3325 12.0825 2.3325 24 P 0 ;1
L 12.0825 2.3825 12.0825 2.3825 24 P 0 ;1
L 12.0825 2.4325 12.0825 2.4325 24 P 0 ;1
L 12.0825 2.7325 12.0825 2.7325 24 P 0 ;1
L 12.0825 2.7825 12.0825 2.7825 24 P 0 ;1
L 12.0825 2.9825 12.0825 2.9825 24 P 0 ;1
L 12.0825 3.0325 12.0825 3.0325 24 P 0 ;1
L 12.0825 3.0825 12.0825 3.0825 24 P 0 ;1
L 12.0825 3.1325 12.0825 3.1325 24 P 0 ;1
L 12.0825 3.1825 12.0825 3.1825 24 P 0 ;1
L 12.0825 3.2325 12.0825 3.2325 24 P 0 ;1
L 12.0825 3.2825 12.0825 3.2825 24 P 0 ;1
L 12.0825 3.3325 12.0825 3.3325 24 P 0 ;1
L 12.0825 3.3825 12.0825 3.3825 24 P 0 ;1
L 12.0825 3.4325 12.0825 3.4325 24 P 0 ;1
L 12.0825 3.4825 12.0825 3.4825 24 P 0 ;1
L 12.0825 3.5325 12.0825 3.5325 24 P 0 ;1
L 12.0825 3.5825 12.0825 3.5825 24 P 0 ;1
L 12.0825 3.6325 12.0825 3.6325 24 P 0 ;1
L 12.0825 3.6825 12.0825 3.6825 24 P 0 ;1
L 12.0825 3.7325 12.0825 3.7325 24 P 0 ;1
L 12.0825 3.7825 12.0825 3.7825 24 P 0 ;1
L 12.0825 3.8325 12.0825 3.8325 24 P 0 ;1
L 12.0825 3.8825 12.0825 3.8825 24 P 0 ;1
L 12.0825 3.9325 12.0825 3.9325 24 P 0 ;1
L 12.0825 4.5825 12.0825 4.5825 24 P 0 ;1
L 12.0825 4.6325 12.0825 4.6325 24 P 0 ;1
L 12.0825 4.6825 12.0825 4.6825 24 P 0 ;1
L 12.0825 4.7325 12.0825 4.7325 24 P 0 ;1
L 12.0825 4.7825 12.0825 4.7825 24 P 0 ;1
L 12.1325 0.1325 12.1325 0.1325 24 P 0 ;1
L 12.1325 0.1825 12.1325 0.1825 24 P 0 ;1
L 12.1325 0.3825 12.1325 0.3825 24 P 0 ;1
L 12.1325 0.4325 12.1325 0.4325 24 P 0 ;1
L 12.1325 0.4825 12.1325 0.4825 24 P 0 ;1
L 12.1325 0.5325 12.1325 0.5325 24 P 0 ;1
L 12.1325 0.5825 12.1325 0.5825 24 P 0 ;1
L 12.1325 0.6325 12.1325 0.6325 24 P 0 ;1
L 12.1325 0.6825 12.1325 0.6825 24 P 0 ;1
L 12.1325 0.7325 12.1325 0.7325 24 P 0 ;1
L 12.1325 0.7825 12.1325 0.7825 24 P 0 ;1
L 12.1325 0.8325 12.1325 0.8325 24 P 0 ;1
L 12.1325 0.8825 12.1325 0.8825 24 P 0 ;1
L 12.1325 0.9325 12.1325 0.9325 24 P 0 ;1
L 12.1325 0.9825 12.1325 0.9825 24 P 0 ;1
L 12.1325 1.0325 12.1325 1.0325 24 P 0 ;1
L 12.1325 1.0825 12.1325 1.0825 24 P 0 ;1
L 12.1325 1.1325 12.1325 1.1325 24 P 0 ;1
L 12.1325 1.1825 12.1325 1.1825 24 P 0 ;1
L 12.1325 1.2325 12.1325 1.2325 24 P 0 ;1
L 12.1325 1.2825 12.1325 1.2825 24 P 0 ;1
L 12.1325 1.7825 12.1325 1.7825 24 P 0 ;1
L 12.1325 2.0825 12.1325 2.0825 24 P 0 ;1
L 12.1325 2.9825 12.1325 2.9825 24 P 0 ;1
L 12.1325 3.0325 12.1325 3.0325 24 P 0 ;1
L 12.1325 3.0825 12.1325 3.0825 24 P 0 ;1
L 12.1325 3.1325 12.1325 3.1325 24 P 0 ;1
L 12.1325 3.1825 12.1325 3.1825 24 P 0 ;1
L 12.1325 3.2325 12.1325 3.2325 24 P 0 ;1
L 12.1325 3.2825 12.1325 3.2825 24 P 0 ;1
L 12.1325 3.3325 12.1325 3.3325 24 P 0 ;1
L 12.1325 3.3825 12.1325 3.3825 24 P 0 ;1
L 12.1325 3.4325 12.1325 3.4325 24 P 0 ;1
L 12.1325 3.4825 12.1325 3.4825 24 P 0 ;1
L 12.1325 3.5325 12.1325 3.5325 24 P 0 ;1
L 12.1325 3.5825 12.1325 3.5825 24 P 0 ;1
L 12.1325 3.6325 12.1325 3.6325 24 P 0 ;1
L 12.1325 3.6825 12.1325 3.6825 24 P 0 ;1
L 12.1325 3.7325 12.1325 3.7325 24 P 0 ;1
L 12.1325 3.7825 12.1325 3.7825 24 P 0 ;1
L 12.1325 3.8325 12.1325 3.8325 24 P 0 ;1
L 12.1325 3.8825 12.1325 3.8825 24 P 0 ;1
L 12.1325 3.9325 12.1325 3.9325 24 P 0 ;1
L 12.1325 4.5825 12.1325 4.5825 24 P 0 ;1
L 12.1325 4.6325 12.1325 4.6325 24 P 0 ;1
L 12.1325 4.6825 12.1325 4.6825 24 P 0 ;1
L 12.1325 4.7325 12.1325 4.7325 24 P 0 ;1
L 12.1325 4.7825 12.1325 4.7825 24 P 0 ;1
L 12.1325 4.8325 12.1325 4.8325 24 P 0 ;1
L 12.1825 0.1325 12.1825 0.1325 24 P 0 ;1
L 12.1825 0.4325 12.1825 0.4325 24 P 0 ;1
L 12.1825 0.4825 12.1825 0.4825 24 P 0 ;1
L 12.1825 0.5325 12.1825 0.5325 24 P 0 ;1
L 12.1825 0.5825 12.1825 0.5825 24 P 0 ;1
L 12.1825 0.6325 12.1825 0.6325 24 P 0 ;1
L 12.1825 0.6825 12.1825 0.6825 24 P 0 ;1
L 12.1825 0.7325 12.1825 0.7325 24 P 0 ;1
L 12.1825 0.7825 12.1825 0.7825 24 P 0 ;1
L 12.1825 0.8325 12.1825 0.8325 24 P 0 ;1
L 12.1825 0.8825 12.1825 0.8825 24 P 0 ;1
L 12.1825 0.9325 12.1825 0.9325 24 P 0 ;1
L 12.1825 0.9825 12.1825 0.9825 24 P 0 ;1
L 12.1825 1.0325 12.1825 1.0325 24 P 0 ;1
L 12.1825 1.0825 12.1825 1.0825 24 P 0 ;1
L 12.1825 1.1325 12.1825 1.1325 24 P 0 ;1
L 12.1825 1.1825 12.1825 1.1825 24 P 0 ;1
L 12.1825 1.2325 12.1825 1.2325 24 P 0 ;1
L 12.1825 1.2825 12.1825 1.2825 24 P 0 ;1
L 12.1825 1.7825 12.1825 1.7825 24 P 0 ;1
L 12.1825 1.8325 12.1825 1.8325 24 P 0 ;1
L 12.1825 2.9825 12.1825 2.9825 24 P 0 ;1
L 12.1825 3.0325 12.1825 3.0325 24 P 0 ;1
L 12.1825 3.0825 12.1825 3.0825 24 P 0 ;1
L 12.1825 3.1325 12.1825 3.1325 24 P 0 ;1
L 12.1825 3.1825 12.1825 3.1825 24 P 0 ;1
L 12.1825 3.2325 12.1825 3.2325 24 P 0 ;1
L 12.1825 3.2825 12.1825 3.2825 24 P 0 ;1
L 12.1825 3.3325 12.1825 3.3325 24 P 0 ;1
L 12.1825 3.3825 12.1825 3.3825 24 P 0 ;1
L 12.1825 3.4325 12.1825 3.4325 24 P 0 ;1
L 12.1825 3.4825 12.1825 3.4825 24 P 0 ;1
L 12.1825 3.5325 12.1825 3.5325 24 P 0 ;1
L 12.1825 3.5825 12.1825 3.5825 24 P 0 ;1
L 12.1825 3.6325 12.1825 3.6325 24 P 0 ;1
L 12.1825 3.6825 12.1825 3.6825 24 P 0 ;1
L 12.1825 3.7325 12.1825 3.7325 24 P 0 ;1
L 12.1825 3.7825 12.1825 3.7825 24 P 0 ;1
L 12.1825 3.8325 12.1825 3.8325 24 P 0 ;1
L 12.1825 3.8825 12.1825 3.8825 24 P 0 ;1
L 12.1825 3.9325 12.1825 3.9325 24 P 0 ;1
L 12.2325 0.1325 12.2325 0.1325 24 P 0 ;1
L 12.2325 0.4325 12.2325 0.4325 24 P 0 ;1
L 12.2325 0.4825 12.2325 0.4825 24 P 0 ;1
L 12.2325 0.5325 12.2325 0.5325 24 P 0 ;1
L 12.2325 0.5825 12.2325 0.5825 24 P 0 ;1
L 12.2325 0.6325 12.2325 0.6325 24 P 0 ;1
L 12.2325 0.6825 12.2325 0.6825 24 P 0 ;1
L 12.2325 0.7325 12.2325 0.7325 24 P 0 ;1
L 12.2325 0.7825 12.2325 0.7825 24 P 0 ;1
L 12.2325 0.8325 12.2325 0.8325 24 P 0 ;1
L 12.2325 0.8825 12.2325 0.8825 24 P 0 ;1
L 12.2325 0.9325 12.2325 0.9325 24 P 0 ;1
L 12.2325 0.9825 12.2325 0.9825 24 P 0 ;1
L 12.2325 1.0325 12.2325 1.0325 24 P 0 ;1
L 12.2325 1.0825 12.2325 1.0825 24 P 0 ;1
L 12.2325 1.1325 12.2325 1.1325 24 P 0 ;1
L 12.2325 1.1825 12.2325 1.1825 24 P 0 ;1
L 12.2325 1.2325 12.2325 1.2325 24 P 0 ;1
L 12.2325 1.2825 12.2325 1.2825 24 P 0 ;1
L 12.2325 1.7825 12.2325 1.7825 24 P 0 ;1
L 12.2325 1.8325 12.2325 1.8325 24 P 0 ;1
L 12.2325 2.9325 12.2325 2.9325 24 P 0 ;1
L 12.2325 2.9825 12.2325 2.9825 24 P 0 ;1
L 12.2325 3.0325 12.2325 3.0325 24 P 0 ;1
L 12.2325 3.0825 12.2325 3.0825 24 P 0 ;1
L 12.2325 3.1325 12.2325 3.1325 24 P 0 ;1
L 12.2325 3.1825 12.2325 3.1825 24 P 0 ;1
L 12.2325 3.2325 12.2325 3.2325 24 P 0 ;1
L 12.2325 3.2825 12.2325 3.2825 24 P 0 ;1
L 12.2325 3.3325 12.2325 3.3325 24 P 0 ;1
L 12.2325 3.3825 12.2325 3.3825 24 P 0 ;1
L 12.2325 3.4325 12.2325 3.4325 24 P 0 ;1
L 12.2325 3.4825 12.2325 3.4825 24 P 0 ;1
L 12.2325 3.5325 12.2325 3.5325 24 P 0 ;1
L 12.2325 3.5825 12.2325 3.5825 24 P 0 ;1
L 12.2325 3.6325 12.2325 3.6325 24 P 0 ;1
L 12.2325 3.6825 12.2325 3.6825 24 P 0 ;1
L 12.2325 3.7325 12.2325 3.7325 24 P 0 ;1
L 12.2325 3.7825 12.2325 3.7825 24 P 0 ;1
L 12.2325 3.8325 12.2325 3.8325 24 P 0 ;1
L 12.2325 3.8825 12.2325 3.8825 24 P 0 ;1
L 12.2325 3.9325 12.2325 3.9325 24 P 0 ;1
L 12.2325 3.9825 12.2325 3.9825 24 P 0 ;1
L 12.2825 0.1325 12.2825 0.1325 24 P 0 ;1
L 12.2825 0.4825 12.2825 0.4825 24 P 0 ;1
L 12.2825 0.5325 12.2825 0.5325 24 P 0 ;1
L 12.2825 0.5825 12.2825 0.5825 24 P 0 ;1
L 12.2825 0.6325 12.2825 0.6325 24 P 0 ;1
L 12.2825 0.6825 12.2825 0.6825 24 P 0 ;1
L 12.2825 0.7325 12.2825 0.7325 24 P 0 ;1
L 12.2825 0.7825 12.2825 0.7825 24 P 0 ;1
L 12.2825 0.8325 12.2825 0.8325 24 P 0 ;1
L 12.2825 0.8825 12.2825 0.8825 24 P 0 ;1
L 12.2825 0.9325 12.2825 0.9325 24 P 0 ;1
L 12.2825 0.9825 12.2825 0.9825 24 P 0 ;1
L 12.2825 1.0325 12.2825 1.0325 24 P 0 ;1
L 12.2825 1.0825 12.2825 1.0825 24 P 0 ;1
L 12.2825 1.1325 12.2825 1.1325 24 P 0 ;1
L 12.2825 1.1825 12.2825 1.1825 24 P 0 ;1
L 12.2825 1.7325 12.2825 1.7325 24 P 0 ;1
L 12.2825 1.7825 12.2825 1.7825 24 P 0 ;1
L 12.2825 1.8325 12.2825 1.8325 24 P 0 ;1
L 12.2825 2.2825 12.2825 2.2825 24 P 0 ;1
L 12.2825 2.3325 12.2825 2.3325 24 P 0 ;1
L 12.2825 2.3825 12.2825 2.3825 24 P 0 ;1
L 12.2825 2.4325 12.2825 2.4325 24 P 0 ;1
L 12.2825 2.4825 12.2825 2.4825 24 P 0 ;1
L 12.2825 2.5325 12.2825 2.5325 24 P 0 ;1
L 12.2825 2.5825 12.2825 2.5825 24 P 0 ;1
L 12.2825 2.6325 12.2825 2.6325 24 P 0 ;1
L 12.2825 2.6825 12.2825 2.6825 24 P 0 ;1
L 12.2825 2.7325 12.2825 2.7325 24 P 0 ;1
L 12.2825 2.7825 12.2825 2.7825 24 P 0 ;1
L 12.2825 2.8325 12.2825 2.8325 24 P 0 ;1
L 12.2825 2.8825 12.2825 2.8825 24 P 0 ;1
L 12.2825 2.9325 12.2825 2.9325 24 P 0 ;1
L 12.2825 2.9825 12.2825 2.9825 24 P 0 ;1
L 12.2825 3.0325 12.2825 3.0325 24 P 0 ;1
L 12.2825 3.0825 12.2825 3.0825 24 P 0 ;1
L 12.2825 3.1325 12.2825 3.1325 24 P 0 ;1
L 12.2825 3.1825 12.2825 3.1825 24 P 0 ;1
L 12.2825 3.2325 12.2825 3.2325 24 P 0 ;1
L 12.2825 3.2825 12.2825 3.2825 24 P 0 ;1
L 12.2825 3.3325 12.2825 3.3325 24 P 0 ;1
L 12.2825 3.3825 12.2825 3.3825 24 P 0 ;1
L 12.2825 3.4325 12.2825 3.4325 24 P 0 ;1
L 12.2825 3.4825 12.2825 3.4825 24 P 0 ;1
L 12.2825 3.5325 12.2825 3.5325 24 P 0 ;1
L 12.2825 3.5825 12.2825 3.5825 24 P 0 ;1
L 12.2825 3.6325 12.2825 3.6325 24 P 0 ;1
L 12.2825 3.6825 12.2825 3.6825 24 P 0 ;1
L 12.2825 3.7325 12.2825 3.7325 24 P 0 ;1
L 12.2825 3.7825 12.2825 3.7825 24 P 0 ;1
L 12.2825 3.8325 12.2825 3.8325 24 P 0 ;1
L 12.2825 3.8825 12.2825 3.8825 24 P 0 ;1
L 12.2825 3.9325 12.2825 3.9325 24 P 0 ;1
L 12.2825 3.9825 12.2825 3.9825 24 P 0 ;1
L 12.3325 0.1325 12.3325 0.1325 24 P 0 ;1
L 12.3325 0.4325 12.3325 0.4325 24 P 0 ;1
L 12.3325 0.4825 12.3325 0.4825 24 P 0 ;1
L 12.3325 0.5325 12.3325 0.5325 24 P 0 ;1
L 12.3325 0.5825 12.3325 0.5825 24 P 0 ;1
L 12.3325 0.6325 12.3325 0.6325 24 P 0 ;1
L 12.3325 0.6825 12.3325 0.6825 24 P 0 ;1
L 12.3325 0.7325 12.3325 0.7325 24 P 0 ;1
L 12.3325 0.7825 12.3325 0.7825 24 P 0 ;1
L 12.3325 0.8325 12.3325 0.8325 24 P 0 ;1
L 12.3325 0.8825 12.3325 0.8825 24 P 0 ;1
L 12.3325 0.9325 12.3325 0.9325 24 P 0 ;1
L 12.3325 0.9825 12.3325 0.9825 24 P 0 ;1
L 12.3325 1.0325 12.3325 1.0325 24 P 0 ;1
L 12.3325 1.0825 12.3325 1.0825 24 P 0 ;1
L 12.3325 1.1325 12.3325 1.1325 24 P 0 ;1
L 12.3325 1.1825 12.3325 1.1825 24 P 0 ;1
L 12.3325 1.6825 12.3325 1.6825 24 P 0 ;1
L 12.3325 1.7325 12.3325 1.7325 24 P 0 ;1
L 12.3325 1.7825 12.3325 1.7825 24 P 0 ;1
L 12.3325 1.8325 12.3325 1.8325 24 P 0 ;1
L 12.3325 2.3325 12.3325 2.3325 24 P 0 ;1
L 12.3325 2.3825 12.3325 2.3825 24 P 0 ;1
L 12.3325 2.4325 12.3325 2.4325 24 P 0 ;1
L 12.3325 2.4825 12.3325 2.4825 24 P 0 ;1
L 12.3325 2.5325 12.3325 2.5325 24 P 0 ;1
L 12.3325 2.5825 12.3325 2.5825 24 P 0 ;1
L 12.3325 2.6325 12.3325 2.6325 24 P 0 ;1
L 12.3325 2.6825 12.3325 2.6825 24 P 0 ;1
L 12.3325 2.7325 12.3325 2.7325 24 P 0 ;1
L 12.3325 2.7825 12.3325 2.7825 24 P 0 ;1
L 12.3325 2.8325 12.3325 2.8325 24 P 0 ;1
L 12.3325 2.8825 12.3325 2.8825 24 P 0 ;1
L 12.3325 2.9325 12.3325 2.9325 24 P 0 ;1
L 12.3325 2.9825 12.3325 2.9825 24 P 0 ;1
L 12.3325 3.0325 12.3325 3.0325 24 P 0 ;1
L 12.3325 3.0825 12.3325 3.0825 24 P 0 ;1
L 12.3325 3.1325 12.3325 3.1325 24 P 0 ;1
L 12.3325 3.1825 12.3325 3.1825 24 P 0 ;1
L 12.3325 3.2325 12.3325 3.2325 24 P 0 ;1
L 12.3325 3.2825 12.3325 3.2825 24 P 0 ;1
L 12.3325 3.3325 12.3325 3.3325 24 P 0 ;1
L 12.3325 3.3825 12.3325 3.3825 24 P 0 ;1
L 12.3325 3.4325 12.3325 3.4325 24 P 0 ;1
L 12.3325 3.4825 12.3325 3.4825 24 P 0 ;1
L 12.3325 3.5325 12.3325 3.5325 24 P 0 ;1
L 12.3325 3.5825 12.3325 3.5825 24 P 0 ;1
L 12.3325 3.6325 12.3325 3.6325 24 P 0 ;1
L 12.3325 3.6825 12.3325 3.6825 24 P 0 ;1
L 12.3325 3.7325 12.3325 3.7325 24 P 0 ;1
L 12.3325 3.7825 12.3325 3.7825 24 P 0 ;1
L 12.3325 3.8325 12.3325 3.8325 24 P 0 ;1
L 12.3325 3.8825 12.3325 3.8825 24 P 0 ;1
L 12.3325 3.9325 12.3325 3.9325 24 P 0 ;1
L 12.3325 3.9825 12.3325 3.9825 24 P 0 ;1
L 12.3325 4.0325 12.3325 4.0325 24 P 0 ;1
L 12.3325 4.0825 12.3325 4.0825 24 P 0 ;1
L 12.3325 4.3325 12.3325 4.3325 24 P 0 ;1
L 12.3325 4.3825 12.3325 4.3825 24 P 0 ;1
L 12.3325 4.4325 12.3325 4.4325 24 P 0 ;1
L 12.3825 0.1325 12.3825 0.1325 24 P 0 ;1
L 12.3825 0.1825 12.3825 0.1825 24 P 0 ;1
L 12.3825 0.4325 12.3825 0.4325 24 P 0 ;1
L 12.3825 0.4825 12.3825 0.4825 24 P 0 ;1
L 12.3825 0.5325 12.3825 0.5325 24 P 0 ;1
L 12.3825 0.5825 12.3825 0.5825 24 P 0 ;1
L 12.3825 0.6325 12.3825 0.6325 24 P 0 ;1
L 12.3825 0.6825 12.3825 0.6825 24 P 0 ;1
L 12.3825 0.7325 12.3825 0.7325 24 P 0 ;1
L 12.3825 0.7825 12.3825 0.7825 24 P 0 ;1
L 12.3825 0.8325 12.3825 0.8325 24 P 0 ;1
L 12.3825 0.8825 12.3825 0.8825 24 P 0 ;1
L 12.3825 0.9325 12.3825 0.9325 24 P 0 ;1
L 12.3825 0.9825 12.3825 0.9825 24 P 0 ;1
L 12.3825 1.0325 12.3825 1.0325 24 P 0 ;1
L 12.3825 1.0825 12.3825 1.0825 24 P 0 ;1
L 12.3825 1.1325 12.3825 1.1325 24 P 0 ;1
L 12.3825 1.1825 12.3825 1.1825 24 P 0 ;1
L 12.3825 1.5325 12.3825 1.5325 24 P 0 ;1
L 12.3825 1.5825 12.3825 1.5825 24 P 0 ;1
L 12.3825 1.6325 12.3825 1.6325 24 P 0 ;1
L 12.3825 1.6825 12.3825 1.6825 24 P 0 ;1
L 12.3825 1.7325 12.3825 1.7325 24 P 0 ;1
L 12.3825 1.7825 12.3825 1.7825 24 P 0 ;1
L 12.3825 1.8325 12.3825 1.8325 24 P 0 ;1
L 12.3825 2.2825 12.3825 2.2825 24 P 0 ;1
L 12.3825 2.3325 12.3825 2.3325 24 P 0 ;1
L 12.3825 2.3825 12.3825 2.3825 24 P 0 ;1
L 12.3825 2.4325 12.3825 2.4325 24 P 0 ;1
L 12.3825 2.4825 12.3825 2.4825 24 P 0 ;1
L 12.3825 2.5325 12.3825 2.5325 24 P 0 ;1
L 12.3825 2.5825 12.3825 2.5825 24 P 0 ;1
L 12.3825 2.6325 12.3825 2.6325 24 P 0 ;1
L 12.3825 2.6825 12.3825 2.6825 24 P 0 ;1
L 12.3825 2.7325 12.3825 2.7325 24 P 0 ;1
L 12.3825 2.7825 12.3825 2.7825 24 P 0 ;1
L 12.3825 2.8325 12.3825 2.8325 24 P 0 ;1
L 12.3825 2.8825 12.3825 2.8825 24 P 0 ;1
L 12.3825 2.9325 12.3825 2.9325 24 P 0 ;1
L 12.3825 2.9825 12.3825 2.9825 24 P 0 ;1
L 12.3825 3.0325 12.3825 3.0325 24 P 0 ;1
L 12.3825 3.0825 12.3825 3.0825 24 P 0 ;1
L 12.3825 3.1325 12.3825 3.1325 24 P 0 ;1
L 12.3825 3.1825 12.3825 3.1825 24 P 0 ;1
L 12.3825 3.2325 12.3825 3.2325 24 P 0 ;1
L 12.3825 3.2825 12.3825 3.2825 24 P 0 ;1
L 12.3825 3.3325 12.3825 3.3325 24 P 0 ;1
L 12.3825 3.3825 12.3825 3.3825 24 P 0 ;1
L 12.3825 3.4325 12.3825 3.4325 24 P 0 ;1
L 12.3825 3.4825 12.3825 3.4825 24 P 0 ;1
L 12.3825 3.5325 12.3825 3.5325 24 P 0 ;1
L 12.3825 3.5825 12.3825 3.5825 24 P 0 ;1
L 12.3825 3.6325 12.3825 3.6325 24 P 0 ;1
L 12.3825 3.6825 12.3825 3.6825 24 P 0 ;1
L 12.3825 3.7325 12.3825 3.7325 24 P 0 ;1
L 12.3825 3.7825 12.3825 3.7825 24 P 0 ;1
L 12.3825 3.8325 12.3825 3.8325 24 P 0 ;1
L 12.3825 3.8825 12.3825 3.8825 24 P 0 ;1
L 12.3825 3.9325 12.3825 3.9325 24 P 0 ;1
L 12.3825 3.9825 12.3825 3.9825 24 P 0 ;1
L 12.3825 4.0325 12.3825 4.0325 24 P 0 ;1
L 12.3825 4.0825 12.3825 4.0825 24 P 0 ;1
L 12.3825 4.1325 12.3825 4.1325 24 P 0 ;1
L 12.3825 4.1825 12.3825 4.1825 24 P 0 ;1
L 12.3825 4.2325 12.3825 4.2325 24 P 0 ;1
L 12.3825 4.2825 12.3825 4.2825 24 P 0 ;1
L 12.3825 4.3325 12.3825 4.3325 24 P 0 ;1
L 12.3825 4.3825 12.3825 4.3825 24 P 0 ;1
L 12.3825 4.4325 12.3825 4.4325 24 P 0 ;1
L 12.3825 4.4825 12.3825 4.4825 24 P 0 ;1
L 12.3825 4.5325 12.3825 4.5325 24 P 0 ;1
L 12.3825 4.5825 12.3825 4.5825 24 P 0 ;1
L 12.3825 4.6325 12.3825 4.6325 24 P 0 ;1
L 12.3825 4.6825 12.3825 4.6825 24 P 0 ;1
L 12.3825 4.7325 12.3825 4.7325 24 P 0 ;1
L 12.3825 4.7825 12.3825 4.7825 24 P 0 ;1
L 12.3825 4.8325 12.3825 4.8325 24 P 0 ;1
L 12.3825 4.8825 12.3825 4.8825 24 P 0 ;1
L 12.3825 4.9325 12.3825 4.9325 24 P 0 ;1
L 12.3825 4.9825 12.3825 4.9825 24 P 0 ;1
L 12.4325 0.1325 12.4325 0.1325 24 P 0 ;1
L 12.4325 0.1825 12.4325 0.1825 24 P 0 ;1
L 12.4325 0.2325 12.4325 0.2325 24 P 0 ;1
L 12.4325 0.2825 12.4325 0.2825 24 P 0 ;1
L 12.4325 0.3325 12.4325 0.3325 24 P 0 ;1
L 12.4325 0.3825 12.4325 0.3825 24 P 0 ;1
L 12.4325 0.4325 12.4325 0.4325 24 P 0 ;1
L 12.4325 0.4825 12.4325 0.4825 24 P 0 ;1
L 12.4325 0.5325 12.4325 0.5325 24 P 0 ;1
L 12.4325 0.5825 12.4325 0.5825 24 P 0 ;1
L 12.4325 0.6325 12.4325 0.6325 24 P 0 ;1
L 12.4325 0.6825 12.4325 0.6825 24 P 0 ;1
L 12.4325 0.7325 12.4325 0.7325 24 P 0 ;1
L 12.4325 0.7825 12.4325 0.7825 24 P 0 ;1
L 12.4325 0.8325 12.4325 0.8325 24 P 0 ;1
L 12.4325 0.8825 12.4325 0.8825 24 P 0 ;1
L 12.4325 0.9325 12.4325 0.9325 24 P 0 ;1
L 12.4325 0.9825 12.4325 0.9825 24 P 0 ;1
L 12.4325 1.0325 12.4325 1.0325 24 P 0 ;1
L 12.4325 1.0825 12.4325 1.0825 24 P 0 ;1
L 12.4325 1.1325 12.4325 1.1325 24 P 0 ;1
L 12.4325 1.1825 12.4325 1.1825 24 P 0 ;1
L 12.4325 1.5825 12.4325 1.5825 24 P 0 ;1
L 12.4325 1.6325 12.4325 1.6325 24 P 0 ;1
L 12.4325 1.6825 12.4325 1.6825 24 P 0 ;1
L 12.4325 1.7325 12.4325 1.7325 24 P 0 ;1
L 12.4325 1.7825 12.4325 1.7825 24 P 0 ;1
L 12.4325 1.8325 12.4325 1.8325 24 P 0 ;1
L 12.4325 2.2825 12.4325 2.2825 24 P 0 ;1
L 12.4325 2.3325 12.4325 2.3325 24 P 0 ;1
L 12.4325 2.3825 12.4325 2.3825 24 P 0 ;1
L 12.4325 2.4325 12.4325 2.4325 24 P 0 ;1
L 12.4325 2.4825 12.4325 2.4825 24 P 0 ;1
L 12.4325 2.5325 12.4325 2.5325 24 P 0 ;1
L 12.4325 2.5825 12.4325 2.5825 24 P 0 ;1
L 12.4325 2.6325 12.4325 2.6325 24 P 0 ;1
L 12.4325 2.6825 12.4325 2.6825 24 P 0 ;1
L 12.4325 2.7325 12.4325 2.7325 24 P 0 ;1
L 12.4325 2.7825 12.4325 2.7825 24 P 0 ;1
L 12.4325 2.8325 12.4325 2.8325 24 P 0 ;1
L 12.4325 2.8825 12.4325 2.8825 24 P 0 ;1
L 12.4325 2.9325 12.4325 2.9325 24 P 0 ;1
L 12.4325 2.9825 12.4325 2.9825 24 P 0 ;1
L 12.4325 3.0325 12.4325 3.0325 24 P 0 ;1
L 12.4325 3.0825 12.4325 3.0825 24 P 0 ;1
L 12.4325 3.1325 12.4325 3.1325 24 P 0 ;1
L 12.4325 3.1825 12.4325 3.1825 24 P 0 ;1
L 12.4325 3.2325 12.4325 3.2325 24 P 0 ;1
L 12.4325 3.2825 12.4325 3.2825 24 P 0 ;1
L 12.4325 3.3325 12.4325 3.3325 24 P 0 ;1
L 12.4325 3.3825 12.4325 3.3825 24 P 0 ;1
L 12.4325 3.4325 12.4325 3.4325 24 P 0 ;1
L 12.4325 3.4825 12.4325 3.4825 24 P 0 ;1
L 12.4325 3.5325 12.4325 3.5325 24 P 0 ;1
L 12.4325 3.5825 12.4325 3.5825 24 P 0 ;1
L 12.4325 3.6325 12.4325 3.6325 24 P 0 ;1
L 12.4325 3.6825 12.4325 3.6825 24 P 0 ;1
L 12.4325 3.7325 12.4325 3.7325 24 P 0 ;1
L 12.4325 3.7825 12.4325 3.7825 24 P 0 ;1
L 12.4325 3.8325 12.4325 3.8325 24 P 0 ;1
L 12.4325 3.8825 12.4325 3.8825 24 P 0 ;1
L 12.4325 3.9325 12.4325 3.9325 24 P 0 ;1
L 12.4325 3.9825 12.4325 3.9825 24 P 0 ;1
L 12.4325 4.0325 12.4325 4.0325 24 P 0 ;1
L 12.4325 4.0825 12.4325 4.0825 24 P 0 ;1
L 12.4325 4.1325 12.4325 4.1325 24 P 0 ;1
L 12.4325 4.1825 12.4325 4.1825 24 P 0 ;1
L 12.4325 4.2325 12.4325 4.2325 24 P 0 ;1
L 12.4325 4.2825 12.4325 4.2825 24 P 0 ;1
L 12.4325 4.3325 12.4325 4.3325 24 P 0 ;1
L 12.4325 4.3825 12.4325 4.3825 24 P 0 ;1
L 12.4325 4.4325 12.4325 4.4325 24 P 0 ;1
L 12.4325 4.4825 12.4325 4.4825 24 P 0 ;1
L 12.4325 4.5325 12.4325 4.5325 24 P 0 ;1
L 12.4325 4.5825 12.4325 4.5825 24 P 0 ;1
L 12.4325 4.6325 12.4325 4.6325 24 P 0 ;1
L 12.4325 4.6825 12.4325 4.6825 24 P 0 ;1
L 12.4325 4.7325 12.4325 4.7325 24 P 0 ;1
L 12.4325 4.7825 12.4325 4.7825 24 P 0 ;1
L 12.4325 4.8325 12.4325 4.8325 24 P 0 ;1
L 12.4325 4.8825 12.4325 4.8825 24 P 0 ;1
L 12.4325 4.9325 12.4325 4.9325 24 P 0 ;1
L 12.4325 4.9825 12.4325 4.9825 24 P 0 ;1
L 12.4325 5.0325 12.4325 5.0325 24 P 0 ;1
L 12.4825 0.1325 12.4825 0.1325 24 P 0 ;1
L 12.4825 0.1825 12.4825 0.1825 24 P 0 ;1
L 12.4825 0.2325 12.4825 0.2325 24 P 0 ;1
L 12.4825 0.2825 12.4825 0.2825 24 P 0 ;1
L 12.4825 0.3325 12.4825 0.3325 24 P 0 ;1
L 12.4825 0.3825 12.4825 0.3825 24 P 0 ;1
L 12.4825 0.4325 12.4825 0.4325 24 P 0 ;1
L 12.4825 0.4825 12.4825 0.4825 24 P 0 ;1
L 12.4825 0.5325 12.4825 0.5325 24 P 0 ;1
L 12.4825 0.5825 12.4825 0.5825 24 P 0 ;1
L 12.4825 0.8825 12.4825 0.8825 24 P 0 ;1
L 12.4825 0.9325 12.4825 0.9325 24 P 0 ;1
L 12.4825 0.9825 12.4825 0.9825 24 P 0 ;1
L 12.4825 1.0325 12.4825 1.0325 24 P 0 ;1
L 12.4825 1.0825 12.4825 1.0825 24 P 0 ;1
L 12.4825 1.1325 12.4825 1.1325 24 P 0 ;1
L 12.4825 1.1825 12.4825 1.1825 24 P 0 ;1
L 12.4825 4.7325 12.4825 4.7325 24 P 0 ;1
L 12.4825 4.7825 12.4825 4.7825 24 P 0 ;1
L 12.4825 4.8325 12.4825 4.8325 24 P 0 ;1
L 12.4825 4.8825 12.4825 4.8825 24 P 0 ;1
L 12.4825 4.9325 12.4825 4.9325 24 P 0 ;1
L 12.4825 4.9825 12.4825 4.9825 24 P 0 ;1
L 12.5325 0.1325 12.5325 0.1325 24 P 0 ;1
L 12.5325 0.1825 12.5325 0.1825 24 P 0 ;1
L 12.5325 0.2325 12.5325 0.2325 24 P 0 ;1
L 12.5325 0.2825 12.5325 0.2825 24 P 0 ;1
L 12.5325 0.3325 12.5325 0.3325 24 P 0 ;1
L 12.5325 0.3825 12.5325 0.3825 24 P 0 ;1
L 12.5325 0.4325 12.5325 0.4325 24 P 0 ;1
L 12.5325 0.4825 12.5325 0.4825 24 P 0 ;1
L 12.5325 0.5325 12.5325 0.5325 24 P 0 ;1
L 12.5325 0.9325 12.5325 0.9325 24 P 0 ;1
L 12.5325 0.9825 12.5325 0.9825 24 P 0 ;1
L 12.5325 1.0325 12.5325 1.0325 24 P 0 ;1
L 12.5325 1.0825 12.5325 1.0825 24 P 0 ;1
L 12.5325 1.1325 12.5325 1.1325 24 P 0 ;1
L 12.5325 1.1825 12.5325 1.1825 24 P 0 ;1
L 12.5325 4.7825 12.5325 4.7825 24 P 0 ;1
L 12.5325 4.8325 12.5325 4.8325 24 P 0 ;1
L 12.5325 4.8825 12.5325 4.8825 24 P 0 ;1
L 12.5325 4.9325 12.5325 4.9325 24 P 0 ;1
L 12.5825 0.1325 12.5825 0.1325 24 P 0 ;1
L 12.5825 0.1825 12.5825 0.1825 24 P 0 ;1
L 12.5825 0.2325 12.5825 0.2325 24 P 0 ;1
L 12.5825 0.2825 12.5825 0.2825 24 P 0 ;1
L 12.5825 0.3325 12.5825 0.3325 24 P 0 ;1
L 12.5825 1.0825 12.5825 1.0825 24 P 0 ;1
L 12.5825 1.1325 12.5825 1.1325 24 P 0 ;1
L 12.5825 1.1825 12.5825 1.1825 24 P 0 ;1
L 12.6325 0.1325 12.6325 0.1325 24 P 0 ;1
L 12.6325 0.1825 12.6325 0.1825 24 P 0 ;1
L 12.6325 0.2325 12.6325 0.2325 24 P 0 ;1
L 12.6325 0.2825 12.6325 0.2825 24 P 0 ;1
L 12.6325 1.1325 12.6325 1.1325 24 P 0 ;1
L 12.6325 1.1825 12.6325 1.1825 24 P 0 ;1
L 12.6325 1.2325 12.6325 1.2325 24 P 0 ;1
L 12.6825 0.1325 12.6825 0.1325 24 P 0 ;1
L 12.6825 0.1825 12.6825 0.1825 24 P 0 ;1
L 12.6825 0.2325 12.6825 0.2325 24 P 0 ;1
L 12.6825 0.2825 12.6825 0.2825 24 P 0 ;1
L 12.6825 1.1325 12.6825 1.1325 24 P 0 ;1
L 12.6825 1.1825 12.6825 1.1825 24 P 0 ;1
L 12.6825 1.2325 12.6825 1.2325 24 P 0 ;1
L 12.6825 5.5825 12.6825 5.5825 24 P 0 ;1
L 12.6825 5.6325 12.6825 5.6325 24 P 0 ;1
L 12.6825 5.6825 12.6825 5.6825 24 P 0 ;1
L 12.6825 5.7325 12.6825 5.7325 24 P 0 ;1
L 12.6825 5.7825 12.6825 5.7825 24 P 0 ;1
L 12.6825 5.8325 12.6825 5.8325 24 P 0 ;1
L 12.6825 5.8825 12.6825 5.8825 24 P 0 ;1
L 12.7325 0.1325 12.7325 0.1325 24 P 0 ;1
L 12.7325 0.1825 12.7325 0.1825 24 P 0 ;1
L 12.7325 0.2325 12.7325 0.2325 24 P 0 ;1
L 12.7325 0.2825 12.7325 0.2825 24 P 0 ;1
L 12.7325 1.1325 12.7325 1.1325 24 P 0 ;1
L 12.7325 1.1825 12.7325 1.1825 24 P 0 ;1
L 12.7325 1.2325 12.7325 1.2325 24 P 0 ;1
L 12.7325 5.5825 12.7325 5.5825 24 P 0 ;1
L 12.7325 5.6325 12.7325 5.6325 24 P 0 ;1
L 12.7325 5.6825 12.7325 5.6825 24 P 0 ;1
L 12.7325 5.7325 12.7325 5.7325 24 P 0 ;1
L 12.7325 5.7825 12.7325 5.7825 24 P 0 ;1
L 12.7325 5.8325 12.7325 5.8325 24 P 0 ;1
L 12.7325 5.8825 12.7325 5.8825 24 P 0 ;1
L 12.7825 0.1325 12.7825 0.1325 24 P 0 ;1
L 12.7825 0.1825 12.7825 0.1825 24 P 0 ;1
L 12.7825 0.2325 12.7825 0.2325 24 P 0 ;1
L 12.7825 0.2825 12.7825 0.2825 24 P 0 ;1
L 12.7825 0.3325 12.7825 0.3325 24 P 0 ;1
L 12.7825 1.0825 12.7825 1.0825 24 P 0 ;1
L 12.7825 1.1325 12.7825 1.1325 24 P 0 ;1
L 12.7825 1.1825 12.7825 1.1825 24 P 0 ;1
L 12.7825 1.2325 12.7825 1.2325 24 P 0 ;1
L 12.7825 5.5825 12.7825 5.5825 24 P 0 ;1
L 12.7825 5.6325 12.7825 5.6325 24 P 0 ;1
L 12.7825 5.6825 12.7825 5.6825 24 P 0 ;1
L 12.7825 5.7325 12.7825 5.7325 24 P 0 ;1
L 12.7825 5.7825 12.7825 5.7825 24 P 0 ;1
L 12.7825 5.8325 12.7825 5.8325 24 P 0 ;1
L 12.7825 5.8825 12.7825 5.8825 24 P 0 ;1

### steps/drc/layers/rout/features
#
#Feature symbol names
#
$0 r0

#
#Layer features
#
L 12.84646004 6.02361998 4.25271004 6.02361998 0 P 1 
A 4.25271004 6.02361998 4.25271004 6.11661998 4.25271004 6.07011998 0 P 1 Y
L 4.25271004 6.11661998 12.9252 6.11661998 0 P 1 
L 12.9252 6.11661998 12.9252 6.43788002 0 P 1 
A 12.9252 6.43788002 12.84646004 6.51661998 12.84646004 6.43788002 0 P 1 N
L 12.84646004 6.51661998 0.07873996 6.51661998 0 P 1 
A 0.07873996 6.51661998 0 6.43788002 0.07873996 6.43788002 0 P 1 N
L 0 6.43788002 0 6.11661998 0 P 1 
L 0 6.11661998 4.05271004 6.11661998 0 P 1 
A 4.05271004 6.11661998 4.05271004 6.02361998 4.05271004 6.07011998 0 P 1 Y
L 4.05271004 6.02361998 0.07873996 6.02361998 0 P 1 
A 0.07873996 6.02361998 0 5.94488002 0.07873996 5.94488002 0 P 1 N
L 0 5.94488002 0 0.07873996 0 P 1 
A 0 0.07873996 0.07873996 0 0.07873996 0.07873996 0 P 1 N
L 0.07873996 0 4.05271004 0 0 P 1 
A 4.05271004 0 4.05271004 -0.093 4.05271004 -0.0465 0 P 1 Y
L 4.05271004 -0.093 0 -0.093 0 P 1 
L 0 -0.093 0 -0.41426004 0 P 1 
A 0 -0.41426004 0.07873996 -0.493 0.07873996 -0.41426004 0 P 1 N
L 0.07873996 -0.493 12.84646004 -0.493 0 P 1 
A 12.84646004 -0.493 12.9252 -0.41426004 12.84646004 -0.41426004 0 P 1 N
L 12.9252 -0.41426004 12.9252 -0.093 0 P 1 
L 12.9252 -0.093 4.25271004 -0.093 0 P 1 
A 4.25271004 -0.093 4.25271004 0 4.25271004 -0.0465 0 P 1 Y
L 4.25271004 0 4.77558996 0 0 P 1 
A 4.77558996 0 4.85433996 0.07873996 4.7755999 0.07873996 0 P 1 N
L 4.85433996 0.07873996 4.85433996 0.35433002 0 P 1 
A 4.85433996 0.35433002 4.93308002 0.43306998 4.93307992 0.35433002 0 P 1 Y
L 4.93308002 0.43306998 6.50788002 0.43306998 0 P 1 
A 6.50788002 0.43306998 6.58661998 0.35433002 6.50788002 0.35433002 0 P 1 Y
L 6.58661998 0.35433002 6.58661998 0.07873996 0 P 1 
A 6.58661998 0.07873996 6.66536004 0 6.66535994 0.07873996 0 P 1 N
L 6.66536004 0 12.84646004 0 0 P 1 
A 12.84646004 0 12.9252 0.07873996 12.84646004 0.07873996 0 P 1 N
L 12.9252 0.07873996 12.9252 5.94488002 0 P 1 
A 12.9252 5.94488002 12.84646004 6.02361998 12.84646004 5.94488002 0 P 1 N

### steps/drc/layers/s-paste/features
#
#Feature symbol names
#
$0 r2
$1 r5
$2 r6
$3 r15
$4 r30
$5 s20
$6 s50
$7 rect35.43x15.75

#
#Feature attribute names
#
@0 .nomenclature
@1 .smd
@2 .test_point
@3 .string_mirrored
@4 .geometry
@5 .string
@6 .pad_usage
@7 .string_angle

#
#Feature attribute text strings
#
&0 S0_508
&1 TPB30V20D10AT28BPM
&2 ICT-TPB30BPM
&3 R0_9X0_4
&4 S1_27
&5 E-C40SM100PM5-G
&6 SHEET
&7 TITLE
&8 SCALE 1:1
&9 LAYER
&10 OF
&11 ART
&12 SOLDER PASTE (BOT)
&13 -
&14 1
&15 Barreleye G2 SXM2-Riser
&16 A1
&17 DATE OCT/27/2017

#
#Layer features
#
P 7.82853996 4.528 5 P 0 0;1,4=0,6=0
P 7.785 4.45 4 P 0 0;2,4=1,6=1
P 9.11353996 4.542 5 P 0 0;1,4=0,6=0
P 7.88353996 4.528 5 P 0 0;1,4=0,6=0
P 7.835 4.45 4 P 0 0;2,4=1,6=1
P 9.16353996 4.542 5 P 0 0;1,4=0,6=0
P 1.8 4.485 4 P 0 0;2,4=1,6=1
P 1.825 4.528 5 P 0 0;1,4=0,6=0
P 3.11 4.542 5 P 0 0;1,4=0,6=0
P 1.86 4.485 4 P 0 0;2,4=1,6=1
P 1.88 4.528 5 P 0 0;1,4=0,6=0
P 3.16 4.542 5 P 0 0;1,4=0,6=0
P 1.857 3.61 5 P 0 0;1,4=0,6=0
P 1.9 3.61 4 P 0 0;2,4=2,6=1
P 7.86093996 3.61 5 P 0 0;1,4=0,6=0
P 7.90393996 3.61 4 P 0 0;2,4=2,6=1
P 6.38348996 4.99705 5 P 0 0;1,4=0,6=0
P 6.42418996 4.99705 5 P 0 0;1,4=0,6=0
P 6.415 4.955 4 P 0 0;2,4=2,6=1
P 3.94 4.545 4 P 0 0;2,4=1,6=1
P 1.08 5.85 4 P 0 0;2,4=1,6=1
P 10.03813996 2.87558996 7 P 0 0;1,4=3,6=0
P 10.099 2.88 5 P 0 0;1,4=0,6=0
P 10.099 2.928 5 P 0 0;1,4=0,6=0
P 4.105 4.985 4 P 0 0;2,4=1,6=1
P 4.05686004 2.65 5 P 0 0;1,4=0,6=0
P 3.99421004 2.64558996 7 P 0 0;1,4=3,6=0
P 4.057 2.7 5 P 0 0;1,4=0,6=0
P 4.02 4.355 4 P 0 0;2,4=1,6=1
P 1.16 5.85 4 P 0 0;2,4=1,6=1
P 12.33998996 1.3061 5 P 0 0;1,4=0,6=0
P 0.58298996 1.3381 5 P 0 0;1,4=0,6=0
P 6.501 5.017 4 P 0 0;2,4=1,6=1
P 6.45818996 4.99705 5 P 0 0;1,4=0,6=0
P 7.82693996 3.61 5 P 0 0;1,4=0,6=0
P 7.425 3.43 4 P 0 0;2,4=1,6=1
P 3.8899 4.765 4 P 0 0;2,4=1,6=1
P 5.46358002 2.6305 5 P 0 0;1,4=0,6=0
P 5.46358002 2.6755 5 P 0 0;1,4=0,6=0
P 7.2926 5.04351004 4 P 0 0;2,4=1,6=1
P 7.3226 4.97551004 5 P 0 0;1,4=0,6=0
P 7.2426 5.04351004 4 P 0 0;2,4=1,6=1
P 7.2726 4.97551004 5 P 0 0;1,4=0,6=0
P 3.38146004 5.298 5 P 0 0;1,4=0,6=0
P 3.33646004 5.298 5 P 0 0;1,4=0,6=0
P 3.45646004 5.3 4 P 0 0;2,4=1,6=1
P 1.28906004 5.04351004 4 P 0 0;2,4=1,6=1
P 1.31906004 4.97551004 5 P 0 0;1,4=0,6=0
P 1.23906004 5.04351004 4 P 0 0;2,4=1,6=1
P 1.26906004 4.97551004 5 P 0 0;1,4=0,6=0
P 9.385 5.298 5 P 0 0;1,4=0,6=0
P 9.34 5.298 5 P 0 0;1,4=0,6=0
P 9.46 5.3 4 P 0 0;2,4=1,6=1
P 5.34275 1.7371 5 P 0 0;1,4=0,6=0
P 5.34275 1.7821 5 P 0 0;1,4=0,6=0
P 5.49758002 2.0853 5 P 0 0;1,4=0,6=0
P 5.49758002 2.1303 5 P 0 0;1,4=0,6=0
P 5.49758002 2.2207 5 P 0 0;1,4=0,6=0
P 5.49758002 2.2657 5 P 0 0;1,4=0,6=0
P 5.34275 2.4687 5 P 0 0;1,4=0,6=0
P 5.49758002 2.4011 5 P 0 0;1,4=0,6=0
P 5.49758002 2.6755 5 P 0 0;1,4=0,6=0
P 5.49758002 1.9894 5 P 0 0;1,4=0,6=0
P 5.49758002 2.4953 5 P 0 0;1,4=0,6=0
P 5.49758002 1.6693 5 P 0 0;1,4=0,6=0
P 5.49758002 2.6305 5 P 0 0;1,4=0,6=0
P 5.49758002 1.7143 5 P 0 0;1,4=0,6=0
P 5.49758002 2.5403 5 P 0 0;1,4=0,6=0
P 5.34275 1.6458 5 P 0 0;1,4=0,6=0
P 5.34275 2.6079 5 P 0 0;1,4=0,6=0
P 5.34275 1.8768 5 P 0 0;1,4=0,6=0
P 5.49758002 2.3561 5 P 0 0;1,4=0,6=0
P 5.34275 1.6008 5 P 0 0;1,4=0,6=0
P 5.34275 2.4237 5 P 0 0;1,4=0,6=0
P 5.34275 1.9218 5 P 0 0;1,4=0,6=0
P 5.34275 2.0572 5 P 0 0;1,4=0,6=0
P 5.49758002 1.9444 5 P 0 0;1,4=0,6=0
P 5.34275 2.0122 5 P 0 0;1,4=0,6=0
P 5.49758002 1.8533 5 P 0 0;1,4=0,6=0
P 5.49758002 1.8083 5 P 0 0;1,4=0,6=0
P 5.34275 2.1529 5 P 0 0;1,4=0,6=0
P 5.34275 2.5629 5 P 0 0;1,4=0,6=0
P 5.34275 2.1979 5 P 0 0;1,4=0,6=0
P 5.34275 2.3333 5 P 0 0;1,4=0,6=0
P 5.34275 2.2883 5 P 0 0;1,4=0,6=0
P 6.74 4.805 4 P 0 0;2,4=1,6=1
P 6.83118996 4.73868002 6 P 0 0;1,4=4,6=0
P 6.74208996 4.6252 6 P 0 0;1,4=4,6=0
P 6.74208996 4.7052 6 P 0 0;1,4=4,6=0
P 6.83118996 4.81705 6 P 0 0;1,4=4,6=0
P 6.83318996 4.89705 5 P 0 0;1,4=0,6=0
P 6.65 5.055 4 P 0 0;2,4=1,6=1
P 6.53918996 5.09705 5 P 0 0;1,4=0,6=0
P 6.49205 5.09705 4 P 0 0;2,4=1,6=1
P 6.45818996 5.04705 5 P 0 0;1,4=0,6=0
P 6.495 4.9328 4 P 0 0;2,4=1,6=1
P 6.57418996 4.99705 5 P 0 0;1,4=0,6=0
P 6.55118996 5.04705 4 P 0 0;2,4=1,6=1
P 6.65418996 4.99705 5 P 0 0;1,4=0,6=0
P 6.60818996 4.99705 5 P 0 0;1,4=0,6=0
P 6.78 4.94705 4 P 0 0;2,4=1,6=1
P 6.755 4.89705 4 P 0 0;2,4=1,6=1
P 6.79918996 4.89705 5 P 0 0;1,4=0,6=0
P 6.74 4.987 4 P 0 0;2,4=1,6=1
P 6.68818996 4.99705 5 P 0 0;1,4=0,6=0
P 6.803 5 5 P 0 0;1,4=0,6=0
P 12.33998996 1.3401 5 P 0 0;1,4=0,6=0
P 12.34198002 2.155 5 P 0 0;1,4=0,6=0
P 12.33901004 1.93958996 5 P 0 0;1,4=0,6=0
P 12.33901004 1.98958996 5 P 0 0;1,4=0,6=0
P 0.58298996 1.91181998 5 P 0 0;1,4=0,6=0
P 0.58298996 1.86181998 5 P 0 0;1,4=0,6=0
P 0.61698996 1.3381 5 P 0 0;1,4=0,6=0
P 0.58298002 2.045 5 P 0 0;1,4=0,6=0
P 0.58298002 1.655 5 P 0 0;1,4=0,6=0
P 5.46358002 1.6693 5 P 0 0;1,4=0,6=0
P 5.46358002 1.9894 5 P 0 0;1,4=0,6=0
P 11.45593002 2.37 5 P 0 0;1,4=0,6=0
P 5.46358002 2.2657 5 P 0 0;1,4=0,6=0
P 11.45593002 1.89 5 P 0 0;1,4=0,6=0
P 10.41393996 4.21 4 P 0 0;2,4=2,6=1
P 5.30875 2.0122 5 P 0 0;1,4=0,6=0
P 11.42193002 2.37 5 P 0 0;1,4=0,6=0
P 5.30875 2.0572 5 P 0 0;1,4=0,6=0
P 11.42193002 2.415 5 P 0 0;1,4=0,6=0
P 11.62193002 2.495 5 P 0 0;1,4=0,6=0
P 5.46358002 2.0853 5 P 0 0;1,4=0,6=0
P 11.45593002 1.57 5 P 0 0;1,4=0,6=0
P 5.46358002 2.1303 5 P 0 0;1,4=0,6=0
P 11.62193002 2.45 5 P 0 0;1,4=0,6=0
P 5.30875 1.8768 5 P 0 0;1,4=0,6=0
P 11.45593002 1.41 5 P 0 0;1,4=0,6=0
P 11.80693002 2.87558996 7 P 0 0;1,4=3,6=0
P 12.308 2.11 5 P 0 0;1,4=0,6=0
P 11.875 2.885 4 P 0 0;2,4=2,6=1
P 11.45593002 1.455 5 P 0 0;1,4=0,6=0
P 5.30875 1.9218 5 P 0 0;1,4=0,6=0
P 11.45593002 2.21 5 P 0 0;1,4=0,6=0
P 11.45593002 1.935 5 P 0 0;1,4=0,6=0
P 11.65593002 1.49 5 P 0 0;1,4=0,6=0
P 11.42193002 2.53 5 P 0 0;1,4=0,6=0
P 11.45593002 2.415 5 P 0 0;1,4=0,6=0
P 11.42193002 2.575 5 P 0 0;1,4=0,6=0
P 3.91351004 2.62 7 P 0 0;1,4=3,6=0
P 9.95743996 2.85 7 P 0 0;1,4=3,6=0
P 1.057 5.027 4 P 0 0;2,4=1,6=1
P 11.65593002 1.695 5 P 0 0;1,4=0,6=0
P 11.65593002 1.65 5 P 0 0;1,4=0,6=0
P 5.6492 3 5 P 0 0;1,4=0,6=0
P 5.72185 3 7 P 0 0;1,4=3,6=0
P 3.88 4.545 4 P 0 0;2,4=1,6=1
P 0.96555 5.78055 4 P 0 0;2,4=1,6=1
P 10.133 2.928 5 P 0 0;1,4=0,6=0
P 9.91 4.433 4 P 0 0;2,4=1,6=1
P 11.45593002 2.255 5 P 0 0;1,4=0,6=0
P 3.9599 5.395 4 P 0 0;2,4=1,6=1
P 0.72933002 5.463 4 P 0 0;2,4=1,6=1
P 11.45593002 2.575 5 P 0 0;1,4=0,6=0
P 4.091 2.7 5 P 0 0;1,4=0,6=0
P 3.94 4.42 4 P 0 0;2,4=1,6=1
P 3.75998996 0.24001004 4 P 0 0;2,4=1,6=1
P 9.55795 0.26133996 4 P 0 0;2,4=1,6=1
P 3.99421004 2.59441004 7 P 0 0;1,4=3,6=0
P 4.09086004 2.65 5 P 0 0;1,4=0,6=0
P 4.05686004 2.59 5 P 0 0;1,4=0,6=0
P 11.35061998 2.73 5 P 0 0;1,4=0,6=0
P 11.395 2.725 4 P 0 0;2,4=1,6=1
P 11.35061998 2.8 5 P 0 0;1,4=0,6=0
P 11.61661998 2.905 5 P 0 0;1,4=0,6=0
P 11.61661998 2.785 5 P 0 0;1,4=0,6=0
P 1.33906004 4.60351004 4 P 0 0;2,4=1,6=1
P 5.34668996 2.8 5 P 0 0;1,4=0,6=0
P 5.387 2.725 4 P 0 0;2,4=1,6=1
P 5.34668996 2.73 5 P 0 0;1,4=0,6=0
P 5.61268996 2.785 5 P 0 0;1,4=0,6=0
P 5.61268996 2.905 5 P 0 0;1,4=0,6=0
P 10.133 2.88 5 P 0 0;1,4=0,6=0
P 10.03813996 2.82441004 7 P 0 0;1,4=3,6=0
P 10.10078996 2.82 5 P 0 0;1,4=0,6=0
P 11.45593002 1.615 5 P 0 0;1,4=0,6=0
P 11.45593002 2.53 5 P 0 0;1,4=0,6=0
P 0.95951004 5.4595 4 P 0 0;2,4=1,6=1
P 9.16353996 4.508 5 P 0 0;1,4=0,6=0
P 7.1926 5.15351004 4 P 0 0;2,4=1,6=1
P 5.31268996 2.73 5 P 0 0;1,4=0,6=0
P 5.42768996 2.73 5 P 0 0;1,4=0,6=0
P 5.27 2.73 4 P 0 0;2,4=2,6=1
P 5.31268996 2.8 5 P 0 0;1,4=0,6=0
P 5.42768996 2.8 5 P 0 0;1,4=0,6=0
P 5.27 2.8 4 P 0 0;2,4=2,6=1
P 1.85421004 2.4781 5 P 0 0;1,4=0,6=0
P 1.9 2.48 4 P 0 0;2,4=2,6=1
P 1.823 3.61 5 P 0 0;1,4=0,6=0
P 4.07408002 4.01978996 4 P 0 0;2,4=1,6=1
P 3.9099 5.395 4 P 0 0;2,4=1,6=1
P 7.86093996 3.51 5 P 0 0;1,4=0,6=0
P 7.90393996 3.51 4 P 0 0;2,4=2,6=1
P 7.90393996 3.56 4 P 0 0;2,4=2,6=1
P 7.86093996 3.56 5 P 0 0;1,4=0,6=0
P 2.63685 2.82 5 P 0 0;1,4=0,6=0
P 5.59 4.475 4 P 0 0;2,4=2,6=1
P 7.82415 2.4781 5 P 0 0;1,4=0,6=0
P 3.09646004 5.332 5 P 0 0;1,4=0,6=0
P 3.23146004 5.332 5 P 0 0;1,4=0,6=0
P 3.38146004 5.332 5 P 0 0;1,4=0,6=0
P 12.30798002 2.155 5 P 0 0;1,4=0,6=0
P 6.34948996 4.99705 5 P 0 0;1,4=0,6=0
P 6.837 5 5 P 0 0;1,4=0,6=0
P 6.27208996 4.7202 6 P 0 0;1,4=4,6=0
P 6.27208996 4.6402 6 P 0 0;1,4=4,6=0
P 6.27208996 4.8802 6 P 0 0;1,4=4,6=0
P 6.27208996 4.8002 6 P 0 0;1,4=4,6=0
P 3.86 0.7751 4 P 0 0;2,4=1,6=1
P 6.91118996 4.81705 6 P 0 0;1,4=4,6=0
P 6.91118996 4.73868002 6 P 0 0;1,4=4,6=0
P 6.66208996 4.6252 6 P 0 0;1,4=4,6=0
P 6.66208996 4.7052 6 P 0 0;1,4=4,6=0
P 5.99708996 4.5552 6 P 0 0;1,4=4,6=0
P 5.91708996 4.5552 6 P 0 0;1,4=4,6=0
P 6.07708996 4.5552 6 P 0 0;1,4=4,6=0
P 5.83708996 4.5552 6 P 0 0;1,4=4,6=0
P 5.75708996 4.5552 6 P 0 0;1,4=4,6=0
P 5.67708996 4.5552 6 P 0 0;1,4=4,6=0
P 5.59778996 4.5552 6 P 0 0;1,4=4,6=0
P 5.40386004 2.96 6 P 0 0;1,4=4,6=0
P 5.40386004 3.04 6 P 0 0;1,4=4,6=0
P 5.40386004 3.12 6 P 0 0;1,4=4,6=0
P 11.40778996 3.04 6 P 0 0;1,4=4,6=0
P 11.40778996 3.12 6 P 0 0;1,4=4,6=0
P 11.40778996 2.96 6 P 0 0;1,4=4,6=0
P 11.80693002 2.85 7 P 0 0;1,4=3,6=0
P 5.6152 3 5 P 0 0;1,4=0,6=0
P 5.72185 3.02558996 7 P 0 0;1,4=3,6=0
P 9.95743996 2.87558996 7 P 0 0;1,4=3,6=0
P 0.66 2.045 4 P 0 0;2,4=1,6=1
P 5.803 2.85 7 P 0 0;1,4=3,6=0
P 5.61268996 2.855 5 P 0 0;1,4=0,6=0
P 10.38498996 4.9231 4 P 0 0;2,4=1,6=1
P 3.91351004 2.64558996 7 P 0 0;1,4=3,6=0
P 4.09086004 2.59 5 P 0 0;1,4=0,6=0
P 10.13478996 2.82 5 P 0 0;1,4=0,6=0
P 11.47061998 2.73 5 P 0 0;1,4=0,6=0
P 11.47061998 2.8 5 P 0 0;1,4=0,6=0
P 11.61661998 2.855 5 P 0 0;1,4=0,6=0
P 5.46168996 2.73 5 P 0 0;1,4=0,6=0
P 5.46168996 2.8 5 P 0 0;1,4=0,6=0
P 11.40778996 3.28 6 P 0 0;1,4=4,6=0
P 11.40778996 3.2 6 P 0 0;1,4=4,6=0
P 5.40386004 3.2 6 P 0 0;1,4=4,6=0
P 5.40386004 3.28 6 P 0 0;1,4=4,6=0
P 0.7 5.267 4 P 0 0;2,4=1,6=1
P 5.917 2.97 5 P 0 0;1,4=0,6=0
P 0.61698002 2.045 5 P 0 0;1,4=0,6=0
P 1.82021004 2.4781 5 P 0 0;1,4=0,6=0
P 6.42418996 5.04705 5 P 0 0;1,4=0,6=0
P 9.1 5.332 5 P 0 0;1,4=0,6=0
P 9.235 5.332 5 P 0 0;1,4=0,6=0
P 9.385 5.332 5 P 0 0;1,4=0,6=0
P 2.11646004 5.377 5 P 0 0;1,4=0,6=0
P 1.95146004 5.377 5 P 0 0;1,4=0,6=0
P 7.78 2.4781 4 P 0 0;2,4=1,6=1
P 7.955 5.377 5 P 0 0;1,4=0,6=0
P 8.12 5.377 5 P 0 0;1,4=0,6=0
P 6.645 4.83 4 P 0 0;2,4=2,6=1
P 4.755 5.03 4 P 0 0;2,4=2,6=1
P 1.857 3.56 5 P 0 0;1,4=0,6=0
P 1.9 3.56 4 P 0 0;2,4=2,6=1
P 2.63685 2.87 5 P 0 0;1,4=0,6=0
P 1.857 3.51 5 P 0 0;1,4=0,6=0
P 1.9 3.51 4 P 0 0;2,4=2,6=1
P 1.33906004 4.69351004 4 P 0 0;2,4=1,6=1
P 1.31906004 4.94151004 5 P 0 0;1,4=0,6=0
P 1.823 3.56 5 P 0 0;1,4=0,6=0
P 0.80806998 5.46193996 4 P 0 0;2,4=1,6=1
P 1.28906004 4.69351004 4 P 0 0;2,4=1,6=1
P 1.26906004 4.94151004 5 P 0 0;1,4=0,6=0
P 1.823 3.51 5 P 0 0;1,4=0,6=0
P 3.94 4.765 4 P 0 0;2,4=1,6=1
P 2.06646004 5.343 5 P 0 0;1,4=0,6=0
P 2.11646004 5.343 5 P 0 0;1,4=0,6=0
P 2.06646004 5.29 4 P 0 0;2,4=1,6=1
P 1.33906004 5.15351004 4 P 0 0;2,4=1,6=1
P 3.11 4.508 5 P 0 0;1,4=0,6=0
P 2.00146004 5.343 5 P 0 0;1,4=0,6=0
P 1.95146004 5.343 5 P 0 0;1,4=0,6=0
P 2.00146004 5.29 4 P 0 0;2,4=1,6=1
P 3.16 4.508 5 P 0 0;1,4=0,6=0
P 1.18906004 5.15351004 4 P 0 0;2,4=1,6=1
P 3.635 0.715 4 P 0 0;2,4=1,6=1
P 4.02 4.42 4 P 0 0;2,4=1,6=1
P 5.71638002 2.82441004 7 P 0 0;1,4=3,6=0
P 5.64668996 2.785 5 P 0 0;1,4=0,6=0
P 5.56 2.82 4 P 0 0;2,4=2,6=1
P 4.06 4.86 4 P 0 0;2,4=1,6=1
P 11.62193002 2.61 5 P 0 0;1,4=0,6=0
P 11.62193002 2.655 5 P 0 0;1,4=0,6=0
P 5.71638002 2.87558996 7 P 0 0;1,4=3,6=0
P 5.64668996 2.905 5 P 0 0;1,4=0,6=0
P 5.56 2.955 4 P 0 0;2,4=2,6=1
P 3.84 0.69 4 P 0 0;2,4=1,6=1
P 3.56 0.49 4 P 0 0;2,4=1,6=1
P 7.3426 5.15351004 4 P 0 0;2,4=1,6=1
P 9.11353996 4.508 5 P 0 0;1,4=0,6=0
P 3.785 0.69 4 P 0 0;2,4=1,6=1
P 5.46358002 1.8533 5 P 0 0;1,4=0,6=0
P 3.75998996 0.345 4 P 0 0;2,4=1,6=1
P 0.58 5.591 4 P 0 0;2,4=1,6=1
P 2.06646004 5.377 5 P 0 0;1,4=0,6=0
P 3.33646004 5.332 5 P 0 0;1,4=0,6=0
P 3.18646004 5.332 5 P 0 0;1,4=0,6=0
P 3.14146004 5.332 5 P 0 0;1,4=0,6=0
P 2.00146004 5.377 5 P 0 0;1,4=0,6=0
P 9.34 5.332 5 P 0 0;1,4=0,6=0
P 9.19 5.332 5 P 0 0;1,4=0,6=0
P 11.65061998 2.855 5 P 0 0;1,4=0,6=0
P 11.72031004 2.85 7 P 0 0;1,4=3,6=0
P 11.865 4.455 4 P 0 0;2,4=1,6=1
P 9.145 5.332 5 P 0 0;1,4=0,6=0
P 8.005 5.377 5 P 0 0;1,4=0,6=0
P 8.07 5.377 5 P 0 0;1,4=0,6=0
P 5.71638002 2.85 7 P 0 0;1,4=3,6=0
P 5.64668996 2.855 5 P 0 0;1,4=0,6=0
P 5.883 3.07 5 P 0 0;1,4=0,6=0
P 5.883 2.97 5 P 0 0;1,4=0,6=0
P 5.80255 2.97441004 7 P 0 0;1,4=3,6=0
P 7.42603996 5.15895 4 P 0 0;2,4=1,6=1
P 1.38906004 5.15351004 4 P 0 0;2,4=1,6=1
P 1.094 5.356 4 P 0 0;2,4=1,6=1
P 1.825 4.562 5 P 0 0;1,4=0,6=0
P 1.88 4.562 5 P 0 0;1,4=0,6=0
P 7.88353996 4.562 5 P 0 0;1,4=0,6=0
P 7.82853996 4.562 5 P 0 0;1,4=0,6=0
P 5.917 3.02 5 P 0 0;1,4=0,6=0
P 5.917 3.07 5 P 0 0;1,4=0,6=0
P 11.80693002 2.82441004 7 P 0 0;1,4=3,6=0
P 5.803 2.82441004 7 P 0 0;1,4=3,6=0
P 5.815 0.925 4 P 0 0;2,4=1,6=1
P 3.635 0.49 4 P 0 0;2,4=1,6=1
P 0.73 4.96 4 P 0 0;2,4=1,6=1
P 6.57318996 5.09705 5 P 0 0;1,4=0,6=0
P 6.83708996 4.5652 4 P 0 0;2,4=1,6=1
P 11.295 4.88 4 P 0 0;2,4=2,6=1
P 5.105 5.05 4 P 0 0;2,4=2,6=1
P 4.41 4.21 4 P 0 0;2,4=2,6=1
P 5.803 2.87558996 7 P 0 0;1,4=3,6=0
P 0.61698002 1.655 5 P 0 0;1,4=0,6=0
P 5.76 2.66 4 P 0 0;2,4=1,6=1
P 5.30875 2.5629 5 P 0 0;1,4=0,6=0
P 5.30875 2.6079 5 P 0 0;1,4=0,6=0
P 5.80255 3.02558996 7 P 0 0;1,4=3,6=0
P 5.883 3.02 5 P 0 0;1,4=0,6=0
P 5.795 3.09 4 P 0 0;2,4=2,6=1
P 9.19 5.298 5 P 0 0;1,4=0,6=0
P 9.235 5.298 5 P 0 0;1,4=0,6=0
P 9.175 5.255 4 P 0 0;2,4=1,6=1
P 9.145 5.298 5 P 0 0;1,4=0,6=0
P 9.1 5.298 5 P 0 0;1,4=0,6=0
P 9.11853996 5.255 4 P 0 0;2,4=1,6=1
P 5.30875 2.4687 5 P 0 0;1,4=0,6=0
P 5.30875 2.1529 5 P 0 0;1,4=0,6=0
P 5.30875 2.1979 5 P 0 0;1,4=0,6=0
P 5.30875 2.2883 5 P 0 0;1,4=0,6=0
P 5.30875 2.3333 5 P 0 0;1,4=0,6=0
P 3.775 5.295 4 P 0 0;2,4=1,6=1
P 8.07 5.343 5 P 0 0;1,4=0,6=0
P 8.12 5.343 5 P 0 0;1,4=0,6=0
P 8.07 5.29 4 P 0 0;2,4=1,6=1
P 3.8399 4.765 4 P 0 0;2,4=1,6=1
P 7.955 5.343 5 P 0 0;1,4=0,6=0
P 8.005 5.343 5 P 0 0;1,4=0,6=0
P 8.005 5.29 4 P 0 0;2,4=1,6=1
P 11.62193002 1.65 5 P 0 0;1,4=0,6=0
P 5.30875 1.7371 5 P 0 0;1,4=0,6=0
P 5.30875 1.7821 5 P 0 0;1,4=0,6=0
P 5.30875 1.6458 5 P 0 0;1,4=0,6=0
P 5.30875 1.6008 5 P 0 0;1,4=0,6=0
P 5.46358002 1.7143 5 P 0 0;1,4=0,6=0
P 5.46358002 1.8083 5 P 0 0;1,4=0,6=0
P 7.85815 2.4781 5 P 0 0;1,4=0,6=0
P 7.90393996 2.48 4 P 0 0;2,4=2,6=1
P 11.31661998 2.73 5 P 0 0;1,4=0,6=0
P 11.43661998 2.73 5 P 0 0;1,4=0,6=0
P 11.27 2.73 4 P 0 0;2,4=2,6=1
P 11.31661998 2.8 5 P 0 0;1,4=0,6=0
P 11.43661998 2.8 5 P 0 0;1,4=0,6=0
P 11.27 2.8 4 P 0 0;2,4=2,6=1
P 11.65061998 2.785 5 P 0 0;1,4=0,6=0
P 11.72031004 2.82441004 7 P 0 0;1,4=3,6=0
P 11.555 2.82 4 P 0 0;2,4=2,6=1
P 11.65061998 2.905 5 P 0 0;1,4=0,6=0
P 11.72031004 2.87558996 7 P 0 0;1,4=3,6=0
P 11.56 2.945 4 P 0 0;2,4=2,6=1
P 9.64 0.71 4 P 0 0;2,4=1,6=1
P 9.43296004 0.49133002 4 P 0 0;2,4=1,6=1
P 9.43296004 0.73633002 4 P 0 0;2,4=1,6=1
P 9.55795 0.36633002 4 P 0 0;2,4=1,6=1
P 9.35796004 0.49133002 4 P 0 0;2,4=1,6=1
P 9.58296004 0.71133002 4 P 0 0;2,4=1,6=1
P 11.62193002 1.695 5 P 0 0;1,4=0,6=0
P 11.62193002 1.535 5 P 0 0;1,4=0,6=0
P 11.62193002 1.49 5 P 0 0;1,4=0,6=0
P 11.42193002 1.455 5 P 0 0;1,4=0,6=0
P 11.42193002 1.41 5 P 0 0;1,4=0,6=0
P 11.42193002 1.57 5 P 0 0;1,4=0,6=0
P 11.42193002 1.615 5 P 0 0;1,4=0,6=0
P 11.62193002 1.81 5 P 0 0;1,4=0,6=0
P 11.62193002 1.855 5 P 0 0;1,4=0,6=0
P 11.42193002 1.73 5 P 0 0;1,4=0,6=0
P 11.42193002 1.775 5 P 0 0;1,4=0,6=0
P 11.62193002 1.97 5 P 0 0;1,4=0,6=0
P 11.62193002 2.015 5 P 0 0;1,4=0,6=0
P 11.42193002 1.89 5 P 0 0;1,4=0,6=0
P 11.42193002 1.935 5 P 0 0;1,4=0,6=0
P 3.14146004 5.298 5 P 0 0;1,4=0,6=0
P 3.09646004 5.298 5 P 0 0;1,4=0,6=0
P 3.115 5.255 4 P 0 0;2,4=1,6=1
P 11.62193002 2.13 5 P 0 0;1,4=0,6=0
P 11.62193002 2.175 5 P 0 0;1,4=0,6=0
P 11.42193002 2.21 5 P 0 0;1,4=0,6=0
P 11.42193002 2.255 5 P 0 0;1,4=0,6=0
P 11.42193002 2.05 5 P 0 0;1,4=0,6=0
P 11.42193002 2.095 5 P 0 0;1,4=0,6=0
P 3.17146004 5.255 4 P 0 0;2,4=1,6=1
P 3.23146004 5.298 5 P 0 0;1,4=0,6=0
P 3.18646004 5.298 5 P 0 0;1,4=0,6=0
P 11.62193002 2.29 5 P 0 0;1,4=0,6=0
P 4 5.29 4 P 0 0;2,4=1,6=1
P 11.62193002 2.335 5 P 0 0;1,4=0,6=0
P 12.30501004 1.98958996 5 P 0 0;1,4=0,6=0
P 8.67478996 2.82 5 P 0 0;1,4=0,6=0
P 8.67478996 2.87 5 P 0 0;1,4=0,6=0
P 3.985 4.88998996 4 P 0 0;2,4=1,6=1
P 11.65593002 2.655 5 P 0 0;1,4=0,6=0
P 11.65593002 2.61 5 P 0 0;1,4=0,6=0
P 8.64078996 2.87 5 P 0 0;1,4=0,6=0
P 0.61698996 1.91181998 5 P 0 0;1,4=0,6=0
P 11.65593002 2.495 5 P 0 0;1,4=0,6=0
P 0.61698996 1.86181998 5 P 0 0;1,4=0,6=0
P 11.65593002 2.45 5 P 0 0;1,4=0,6=0
P 8.64078996 2.82 5 P 0 0;1,4=0,6=0
P 11.65593002 2.335 5 P 0 0;1,4=0,6=0
P 11.65593002 2.29 5 P 0 0;1,4=0,6=0
P 12.30501004 1.93958996 5 P 0 0;1,4=0,6=0
P 11.45593002 2.095 5 P 0 0;1,4=0,6=0
P 11.45593002 2.05 5 P 0 0;1,4=0,6=0
P 7.3226 4.94151004 5 P 0 0;1,4=0,6=0
P 7.3426 4.69351004 4 P 0 0;2,4=1,6=1
P 7.82693996 3.56 5 P 0 0;1,4=0,6=0
P 11.65593002 1.535 5 P 0 0;1,4=0,6=0
P 7.2726 4.94151004 5 P 0 0;1,4=0,6=0
P 7.2926 4.69351004 4 P 0 0;2,4=1,6=1
P 7.82693996 3.51 5 P 0 0;1,4=0,6=0
P 11.65593002 2.175 5 P 0 0;1,4=0,6=0
P 5.46358002 2.4953 5 P 0 0;1,4=0,6=0
P 11.65593002 2.13 5 P 0 0;1,4=0,6=0
P 2.67085 2.87 5 P 0 0;1,4=0,6=0
P 5.46358002 2.5403 5 P 0 0;1,4=0,6=0
P 12.342 2.11 5 P 0 0;1,4=0,6=0
P 2.67085 2.82 5 P 0 0;1,4=0,6=0
P 5.32386004 2.96 6 P 0 0;1,4=4,6=0
P 5.32386004 3.04 6 P 0 0;1,4=4,6=0
P 5.32386004 3.12 6 P 0 0;1,4=4,6=0
P 5.32386004 3.2 6 P 0 0;1,4=4,6=0
P 5.32386004 3.28 6 P 0 0;1,4=4,6=0
P 11.32778996 3.2 6 P 0 0;1,4=4,6=0
P 11.32778996 3.28 6 P 0 0;1,4=4,6=0
P 11.32778996 2.96 6 P 0 0;1,4=4,6=0
P 11.32778996 3.12 6 P 0 0;1,4=4,6=0
P 11.32778996 3.04 6 P 0 0;1,4=4,6=0
P 5.59778996 4.6352 6 P 0 0;1,4=4,6=0
P 5.67708996 4.6352 6 P 0 0;1,4=4,6=0
P 5.75708996 4.6352 6 P 0 0;1,4=4,6=0
P 5.83708996 4.6352 6 P 0 0;1,4=4,6=0
P 6.07708996 4.6352 6 P 0 0;1,4=4,6=0
P 5.91708996 4.6352 6 P 0 0;1,4=4,6=0
P 5.99708996 4.6352 6 P 0 0;1,4=4,6=0
P 6.19208996 4.7202 6 P 0 0;1,4=4,6=0
P 6.19208996 4.6402 6 P 0 0;1,4=4,6=0
P 6.19208996 4.8802 6 P 0 0;1,4=4,6=0
P 6.19208996 4.8002 6 P 0 0;1,4=4,6=0
P 6.09 4.925 4 P 0 0;2,4=2,6=1
P 5.46358002 2.3561 5 P 0 0;1,4=0,6=0
P 5.46358002 2.4011 5 P 0 0;1,4=0,6=0
P 5.30875 2.4237 5 P 0 0;1,4=0,6=0
P 11.65593002 2.015 5 P 0 0;1,4=0,6=0
P 11.65593002 1.97 5 P 0 0;1,4=0,6=0
P 11.45593002 1.73 5 P 0 0;1,4=0,6=0
P 11.45593002 1.775 5 P 0 0;1,4=0,6=0
P 11.65593002 1.855 5 P 0 0;1,4=0,6=0
P 11.65593002 1.81 5 P 0 0;1,4=0,6=0
P 5.46358002 1.9444 5 P 0 0;1,4=0,6=0
P 5.46358002 2.2207 5 P 0 0;1,4=0,6=0
P 5.72185 2.97441004 7 P 0 0;1,4=3
P 9.95743996 2.82441004 7 P 0 0;1,4=3
P 3.91351004 2.59441004 7 P 0 0;1,4=3
P 11.99518996 0.29 1 P 0 0;1,4=5
P 0.9211 0.2854 1 P 0 0;1,4=5
P 0.5836 5.36731998 1 P 0 0;1,4=5
P 0.5 -0.293 1 P 0 0;1,4=5
P 12.4252 6.31661998 1 P 0 0;1,4=5
P 0.5 6.31661998 1 P 0 0;1,4=5
P 12.4252 -0.293 1 P 0 0;1,4=5
L 1.88908002 -1.91246004 1.89293002 -1.91246004 0 P 0 
L 1.89126998 -1.91146004 1.89656998 -1.91146004 0 P 0 
L 1.89393996 -1.91046004 1.9155 -1.91046004 0 P 0 
L 1.91593996 -1.91246004 1.92048996 -1.91246004 0 P 0 
L 1.9126 -1.91146004 1.9184 -1.91146004 0 P 0 
L 1.89763002 -1.90946004 1.91016998 -1.90946004 0 P 0 
L 1.89053002 -1.96001004 1.8974 -1.96001004 0 P 0 
L 1.89053002 -1.95901004 1.8974 -1.95901004 0 P 0 
L 1.89053002 -1.95801004 1.8974 -1.95801004 0 P 0 
L 1.89053002 -1.95701004 1.8974 -1.95701004 0 P 0 
L 1.89053002 -1.95601004 1.8974 -1.95601004 0 P 0 
L 1.89053002 -1.95501004 1.8974 -1.95501004 0 P 0 
L 1.89053002 -1.95401004 1.8974 -1.95401004 0 P 0 
L 1.89053002 -1.95301004 1.89741004 -1.95301004 0 P 0 
L 1.89053002 -1.95201004 1.89741998 -1.95201004 0 P 0 
L 1.89053002 -1.95101004 1.89743996 -1.95101004 0 P 0 
L 1.89053002 -1.95001004 1.89745 -1.95001004 0 P 0 
L 1.89053002 -1.94901004 1.89746004 -1.94901004 0 P 0 
L 1.89053002 -1.94801004 1.89753002 -1.94801004 0 P 0 
L 1.89053002 -1.94701004 1.8977 -1.94701004 0 P 0 
L 1.89053002 -1.94601004 1.89798002 -1.94601004 0 P 0 
L 1.89053002 -1.94501004 1.89861004 -1.94501004 0 P 0 
L 1.89053002 -1.94401004 1.90005 -1.94401004 0 P 0 
L 1.89053002 -1.94301004 1.9113 -1.94301004 0 P 0 
L 1.89053002 -1.94201004 1.91168002 -1.94201004 0 P 0 
L 1.89053002 -1.94101004 1.91246998 -1.94101004 0 P 0 
L 1.89053002 -1.94001004 1.90093996 -1.94001004 0 P 0 
L 1.89053002 -1.93901004 1.89856004 -1.93901004 0 P 0 
L 1.89053002 -1.93801004 1.89786998 -1.93801004 0 P 0 
L 1.89053002 -1.93701004 1.89753996 -1.93701004 0 P 0 
L 1.89053002 -1.93601004 1.89746998 -1.93601004 0 P 0 
L 1.89053002 -1.93501004 1.89743996 -1.93501004 0 P 0 
L 1.89053002 -1.93401004 1.89741998 -1.93401004 0 P 0 
L 1.89053002 -1.93301004 1.8974 -1.93301004 0 P 0 
L 1.89053002 -1.93201004 1.8974 -1.93201004 0 P 0 
L 1.89053002 -1.93101004 1.8974 -1.93101004 0 P 0 
L 1.89053002 -1.93001004 1.8974 -1.93001004 0 P 0 
L 1.89053002 -1.92901004 1.8974 -1.92901004 0 P 0 
L 1.89053002 -1.92801004 1.89753002 -1.92801004 0 P 0 
L 1.89053002 -1.92701004 1.89793996 -1.92701004 0 P 0 
L 1.89053002 -1.92601004 1.91713002 -1.92601004 0 P 0 
L 1.89053002 -1.92501004 1.91628996 -1.92501004 0 P 0 
L 1.89053002 -1.92401004 1.91513996 -1.92401004 0 P 0 
L 1.89053002 -1.92301004 1.91321998 -1.92301004 0 P 0 
L 1.89053002 -1.92201004 1.90551004 -1.92201004 0 P 0 
L 1.89438996 -1.97246004 1.91331004 -1.97246004 0 P 0 
L 1.89106998 -1.97146004 1.89973002 -1.97146004 0 P 0 
L 1.88878002 -1.97046004 1.8949 -1.97046004 0 P 0 
L 1.88698002 -1.96946004 1.89206998 -1.96946004 0 P 0 
L 1.88546004 -1.96846004 1.88986998 -1.96846004 0 P 0 
L 1.88416998 -1.96746004 1.88808996 -1.96746004 0 P 0 
L 1.88288002 -1.96646004 1.88655 -1.96646004 0 P 0 
L 1.88176998 -1.96546004 1.88518002 -1.96546004 0 P 0 
L 1.88068996 -1.96446004 1.88393996 -1.96446004 0 P 0 
L 1.87968996 -1.96346004 1.88286004 -1.96346004 0 P 0 
L 1.87878002 -1.96246004 1.88186004 -1.96246004 0 P 0 
L 1.8786 -1.92046004 1.88126998 -1.92046004 0 P 0 
L 1.87946998 -1.91946004 1.88223002 -1.91946004 0 P 0 
L 1.88048002 -1.91846004 1.88321004 -1.91846004 0 P 0 
L 1.88153996 -1.91746004 1.88436998 -1.91746004 0 P 0 
L 1.88273002 -1.91646004 1.88558996 -1.91646004 0 P 0 
L 1.88406004 -1.91546004 1.88696998 -1.91546004 0 P 0 
L 1.88548996 -1.91446004 1.88853002 -1.91446004 0 P 0 
L 1.88718002 -1.91346004 1.89041998 -1.91346004 0 P 0 
L 1.90896004 -1.92963996 1.90921998 -1.92991998 0 P 0 
L 1.90921998 -1.92991998 1.90945 -1.93021998 0 P 0 
L 1.90945 -1.93021998 1.90966004 -1.93053002 0 P 0 
L 1.90966004 -1.93053002 1.90983002 -1.93086004 0 P 0 
L 1.90983002 -1.93086004 1.90998002 -1.93121004 0 P 0 
L 1.90998002 -1.93121004 1.9101 -1.93156998 0 P 0 
L 1.9101 -1.93156998 1.91018996 -1.93193996 0 P 0 
L 1.91018996 -1.93193996 1.91023996 -1.93231004 0 P 0 
L 1.91023996 -1.93231004 1.91026998 -1.93265 0 P 0 
L 1.91026998 -1.93265 1.91026004 -1.93298002 0 P 0 
L 1.91026004 -1.93298002 1.91023002 -1.93331004 0 P 0 
L 1.91023002 -1.93331004 1.91016998 -1.93363996 0 P 0 
L 1.91016998 -1.93363996 1.91008996 -1.93396004 0 P 0 
L 1.91008996 -1.93396004 1.90998002 -1.93428002 0 P 0 
L 1.90998002 -1.93428002 1.90983996 -1.93458002 0 P 0 
L 1.90983996 -1.93458002 1.90968996 -1.93486998 0 P 0 
L 1.90968996 -1.93486998 1.90951004 -1.93516004 0 P 0 
L 1.90951004 -1.93516004 1.90921004 -1.93556004 0 P 0 
L 1.90921004 -1.93556004 1.90888002 -1.93593002 0 P 0 
L 1.90888002 -1.93593002 1.90853002 -1.93626998 0 P 0 
L 1.90853002 -1.93626998 1.90815 -1.93658996 0 P 0 
L 1.90815 -1.93658996 1.90773996 -1.93686998 0 P 0 
L 1.90773996 -1.93686998 1.90731998 -1.93711998 0 P 0 
L 1.90731998 -1.93711998 1.90686998 -1.93733996 0 P 0 
L 1.90686998 -1.93733996 1.90615 -1.93761004 0 P 0 
L 1.90615 -1.93761004 1.90541998 -1.93783002 0 P 0 
L 1.90541998 -1.93783002 1.90466004 -1.93798002 0 P 0 
L 1.90466004 -1.93798002 1.9039 -1.93808002 0 P 0 
L 1.9039 -1.93808002 1.90311998 -1.9381 0 P 0 
L 1.90311998 -1.9381 1.90196004 -1.93808002 0 P 0 
L 1.90196004 -1.93808002 1.90078996 -1.93798996 0 P 0 
L 1.90078996 -1.93798996 1.90068002 -1.93798002 0 P 0 
L 1.90068002 -1.93798002 1.90058002 -1.93795 0 P 0 
L 1.90058002 -1.93795 1.90046998 -1.93791998 0 P 0 
L 1.90046998 -1.93791998 1.90038002 -1.93788002 0 P 0 
L 1.90038002 -1.93788002 1.90028002 -1.93783002 0 P 0 
L 1.90028002 -1.93783002 1.90018996 -1.93778002 0 P 0 
L 1.90018996 -1.93778002 1.9001 -1.93771004 0 P 0 
L 1.9001 -1.93771004 1.90001998 -1.93763996 0 P 0 
L 1.90001998 -1.93763996 1.89988002 -1.93748002 0 P 0 
L 1.89988002 -1.93748002 1.89978002 -1.93733996 0 P 0 
L 1.89978002 -1.93733996 1.89961998 -1.93703996 0 P 0 
L 1.89961998 -1.93703996 1.89956998 -1.93688002 0 P 0 
L 1.89956998 -1.93688002 1.89951998 -1.93671004 0 P 0 
L 1.89951998 -1.93671004 1.89948996 -1.93655 0 P 0 
L 1.89948996 -1.93655 1.89946998 -1.93636998 0 P 0 
L 1.89946998 -1.93636998 1.8994 -1.93323002 0 P 0 
L 1.8994 -1.93323002 1.8994 -1.92833002 0 P 0 
L 1.8994 -1.92833002 1.90353996 -1.92833002 0 P 0 
L 1.90353996 -1.92833002 1.90436998 -1.92835 0 P 0 
L 1.90436998 -1.92835 1.9052 -1.92843002 0 P 0 
L 1.9052 -1.92843002 1.90603002 -1.92853996 0 P 0 
L 1.90603002 -1.92853996 1.90683996 -1.92871004 0 P 0 
L 1.90683996 -1.92871004 1.90751004 -1.9289 0 P 0 
L 1.90751004 -1.9289 1.90818002 -1.92913002 0 P 0 
L 1.90818002 -1.92913002 1.90851998 -1.92928996 0 P 0 
L 1.90851998 -1.92928996 1.90868002 -1.92938996 0 P 0 
L 1.90868002 -1.92938996 1.90883002 -1.92951004 0 P 0 
L 1.90883002 -1.92951004 1.90896004 -1.92963996 0 P 0 
L 1.91188996 -1.96001004 1.91638996 -1.96001004 0 P 0 
L 1.91156998 -1.95901004 1.91926998 -1.95901004 0 P 0 
L 1.91125 -1.95801004 1.91891998 -1.95801004 0 P 0 
L 1.91091998 -1.95701004 1.91853002 -1.95701004 0 P 0 
L 1.9106 -1.95601004 1.91811004 -1.95601004 0 P 0 
L 1.91025 -1.95501004 1.91765 -1.95501004 0 P 0 
L 1.90988996 -1.95401004 1.91718996 -1.95401004 0 P 0 
L 1.90953002 -1.95301004 1.91673002 -1.95301004 0 P 0 
L 1.90918002 -1.95201004 1.91626998 -1.95201004 0 P 0 
L 1.90881998 -1.95101004 1.91576004 -1.95101004 0 P 0 
L 1.90841004 -1.95001004 1.91523996 -1.95001004 0 P 0 
L 1.90793996 -1.94901004 1.91471004 -1.94901004 0 P 0 
L 1.90738996 -1.94801004 1.91418002 -1.94801004 0 P 0 
L 1.90676998 -1.94701004 1.9136 -1.94701004 0 P 0 
L 1.90598996 -1.94601004 1.91261004 -1.94601004 0 P 0 
L 1.90495 -1.94501004 1.91175 -1.94501004 0 P 0 
L 1.90325 -1.94401004 1.91133002 -1.94401004 0 P 0 
L 1.90456004 -1.94001004 1.91383002 -1.94001004 0 P 0 
L 1.90801004 -1.93901004 1.91523002 -1.93901004 0 P 0 
L 1.90956998 -1.93801004 1.91635 -1.93801004 0 P 0 
L 1.9106 -1.93701004 1.91718002 -1.93701004 0 P 0 
L 1.91133996 -1.93601004 1.91781004 -1.93601004 0 P 0 
L 1.91183996 -1.93501004 1.91826004 -1.93501004 0 P 0 
L 1.91213002 -1.93401004 1.9186 -1.93401004 0 P 0 
L 1.91226004 -1.93301004 1.9188 -1.93301004 0 P 0 
L 1.91221998 -1.93201004 1.9189 -1.93201004 0 P 0 
L 1.91201998 -1.93101004 1.9189 -1.93101004 0 P 0 
L 1.91163996 -1.93001004 1.91878996 -1.93001004 0 P 0 
L 1.91105 -1.92901004 1.91856998 -1.92901004 0 P 0 
L 1.91013996 -1.92801004 1.91823002 -1.92801004 0 P 0 
L 1.90816998 -1.92701004 1.91776004 -1.92701004 0 P 0 
L 1.90313996 -1.94011004 1.90316998 -1.9401 0 P 0 
L 1.90316998 -1.9401 1.9032 -1.9401 0 P 0 
L 1.9032 -1.9401 1.90398002 -1.94006998 0 P 0 
L 1.90398002 -1.94006998 1.90406004 -1.94006998 0 P 0 
L 1.90406004 -1.94006998 1.90413996 -1.94006004 0 P 0 
L 1.90413996 -1.94006004 1.9049 -1.93996998 0 P 0 
L 1.9049 -1.93996998 1.90493996 -1.93996004 0 P 0 
L 1.90493996 -1.93996004 1.90498996 -1.93996004 0 P 0 
L 1.90498996 -1.93996004 1.90506998 -1.93993996 0 P 0 
L 1.90506998 -1.93993996 1.90581998 -1.93978002 0 P 0 
L 1.90581998 -1.93978002 1.90586004 -1.93978002 0 P 0 
L 1.90586004 -1.93978002 1.90593996 -1.93976004 0 P 0 
L 1.90593996 -1.93976004 1.90596998 -1.93973996 0 P 0 
L 1.90596998 -1.93973996 1.90671004 -1.93953002 0 P 0 
L 1.90671004 -1.93953002 1.90678996 -1.93951004 0 P 0 
L 1.90678996 -1.93951004 1.90758996 -1.93921004 0 P 0 
L 1.90758996 -1.93921004 1.90766004 -1.93916998 0 P 0 
L 1.90766004 -1.93916998 1.9077 -1.93915 0 P 0 
L 1.9077 -1.93915 1.90773996 -1.93913996 0 P 0 
L 1.90773996 -1.93913996 1.90818996 -1.93891998 0 P 0 
L 1.90818996 -1.93891998 1.90821998 -1.9389 0 P 0 
L 1.90821998 -1.9389 1.90826004 -1.93888996 0 P 0 
L 1.90826004 -1.93888996 1.90828996 -1.93886998 0 P 0 
L 1.90828996 -1.93886998 1.90833002 -1.93885 0 P 0 
L 1.90833002 -1.93885 1.90875 -1.9386 0 P 0 
L 1.90875 -1.9386 1.90883002 -1.93856004 0 P 0 
L 1.90883002 -1.93856004 1.90888996 -1.93851004 0 P 0 
L 1.90888996 -1.93851004 1.90928996 -1.93823002 0 P 0 
L 1.90928996 -1.93823002 1.90933002 -1.9382 0 P 0 
L 1.90933002 -1.9382 1.90936004 -1.93818002 0 P 0 
L 1.90936004 -1.93818002 1.90938996 -1.93815 0 P 0 
L 1.90938996 -1.93815 1.90941998 -1.93813002 0 P 0 
L 1.90941998 -1.93813002 1.9098 -1.93781998 0 P 0 
L 1.9098 -1.93781998 1.90986004 -1.93776004 0 P 0 
L 1.90986004 -1.93776004 1.90988996 -1.93773996 0 P 0 
L 1.90988996 -1.93773996 1.90991998 -1.93771004 0 P 0 
L 1.90991998 -1.93771004 1.91028002 -1.93736004 0 P 0 
L 1.91028002 -1.93736004 1.91038996 -1.93725 0 P 0 
L 1.91038996 -1.93725 1.91071004 -1.93688002 0 P 0 
L 1.91071004 -1.93688002 1.91073996 -1.93685 0 P 0 
L 1.91073996 -1.93685 1.91116004 -1.9363 0 P 0 
L 1.91116004 -1.9363 1.9112 -1.93623002 0 P 0 
L 1.9112 -1.93623002 1.91138002 -1.93595 0 P 0 
L 1.91138002 -1.93595 1.9114 -1.93591004 0 P 0 
L 1.9114 -1.93591004 1.91143996 -1.93585 0 P 0 
L 1.91143996 -1.93585 1.91146004 -1.93581004 0 P 0 
L 1.91146004 -1.93581004 1.91161004 -1.93551998 0 P 0 
L 1.91161004 -1.93551998 1.91163002 -1.93548996 0 P 0 
L 1.91163002 -1.93548996 1.91165 -1.93545 0 P 0 
L 1.91165 -1.93545 1.91166004 -1.93541004 0 P 0 
L 1.91166004 -1.93541004 1.91168002 -1.93538002 0 P 0 
L 1.91168002 -1.93538002 1.91181004 -1.93506998 0 P 0 
L 1.91181004 -1.93506998 1.91183996 -1.935 0 P 0 
L 1.91183996 -1.935 1.91186004 -1.93496004 0 P 0 
L 1.91186004 -1.93496004 1.91186998 -1.93493002 0 P 0 
L 1.91186998 -1.93493002 1.91198002 -1.93461004 0 P 0 
L 1.91198002 -1.93461004 1.91198996 -1.93456998 0 P 0 
L 1.91198996 -1.93456998 1.912 -1.93453996 0 P 0 
L 1.912 -1.93453996 1.9121 -1.93413996 0 P 0 
L 1.9121 -1.93413996 1.91211998 -1.9341 0 P 0 
L 1.91211998 -1.9341 1.91211998 -1.93406004 0 P 0 
L 1.91211998 -1.93406004 1.91213002 -1.93401998 0 P 0 
L 1.91213002 -1.93401998 1.91213996 -1.93398996 0 P 0 
L 1.91213996 -1.93398996 1.9122 -1.93366004 0 P 0 
L 1.9122 -1.93366004 1.91221004 -1.93358002 0 P 0 
L 1.91221004 -1.93358002 1.91221004 -1.93353996 0 P 0 
L 1.91221004 -1.93353996 1.91221998 -1.9335 0 P 0 
L 1.91221998 -1.9335 1.91225 -1.93316998 0 P 0 
L 1.91225 -1.93316998 1.91226004 -1.93308996 0 P 0 
L 1.91226004 -1.93308996 1.91226004 -1.93268002 0 P 0 
L 1.91226004 -1.93268002 1.91226998 -1.93263996 0 P 0 
L 1.91226998 -1.93263996 1.91226998 -1.9326 0 P 0 
L 1.91226998 -1.9326 1.91226004 -1.93251998 0 P 0 
L 1.91226004 -1.93251998 1.91223996 -1.93218996 0 P 0 
L 1.91223996 -1.93218996 1.91223996 -1.93215 0 P 0 
L 1.91223996 -1.93215 1.91223002 -1.9321 0 P 0 
L 1.91223002 -1.9321 1.91223002 -1.93206004 0 P 0 
L 1.91223002 -1.93206004 1.91221998 -1.93201998 0 P 0 
L 1.91221998 -1.93201998 1.91216998 -1.93163996 0 P 0 
L 1.91216998 -1.93163996 1.91216004 -1.9316 0 P 0 
L 1.91216004 -1.9316 1.91213996 -1.93151004 0 P 0 
L 1.91213996 -1.93151004 1.91213002 -1.93146998 0 P 0 
L 1.91213002 -1.93146998 1.91205 -1.93111004 0 P 0 
L 1.91205 -1.93111004 1.91203996 -1.93106004 0 P 0 
L 1.91203996 -1.93106004 1.91203002 -1.93101998 0 P 0 
L 1.91203002 -1.93101998 1.91201004 -1.93098002 0 P 0 
L 1.91201004 -1.93098002 1.912 -1.93093996 0 P 0 
L 1.912 -1.93093996 1.91188002 -1.93058002 0 P 0 
L 1.91188002 -1.93058002 1.91186998 -1.93053996 0 P 0 
L 1.91186998 -1.93053996 1.91185 -1.9305 0 P 0 
L 1.91185 -1.9305 1.91183996 -1.93046004 0 P 0 
L 1.91183996 -1.93046004 1.91181998 -1.93043002 0 P 0 
L 1.91181998 -1.93043002 1.91166998 -1.93008002 0 P 0 
L 1.91166998 -1.93008002 1.91166004 -1.93003996 0 P 0 
L 1.91166004 -1.93003996 1.9116 -1.92991998 0 P 0 
L 1.9116 -1.92991998 1.91141998 -1.92958996 0 P 0 
L 1.91141998 -1.92958996 1.9114 -1.92955 0 P 0 
L 1.9114 -1.92955 1.91138002 -1.92951998 0 P 0 
L 1.91138002 -1.92951998 1.91133002 -1.92945 0 P 0 
L 1.91133002 -1.92945 1.91113002 -1.92913002 0 P 0 
L 1.91113002 -1.92913002 1.91111004 -1.92908996 0 P 0 
L 1.91111004 -1.92908996 1.91108996 -1.92906004 0 P 0 
L 1.91108996 -1.92906004 1.91106004 -1.92901998 0 P 0 
L 1.91106004 -1.92901998 1.91103002 -1.92898996 0 P 0 
L 1.91103002 -1.92898996 1.9108 -1.92868996 0 P 0 
L 1.9108 -1.92868996 1.91076998 -1.92866004 0 P 0 
L 1.91076998 -1.92866004 1.91075 -1.92861998 0 P 0 
L 1.91075 -1.92861998 1.91068996 -1.92856004 0 P 0 
L 1.91068996 -1.92856004 1.91043002 -1.92828002 0 P 0 
L 1.91043002 -1.92828002 1.91035 -1.9282 0 P 0 
L 1.91035 -1.9282 1.91033002 -1.92816998 0 P 0 
L 1.91033002 -1.92816998 1.91018996 -1.92803996 0 P 0 
L 1.91018996 -1.92803996 1.91018002 -1.92803996 0 P 0 
L 1.91018002 -1.92803996 1.91016004 -1.92801998 0 P 0 
L 1.91016004 -1.92801998 1.91011998 -1.92798996 0 P 0 
L 1.91011998 -1.92798996 1.91006004 -1.92793002 0 P 0 
L 1.91006004 -1.92793002 1.90991004 -1.92781998 0 P 0 
L 1.90991004 -1.92781998 1.90988002 -1.9278 0 P 0 
L 1.90988002 -1.9278 1.90983996 -1.92776998 0 P 0 
L 1.90983996 -1.92776998 1.90976998 -1.92771998 0 P 0 
L 1.90976998 -1.92771998 1.90961004 -1.92761998 0 P 0 
L 1.90961004 -1.92761998 1.90953996 -1.92756998 0 P 0 
L 1.90953996 -1.92756998 1.9095 -1.92755 0 P 0 
L 1.9095 -1.92755 1.90946998 -1.92753002 0 P 0 
L 1.90946998 -1.92753002 1.9093 -1.92743996 0 P 0 
L 1.9093 -1.92743996 1.90926004 -1.92741998 0 P 0 
L 1.90926004 -1.92741998 1.90923002 -1.9274 0 P 0 
L 1.90923002 -1.9274 1.90915 -1.92736998 0 P 0 
L 1.90915 -1.92736998 1.90896998 -1.92728996 0 P 0 
L 1.90896998 -1.92728996 1.90893996 -1.92728002 0 P 0 
L 1.90893996 -1.92728002 1.9089 -1.92726004 0 P 0 
L 1.9089 -1.92726004 1.90886998 -1.92725 0 P 0 
L 1.90886998 -1.92725 1.90883002 -1.92723996 0 P 0 
L 1.90883002 -1.92723996 1.90816004 -1.92701004 0 P 0 
L 1.90816004 -1.92701004 1.90813996 -1.927 0 P 0 
L 1.90813996 -1.927 1.9081 -1.92698996 0 P 0 
L 1.9081 -1.92698996 1.90803996 -1.92696998 0 P 0 
L 1.90803996 -1.92696998 1.90736998 -1.92678002 0 P 0 
L 1.90736998 -1.92678002 1.90723996 -1.92675 0 P 0 
L 1.90723996 -1.92675 1.90643002 -1.92658996 0 P 0 
L 1.90643002 -1.92658996 1.90636998 -1.92656998 0 P 0 
L 1.90636998 -1.92656998 1.90633996 -1.92656998 0 P 0 
L 1.90633996 -1.92656998 1.90631004 -1.92656004 0 P 0 
L 1.90631004 -1.92656004 1.90548996 -1.92645 0 P 0 
L 1.90548996 -1.92645 1.90543996 -1.92643996 0 P 0 
L 1.90543996 -1.92643996 1.9054 -1.92643002 0 P 0 
L 1.9054 -1.92643002 1.90538002 -1.92643002 0 P 0 
L 1.90538002 -1.92643002 1.90455 -1.92636004 0 P 0 
L 1.90455 -1.92636004 1.90443002 -1.92636004 0 P 0 
L 1.90443002 -1.92636004 1.9036 -1.92633002 0 P 0 
L 1.9036 -1.92633002 1.8994 -1.92633002 0 P 0 
L 1.8994 -1.92633002 1.89798002 -1.92691004 0 P 0 
L 1.89798002 -1.92691004 1.8974 -1.92833002 0 P 0 
L 1.8974 -1.92833002 1.8974 -1.93328002 0 P 0 
L 1.8974 -1.93328002 1.89748002 -1.93643002 0 P 0 
L 1.89748002 -1.93643002 1.89748002 -1.93656004 0 P 0 
L 1.89748002 -1.93656004 1.8975 -1.93673002 0 P 0 
L 1.8975 -1.93673002 1.89751004 -1.93681004 0 P 0 
L 1.89751004 -1.93681004 1.89751998 -1.9369 0 P 0 
L 1.89751998 -1.9369 1.89755 -1.93706004 0 P 0 
L 1.89755 -1.93706004 1.89758002 -1.93718996 0 P 0 
L 1.89758002 -1.93718996 1.89758996 -1.93723002 0 P 0 
L 1.89758996 -1.93723002 1.89763002 -1.9374 0 P 0 
L 1.89763002 -1.9374 1.89763996 -1.93743996 0 P 0 
L 1.89763996 -1.93743996 1.89766004 -1.93748002 0 P 0 
L 1.89766004 -1.93748002 1.89768002 -1.93756004 0 P 0 
L 1.89768002 -1.93756004 1.89773996 -1.93771998 0 P 0 
L 1.89773996 -1.93771998 1.89776004 -1.93776004 0 P 0 
L 1.89776004 -1.93776004 1.89776998 -1.9378 0 P 0 
L 1.89776998 -1.9378 1.89781004 -1.93788002 0 P 0 
L 1.89781004 -1.93788002 1.89788002 -1.93803996 0 P 0 
L 1.89788002 -1.93803996 1.8979 -1.93808002 0 P 0 
L 1.8979 -1.93808002 1.89791998 -1.93811004 0 P 0 
L 1.89791998 -1.93811004 1.89796004 -1.93818996 0 P 0 
L 1.89796004 -1.93818996 1.89803996 -1.93833996 0 P 0 
L 1.89803996 -1.93833996 1.89813996 -1.93848002 0 P 0 
L 1.89813996 -1.93848002 1.89823002 -1.93861998 0 P 0 
L 1.89823002 -1.93861998 1.89828002 -1.93868996 0 P 0 
L 1.89828002 -1.93868996 1.89831004 -1.93873002 0 P 0 
L 1.89831004 -1.93873002 1.89833996 -1.93876004 0 P 0 
L 1.89833996 -1.93876004 1.8984 -1.93883996 0 P 0 
L 1.8984 -1.93883996 1.89848996 -1.93893002 0 P 0 
L 1.89848996 -1.93893002 1.89851004 -1.93896004 0 P 0 
L 1.89851004 -1.93896004 1.89868002 -1.93913002 0 P 0 
L 1.89868002 -1.93913002 1.89871004 -1.93915 0 P 0 
L 1.89871004 -1.93915 1.89878996 -1.93921998 0 P 0 
L 1.89878996 -1.93921998 1.89885 -1.93928002 0 P 0 
L 1.89885 -1.93928002 1.89888002 -1.9393 0 P 0 
L 1.89888002 -1.9393 1.89891998 -1.93931998 0 P 0 
L 1.89891998 -1.93931998 1.89901004 -1.93938996 0 P 0 
L 1.89901004 -1.93938996 1.89903996 -1.93941004 0 P 0 
L 1.89903996 -1.93941004 1.89906998 -1.93943996 0 P 0 
L 1.89906998 -1.93943996 1.8991 -1.93946004 0 P 0 
L 1.8991 -1.93946004 1.89913996 -1.93948002 0 P 0 
L 1.89913996 -1.93948002 1.89923002 -1.93953996 0 P 0 
L 1.89923002 -1.93953996 1.89926998 -1.93956004 0 P 0 
L 1.89926998 -1.93956004 1.8993 -1.93958002 0 P 0 
L 1.8993 -1.93958002 1.89933996 -1.9396 0 P 0 
L 1.89933996 -1.9396 1.89936998 -1.93961004 0 P 0 
L 1.89936998 -1.93961004 1.89938002 -1.93961004 0 P 0 
L 1.89938002 -1.93961004 1.89946998 -1.93966004 0 P 0 
L 1.89946998 -1.93966004 1.89953996 -1.9397 0 P 0 
L 1.89953996 -1.9397 1.89971998 -1.93976998 0 P 0 
L 1.89971998 -1.93976998 1.89975 -1.93978996 0 P 0 
L 1.89975 -1.93978996 1.89978996 -1.9398 0 P 0 
L 1.89978996 -1.9398 1.89986998 -1.93983002 0 P 0 
L 1.89986998 -1.93983002 1.89996998 -1.93986004 0 P 0 
L 1.89996998 -1.93986004 1.90001004 -1.93986998 0 P 0 
L 1.90001004 -1.93986998 1.90005 -1.93988996 0 P 0 
L 1.90005 -1.93988996 1.90013002 -1.9399 0 P 0 
L 1.90013002 -1.9399 1.90023002 -1.93993002 0 P 0 
L 1.90023002 -1.93993002 1.90023996 -1.93993002 0 P 0 
L 1.90023996 -1.93993002 1.90028002 -1.93993996 0 P 0 
L 1.90028002 -1.93993996 1.90031004 -1.93995 0 P 0 
L 1.90031004 -1.93995 1.90036004 -1.93995 0 P 0 
L 1.90036004 -1.93995 1.9004 -1.93996004 0 P 0 
L 1.9004 -1.93996004 1.9005 -1.93996998 0 P 0 
L 1.9005 -1.93996998 1.90061004 -1.93998996 0 P 0 
L 1.90061004 -1.93998996 1.90063996 -1.93998996 0 P 0 
L 1.90063996 -1.93998996 1.90181004 -1.94006998 0 P 0 
L 1.90181004 -1.94006998 1.90183996 -1.94008002 0 P 0 
L 1.90183996 -1.94008002 1.90191004 -1.94008002 0 P 0 
L 1.90191004 -1.94008002 1.90308002 -1.9401 0 P 0 
L 1.90308002 -1.9401 1.90311004 -1.9401 0 P 0 
L 1.90311004 -1.9401 1.90313996 -1.94011004 0 P 0 
L 1.90841004 -1.97146004 1.91683996 -1.97146004 0 P 0 
L 1.9135 -1.97046004 1.91931004 -1.97046004 0 P 0 
L 1.91655 -1.96946004 1.92131004 -1.96946004 0 P 0 
L 1.91891998 -1.96846004 1.92301004 -1.96846004 0 P 0 
L 1.92088996 -1.96746004 1.9245 -1.96746004 0 P 0 
L 1.92251004 -1.96646004 1.9258 -1.96646004 0 P 0 
L 1.92391004 -1.96546004 1.92696004 -1.96546004 0 P 0 
L 1.92513002 -1.96446004 1.92803002 -1.96446004 0 P 0 
L 1.9262 -1.96346004 1.92898996 -1.96346004 0 P 0 
L 1.92713996 -1.96246004 1.92986004 -1.96246004 0 P 0 
L 1.928 -1.96146004 1.93068996 -1.96146004 0 P 0 
L 1.92878002 -1.96046004 1.93143002 -1.96046004 0 P 0 
L 1.92951004 -1.95946004 1.93216004 -1.95946004 0 P 0 
L 1.93016998 -1.95846004 1.93278996 -1.95846004 0 P 0 
L 1.93078002 -1.95746004 1.93341004 -1.95746004 0 P 0 
L 1.93133002 -1.95646004 1.93396004 -1.95646004 0 P 0 
L 1.93185 -1.95546004 1.93448996 -1.95546004 0 P 0 
L 1.93231004 -1.95446004 1.93495 -1.95446004 0 P 0 
L 1.93275 -1.95346004 1.93541004 -1.95346004 0 P 0 
L 1.93311998 -1.95246004 1.93586004 -1.95246004 0 P 0 
L 1.93348002 -1.95146004 1.93628996 -1.95146004 0 P 0 
L 1.93376998 -1.95046004 1.93666004 -1.95046004 0 P 0 
L 1.93405 -1.94946004 1.93693002 -1.94946004 0 P 0 
L 1.93428002 -1.94846004 1.93715 -1.94846004 0 P 0 
L 1.93446998 -1.94746004 1.93733002 -1.94746004 0 P 0 
L 1.93466004 -1.94646004 1.93743002 -1.94646004 0 P 0 
L 1.93478996 -1.94546004 1.93748996 -1.94546004 0 P 0 
L 1.9349 -1.94446998 1.93751998 -1.94446998 0 P 0 
L 1.93496998 -1.94346004 1.93755 -1.94346004 0 P 0 
L 1.93501998 -1.94246004 1.93758002 -1.94246004 0 P 0 
L 1.93505 -1.94146998 1.93758996 -1.94146998 0 P 0 
L 1.93503002 -1.94046004 1.93755 -1.94046004 0 P 0 
L 1.935 -1.93946004 1.93751998 -1.93946004 0 P 0 
L 1.93491998 -1.93846004 1.93748002 -1.93846004 0 P 0 
L 1.93481004 -1.93746004 1.93738996 -1.93746004 0 P 0 
L 1.93468996 -1.93646004 1.93726998 -1.93646004 0 P 0 
L 1.93451004 -1.93546004 1.93716004 -1.93546004 0 P 0 
L 1.93433002 -1.93446004 1.93703996 -1.93446004 0 P 0 
L 1.93408996 -1.93346004 1.93685 -1.93346004 0 P 0 
L 1.93383002 -1.93246004 1.93666004 -1.93246004 0 P 0 
L 1.93353002 -1.93146004 1.93638996 -1.93146004 0 P 0 
L 1.9332 -1.93046004 1.93611998 -1.93046004 0 P 0 
L 1.93283996 -1.92946004 1.93576998 -1.92946004 0 P 0 
L 1.93241004 -1.92846004 1.93541004 -1.92846004 0 P 0 
L 1.93198996 -1.92746004 1.93498002 -1.92746004 0 P 0 
L 1.93146998 -1.92646004 1.93451004 -1.92646004 0 P 0 
L 1.93096004 -1.92546004 1.93398002 -1.92546004 0 P 0 
L 1.93035 -1.92446998 1.93338002 -1.92446998 0 P 0 
L 1.92973002 -1.92346004 1.93275 -1.92346004 0 P 0 
L 1.92903002 -1.92246004 1.93201004 -1.92246004 0 P 0 
L 1.92831004 -1.92146004 1.93125 -1.92146004 0 P 0 
L 1.92746998 -1.92046004 1.93041004 -1.92046004 0 P 0 
L 1.92661004 -1.91946004 1.92948996 -1.91946004 0 P 0 
L 1.92558996 -1.91846004 1.92851004 -1.91846004 0 P 0 
L 1.9245 -1.91746004 1.92741998 -1.91746004 0 P 0 
L 1.92328996 -1.91646004 1.92621998 -1.91646004 0 P 0 
L 1.92188002 -1.91546004 1.92491998 -1.91546004 0 P 0 
L 1.92026004 -1.91446004 1.92358996 -1.91446004 0 P 0 
L 1.91835 -1.91346004 1.92208002 -1.91346004 0 P 0 
L 1.82446998 -2.08323996 1.87608002 -2.08323996 0 P 0 
L 1.82403002 -2.08223996 1.87601004 -2.08223996 0 P 0 
L 1.8234 -2.08123996 1.87591004 -2.08123996 0 P 0 
L 1.82256004 -2.08023996 1.87578002 -2.08023996 0 P 0 
L 1.82166004 -2.07923996 1.87558996 -2.07923996 0 P 0 
L 1.82061998 -2.07823996 1.87533002 -2.07823996 0 P 0 
L 1.81946004 -2.07723996 1.87498996 -2.07723996 0 P 0 
L 1.81818002 -2.07623996 1.8746 -2.07623996 0 P 0 
L 1.8168 -2.07523996 1.87416998 -2.07523996 0 P 0 
L 1.81541998 -2.07423996 1.87371004 -2.07423996 0 P 0 
L 1.81403002 -2.07323996 1.87316998 -2.07323996 0 P 0 
L 1.81265 -2.07223996 1.87261004 -2.07223996 0 P 0 
L 1.81126998 -2.07123996 1.87196004 -2.07123996 0 P 0 
L 1.80986004 -2.07023996 1.87128002 -2.07023996 0 P 0 
L 1.80843996 -2.06923996 1.87051998 -2.06923996 0 P 0 
L 1.80703002 -2.06823996 1.8697 -2.06823996 0 P 0 
L 1.80561004 -2.06723996 1.86883002 -2.06723996 0 P 0 
L 1.8042 -2.06623996 1.86796004 -2.06623996 0 P 0 
L 1.80278002 -2.06523996 1.86705 -2.06523996 0 P 0 
L 1.80136004 -2.06423996 1.86608002 -2.06423996 0 P 0 
L 1.79995 -2.06323996 1.8651 -2.06323996 0 P 0 
L 1.79865 -2.06223996 1.86411004 -2.06223996 0 P 0 
L 1.79735 -2.06123996 1.86301998 -2.06123996 0 P 0 
L 1.79605 -2.06023996 1.86193002 -2.06023996 0 P 0 
L 1.79475 -2.05923996 1.86083996 -2.05923996 0 P 0 
L 1.79345 -2.05823996 1.85966998 -2.05823996 0 P 0 
L 1.79215 -2.05723996 1.85846004 -2.05723996 0 P 0 
L 1.79088002 -2.05623996 1.85726004 -2.05623996 0 P 0 
L 1.78971998 -2.05523996 1.85598996 -2.05523996 0 P 0 
L 1.78856004 -2.05423996 1.85461998 -2.05423996 0 P 0 
L 1.7874 -2.05323996 1.85326004 -2.05323996 0 P 0 
L 1.78623002 -2.05223996 1.8519 -2.05223996 0 P 0 
L 1.78506998 -2.05123996 1.85053996 -2.05123996 0 P 0 
L 1.78398002 -2.05023996 1.84918002 -2.05023996 0 P 0 
L 1.783 -2.04923996 1.84781004 -2.04923996 0 P 0 
L 1.87086004 -2.03023996 1.87535 -2.03023996 0 P 0 
L 1.91633002 -1.91473002 1.9183 -1.91565 0 P 0 
L 1.9183 -1.91565 1.92018996 -1.91673002 0 P 0 
L 1.92018996 -1.91673002 1.92196998 -1.91796998 0 P 0 
L 1.92196998 -1.91796998 1.92365 -1.91936004 0 P 0 
L 1.92365 -1.91936004 1.9252 -1.92088002 0 P 0 
L 1.9252 -1.92088002 1.92661004 -1.92253996 0 P 0 
L 1.92661004 -1.92253996 1.92795 -1.92436998 0 P 0 
L 1.92795 -1.92436998 1.92913996 -1.9263 0 P 0 
L 1.92913996 -1.9263 1.93018002 -1.92831998 0 P 0 
L 1.93018002 -1.92831998 1.93106998 -1.93041004 0 P 0 
L 1.93106998 -1.93041004 1.93178996 -1.93256004 0 P 0 
L 1.93178996 -1.93256004 1.93236004 -1.93476004 0 P 0 
L 1.93236004 -1.93476004 1.93276004 -1.93703996 0 P 0 
L 1.93276004 -1.93703996 1.93298996 -1.93933996 0 P 0 
L 1.93298996 -1.93933996 1.93306004 -1.94165 0 P 0 
L 1.93306004 -1.94165 1.93295 -1.94396998 0 P 0 
L 1.93295 -1.94396998 1.93268002 -1.94626004 0 P 0 
L 1.93268002 -1.94626004 1.93223002 -1.94853996 0 P 0 
L 1.93223002 -1.94853996 1.93161998 -1.95071998 0 P 0 
L 1.93161998 -1.95071998 1.93085 -1.95285 0 P 0 
L 1.93085 -1.95285 1.92991004 -1.95491004 0 P 0 
L 1.92991004 -1.95491004 1.92881004 -1.95688996 0 P 0 
L 1.92881004 -1.95688996 1.92756004 -1.95878002 0 P 0 
L 1.92756004 -1.95878002 1.92616004 -1.96056998 0 P 0 
L 1.92616004 -1.96056998 1.92493996 -1.9619 0 P 0 
L 1.92493996 -1.9619 1.92361998 -1.96313996 0 P 0 
L 1.92361998 -1.96313996 1.9222 -1.96426004 0 P 0 
L 1.9222 -1.96426004 1.9207 -1.96526998 0 P 0 
L 1.9207 -1.96526998 1.91911004 -1.96616998 0 P 0 
L 1.91911004 -1.96616998 1.91686998 -1.96721004 0 P 0 
L 1.91686998 -1.96721004 1.91456004 -1.96806998 0 P 0 
L 1.91456004 -1.96806998 1.91218996 -1.96876004 0 P 0 
L 1.91218996 -1.96876004 1.90975 -1.96926998 0 P 0 
L 1.90975 -1.96926998 1.90725 -1.9696 0 P 0 
L 1.90725 -1.9696 1.90473002 -1.96973996 0 P 0 
L 1.90473002 -1.96973996 1.9022 -1.96968996 0 P 0 
L 1.9022 -1.96968996 1.89966998 -1.96945 0 P 0 
L 1.89966998 -1.96945 1.89778002 -1.96913002 0 P 0 
L 1.89778002 -1.96913002 1.89591998 -1.96868996 0 P 0 
L 1.89591998 -1.96868996 1.8941 -1.96811004 0 P 0 
L 1.8941 -1.96811004 1.89231004 -1.96741004 0 P 0 
L 1.89231004 -1.96741004 1.89058002 -1.96658002 0 P 0 
L 1.89058002 -1.96658002 1.88875 -1.96553996 0 P 0 
L 1.88875 -1.96553996 1.88698996 -1.96435 0 P 0 
L 1.88698996 -1.96435 1.88533996 -1.96303002 0 P 0 
L 1.88533996 -1.96303002 1.88378996 -1.9616 0 P 0 
L 1.88378996 -1.9616 1.88235 -1.96003996 0 P 0 
L 1.88235 -1.96003996 1.88103002 -1.95838996 0 P 0 
L 1.88103002 -1.95838996 1.87983996 -1.95663002 0 P 0 
L 1.87983996 -1.95663002 1.87861998 -1.95446998 0 P 0 
L 1.87861998 -1.95446998 1.87758002 -1.9522 0 P 0 
L 1.87758002 -1.9522 1.87673996 -1.94986004 0 P 0 
L 1.87673996 -1.94986004 1.8761 -1.94745 0 P 0 
L 1.8761 -1.94745 1.87568002 -1.945 0 P 0 
L 1.87568002 -1.945 1.87546004 -1.94248996 0 P 0 
L 1.87546004 -1.94248996 1.87546004 -1.93998996 0 P 0 
L 1.87546004 -1.93998996 1.87566998 -1.93748996 0 P 0 
L 1.87566998 -1.93748996 1.87608996 -1.93501998 0 P 0 
L 1.87608996 -1.93501998 1.87671998 -1.9326 0 P 0 
L 1.87671998 -1.9326 1.87755 -1.93023002 0 P 0 
L 1.87755 -1.93023002 1.8786 -1.92793002 0 P 0 
L 1.8786 -1.92793002 1.87981998 -1.92575 0 P 0 
L 1.87981998 -1.92575 1.88123002 -1.92368002 0 P 0 
L 1.88123002 -1.92368002 1.88281004 -1.92175 0 P 0 
L 1.88281004 -1.92175 1.88455 -1.91996004 0 P 0 
L 1.88455 -1.91996004 1.88643002 -1.91831998 0 P 0 
L 1.88643002 -1.91831998 1.88845 -1.91686004 0 P 0 
L 1.88845 -1.91686004 1.88986998 -1.91598996 0 P 0 
L 1.88986998 -1.91598996 1.89135 -1.91523002 0 P 0 
L 1.89135 -1.91523002 1.89288002 -1.91458996 0 P 0 
L 1.89288002 -1.91458996 1.89446998 -1.91406004 0 P 0 
L 1.89446998 -1.91406004 1.89688996 -1.91343996 0 P 0 
L 1.89688996 -1.91343996 1.89935 -1.91298996 0 P 0 
L 1.89935 -1.91298996 1.90183996 -1.91271004 0 P 0 
L 1.90183996 -1.91271004 1.9044 -1.91261004 0 P 0 
L 1.9044 -1.91261004 1.90695 -1.91268002 0 P 0 
L 1.90695 -1.91268002 1.90948996 -1.91291998 0 P 0 
L 1.90948996 -1.91291998 1.91181998 -1.91331998 0 P 0 
L 1.91181998 -1.91331998 1.91408996 -1.91393002 0 P 0 
L 1.91408996 -1.91393002 1.91633002 -1.91473002 0 P 0 
L 1.89498002 -1.90801998 1.8922 -1.90893002 0 P 0 
L 1.8922 -1.90893002 1.88948002 -1.91003002 0 P 0 
L 1.88948002 -1.91003002 1.88686004 -1.91133002 0 P 0 
L 1.88686004 -1.91133002 1.88431004 -1.91283996 0 P 0 
L 1.88431004 -1.91283996 1.88201004 -1.91446004 0 P 0 
L 1.88201004 -1.91446004 1.87985 -1.91626998 0 P 0 
L 1.87985 -1.91626998 1.87785 -1.91826004 0 P 0 
L 1.87785 -1.91826004 1.87601998 -1.92041004 0 P 0 
L 1.87601998 -1.92041004 1.87441004 -1.92266998 0 P 0 
L 1.87441004 -1.92266998 1.87298996 -1.92505 0 P 0 
L 1.87298996 -1.92505 1.87178002 -1.92756004 0 P 0 
L 1.87178002 -1.92756004 1.87078996 -1.93015 0 P 0 
L 1.87078996 -1.93015 1.87 -1.93286998 0 P 0 
L 1.87 -1.93286998 1.86943996 -1.93563996 0 P 0 
L 1.86943996 -1.93563996 1.86908996 -1.93845 0 P 0 
L 1.86908996 -1.93845 1.86898002 -1.94128996 0 P 0 
L 1.86898002 -1.94128996 1.86911998 -1.94485 0 P 0 
L 1.86911998 -1.94485 1.86953996 -1.94841004 0 P 0 
L 1.86953996 -1.94841004 1.86996004 -1.95048996 0 P 0 
L 1.86996004 -1.95048996 1.87053002 -1.95251998 0 P 0 
L 1.87053002 -1.95251998 1.87125 -1.95451998 0 P 0 
L 1.87125 -1.95451998 1.87211004 -1.95643002 0 P 0 
L 1.87211004 -1.95643002 1.8731 -1.95826004 0 P 0 
L 1.8731 -1.95826004 1.87423996 -1.96001998 0 P 0 
L 1.87423996 -1.96001998 1.87636998 -1.96278996 0 P 0 
L 1.87636998 -1.96278996 1.87871998 -1.96536998 0 P 0 
L 1.87871998 -1.96536998 1.88145 -1.96788002 0 P 0 
L 1.88145 -1.96788002 1.88436998 -1.97015 0 P 0 
L 1.88436998 -1.97015 1.88621004 -1.97135 0 P 0 
L 1.88621004 -1.97135 1.88813002 -1.97238002 0 P 0 
L 1.88813002 -1.97238002 1.89013002 -1.97326004 0 P 0 
L 1.89013002 -1.97326004 1.89228002 -1.97398996 0 P 0 
L 1.89228002 -1.97398996 1.89446998 -1.97455 0 P 0 
L 1.89446998 -1.97455 1.89671004 -1.97493996 0 P 0 
L 1.89671004 -1.97493996 1.90076998 -1.97533996 0 P 0 
L 1.90076998 -1.97533996 1.90485 -1.97546998 0 P 0 
L 1.90485 -1.97546998 1.90821004 -1.97531998 0 P 0 
L 1.90821004 -1.97531998 1.91153996 -1.97488996 0 P 0 
L 1.91153996 -1.97488996 1.91481998 -1.97418996 0 P 0 
L 1.91481998 -1.97418996 1.9171 -1.9735 0 P 0 
L 1.9171 -1.9735 1.91933002 -1.97266004 0 P 0 
L 1.91933002 -1.97266004 1.92148002 -1.97166004 0 P 0 
L 1.92148002 -1.97166004 1.92356998 -1.97048996 0 P 0 
L 1.92356998 -1.97048996 1.92553996 -1.96918996 0 P 0 
L 1.92553996 -1.96918996 1.92741004 -1.96773996 0 P 0 
L 1.92741004 -1.96773996 1.92916004 -1.96616998 0 P 0 
L 1.92916004 -1.96616998 1.93081004 -1.96446004 0 P 0 
L 1.93081004 -1.96446004 1.93236998 -1.96256998 0 P 0 
L 1.93236998 -1.96256998 1.93381004 -1.96058996 0 P 0 
L 1.93381004 -1.96058996 1.93511998 -1.95851004 0 P 0 
L 1.93511998 -1.95851004 1.93628996 -1.95633996 0 P 0 
L 1.93628996 -1.95633996 1.93803996 -1.95251998 0 P 0 
L 1.93803996 -1.95251998 1.93858002 -1.95101998 0 P 0 
L 1.93858002 -1.95101998 1.93898996 -1.94948002 0 P 0 
L 1.93898996 -1.94948002 1.93928996 -1.94786998 0 P 0 
L 1.93928996 -1.94786998 1.93946004 -1.94625 0 P 0 
L 1.93946004 -1.94625 1.9396 -1.94178002 0 P 0 
L 1.9396 -1.94178002 1.93946004 -1.93803996 0 P 0 
L 1.93946004 -1.93803996 1.93905 -1.9343 0 P 0 
L 1.93905 -1.9343 1.93863996 -1.93213996 0 P 0 
L 1.93863996 -1.93213996 1.93808002 -1.93001998 0 P 0 
L 1.93808002 -1.93001998 1.93736004 -1.92795 0 P 0 
L 1.93736004 -1.92795 1.93653002 -1.92601004 0 P 0 
L 1.93653002 -1.92601004 1.93555 -1.92415 0 P 0 
L 1.93555 -1.92415 1.93441998 -1.92236004 0 P 0 
L 1.93441998 -1.92236004 1.9331 -1.92056004 0 P 0 
L 1.9331 -1.92056004 1.93166998 -1.91885 0 P 0 
L 1.93166998 -1.91885 1.93011998 -1.91723002 0 P 0 
L 1.93011998 -1.91723002 1.92896004 -1.91615 0 P 0 
L 1.92896004 -1.91615 1.92775 -1.91511004 0 P 0 
L 1.92775 -1.91511004 1.92493002 -1.91295 0 P 0 
L 1.92493002 -1.91295 1.9221 -1.91108002 0 P 0 
L 1.9221 -1.91108002 1.92095 -1.91043002 0 P 0 
L 1.92095 -1.91043002 1.91975 -1.90985 0 P 0 
L 1.91975 -1.90985 1.91796004 -1.90913996 0 P 0 
L 1.91796004 -1.90913996 1.91613002 -1.90856004 0 P 0 
L 1.91613002 -1.90856004 1.91423996 -1.9081 0 P 0 
L 1.91423996 -1.9081 1.91086004 -1.90751998 0 P 0 
L 1.91086004 -1.90751998 1.90743002 -1.90716004 0 P 0 
L 1.90743002 -1.90716004 1.90401004 -1.90701004 0 P 0 
L 1.90401004 -1.90701004 1.90058002 -1.90708002 0 P 0 
L 1.90058002 -1.90708002 1.8987 -1.90726004 0 P 0 
L 1.8987 -1.90726004 1.89683002 -1.90756998 0 P 0 
L 1.89683002 -1.90756998 1.89498002 -1.90801998 0 P 0 
L 1.86643002 -2.02923996 1.87525 -2.02923996 0 P 0 
L 1.86176998 -2.02823996 1.87515 -2.02823996 0 P 0 
L 1.85588996 -2.02723996 1.87505 -2.02723996 0 P 0 
L 1.78365 -2.00523996 1.87281004 -2.00523996 0 P 0 
L 1.78451004 -2.00423996 1.87271004 -2.00423996 0 P 0 
L 1.78546998 -2.00323996 1.87261004 -2.00323996 0 P 0 
L 1.78655 -2.00223996 1.8725 -2.00223996 0 P 0 
L 1.78776004 -2.00123996 1.8724 -2.00123996 0 P 0 
L 1.78915 -2.00023996 1.8723 -2.00023996 0 P 0 
L 1.79078996 -1.99923996 1.8722 -1.99923996 0 P 0 
L 1.79263996 -1.99823996 1.87208996 -1.99823996 0 P 0 
L 1.79458996 -1.99723996 1.87198996 -1.99723996 0 P 0 
L 1.79686998 -1.99623996 1.87188002 -1.99623996 0 P 0 
L 1.79946004 -1.99523996 1.87178002 -1.99523996 0 P 0 
L 1.80231004 -1.99423996 1.86961998 -1.99423996 0 P 0 
L 1.80596004 -1.99323996 1.86218002 -1.99323996 0 P 0 
L 1.81051004 -1.99223996 1.85398002 -1.99223996 0 P 0 
L 1.81676004 -1.99123996 1.84395 -1.99123996 0 P 0 
L 1.87786998 -1.96146004 1.88093996 -1.96146004 0 P 0 
L 1.8771 -1.96046004 1.88013002 -1.96046004 0 P 0 
L 1.87633996 -1.95946004 1.87933996 -1.95946004 0 P 0 
L 1.87561998 -1.95846004 1.87866998 -1.95846004 0 P 0 
L 1.87496998 -1.95746004 1.87801998 -1.95746004 0 P 0 
L 1.8744 -1.95646004 1.87745 -1.95646004 0 P 0 
L 1.87386998 -1.95546004 1.87688002 -1.95546004 0 P 0 
L 1.87341998 -1.95446004 1.87641998 -1.95446004 0 P 0 
L 1.87298996 -1.95346004 1.87596004 -1.95346004 0 P 0 
L 1.87263002 -1.95246004 1.87555 -1.95246004 0 P 0 
L 1.87231004 -1.95146004 1.87518996 -1.95146004 0 P 0 
L 1.87203002 -1.95046004 1.87483002 -1.95046004 0 P 0 
L 1.87178996 -1.94946004 1.87456998 -1.94946004 0 P 0 
L 1.87158996 -1.94846004 1.87431004 -1.94846004 0 P 0 
L 1.87143996 -1.94746004 1.87408002 -1.94746004 0 P 0 
L 1.87133002 -1.94646004 1.8739 -1.94646004 0 P 0 
L 1.87121004 -1.94546004 1.87373002 -1.94546004 0 P 0 
L 1.8711 -1.94446998 1.87361998 -1.94446998 0 P 0 
L 1.87106998 -1.94346004 1.87353996 -1.94346004 0 P 0 
L 1.87103002 -1.94246004 1.87346004 -1.94246004 0 P 0 
L 1.87098996 -1.94146998 1.87346004 -1.94146998 0 P 0 
L 1.87101004 -1.94046004 1.87346004 -1.94046004 0 P 0 
L 1.87106004 -1.93946004 1.87348996 -1.93946004 0 P 0 
L 1.87111004 -1.93846004 1.87358002 -1.93846004 0 P 0 
L 1.87123002 -1.93746004 1.87366004 -1.93746004 0 P 0 
L 1.87135 -1.93646004 1.87381998 -1.93646004 0 P 0 
L 1.87151004 -1.93546004 1.87398996 -1.93546004 0 P 0 
L 1.87171998 -1.93446004 1.87416998 -1.93446004 0 P 0 
L 1.87191998 -1.93346004 1.87443002 -1.93346004 0 P 0 
L 1.8722 -1.93246004 1.87468996 -1.93246004 0 P 0 
L 1.87248996 -1.93146004 1.875 -1.93146004 0 P 0 
L 1.87281004 -1.93046004 1.87535 -1.93046004 0 P 0 
L 1.87318996 -1.92946004 1.87571004 -1.92946004 0 P 0 
L 1.87356998 -1.92846004 1.87616004 -1.92846004 0 P 0 
L 1.87405 -1.92746004 1.87661004 -1.92746004 0 P 0 
L 1.87453002 -1.92646004 1.87711998 -1.92646004 0 P 0 
L 1.87506998 -1.92546004 1.87768996 -1.92546004 0 P 0 
L 1.87566004 -1.92446998 1.87826998 -1.92446998 0 P 0 
L 1.87628996 -1.92346004 1.87896004 -1.92346004 0 P 0 
L 1.87701004 -1.92246004 1.87963996 -1.92246004 0 P 0 
L 1.87775 -1.92146004 1.88046004 -1.92146004 0 P 0 
L 1.90483996 -1.97346004 1.9009 -1.97333996 0 P 0 
L 1.9009 -1.97333996 1.89698002 -1.97295 0 P 0 
L 1.89698002 -1.97295 1.89488996 -1.97258996 0 P 0 
L 1.89488996 -1.97258996 1.89285 -1.97206998 0 P 0 
L 1.89285 -1.97206998 1.89086004 -1.97138996 0 P 0 
L 1.89086004 -1.97138996 1.889 -1.97058002 0 P 0 
L 1.889 -1.97058002 1.88723002 -1.96961998 0 P 0 
L 1.88723002 -1.96961998 1.88553002 -1.96851998 0 P 0 
L 1.88553002 -1.96851998 1.88273996 -1.96636004 0 P 0 
L 1.88273996 -1.96636004 1.88013996 -1.96396004 0 P 0 
L 1.88013996 -1.96396004 1.8779 -1.9615 0 P 0 
L 1.8779 -1.9615 1.87588002 -1.95886998 0 P 0 
L 1.87588002 -1.95886998 1.87483002 -1.95723996 0 P 0 
L 1.87483002 -1.95723996 1.8739 -1.95553996 0 P 0 
L 1.8739 -1.95553996 1.87311004 -1.95376998 0 P 0 
L 1.87311004 -1.95376998 1.87243002 -1.95191004 0 P 0 
L 1.87243002 -1.95191004 1.8719 -1.95001998 0 P 0 
L 1.8719 -1.95001998 1.87151998 -1.9481 0 P 0 
L 1.87151998 -1.9481 1.87111004 -1.94468996 0 P 0 
L 1.87111004 -1.94468996 1.87098002 -1.94128996 0 P 0 
L 1.87098002 -1.94128996 1.87108996 -1.93861004 0 P 0 
L 1.87108996 -1.93861004 1.87141004 -1.93596998 0 P 0 
L 1.87141004 -1.93596998 1.87195 -1.93335 0 P 0 
L 1.87195 -1.93335 1.87268996 -1.93078996 0 P 0 
L 1.87268996 -1.93078996 1.87361998 -1.92835 0 P 0 
L 1.87361998 -1.92835 1.87475 -1.926 0 P 0 
L 1.87475 -1.926 1.87608996 -1.92376004 0 P 0 
L 1.87608996 -1.92376004 1.8776 -1.92163996 0 P 0 
L 1.8776 -1.92163996 1.87931998 -1.91961998 0 P 0 
L 1.87931998 -1.91961998 1.8812 -1.91775 0 P 0 
L 1.8812 -1.91775 1.88323002 -1.91605 0 P 0 
L 1.88323002 -1.91605 1.8854 -1.91451998 0 P 0 
L 1.8854 -1.91451998 1.88781004 -1.91308996 0 P 0 
L 1.88781004 -1.91308996 1.89031004 -1.91186004 0 P 0 
L 1.89031004 -1.91186004 1.89288002 -1.9108 0 P 0 
L 1.89288002 -1.9108 1.89553002 -1.90995 0 P 0 
L 1.89553002 -1.90995 1.89723002 -1.90953002 0 P 0 
L 1.89723002 -1.90953002 1.89896004 -1.90923996 0 P 0 
L 1.89896004 -1.90923996 1.90068996 -1.90908002 0 P 0 
L 1.90068996 -1.90908002 1.90398996 -1.90901004 0 P 0 
L 1.90398996 -1.90901004 1.90728002 -1.90915 0 P 0 
L 1.90728002 -1.90915 1.91058996 -1.90951004 0 P 0 
L 1.91058996 -1.90951004 1.91383996 -1.91006004 0 P 0 
L 1.91383996 -1.91006004 1.91558996 -1.91048996 0 P 0 
L 1.91558996 -1.91048996 1.91728996 -1.91101998 0 P 0 
L 1.91728996 -1.91101998 1.91895 -1.91168002 0 P 0 
L 1.91895 -1.91168002 1.92001998 -1.9122 0 P 0 
L 1.92001998 -1.9122 1.92105 -1.91278996 0 P 0 
L 1.92105 -1.91278996 1.92376998 -1.91458002 0 P 0 
L 1.92376998 -1.91458002 1.92648996 -1.91666998 0 P 0 
L 1.92648996 -1.91666998 1.92763002 -1.91763996 0 P 0 
L 1.92763002 -1.91763996 1.92871004 -1.91865 0 P 0 
L 1.92871004 -1.91865 1.93018002 -1.92018996 0 P 0 
L 1.93018002 -1.92018996 1.93153002 -1.9218 0 P 0 
L 1.93153002 -1.9218 1.93276998 -1.92348996 0 P 0 
L 1.93276998 -1.92348996 1.93381004 -1.92515 0 P 0 
L 1.93381004 -1.92515 1.93471998 -1.92686998 0 P 0 
L 1.93471998 -1.92686998 1.9355 -1.92866998 0 P 0 
L 1.9355 -1.92866998 1.93616998 -1.93061004 0 P 0 
L 1.93616998 -1.93061004 1.93668996 -1.93258002 0 P 0 
L 1.93668996 -1.93258002 1.93706998 -1.93458996 0 P 0 
L 1.93706998 -1.93458996 1.93746998 -1.93818996 0 P 0 
L 1.93746998 -1.93818996 1.9376 -1.94178996 0 P 0 
L 1.9376 -1.94178996 1.93746004 -1.94611004 0 P 0 
L 1.93746004 -1.94611004 1.93731004 -1.94758996 0 P 0 
L 1.93731004 -1.94758996 1.93705 -1.94903996 0 P 0 
L 1.93705 -1.94903996 1.93666998 -1.95041998 0 P 0 
L 1.93666998 -1.95041998 1.93618002 -1.95176004 0 P 0 
L 1.93618002 -1.95176004 1.9345 -1.95545 0 P 0 
L 1.9345 -1.95545 1.93338996 -1.9575 0 P 0 
L 1.93338996 -1.9575 1.93216004 -1.95946998 0 P 0 
L 1.93216004 -1.95946998 1.93078996 -1.96133996 0 P 0 
L 1.93078996 -1.96133996 1.92931004 -1.96311998 0 P 0 
L 1.92931004 -1.96311998 1.92776998 -1.96473002 0 P 0 
L 1.92776998 -1.96473002 1.92613002 -1.96621004 0 P 0 
L 1.92613002 -1.96621004 1.92438002 -1.96756004 0 P 0 
L 1.92438002 -1.96756004 1.92253002 -1.96878002 0 P 0 
L 1.92253002 -1.96878002 1.92056998 -1.96986998 0 P 0 
L 1.92056998 -1.96986998 1.91855 -1.97081998 0 P 0 
L 1.91855 -1.97081998 1.91646004 -1.97161004 0 P 0 
L 1.91646004 -1.97161004 1.91433002 -1.97223996 0 P 0 
L 1.91433002 -1.97223996 1.9112 -1.97291004 0 P 0 
L 1.9112 -1.97291004 1.90803996 -1.97331998 0 P 0 
L 1.90803996 -1.97331998 1.90483996 -1.97346004 0 P 0 
L 1.90476004 -1.97173996 1.9048 -1.97173996 0 P 0 
L 1.9048 -1.97173996 1.90483996 -1.97173002 0 P 0 
L 1.90483996 -1.97173002 1.90736004 -1.9716 0 P 0 
L 1.90736004 -1.9716 1.9074 -1.97158996 0 P 0 
L 1.9074 -1.97158996 1.90746998 -1.97158996 0 P 0 
L 1.90746998 -1.97158996 1.90751004 -1.97158002 0 P 0 
L 1.90751004 -1.97158002 1.91001004 -1.97126004 0 P 0 
L 1.91001004 -1.97126004 1.91005 -1.97125 0 P 0 
L 1.91005 -1.97125 1.91008002 -1.97123996 0 P 0 
L 1.91008002 -1.97123996 1.91011998 -1.97123996 0 P 0 
L 1.91011998 -1.97123996 1.91016004 -1.97123002 0 P 0 
L 1.91016004 -1.97123002 1.9126 -1.97071998 0 P 0 
L 1.9126 -1.97071998 1.9126 -1.97071004 0 P 0 
L 1.9126 -1.97071004 1.91266998 -1.97071004 0 P 0 
L 1.91266998 -1.97071004 1.91271004 -1.97068996 0 P 0 
L 1.91271004 -1.97068996 1.91275 -1.97068002 0 P 0 
L 1.91275 -1.97068002 1.91511998 -1.96998996 0 P 0 
L 1.91511998 -1.96998996 1.91515 -1.96998996 0 P 0 
L 1.91515 -1.96998996 1.91518996 -1.96996998 0 P 0 
L 1.91518996 -1.96996998 1.91523002 -1.96996004 0 P 0 
L 1.91523002 -1.96996004 1.91526004 -1.96995 0 P 0 
L 1.91526004 -1.96995 1.91756998 -1.96908002 0 P 0 
L 1.91756998 -1.96908002 1.91761004 -1.96906998 0 P 0 
L 1.91761004 -1.96906998 1.91768002 -1.96903996 0 P 0 
L 1.91768002 -1.96903996 1.91771004 -1.96901998 0 P 0 
L 1.91771004 -1.96901998 1.91995 -1.96798002 0 P 0 
L 1.91995 -1.96798002 1.92001998 -1.96795 0 P 0 
L 1.92001998 -1.96795 1.92005 -1.96793002 0 P 0 
L 1.92005 -1.96793002 1.92008996 -1.96791004 0 P 0 
L 1.92008996 -1.96791004 1.92168002 -1.96701998 0 P 0 
L 1.92168002 -1.96701998 1.92171998 -1.967 0 P 0 
L 1.92171998 -1.967 1.92175 -1.96698002 0 P 0 
L 1.92175 -1.96698002 1.92178996 -1.96695 0 P 0 
L 1.92178996 -1.96695 1.92181998 -1.96693002 0 P 0 
L 1.92181998 -1.96693002 1.92331998 -1.96591998 0 P 0 
L 1.92331998 -1.96591998 1.92336004 -1.9659 0 P 0 
L 1.92336004 -1.9659 1.92341998 -1.96586004 0 P 0 
L 1.92341998 -1.96586004 1.92345 -1.96583002 0 P 0 
L 1.92345 -1.96583002 1.92486004 -1.9647 0 P 0 
L 1.92486004 -1.9647 1.92493002 -1.96465 0 P 0 
L 1.92493002 -1.96465 1.92496004 -1.96463002 0 P 0 
L 1.92496004 -1.96463002 1.92498996 -1.9646 0 P 0 
L 1.92498996 -1.9646 1.92631004 -1.96336998 0 P 0 
L 1.92631004 -1.96336998 1.9264 -1.96328002 0 P 0 
L 1.9264 -1.96328002 1.92641998 -1.96325 0 P 0 
L 1.92641998 -1.96325 1.92763996 -1.96191998 0 P 0 
L 1.92763996 -1.96191998 1.92766998 -1.96188996 0 P 0 
L 1.92766998 -1.96188996 1.92768996 -1.96186004 0 P 0 
L 1.92768996 -1.96186004 1.92771998 -1.96183002 0 P 0 
L 1.92771998 -1.96183002 1.92773996 -1.9618 0 P 0 
L 1.92773996 -1.9618 1.92913996 -1.96001004 0 P 0 
L 1.92913996 -1.96001004 1.92918996 -1.95995 0 P 0 
L 1.92918996 -1.95995 1.92921004 -1.95991004 0 P 0 
L 1.92921004 -1.95991004 1.92923002 -1.95988002 0 P 0 
L 1.92923002 -1.95988002 1.93048002 -1.95798996 0 P 0 
L 1.93048002 -1.95798996 1.93051998 -1.95793002 0 P 0 
L 1.93051998 -1.95793002 1.93053996 -1.95788996 0 P 0 
L 1.93053996 -1.95788996 1.93056004 -1.95786004 0 P 0 
L 1.93056004 -1.95786004 1.93166004 -1.95588002 0 P 0 
L 1.93166004 -1.95588002 1.93171004 -1.95576998 0 P 0 
L 1.93171004 -1.95576998 1.93173002 -1.95573996 0 P 0 
L 1.93173002 -1.95573996 1.93266998 -1.95366998 0 P 0 
L 1.93266998 -1.95366998 1.93271004 -1.95356998 0 P 0 
L 1.93271004 -1.95356998 1.93273002 -1.95353002 0 P 0 
L 1.93273002 -1.95353002 1.9335 -1.9514 0 P 0 
L 1.9335 -1.9514 1.93351004 -1.95136998 0 P 0 
L 1.93351004 -1.95136998 1.93353002 -1.95133002 0 P 0 
L 1.93353002 -1.95133002 1.93355 -1.95125 0 P 0 
L 1.93355 -1.95125 1.93416004 -1.94906998 0 P 0 
L 1.93416004 -1.94906998 1.93416998 -1.94903002 0 P 0 
L 1.93416998 -1.94903002 1.93418002 -1.949 0 P 0 
L 1.93418002 -1.949 1.93418002 -1.94896004 0 P 0 
L 1.93418002 -1.94896004 1.93418996 -1.94891998 0 P 0 
L 1.93418996 -1.94891998 1.93463996 -1.94665 0 P 0 
L 1.93463996 -1.94665 1.93463996 -1.94661004 0 P 0 
L 1.93463996 -1.94661004 1.93465 -1.94656998 0 P 0 
L 1.93465 -1.94656998 1.93466004 -1.9465 0 P 0 
L 1.93466004 -1.9465 1.93493996 -1.9442 0 P 0 
L 1.93493996 -1.9442 1.93493996 -1.94413002 0 P 0 
L 1.93493996 -1.94413002 1.93495 -1.94408996 0 P 0 
L 1.93495 -1.94408996 1.93495 -1.94406004 0 P 0 
L 1.93495 -1.94406004 1.93505 -1.94173996 0 P 0 
L 1.93505 -1.94173996 1.93506004 -1.94171004 0 P 0 
L 1.93506004 -1.94171004 1.93506004 -1.9416 0 P 0 
L 1.93506004 -1.9416 1.93498996 -1.93928996 0 P 0 
L 1.93498996 -1.93928996 1.93498996 -1.93921004 0 P 0 
L 1.93498996 -1.93921004 1.93498002 -1.93913996 0 P 0 
L 1.93498002 -1.93913996 1.93475 -1.93683996 0 P 0 
L 1.93475 -1.93683996 1.93473996 -1.93676998 0 P 0 
L 1.93473996 -1.93676998 1.93473002 -1.93673002 0 P 0 
L 1.93473002 -1.93673002 1.93473002 -1.93668996 0 P 0 
L 1.93473002 -1.93668996 1.93433002 -1.93441004 0 P 0 
L 1.93433002 -1.93441004 1.93431998 -1.93436998 0 P 0 
L 1.93431998 -1.93436998 1.93431004 -1.93433996 0 P 0 
L 1.93431004 -1.93433996 1.93428996 -1.93426004 0 P 0 
L 1.93428996 -1.93426004 1.93373002 -1.93206004 0 P 0 
L 1.93373002 -1.93206004 1.93368996 -1.93191998 0 P 0 
L 1.93368996 -1.93191998 1.93296004 -1.92976998 0 P 0 
L 1.93296004 -1.92976998 1.93293996 -1.9297 0 P 0 
L 1.93293996 -1.9297 1.93291004 -1.92963002 0 P 0 
L 1.93291004 -1.92963002 1.93201998 -1.92753996 0 P 0 
L 1.93201998 -1.92753996 1.93196998 -1.92743002 0 P 0 
L 1.93196998 -1.92743002 1.93196004 -1.9274 0 P 0 
L 1.93196004 -1.9274 1.93091998 -1.92538996 0 P 0 
L 1.93091998 -1.92538996 1.9309 -1.92536004 0 P 0 
L 1.9309 -1.92536004 1.93088002 -1.92531998 0 P 0 
L 1.93088002 -1.92531998 1.93086004 -1.92528996 0 P 0 
L 1.93086004 -1.92528996 1.93083996 -1.92525 0 P 0 
L 1.93083996 -1.92525 1.92965 -1.92331998 0 P 0 
L 1.92965 -1.92331998 1.92956998 -1.9232 0 P 0 
L 1.92956998 -1.9232 1.92823002 -1.92136004 0 P 0 
L 1.92823002 -1.92136004 1.92818002 -1.9213 0 P 0 
L 1.92818002 -1.9213 1.92816004 -1.92126998 0 P 0 
L 1.92816004 -1.92126998 1.92813002 -1.92123996 0 P 0 
L 1.92813002 -1.92123996 1.92671998 -1.91958002 0 P 0 
L 1.92671998 -1.91958002 1.9266 -1.91946004 0 P 0 
L 1.9266 -1.91946004 1.92505 -1.91793002 0 P 0 
L 1.92505 -1.91793002 1.92498996 -1.91786998 0 P 0 
L 1.92498996 -1.91786998 1.92493002 -1.91781998 0 P 0 
L 1.92493002 -1.91781998 1.92325 -1.91643002 0 P 0 
L 1.92325 -1.91643002 1.92318996 -1.91636998 0 P 0 
L 1.92318996 -1.91636998 1.92311998 -1.91631998 0 P 0 
L 1.92311998 -1.91631998 1.92133002 -1.91508002 0 P 0 
L 1.92133002 -1.91508002 1.92126004 -1.91503996 0 P 0 
L 1.92126004 -1.91503996 1.92121998 -1.91501004 0 P 0 
L 1.92121998 -1.91501004 1.92118002 -1.91498996 0 P 0 
L 1.92118002 -1.91498996 1.91928996 -1.91391004 0 P 0 
L 1.91928996 -1.91391004 1.91926004 -1.91388996 0 P 0 
L 1.91926004 -1.91388996 1.91913996 -1.91383002 0 P 0 
L 1.91913996 -1.91383002 1.91716998 -1.91291004 0 P 0 
L 1.91716998 -1.91291004 1.91711998 -1.91288996 0 P 0 
L 1.91711998 -1.91288996 1.91705 -1.91286004 0 P 0 
L 1.91705 -1.91286004 1.917 -1.91285 0 P 0 
L 1.917 -1.91285 1.91476998 -1.91203996 0 P 0 
L 1.91476998 -1.91203996 1.91468996 -1.91201998 0 P 0 
L 1.91468996 -1.91201998 1.91465 -1.912 0 P 0 
L 1.91465 -1.912 1.9146 -1.91198996 0 P 0 
L 1.9146 -1.91198996 1.91233002 -1.91138996 0 P 0 
L 1.91233002 -1.91138996 1.91228002 -1.91138002 0 P 0 
L 1.91228002 -1.91138002 1.91223996 -1.91136998 0 P 0 
L 1.91223996 -1.91136998 1.91216004 -1.91136004 0 P 0 
L 1.91216004 -1.91136004 1.90983002 -1.91095 0 P 0 
L 1.90983002 -1.91095 1.9098 -1.91093996 0 P 0 
L 1.9098 -1.91093996 1.90976004 -1.91093996 0 P 0 
L 1.90976004 -1.91093996 1.90971998 -1.91093002 0 P 0 
L 1.90971998 -1.91093002 1.90968002 -1.91093002 0 P 0 
L 1.90968002 -1.91093002 1.90713996 -1.91068996 0 P 0 
L 1.90713996 -1.91068996 1.9071 -1.91068002 0 P 0 
L 1.9071 -1.91068002 1.907 -1.91068002 0 P 0 
L 1.907 -1.91068002 1.90445 -1.91061004 0 P 0 
L 1.90445 -1.91061004 1.90431004 -1.91061004 0 P 0 
L 1.90431004 -1.91061004 1.90176004 -1.91071004 0 P 0 
L 1.90176004 -1.91071004 1.90173002 -1.91071998 0 P 0 
L 1.90173002 -1.91071998 1.90166004 -1.91071998 0 P 0 
L 1.90166004 -1.91071998 1.90161998 -1.91073002 0 P 0 
L 1.90161998 -1.91073002 1.89913002 -1.911 0 P 0 
L 1.89913002 -1.911 1.89906004 -1.91101004 0 P 0 
L 1.89906004 -1.91101004 1.89901998 -1.91101998 0 P 0 
L 1.89901998 -1.91101998 1.89898996 -1.91101998 0 P 0 
L 1.89898996 -1.91101998 1.89653002 -1.91146998 0 P 0 
L 1.89653002 -1.91146998 1.8965 -1.91148002 0 P 0 
L 1.8965 -1.91148002 1.89646004 -1.91148002 0 P 0 
L 1.89646004 -1.91148002 1.8964 -1.9115 0 P 0 
L 1.8964 -1.9115 1.89396998 -1.91211998 0 P 0 
L 1.89396998 -1.91211998 1.89393996 -1.91213002 0 P 0 
L 1.89393996 -1.91213002 1.89383002 -1.91216004 0 P 0 
L 1.89383002 -1.91216004 1.89225 -1.91268996 0 P 0 
L 1.89225 -1.91268996 1.89218002 -1.91271998 0 P 0 
L 1.89218002 -1.91271998 1.89211004 -1.91273996 0 P 0 
L 1.89211004 -1.91273996 1.8921 -1.91273996 0 P 0 
L 1.8921 -1.91273996 1.89058002 -1.91338996 0 P 0 
L 1.89058002 -1.91338996 1.89043996 -1.91345 0 P 0 
L 1.89043996 -1.91345 1.88896004 -1.91421004 0 P 0 
L 1.88896004 -1.91421004 1.88893002 -1.91423002 0 P 0 
L 1.88893002 -1.91423002 1.8889 -1.91423996 0 P 0 
L 1.8889 -1.91423996 1.88886004 -1.91426004 0 P 0 
L 1.88886004 -1.91426004 1.88883002 -1.91428002 0 P 0 
L 1.88883002 -1.91428002 1.88741004 -1.91515 0 P 0 
L 1.88741004 -1.91515 1.88733996 -1.91518996 0 P 0 
L 1.88733996 -1.91518996 1.88728002 -1.91523996 0 P 0 
L 1.88728002 -1.91523996 1.88526004 -1.9167 0 P 0 
L 1.88526004 -1.9167 1.88521998 -1.91673002 0 P 0 
L 1.88521998 -1.91673002 1.88518996 -1.91675 0 P 0 
L 1.88518996 -1.91675 1.88516004 -1.91678002 0 P 0 
L 1.88516004 -1.91678002 1.88511998 -1.91681004 0 P 0 
L 1.88511998 -1.91681004 1.88323002 -1.91845 0 P 0 
L 1.88323002 -1.91845 1.8832 -1.91846998 0 P 0 
L 1.8832 -1.91846998 1.88311004 -1.91856004 0 P 0 
L 1.88311004 -1.91856004 1.88136998 -1.92036004 0 P 0 
L 1.88136998 -1.92036004 1.88128002 -1.92045 0 P 0 
L 1.88128002 -1.92045 1.88125 -1.92048996 0 P 0 
L 1.88125 -1.92048996 1.87968002 -1.92241998 0 P 0 
L 1.87968002 -1.92241998 1.87965 -1.92245 0 P 0 
L 1.87965 -1.92245 1.87961998 -1.92248996 0 P 0 
L 1.87961998 -1.92248996 1.87956998 -1.92256004 0 P 0 
L 1.87956998 -1.92256004 1.87816998 -1.92461998 0 P 0 
L 1.87816998 -1.92461998 1.8781 -1.92473002 0 P 0 
L 1.8781 -1.92473002 1.87808002 -1.92476998 0 P 0 
L 1.87808002 -1.92476998 1.87685 -1.92695 0 P 0 
L 1.87685 -1.92695 1.87683002 -1.92698996 0 P 0 
L 1.87683002 -1.92698996 1.87681004 -1.92701998 0 P 0 
L 1.87681004 -1.92701998 1.87678996 -1.92706998 0 P 0 
L 1.87678996 -1.92706998 1.87676998 -1.92711004 0 P 0 
L 1.87676998 -1.92711004 1.87573002 -1.92941004 0 P 0 
L 1.87573002 -1.92941004 1.87571004 -1.92945 0 P 0 
L 1.87571004 -1.92945 1.8757 -1.92948996 0 P 0 
L 1.8757 -1.92948996 1.87568002 -1.92951998 0 P 0 
L 1.87568002 -1.92951998 1.87566998 -1.92956998 0 P 0 
L 1.87566998 -1.92956998 1.87483996 -1.93193002 0 P 0 
L 1.87483996 -1.93193002 1.87481004 -1.93201004 0 P 0 
L 1.87481004 -1.93201004 1.87478996 -1.93208996 0 P 0 
L 1.87478996 -1.93208996 1.87416004 -1.93451998 0 P 0 
L 1.87416004 -1.93451998 1.87413996 -1.93456004 0 P 0 
L 1.87413996 -1.93456004 1.87413002 -1.9346 0 P 0 
L 1.87413002 -1.9346 1.87413002 -1.93463996 0 P 0 
L 1.87413002 -1.93463996 1.87411998 -1.93468002 0 P 0 
L 1.87411998 -1.93468002 1.8737 -1.93715 0 P 0 
L 1.8737 -1.93715 1.87368996 -1.93718996 0 P 0 
L 1.87368996 -1.93718996 1.87368002 -1.93723996 0 P 0 
L 1.87368002 -1.93723996 1.87368002 -1.93731998 0 P 0 
L 1.87368002 -1.93731998 1.87346998 -1.93981998 0 P 0 
L 1.87346998 -1.93981998 1.87346004 -1.93986004 0 P 0 
L 1.87346004 -1.93986004 1.87346004 -1.94258002 0 P 0 
L 1.87346004 -1.94258002 1.87346998 -1.94266004 0 P 0 
L 1.87346998 -1.94266004 1.87368002 -1.94516998 0 P 0 
L 1.87368002 -1.94516998 1.87368996 -1.94521004 0 P 0 
L 1.87368996 -1.94521004 1.87368996 -1.94525 0 P 0 
L 1.87368996 -1.94525 1.87371004 -1.94533996 0 P 0 
L 1.87371004 -1.94533996 1.87413996 -1.94778996 0 P 0 
L 1.87413996 -1.94778996 1.87413996 -1.94783996 0 P 0 
L 1.87413996 -1.94783996 1.87416998 -1.94796004 0 P 0 
L 1.87416998 -1.94796004 1.87481004 -1.95036998 0 P 0 
L 1.87481004 -1.95036998 1.87483996 -1.95048996 0 P 0 
L 1.87483996 -1.95048996 1.87486004 -1.95053002 0 P 0 
L 1.87486004 -1.95053002 1.8757 -1.95288002 0 P 0 
L 1.8757 -1.95288002 1.87571004 -1.95291998 0 P 0 
L 1.87571004 -1.95291998 1.87575 -1.953 0 P 0 
L 1.87575 -1.953 1.87576004 -1.95303996 0 P 0 
L 1.87576004 -1.95303996 1.8768 -1.9553 0 P 0 
L 1.8768 -1.9553 1.87686004 -1.95541998 0 P 0 
L 1.87686004 -1.95541998 1.87688002 -1.95545 0 P 0 
L 1.87688002 -1.95545 1.8781 -1.95761004 0 P 0 
L 1.8781 -1.95761004 1.87811998 -1.95761004 0 P 0 
L 1.87811998 -1.95761004 1.8781 -1.95761998 0 P 0 
L 1.8781 -1.95761998 1.87813996 -1.95768996 0 P 0 
L 1.87813996 -1.95768996 1.87816998 -1.95771998 0 P 0 
L 1.87816998 -1.95771998 1.87818996 -1.95775 0 P 0 
L 1.87818996 -1.95775 1.87938002 -1.95951004 0 P 0 
L 1.87938002 -1.95951004 1.87943996 -1.9596 0 P 0 
L 1.87943996 -1.9596 1.87946998 -1.95963002 0 P 0 
L 1.87946998 -1.95963002 1.88078002 -1.96128996 0 P 0 
L 1.88078002 -1.96128996 1.88081004 -1.96131998 0 P 0 
L 1.88081004 -1.96131998 1.88083002 -1.96135 0 P 0 
L 1.88083002 -1.96135 1.88086004 -1.96136998 0 P 0 
L 1.88086004 -1.96136998 1.88088002 -1.9614 0 P 0 
L 1.88088002 -1.9614 1.88231998 -1.96295 0 P 0 
L 1.88231998 -1.96295 1.88233996 -1.96298002 0 P 0 
L 1.88233996 -1.96298002 1.8824 -1.96303996 0 P 0 
L 1.8824 -1.96303996 1.88243002 -1.96306004 0 P 0 
L 1.88243002 -1.96306004 1.88398002 -1.9645 0 P 0 
L 1.88398002 -1.9645 1.88401004 -1.96451998 0 P 0 
L 1.88401004 -1.96451998 1.88403002 -1.96455 0 P 0 
L 1.88403002 -1.96455 1.88406998 -1.96458002 0 P 0 
L 1.88406998 -1.96458002 1.88408996 -1.9646 0 P 0 
L 1.88408996 -1.9646 1.88575 -1.96591004 0 P 0 
L 1.88575 -1.96591004 1.88578002 -1.96593996 0 P 0 
L 1.88578002 -1.96593996 1.88586998 -1.966 0 P 0 
L 1.88586998 -1.966 1.88761998 -1.96718996 0 P 0 
L 1.88761998 -1.96718996 1.88766004 -1.96721004 0 P 0 
L 1.88766004 -1.96721004 1.88775 -1.96726998 0 P 0 
L 1.88775 -1.96726998 1.88958996 -1.96831998 0 P 0 
L 1.88958996 -1.96831998 1.88965 -1.96836004 0 P 0 
L 1.88965 -1.96836004 1.88968002 -1.96836998 0 P 0 
L 1.88968002 -1.96836998 1.88971998 -1.96838996 0 P 0 
L 1.88971998 -1.96838996 1.89145 -1.96921998 0 P 0 
L 1.89145 -1.96921998 1.89151004 -1.96925 0 P 0 
L 1.89151004 -1.96925 1.89155 -1.96926004 0 P 0 
L 1.89155 -1.96926004 1.89158002 -1.96926998 0 P 0 
L 1.89158002 -1.96926998 1.89336004 -1.96996998 0 P 0 
L 1.89336004 -1.96996998 1.89336004 -1.96998002 0 P 0 
L 1.89336004 -1.96998002 1.89346004 -1.97001004 0 P 0 
L 1.89346004 -1.97001004 1.89348996 -1.97001998 0 P 0 
L 1.89348996 -1.97001998 1.89531998 -1.9706 0 P 0 
L 1.89531998 -1.9706 1.89536004 -1.97061004 0 P 0 
L 1.89536004 -1.97061004 1.89541998 -1.97063002 0 P 0 
L 1.89541998 -1.97063002 1.89546004 -1.97063002 0 P 0 
L 1.89546004 -1.97063002 1.89731998 -1.97108002 0 P 0 
L 1.89731998 -1.97108002 1.89741998 -1.9711 0 P 0 
L 1.89741998 -1.9711 1.89746004 -1.9711 0 P 0 
L 1.89746004 -1.9711 1.89746004 -1.97111004 0 P 0 
L 1.89746004 -1.97111004 1.89933996 -1.97141998 0 P 0 
L 1.89933996 -1.97141998 1.89936998 -1.97143002 0 P 0 
L 1.89936998 -1.97143002 1.89941004 -1.97143002 0 P 0 
L 1.89941004 -1.97143002 1.89945 -1.97143996 0 P 0 
L 1.89945 -1.97143996 1.89948002 -1.97143996 0 P 0 
L 1.89948002 -1.97143996 1.90201004 -1.97168002 0 P 0 
L 1.90201004 -1.97168002 1.90205 -1.97168002 0 P 0 
L 1.90205 -1.97168002 1.90208996 -1.97168996 0 P 0 
L 1.90208996 -1.97168996 1.90216004 -1.97168996 0 P 0 
L 1.90216004 -1.97168996 1.90468996 -1.97173996 0 P 0 
L 1.90468996 -1.97173996 1.90476004 -1.97173996 0 P 0 
L 1.80616004 -2.12823996 1.83348996 -2.12823996 0 P 0 
L 1.79591998 -2.12723996 1.8396 -2.12723996 0 P 0 
L 1.78818002 -2.12623996 1.84465 -2.12623996 0 P 0 
L 1.82003996 -2.09123996 1.87618996 -2.09123996 0 P 0 
L 1.82198996 -2.09023996 1.8762 -2.09023996 0 P 0 
L 1.82325 -2.08923996 1.8762 -2.08923996 0 P 0 
L 1.82411998 -2.08823996 1.87618996 -2.08823996 0 P 0 
L 1.82463002 -2.08723996 1.87616998 -2.08723996 0 P 0 
L 1.82488002 -2.08623996 1.87615 -2.08623996 0 P 0 
L 1.82493002 -2.08523996 1.87613002 -2.08523996 0 P 0 
L 1.82476998 -2.08423996 1.87611004 -2.08423996 0 P 0 
L 1.64846004 -2.08295 1.73316998 -2.08295 0 P 0 
L 1.64811998 -2.08195 1.73356998 -2.08195 0 P 0 
L 1.64776998 -2.08095 1.73398002 -2.08095 0 P 0 
L 1.64743002 -2.07995 1.73438002 -2.07995 0 P 0 
L 1.64708996 -2.07895 1.73478996 -2.07895 0 P 0 
L 1.64673996 -2.07795 1.7352 -2.07795 0 P 0 
L 1.6464 -2.07695 1.7356 -2.07695 0 P 0 
L 1.64605 -2.07595 1.73601004 -2.07595 0 P 0 
L 1.64571004 -2.07495 1.73641004 -2.07495 0 P 0 
L 1.64536004 -2.07395 1.73681004 -2.07395 0 P 0 
L 1.64501998 -2.07295 1.73721998 -2.07295 0 P 0 
L 1.64466998 -2.07195 1.73761998 -2.07195 0 P 0 
L 1.64433002 -2.07095 1.73803002 -2.07095 0 P 0 
L 1.64398002 -2.06995 1.69251004 -2.06995 0 P 0 
L 1.69583002 -2.06995 1.73843996 -2.06995 0 P 0 
L 1.64363002 -2.06895 1.69168002 -2.06895 0 P 0 
L 1.69671998 -2.06895 1.73883996 -2.06895 0 P 0 
L 1.64328996 -2.06795 1.69136004 -2.06795 0 P 0 
L 1.69708996 -2.06795 1.73925 -2.06795 0 P 0 
L 1.64293996 -2.06695 1.69108002 -2.06695 0 P 0 
L 1.69738002 -2.06695 1.73965 -2.06695 0 P 0 
L 1.64258996 -2.06595 1.6908 -2.06595 0 P 0 
L 1.69768002 -2.06595 1.74006004 -2.06595 0 P 0 
L 1.64223996 -2.06495 1.69051998 -2.06495 0 P 0 
L 1.69796998 -2.06495 1.74046004 -2.06495 0 P 0 
L 1.6419 -2.06395 1.69023002 -2.06395 0 P 0 
L 1.69826998 -2.06395 1.74086004 -2.06395 0 P 0 
L 1.64155 -2.06295 1.68996004 -2.06295 0 P 0 
L 1.69856004 -2.06295 1.74126998 -2.06295 0 P 0 
L 1.6412 -2.06195 1.68966998 -2.06195 0 P 0 
L 1.69886004 -2.06195 1.74168002 -2.06195 0 P 0 
L 1.64085 -2.06095 1.68938996 -2.06095 0 P 0 
L 1.69915 -2.06095 1.74208002 -2.06095 0 P 0 
L 1.6405 -2.05995 1.68911004 -2.05995 0 P 0 
L 1.69945 -2.05995 1.74248002 -2.05995 0 P 0 
L 1.64016004 -2.05895 1.68883002 -2.05895 0 P 0 
L 1.69973996 -2.05895 1.74288996 -2.05895 0 P 0 
L 1.63981004 -2.05795 1.68855 -2.05795 0 P 0 
L 1.70003996 -2.05795 1.74328996 -2.05795 0 P 0 
L 1.63946004 -2.05695 1.68826998 -2.05695 0 P 0 
L 1.70033002 -2.05695 1.7437 -2.05695 0 P 0 
L 1.63911004 -2.05595 1.68798996 -2.05595 0 P 0 
L 1.70063002 -2.05595 1.7441 -2.05595 0 P 0 
L 1.63876998 -2.05495 1.68771004 -2.05495 0 P 0 
L 1.70091998 -2.05495 1.74451004 -2.05495 0 P 0 
L 1.63841998 -2.05395 1.68741998 -2.05395 0 P 0 
L 1.70121998 -2.05395 1.74491004 -2.05395 0 P 0 
L 1.63806998 -2.05295 1.68713996 -2.05295 0 P 0 
L 1.70151004 -2.05295 1.74531004 -2.05295 0 P 0 
L 1.63771998 -2.05195 1.68686004 -2.05195 0 P 0 
L 1.70181004 -2.05195 1.74571998 -2.05195 0 P 0 
L 1.63738002 -2.05095 1.68658002 -2.05095 0 P 0 
L 1.7021 -2.05095 1.74611998 -2.05095 0 P 0 
L 1.63703002 -2.04995 1.6863 -2.04995 0 P 0 
L 1.7024 -2.04995 1.74653002 -2.04995 0 P 0 
L 1.63668002 -2.04895 1.68601998 -2.04895 0 P 0 
L 1.70268996 -2.04895 1.74693002 -2.04895 0 P 0 
L 1.63633002 -2.04795 1.68573996 -2.04795 0 P 0 
L 1.70298996 -2.04795 1.74733002 -2.04795 0 P 0 
L 1.63598002 -2.04695 1.68546004 -2.04695 0 P 0 
L 1.70328002 -2.04695 1.74773996 -2.04695 0 P 0 
L 1.63563996 -2.04595 1.68518002 -2.04595 0 P 0 
L 1.70358002 -2.04595 1.74813996 -2.04595 0 P 0 
L 1.63528996 -2.04495 1.6849 -2.04495 0 P 0 
L 1.70386998 -2.04495 1.74855 -2.04495 0 P 0 
L 1.63493996 -2.04395 1.68461004 -2.04395 0 P 0 
L 1.70416998 -2.04395 1.74895 -2.04395 0 P 0 
L 1.63458996 -2.04295 1.68433002 -2.04295 0 P 0 
L 1.70446004 -2.04295 1.74936004 -2.04295 0 P 0 
L 1.63425 -2.04195 1.68405 -2.04195 0 P 0 
L 1.70475 -2.04195 1.74976004 -2.04195 0 P 0 
L 1.6339 -2.04095 1.68376998 -2.04095 0 P 0 
L 1.70503002 -2.04095 1.75016004 -2.04095 0 P 0 
L 1.63355 -2.03995 1.68348996 -2.03995 0 P 0 
L 1.70531998 -2.03995 1.75056998 -2.03995 0 P 0 
L 1.6332 -2.03895 1.68321004 -2.03895 0 P 0 
L 1.7056 -2.03895 1.75096998 -2.03895 0 P 0 
L 1.63286004 -2.03795 1.68293002 -2.03795 0 P 0 
L 1.70588996 -2.03795 1.75138002 -2.03795 0 P 0 
L 1.63251004 -2.03695 1.68266004 -2.03695 0 P 0 
L 1.70618002 -2.03695 1.75178002 -2.03695 0 P 0 
L 1.63216004 -2.03595 1.68238002 -2.03595 0 P 0 
L 1.70646998 -2.03595 1.75218996 -2.03595 0 P 0 
L 1.63181004 -2.03495 1.6821 -2.03495 0 P 0 
L 1.70675 -2.03495 1.75258996 -2.03495 0 P 0 
L 1.63146998 -2.03395 1.68183002 -2.03395 0 P 0 
L 1.70703996 -2.03395 1.75298996 -2.03395 0 P 0 
L 1.63111998 -2.03295 1.68155 -2.03295 0 P 0 
L 1.70733002 -2.03295 1.7534 -2.03295 0 P 0 
L 1.63076998 -2.03195 1.68126998 -2.03195 0 P 0 
L 1.70761004 -2.03195 1.75381004 -2.03195 0 P 0 
L 1.63041998 -2.03095 1.68098996 -2.03095 0 P 0 
L 1.7079 -2.03095 1.75421004 -2.03095 0 P 0 
L 1.63006998 -2.02995 1.68071004 -2.02995 0 P 0 
L 1.70818996 -2.02995 1.75461004 -2.02995 0 P 0 
L 1.62973002 -2.02895 1.68043996 -2.02895 0 P 0 
L 1.70846998 -2.02895 1.75501998 -2.02895 0 P 0 
L 1.62938002 -2.02795 1.68016004 -2.02795 0 P 0 
L 1.70876004 -2.02795 1.75541998 -2.02795 0 P 0 
L 1.62903002 -2.02695 1.67988002 -2.02695 0 P 0 
L 1.70905 -2.02695 1.75583002 -2.02695 0 P 0 
L 1.62868002 -2.02595 1.6796 -2.02595 0 P 0 
L 1.70933996 -2.02595 1.75623002 -2.02595 0 P 0 
L 1.62831004 -2.02495 1.67933002 -2.02495 0 P 0 
L 1.70961998 -2.02495 1.75663996 -2.02495 0 P 0 
L 1.62793996 -2.02395 1.67905 -2.02395 0 P 0 
L 1.70991004 -2.02395 1.75703996 -2.02395 0 P 0 
L 1.62756998 -2.02295 1.67876998 -2.02295 0 P 0 
L 1.7102 -2.02295 1.75743996 -2.02295 0 P 0 
L 1.6272 -2.02195 1.6785 -2.02195 0 P 0 
L 1.71048002 -2.02195 1.75785 -2.02195 0 P 0 
L 1.62683002 -2.02095 1.67821998 -2.02095 0 P 0 
L 1.71076004 -2.02095 1.75825 -2.02095 0 P 0 
L 1.62646998 -2.01995 1.67793996 -2.01995 0 P 0 
L 1.71101004 -2.01995 1.75866004 -2.01995 0 P 0 
L 1.6261 -2.01895 1.67766004 -2.01895 0 P 0 
L 1.71126998 -2.01895 1.75906004 -2.01895 0 P 0 
L 1.62573002 -2.01795 1.67738996 -2.01795 0 P 0 
L 1.71151998 -2.01795 1.75946998 -2.01795 0 P 0 
L 1.62536004 -2.01695 1.67711004 -2.01695 0 P 0 
L 1.71176998 -2.01695 1.75986998 -2.01695 0 P 0 
L 1.62498996 -2.01595 1.67683002 -2.01595 0 P 0 
L 1.71203002 -2.01595 1.76026998 -2.01595 0 P 0 
L 1.62461998 -2.01495 1.67656004 -2.01495 0 P 0 
L 1.71228002 -2.01495 1.76068002 -2.01495 0 P 0 
L 1.62425 -2.01395 1.67628002 -2.01395 0 P 0 
L 1.71253996 -2.01395 1.76108002 -2.01395 0 P 0 
L 1.62388002 -2.01295 1.67601998 -2.01295 0 P 0 
L 1.71278996 -2.01295 1.76148996 -2.01295 0 P 0 
L 1.62351004 -2.01195 1.67576998 -2.01195 0 P 0 
L 1.71305 -2.01195 1.76188996 -2.01195 0 P 0 
L 1.62313996 -2.01095 1.67551998 -2.01095 0 P 0 
L 1.7133 -2.01095 1.76228996 -2.01095 0 P 0 
L 1.62276998 -2.00995 1.67528002 -2.00995 0 P 0 
L 1.71355 -2.00995 1.7627 -2.00995 0 P 0 
L 1.6224 -2.00895 1.67503002 -2.00895 0 P 0 
L 1.71381004 -2.00895 1.7631 -2.00895 0 P 0 
L 1.62203002 -2.00795 1.67478996 -2.00795 0 P 0 
L 1.71406004 -2.00795 1.76351004 -2.00795 0 P 0 
L 1.62166004 -2.00695 1.67453996 -2.00695 0 P 0 
L 1.71431004 -2.00695 1.76391004 -2.00695 0 P 0 
L 1.62128996 -2.00595 1.67428996 -2.00595 0 P 0 
L 1.71453996 -2.00595 1.76431998 -2.00595 0 P 0 
L 1.62091004 -2.00495 1.67405 -2.00495 0 P 0 
L 1.71476998 -2.00495 1.76471998 -2.00495 0 P 0 
L 1.62051998 -2.00395 1.6738 -2.00395 0 P 0 
L 1.715 -2.00395 1.76511998 -2.00395 0 P 0 
L 1.62013002 -2.00295 1.67355 -2.00295 0 P 0 
L 1.71523002 -2.00295 1.76553002 -2.00295 0 P 0 
L 1.61973996 -2.00195 1.67331004 -2.00195 0 P 0 
L 1.71546004 -2.00195 1.76593996 -2.00195 0 P 0 
L 1.61935 -2.00095 1.67306004 -2.00095 0 P 0 
L 1.71568996 -2.00095 1.76633996 -2.00095 0 P 0 
L 1.61896004 -1.99995 1.67283996 -1.99995 0 P 0 
L 1.71591998 -1.99995 1.76673996 -1.99995 0 P 0 
L 1.61856998 -1.99895 1.67261998 -1.99895 0 P 0 
L 1.71613996 -1.99895 1.76715 -1.99895 0 P 0 
L 1.71638002 -1.99795 1.76755 -1.99795 0 P 0 
L 1.7166 -1.99695 1.76796004 -1.99695 0 P 0 
L 1.71683002 -1.99595 1.76836004 -1.99595 0 P 0 
L 1.71866998 -1.99495 1.76876998 -1.99495 0 P 0 
L 1.78213996 -2.04823996 1.84641998 -2.04823996 0 P 0 
L 1.78138002 -2.04723996 1.84498996 -2.04723996 0 P 0 
L 1.78071004 -2.04623996 1.84356004 -2.04623996 0 P 0 
L 1.7801 -2.04523996 1.84213996 -2.04523996 0 P 0 
L 1.77956004 -2.04423996 1.84071004 -2.04423996 0 P 0 
L 1.77908996 -2.04323996 1.83928002 -2.04323996 0 P 0 
L 1.77866004 -2.04223996 1.83786004 -2.04223996 0 P 0 
L 1.77831004 -2.04123996 1.83658996 -2.04123996 0 P 0 
L 1.77796004 -2.04023996 1.83536004 -2.04023996 0 P 0 
L 1.77761004 -2.03923996 1.83428002 -2.03923996 0 P 0 
L 1.77733996 -2.03823996 1.83321998 -2.03823996 0 P 0 
L 1.77706998 -2.03723996 1.83236998 -2.03723996 0 P 0 
L 1.7768 -2.03623996 1.83171004 -2.03623996 0 P 0 
L 1.7766 -2.03523996 1.83121004 -2.03523996 0 P 0 
L 1.77641004 -2.03423996 1.83085 -2.03423996 0 P 0 
L 1.77621004 -2.03323996 1.83071004 -2.03323996 0 P 0 
L 1.77608002 -2.03223996 1.83076998 -2.03223996 0 P 0 
L 1.77596004 -2.03123996 1.83106004 -2.03123996 0 P 0 
L 1.77583996 -2.03023996 1.83158996 -2.03023996 0 P 0 
L 1.77576004 -2.02923996 1.83238002 -2.02923996 0 P 0 
L 1.7757 -2.02823996 1.83356998 -2.02823996 0 P 0 
L 1.7757 -2.02723996 1.83591998 -2.02723996 0 P 0 
L 1.77571998 -2.02623996 1.87495 -2.02623996 0 P 0 
L 1.7758 -2.02523996 1.87485 -2.02523996 0 P 0 
L 1.77588996 -2.02423996 1.87475 -2.02423996 0 P 0 
L 1.77605 -2.02323996 1.87465 -2.02323996 0 P 0 
L 1.77621004 -2.02223996 1.87455 -2.02223996 0 P 0 
L 1.7764 -2.02123996 1.87445 -2.02123996 0 P 0 
L 1.77665 -2.02023996 1.87433996 -2.02023996 0 P 0 
L 1.7769 -2.01923996 1.87425 -2.01923996 0 P 0 
L 1.7772 -2.01823996 1.87413996 -2.01823996 0 P 0 
L 1.77753002 -2.01723996 1.87405 -2.01723996 0 P 0 
L 1.77786004 -2.01623996 1.87393996 -2.01623996 0 P 0 
L 1.77823002 -2.01523996 1.87383996 -2.01523996 0 P 0 
L 1.77863996 -2.01423996 1.87373996 -2.01423996 0 P 0 
L 1.77903996 -2.01323996 1.87363996 -2.01323996 0 P 0 
L 1.7795 -2.01223996 1.87353996 -2.01223996 0 P 0 
L 1.77998996 -2.01123996 1.87343996 -2.01123996 0 P 0 
L 1.78046998 -2.01023996 1.87333002 -2.01023996 0 P 0 
L 1.78103996 -2.00923996 1.87323002 -2.00923996 0 P 0 
L 1.78161004 -2.00823996 1.87311998 -2.00823996 0 P 0 
L 1.78221004 -2.00723996 1.87301998 -2.00723996 0 P 0 
L 1.78288002 -2.00623996 1.87291998 -2.00623996 0 P 0 
L 1.64213996 -2.14795 1.70566004 -2.14795 0 P 0 
L 1.64518996 -2.14695 1.7062 -2.14695 0 P 0 
L 1.64728996 -2.14595 1.70673996 -2.14595 0 P 0 
L 1.64906998 -2.14495 1.70728002 -2.14495 0 P 0 
L 1.65058002 -2.14395 1.70783002 -2.14395 0 P 0 
L 1.6519 -2.14295 1.70836998 -2.14295 0 P 0 
L 1.65311998 -2.14195 1.70881998 -2.14195 0 P 0 
L 1.65416998 -2.14095 1.70926998 -2.14095 0 P 0 
L 1.65508996 -2.13995 1.70973002 -2.13995 0 P 0 
L 1.65588002 -2.13895 1.71018002 -2.13895 0 P 0 
L 1.65658002 -2.13795 1.71063002 -2.13795 0 P 0 
L 1.65726998 -2.13695 1.71108996 -2.13695 0 P 0 
L 1.65791998 -2.13595 1.71153996 -2.13595 0 P 0 
L 1.65853002 -2.13495 1.71198996 -2.13495 0 P 0 
L 1.65913002 -2.13395 1.71245 -2.13395 0 P 0 
L 1.65968002 -2.13295 1.7129 -2.13295 0 P 0 
L 1.66021998 -2.13195 1.71331004 -2.13195 0 P 0 
L 1.66071998 -2.13095 1.71371998 -2.13095 0 P 0 
L 1.66121004 -2.12995 1.71411998 -2.12995 0 P 0 
L 1.66166998 -2.12895 1.71453002 -2.12895 0 P 0 
L 1.66201004 -2.12795 1.71493996 -2.12795 0 P 0 
L 1.66223996 -2.12695 1.71533996 -2.12695 0 P 0 
L 1.66235 -2.12595 1.71575 -2.12595 0 P 0 
L 1.66236004 -2.12495 1.71615 -2.12495 0 P 0 
L 1.66228002 -2.12395 1.71656004 -2.12395 0 P 0 
L 1.66211998 -2.12295 1.71696004 -2.12295 0 P 0 
L 1.66188002 -2.12195 1.71736004 -2.12195 0 P 0 
L 1.66156004 -2.12095 1.71776998 -2.12095 0 P 0 
L 1.66121004 -2.11995 1.71818002 -2.11995 0 P 0 
L 1.66086998 -2.11895 1.71858002 -2.11895 0 P 0 
L 1.66053002 -2.11795 1.71898996 -2.11795 0 P 0 
L 1.66018002 -2.11695 1.71938996 -2.11695 0 P 0 
L 1.65983996 -2.11595 1.7198 -2.11595 0 P 0 
L 1.65948996 -2.11495 1.7202 -2.11495 0 P 0 
L 1.65913996 -2.11395 1.72061004 -2.11395 0 P 0 
L 1.6588 -2.11295 1.72101004 -2.11295 0 P 0 
L 1.65846004 -2.11195 1.72141998 -2.11195 0 P 0 
L 1.65811004 -2.11095 1.72181998 -2.11095 0 P 0 
L 1.65776998 -2.10995 1.72223002 -2.10995 0 P 0 
L 1.65741998 -2.10895 1.72263002 -2.10895 0 P 0 
L 1.65708002 -2.10795 1.72303996 -2.10795 0 P 0 
L 1.65673002 -2.10695 1.72343996 -2.10695 0 P 0 
L 1.65638996 -2.10595 1.72385 -2.10595 0 P 0 
L 1.65605 -2.10495 1.72425 -2.10495 0 P 0 
L 1.6557 -2.10395 1.72466004 -2.10395 0 P 0 
L 1.65536004 -2.10295 1.72506998 -2.10295 0 P 0 
L 1.65501004 -2.10195 1.72546998 -2.10195 0 P 0 
L 1.65466998 -2.10095 1.72588002 -2.10095 0 P 0 
L 1.65431998 -2.09995 1.72628002 -2.09995 0 P 0 
L 1.65398002 -2.09895 1.72668996 -2.09895 0 P 0 
L 1.65363002 -2.09795 1.72708996 -2.09795 0 P 0 
L 1.65328996 -2.09695 1.72748996 -2.09695 0 P 0 
L 1.65293996 -2.09595 1.7279 -2.09595 0 P 0 
L 1.6526 -2.09495 1.72831004 -2.09495 0 P 0 
L 1.65225 -2.09395 1.72871004 -2.09395 0 P 0 
L 1.65191004 -2.09295 1.72911998 -2.09295 0 P 0 
L 1.65156998 -2.09195 1.72951998 -2.09195 0 P 0 
L 1.65121998 -2.09095 1.72993002 -2.09095 0 P 0 
L 1.65088002 -2.08995 1.73033002 -2.08995 0 P 0 
L 1.65053002 -2.08895 1.73073996 -2.08895 0 P 0 
L 1.65018996 -2.08795 1.73113996 -2.08795 0 P 0 
L 1.64983996 -2.08695 1.73155 -2.08695 0 P 0 
L 1.6495 -2.08595 1.73195 -2.08595 0 P 0 
L 1.64915 -2.08495 1.73236004 -2.08495 0 P 0 
L 1.64881004 -2.08395 1.73276004 -2.08395 0 P 0 
L 1.81726998 -1.98915 1.81196004 -1.9899 0 P 0 
L 1.81196004 -1.9899 1.80668996 -1.99096998 0 P 0 
L 1.80668996 -1.99096998 1.8019 -1.99226004 0 P 0 
L 1.8019 -1.99226004 1.79718996 -1.99391004 0 P 0 
L 1.79718996 -1.99391004 1.79316004 -1.99568002 0 P 0 
L 1.79316004 -1.99568002 1.78926998 -1.99778002 0 P 0 
L 1.78926998 -1.99778002 1.78771004 -1.99878002 0 P 0 
L 1.78771004 -1.99878002 1.78623002 -1.99988002 0 P 0 
L 1.78623002 -1.99988002 1.78481004 -2.00108002 0 P 0 
L 1.78481004 -2.00108002 1.78346998 -2.00238996 0 P 0 
L 1.78346998 -2.00238996 1.78228996 -2.00371998 0 P 0 
L 1.78228996 -2.00371998 1.78121004 -2.00513002 0 P 0 
L 1.78121004 -2.00513002 1.78023002 -2.00661004 0 P 0 
L 1.78023002 -2.00661004 1.77868002 -2.00933996 0 P 0 
L 1.77868002 -2.00933996 1.77731998 -2.01216998 0 P 0 
L 1.77731998 -2.01216998 1.77611004 -2.01516004 0 P 0 
L 1.77611004 -2.01516004 1.77508996 -2.01823002 0 P 0 
L 1.77508996 -2.01823002 1.77436998 -2.02111004 0 P 0 
L 1.77436998 -2.02111004 1.77388996 -2.02406004 0 P 0 
L 1.77388996 -2.02406004 1.77371998 -2.02603996 0 P 0 
L 1.77371998 -2.02603996 1.77368996 -2.02801998 0 P 0 
L 1.77368996 -2.02801998 1.7738 -2.03001998 0 P 0 
L 1.7738 -2.03001998 1.7742 -2.03338996 0 P 0 
L 1.7742 -2.03338996 1.77485 -2.03671004 0 P 0 
L 1.77485 -2.03671004 1.77573002 -2.03993996 0 P 0 
L 1.77573002 -2.03993996 1.77683996 -2.04308002 0 P 0 
L 1.77683996 -2.04308002 1.7776 -2.04481998 0 P 0 
L 1.7776 -2.04481998 1.7785 -2.04648996 0 P 0 
L 1.7785 -2.04648996 1.77953002 -2.04808996 0 P 0 
L 1.77953002 -2.04808996 1.78061004 -2.04953996 0 P 0 
L 1.78061004 -2.04953996 1.78181004 -2.05091004 0 P 0 
L 1.78181004 -2.05091004 1.78311004 -2.05218996 0 P 0 
L 1.78311004 -2.05218996 1.78988996 -2.05801998 0 P 0 
L 1.78988996 -2.05801998 1.79883996 -2.06491004 0 P 0 
L 1.79883996 -2.06491004 1.80976998 -2.07261004 0 P 0 
L 1.80976998 -2.07261004 1.81753002 -2.07823002 0 P 0 
L 1.81753002 -2.07823002 1.81896998 -2.07943002 0 P 0 
L 1.81896998 -2.07943002 1.82033002 -2.08073002 0 P 0 
L 1.82033002 -2.08073002 1.82156998 -2.08213996 0 P 0 
L 1.82156998 -2.08213996 1.82186004 -2.08251004 0 P 0 
L 1.82186004 -2.08251004 1.82211004 -2.0829 0 P 0 
L 1.82211004 -2.0829 1.82233002 -2.08331004 0 P 0 
L 1.82233002 -2.08331004 1.82253002 -2.08373996 0 P 0 
L 1.82253002 -2.08373996 1.82268002 -2.08418002 0 P 0 
L 1.82268002 -2.08418002 1.82281004 -2.08463002 0 P 0 
L 1.82281004 -2.08463002 1.8229 -2.0851 0 P 0 
L 1.8229 -2.0851 1.82293002 -2.08533996 0 P 0 
L 1.82293002 -2.08533996 1.82293996 -2.08558996 0 P 0 
L 1.82293996 -2.08558996 1.82291998 -2.08583996 0 P 0 
L 1.82291998 -2.08583996 1.82288002 -2.08608002 0 P 0 
L 1.82288002 -2.08608002 1.82283002 -2.08631998 0 P 0 
L 1.82283002 -2.08631998 1.82275 -2.08656004 0 P 0 
L 1.82275 -2.08656004 1.82265 -2.08678996 0 P 0 
L 1.82265 -2.08678996 1.82253996 -2.087 0 P 0 
L 1.82253996 -2.087 1.8224 -2.08721004 0 P 0 
L 1.8224 -2.08721004 1.82225 -2.08741004 0 P 0 
L 1.82225 -2.08741004 1.82208996 -2.08758996 0 P 0 
L 1.82208996 -2.08758996 1.8216 -2.08803996 0 P 0 
L 1.8216 -2.08803996 1.82106998 -2.08845 0 P 0 
L 1.82106998 -2.08845 1.82051004 -2.08881004 0 P 0 
L 1.82051004 -2.08881004 1.81991998 -2.08911998 0 P 0 
L 1.81991998 -2.08911998 1.81931004 -2.08936998 0 P 0 
L 1.81931004 -2.08936998 1.81868002 -2.08958002 0 P 0 
L 1.81868002 -2.08958002 1.81803002 -2.08973002 0 P 0 
L 1.81803002 -2.08973002 1.81736004 -2.08981998 0 P 0 
L 1.81736004 -2.08981998 1.81293002 -2.09001998 0 P 0 
L 1.81293002 -2.09001998 1.80846998 -2.08986004 0 P 0 
L 1.80846998 -2.08986004 1.80256998 -2.08923002 0 P 0 
L 1.80256998 -2.08923002 1.79668002 -2.08818996 0 P 0 
L 1.79668002 -2.08818996 1.78223002 -2.08458002 0 P 0 
L 1.78223002 -2.08458002 1.77788996 -2.08338002 0 P 0 
L 1.77788996 -2.08338002 1.77415 -2.08246004 0 P 0 
L 1.77415 -2.08246004 1.77095 -2.08175 0 P 0 
L 1.77095 -2.08175 1.7709 -2.08173996 0 P 0 
L 1.7709 -2.08173996 1.77076998 -2.08173996 0 P 0 
L 1.77076998 -2.08173996 1.77068996 -2.08176004 0 P 0 
L 1.77068996 -2.08176004 1.77053002 -2.08183996 0 P 0 
L 1.77053002 -2.08183996 1.77043002 -2.08193996 0 P 0 
L 1.77043002 -2.08193996 1.77036998 -2.08201998 0 P 0 
L 1.77036998 -2.08201998 1.77031998 -2.08211998 0 P 0 
L 1.77031998 -2.08211998 1.7703 -2.08216998 0 P 0 
L 1.7703 -2.08216998 1.77028996 -2.08223002 0 P 0 
L 1.77028996 -2.08223002 1.77028002 -2.08228002 0 P 0 
L 1.77028002 -2.08228002 1.77028002 -2.08238996 0 P 0 
L 1.77028002 -2.08238996 1.77056998 -2.08838996 0 P 0 
L 1.77056998 -2.08838996 1.77096004 -2.09526004 0 P 0 
L 1.77096004 -2.09526004 1.77153996 -2.1033 0 P 0 
L 1.77153996 -2.1033 1.77236004 -2.11291004 0 P 0 
L 1.77236004 -2.11291004 1.77311004 -2.1194 0 P 0 
L 1.77311004 -2.1194 1.77383002 -2.12398002 0 P 0 
L 1.77383002 -2.12398002 1.77386004 -2.12411004 0 P 0 
L 1.77386004 -2.12411004 1.7739 -2.12423002 0 P 0 
L 1.7739 -2.12423002 1.77395 -2.12436004 0 P 0 
L 1.77395 -2.12436004 1.77401004 -2.12448002 0 P 0 
L 1.77401004 -2.12448002 1.77408002 -2.12458996 0 P 0 
L 1.77408002 -2.12458996 1.77416004 -2.1247 0 P 0 
L 1.77416004 -2.1247 1.77425 -2.1248 0 P 0 
L 1.77425 -2.1248 1.77435 -2.12488996 0 P 0 
L 1.77435 -2.12488996 1.77445 -2.12496998 0 P 0 
L 1.77445 -2.12496998 1.77456998 -2.12505 0 P 0 
L 1.77456998 -2.12505 1.77571004 -2.12568996 0 P 0 
L 1.77571004 -2.12568996 1.7769 -2.12623996 0 P 0 
L 1.7769 -2.12623996 1.77813002 -2.12668996 0 P 0 
L 1.77813002 -2.12668996 1.7794 -2.12703996 0 P 0 
L 1.7794 -2.12703996 1.78068996 -2.12728996 0 P 0 
L 1.78068996 -2.12728996 1.79791998 -2.12951004 0 P 0 
L 1.79791998 -2.12951004 1.81536004 -2.13106004 0 P 0 
L 1.81536004 -2.13106004 1.82125 -2.13123996 0 P 0 
L 1.82125 -2.13123996 1.82716004 -2.13098996 0 P 0 
L 1.82716004 -2.13098996 1.83583996 -2.12998002 0 P 0 
L 1.83583996 -2.12998002 1.84445 -2.12836004 0 P 0 
L 1.84445 -2.12836004 1.84911998 -2.12711004 0 P 0 
L 1.84911998 -2.12711004 1.85366004 -2.12548002 0 P 0 
L 1.85366004 -2.12548002 1.85806998 -2.12348002 0 P 0 
L 1.85806998 -2.12348002 1.86078996 -2.12196998 0 P 0 
L 1.86078996 -2.12196998 1.8634 -2.12026998 0 P 0 
L 1.8634 -2.12026998 1.86586998 -2.11836998 0 P 0 
L 1.86586998 -2.11836998 1.86821004 -2.11628002 0 P 0 
L 1.86821004 -2.11628002 1.87026004 -2.11413002 0 P 0 
L 1.87026004 -2.11413002 1.8721 -2.11181998 0 P 0 
L 1.8721 -2.11181998 1.87375 -2.10936004 0 P 0 
L 1.87375 -2.10936004 1.87516998 -2.10673996 0 P 0 
L 1.87516998 -2.10673996 1.87605 -2.10483996 0 P 0 
L 1.87605 -2.10483996 1.87683996 -2.10291004 0 P 0 
L 1.87683996 -2.10291004 1.8772 -2.10188002 0 P 0 
L 1.8772 -2.10188002 1.87748996 -2.10083002 0 P 0 
L 1.87748996 -2.10083002 1.87771004 -2.09976998 0 P 0 
L 1.87771004 -2.09976998 1.87798002 -2.09788996 0 P 0 
L 1.87798002 -2.09788996 1.87811998 -2.09601004 0 P 0 
L 1.87811998 -2.09601004 1.87821004 -2.08966998 0 P 0 
L 1.87821004 -2.08966998 1.8781 -2.08353996 0 P 0 
L 1.8781 -2.08353996 1.87798002 -2.08166004 0 P 0 
L 1.87798002 -2.08166004 1.87773002 -2.07976998 0 P 0 
L 1.87773002 -2.07976998 1.87753002 -2.07873996 0 P 0 
L 1.87753002 -2.07873996 1.87726998 -2.07773996 0 P 0 
L 1.87726998 -2.07773996 1.87695 -2.07673996 0 P 0 
L 1.87695 -2.07673996 1.87628996 -2.07505 0 P 0 
L 1.87628996 -2.07505 1.87553002 -2.07338002 0 P 0 
L 1.87553002 -2.07338002 1.87441004 -2.07133996 0 P 0 
L 1.87441004 -2.07133996 1.87313996 -2.06938002 0 P 0 
L 1.87313996 -2.06938002 1.87171004 -2.06751004 0 P 0 
L 1.87171004 -2.06751004 1.8688 -2.06416004 0 P 0 
L 1.8688 -2.06416004 1.86566998 -2.06095 0 P 0 
L 1.86566998 -2.06095 1.86181998 -2.05741998 0 P 0 
L 1.86181998 -2.05741998 1.85778002 -2.05406998 0 P 0 
L 1.85778002 -2.05406998 1.84833996 -2.04715 0 P 0 
L 1.84833996 -2.04715 1.83913996 -2.0407 0 P 0 
L 1.83913996 -2.0407 1.83686004 -2.0389 0 P 0 
L 1.83686004 -2.0389 1.83471998 -2.03691998 0 P 0 
L 1.83471998 -2.03691998 1.83428002 -2.03643002 0 P 0 
L 1.83428002 -2.03643002 1.83386998 -2.0359 0 P 0 
L 1.83386998 -2.0359 1.83351004 -2.03535 0 P 0 
L 1.83351004 -2.03535 1.83318996 -2.03476004 0 P 0 
L 1.83318996 -2.03476004 1.83291998 -2.03415 0 P 0 
L 1.83291998 -2.03415 1.83283996 -2.03393996 0 P 0 
L 1.83283996 -2.03393996 1.83278002 -2.03371004 0 P 0 
L 1.83278002 -2.03371004 1.83273002 -2.03348996 0 P 0 
L 1.83273002 -2.03348996 1.83271004 -2.03326004 0 P 0 
L 1.83271004 -2.03326004 1.8327 -2.03303002 0 P 0 
L 1.8327 -2.03303002 1.83271004 -2.0328 0 P 0 
L 1.83271004 -2.0328 1.83275 -2.03258002 0 P 0 
L 1.83275 -2.03258002 1.83278996 -2.03235 0 P 0 
L 1.83278996 -2.03235 1.83286004 -2.03213002 0 P 0 
L 1.83286004 -2.03213002 1.83293996 -2.03191998 0 P 0 
L 1.83293996 -2.03191998 1.83305 -2.03171004 0 P 0 
L 1.83305 -2.03171004 1.83325 -2.03135 0 P 0 
L 1.83325 -2.03135 1.83348996 -2.03101998 0 P 0 
L 1.83348996 -2.03101998 1.83375 -2.03071004 0 P 0 
L 1.83375 -2.03071004 1.83403002 -2.03041004 0 P 0 
L 1.83403002 -2.03041004 1.83433996 -2.03015 0 P 0 
L 1.83433996 -2.03015 1.83466998 -2.02991004 0 P 0 
L 1.83466998 -2.02991004 1.83501998 -2.02968996 0 P 0 
L 1.83501998 -2.02968996 1.83538002 -2.02951004 0 P 0 
L 1.83538002 -2.02951004 1.83576004 -2.02936004 0 P 0 
L 1.83576004 -2.02936004 1.83615 -2.02923996 0 P 0 
L 1.83615 -2.02923996 1.83655 -2.02915 0 P 0 
L 1.83655 -2.02915 1.8392 -2.02873996 0 P 0 
L 1.8392 -2.02873996 1.84188002 -2.0285 0 P 0 
L 1.84188002 -2.0285 1.84458002 -2.02841004 0 P 0 
L 1.84458002 -2.02841004 1.84993996 -2.02858002 0 P 0 
L 1.84993996 -2.02858002 1.85526998 -2.02916004 0 P 0 
L 1.85526998 -2.02916004 1.86155 -2.03023002 0 P 0 
L 1.86155 -2.03023002 1.86778002 -2.03158002 0 P 0 
L 1.86778002 -2.03158002 1.8713 -2.03238996 0 P 0 
L 1.8713 -2.03238996 1.87428996 -2.03303002 0 P 0 
L 1.87428996 -2.03303002 1.8769 -2.03356004 0 P 0 
L 1.8769 -2.03356004 1.87691998 -2.03356998 0 P 0 
L 1.87691998 -2.03356998 1.87696004 -2.03356998 0 P 0 
L 1.87696004 -2.03356998 1.87696998 -2.03356004 0 P 0 
L 1.87696998 -2.03356004 1.87701004 -2.03356004 0 P 0 
L 1.87701004 -2.03356004 1.87703996 -2.03353996 0 P 0 
L 1.87703996 -2.03353996 1.87706004 -2.03353002 0 P 0 
L 1.87706004 -2.03353002 1.87706998 -2.03351998 0 P 0 
L 1.87706998 -2.03351998 1.87708996 -2.03351004 0 P 0 
L 1.87708996 -2.03351004 1.8771 -2.03348996 0 P 0 
L 1.8771 -2.03348996 1.87711004 -2.03348002 0 P 0 
L 1.87711004 -2.03348002 1.87721998 -2.0333 0 P 0 
L 1.87721998 -2.0333 1.87731998 -2.0331 0 P 0 
L 1.87731998 -2.0331 1.8774 -2.0329 0 P 0 
L 1.8774 -2.0329 1.87746004 -2.03268996 0 P 0 
L 1.87746004 -2.03268996 1.87751004 -2.03248002 0 P 0 
L 1.87751004 -2.03248002 1.87753002 -2.03226998 0 P 0 
L 1.87753002 -2.03226998 1.87753996 -2.03205 0 P 0 
L 1.87753996 -2.03205 1.87753002 -2.03183002 0 P 0 
L 1.87753002 -2.03183002 1.87565 -2.01323996 0 P 0 
L 1.87565 -2.01323996 1.87371004 -1.99451998 0 P 0 
L 1.87371004 -1.99451998 1.8737 -1.99438996 0 P 0 
L 1.8737 -1.99438996 1.87366998 -1.99426998 0 P 0 
L 1.87366998 -1.99426998 1.87363002 -1.99415 0 P 0 
L 1.87363002 -1.99415 1.87358002 -1.99403002 0 P 0 
L 1.87358002 -1.99403002 1.87351998 -1.99391004 0 P 0 
L 1.87351998 -1.99391004 1.87346004 -1.9938 0 P 0 
L 1.87346004 -1.9938 1.87338002 -1.9937 0 P 0 
L 1.87338002 -1.9937 1.87328996 -1.9936 0 P 0 
L 1.87328996 -1.9936 1.8732 -1.99351004 0 P 0 
L 1.8732 -1.99351004 1.8731 -1.99343002 0 P 0 
L 1.8731 -1.99343002 1.87298996 -1.99335 0 P 0 
L 1.87298996 -1.99335 1.87248002 -1.99305 0 P 0 
L 1.87248002 -1.99305 1.87193996 -1.99278002 0 P 0 
L 1.87193996 -1.99278002 1.87136998 -1.99256998 0 P 0 
L 1.87136998 -1.99256998 1.87078996 -1.99241004 0 P 0 
L 1.87078996 -1.99241004 1.8702 -1.9923 0 P 0 
L 1.8702 -1.9923 1.85876004 -1.99076004 0 P 0 
L 1.85876004 -1.99076004 1.84691998 -1.98943002 0 P 0 
L 1.84691998 -1.98943002 1.83693002 -1.98876004 0 P 0 
L 1.83693002 -1.98876004 1.8318 -1.98863002 0 P 0 
L 1.8318 -1.98863002 1.82623002 -1.98866998 0 P 0 
L 1.82623002 -1.98866998 1.82106004 -1.98883996 0 P 0 
L 1.82106004 -1.98883996 1.81726998 -1.98915 0 P 0 
L 1.78061004 -2.12523996 1.84838002 -2.12523996 0 P 0 
L 1.77733002 -2.12423996 1.85121004 -2.12423996 0 P 0 
L 1.77573996 -2.12323996 1.85376998 -2.12323996 0 P 0 
L 1.77558002 -2.12223996 1.85596998 -2.12223996 0 P 0 
L 1.77541998 -2.12123996 1.85798996 -2.12123996 0 P 0 
L 1.77526998 -2.12023996 1.85978996 -2.12023996 0 P 0 
L 1.77511004 -2.11923996 1.86131998 -2.11923996 0 P 0 
L 1.77498996 -2.11823996 1.86276004 -2.11823996 0 P 0 
L 1.77486998 -2.11723996 1.86406998 -2.11723996 0 P 0 
L 1.77475 -2.11623996 1.86526004 -2.11623996 0 P 0 
L 1.77463996 -2.11523996 1.86638002 -2.11523996 0 P 0 
L 1.77451998 -2.11423996 1.8674 -2.11423996 0 P 0 
L 1.77441004 -2.11323996 1.86835 -2.11323996 0 P 0 
L 1.77431004 -2.11223996 1.86921004 -2.11223996 0 P 0 
L 1.77421998 -2.11123996 1.87001004 -2.11123996 0 P 0 
L 1.77413996 -2.11023996 1.87075 -2.11023996 0 P 0 
L 1.77405 -2.10923996 1.87141998 -2.10923996 0 P 0 
L 1.77396998 -2.10823996 1.87208002 -2.10823996 0 P 0 
L 1.77388002 -2.10723996 1.87261998 -2.10723996 0 P 0 
L 1.7738 -2.10623996 1.87316998 -2.10623996 0 P 0 
L 1.77371004 -2.10523996 1.87366004 -2.10523996 0 P 0 
L 1.77363002 -2.10423996 1.87411998 -2.10423996 0 P 0 
L 1.77353996 -2.10323996 1.87453996 -2.10323996 0 P 0 
L 1.77346998 -2.10223996 1.87495 -2.10223996 0 P 0 
L 1.7734 -2.10123996 1.8753 -2.10123996 0 P 0 
L 1.77333002 -2.10023996 1.87556998 -2.10023996 0 P 0 
L 1.77325 -2.09923996 1.87576998 -2.09923996 0 P 0 
L 1.77318002 -2.09823996 1.87591998 -2.09823996 0 P 0 
L 1.77311004 -2.09723996 1.87603002 -2.09723996 0 P 0 
L 1.77303996 -2.09623996 1.8761 -2.09623996 0 P 0 
L 1.77296998 -2.09523996 1.87613002 -2.09523996 0 P 0 
L 1.77291004 -2.09423996 1.87613996 -2.09423996 0 P 0 
L 1.77285 -2.09323996 1.87616004 -2.09323996 0 P 0 
L 1.77278996 -2.09223996 1.87616998 -2.09223996 0 P 0 
L 1.77273002 -2.09123996 1.80256998 -2.09123996 0 P 0 
L 1.77268002 -2.09023996 1.7968 -2.09023996 0 P 0 
L 1.77261998 -2.08923996 1.79263002 -2.08923996 0 P 0 
L 1.77256004 -2.08823996 1.78861998 -2.08823996 0 P 0 
L 1.77251004 -2.08723996 1.7846 -2.08723996 0 P 0 
L 1.77246004 -2.08623996 1.7807 -2.08623996 0 P 0 
L 1.77241998 -2.08523996 1.77705 -2.08523996 0 P 0 
L 1.77236998 -2.08423996 1.77293996 -2.08423996 0 P 0 
L 1.62463996 -2.18195 1.65948996 -2.18195 0 P 0 
L 1.61963996 -2.18095 1.66483002 -2.18095 0 P 0 
L 1.61818002 -1.99795 1.6724 -1.99795 0 P 0 
L 1.61778996 -1.99695 1.67218002 -1.99695 0 P 0 
L 1.6174 -1.99595 1.67196004 -1.99595 0 P 0 
L 1.61701004 -1.99495 1.67173996 -1.99495 0 P 0 
L 1.61391998 -2.15695 1.70026004 -2.15695 0 P 0 
L 1.61386004 -2.15595 1.70088002 -2.15595 0 P 0 
L 1.61381004 -2.15495 1.70151004 -2.15495 0 P 0 
L 1.61375 -2.15395 1.70213996 -2.15395 0 P 0 
L 1.6137 -2.15295 1.70276004 -2.15295 0 P 0 
L 1.61365 -2.15195 1.70338996 -2.15195 0 P 0 
L 1.6136 -2.15095 1.70401004 -2.15095 0 P 0 
L 1.61355 -2.14995 1.70456998 -2.14995 0 P 0 
L 1.61348996 -2.14895 1.70511998 -2.14895 0 P 0 
L 1.61343996 -2.14795 1.61738002 -2.14795 0 P 0 
L 1.55341004 -2.08286998 1.60538002 -2.08286998 0 P 0 
L 1.55286004 -2.08186998 1.60526998 -2.08186998 0 P 0 
L 1.5521 -2.08086998 1.6051 -2.08086998 0 P 0 
L 1.55126998 -2.07986998 1.6049 -2.07986998 0 P 0 
L 1.55033996 -2.07886998 1.60463996 -2.07886998 0 P 0 
L 1.54928996 -2.07786998 1.60433002 -2.07786998 0 P 0 
L 1.54806998 -2.07686998 1.60398996 -2.07686998 0 P 0 
L 1.5467 -2.07586998 1.60356998 -2.07586998 0 P 0 
L 1.54531004 -2.07486998 1.6031 -2.07486998 0 P 0 
L 1.54391004 -2.07386998 1.60258996 -2.07386998 0 P 0 
L 1.54251004 -2.07286998 1.60201004 -2.07286998 0 P 0 
L 1.54111998 -2.07186998 1.60138002 -2.07186998 0 P 0 
L 1.53971998 -2.07086998 1.60068002 -2.07086998 0 P 0 
L 1.53833002 -2.06986998 1.59993002 -2.06986998 0 P 0 
L 1.53693002 -2.06886998 1.59908002 -2.06886998 0 P 0 
L 1.53556004 -2.06786998 1.59821004 -2.06786998 0 P 0 
L 1.53418996 -2.06686998 1.59733996 -2.06686998 0 P 0 
L 1.53281998 -2.06586998 1.59646998 -2.06586998 0 P 0 
L 1.53145 -2.06486998 1.5955 -2.06486998 0 P 0 
L 1.53008002 -2.06386998 1.59453002 -2.06386998 0 P 0 
L 1.52871004 -2.06286998 1.59356004 -2.06286998 0 P 0 
L 1.52733996 -2.06186998 1.59253002 -2.06186998 0 P 0 
L 1.52596998 -2.06086998 1.59145 -2.06086998 0 P 0 
L 1.5246 -2.05986998 1.59038002 -2.05986998 0 P 0 
L 1.52323002 -2.05886998 1.5893 -2.05886998 0 P 0 
L 1.52186004 -2.05786998 1.58813996 -2.05786998 0 P 0 
L 1.52053996 -2.05686998 1.58696004 -2.05686998 0 P 0 
L 1.51935 -2.05586998 1.58576998 -2.05586998 0 P 0 
L 1.51816004 -2.05486998 1.58456998 -2.05486998 0 P 0 
L 1.51706998 -2.05386998 1.58321004 -2.05386998 0 P 0 
L 1.51603996 -2.05286998 1.58185 -2.05286998 0 P 0 
L 1.51501998 -2.05186998 1.58048996 -2.05186998 0 P 0 
L 1.51408996 -2.05086998 1.57913002 -2.05086998 0 P 0 
L 1.5132 -2.04986998 1.57776998 -2.04986998 0 P 0 
L 1.51231998 -2.04886998 1.57641998 -2.04886998 0 P 0 
L 1.51151004 -2.04786998 1.57505 -2.04786998 0 P 0 
L 1.51075 -2.04686998 1.57365 -2.04686998 0 P 0 
L 1.51008002 -2.04586998 1.57223002 -2.04586998 0 P 0 
L 1.50945 -2.04486998 1.57081004 -2.04486998 0 P 0 
L 1.50888002 -2.04386998 1.56938996 -2.04386998 0 P 0 
L 1.50836004 -2.04286998 1.56796998 -2.04286998 0 P 0 
L 1.5079 -2.04186998 1.56655 -2.04186998 0 P 0 
L 1.50748002 -2.04086998 1.56518996 -2.04086998 0 P 0 
L 1.50708996 -2.03986998 1.564 -2.03986998 0 P 0 
L 1.50676004 -2.03886998 1.56296998 -2.03886998 0 P 0 
L 1.50641998 -2.03786998 1.56206004 -2.03786998 0 P 0 
L 1.50616998 -2.03686998 1.56125 -2.03686998 0 P 0 
L 1.50591004 -2.03586998 1.56066998 -2.03586998 0 P 0 
L 1.5057 -2.03486998 1.56031998 -2.03486998 0 P 0 
L 1.50551998 -2.03386998 1.56016004 -2.03386998 0 P 0 
L 1.50533996 -2.03286998 1.56016998 -2.03286998 0 P 0 
L 1.50523996 -2.03186998 1.56036004 -2.03186998 0 P 0 
L 1.50513002 -2.03086998 1.56071998 -2.03086998 0 P 0 
L 1.50506998 -2.02986998 1.56131004 -2.02986998 0 P 0 
L 1.50503996 -2.02886998 1.5622 -2.02886998 0 P 0 
L 1.50501004 -2.02786998 1.56355 -2.02786998 0 P 0 
L 1.50501998 -2.02686998 1.5657 -2.02686998 0 P 0 
L 1.50506998 -2.02586998 1.60378996 -2.02586998 0 P 0 
L 1.50511998 -2.02486998 1.60371004 -2.02486998 0 P 0 
L 1.50521004 -2.02386998 1.60363996 -2.02386998 0 P 0 
L 1.50533996 -2.02286998 1.60356998 -2.02286998 0 P 0 
L 1.50546998 -2.02186998 1.6035 -2.02186998 0 P 0 
L 1.50563996 -2.02086998 1.60343002 -2.02086998 0 P 0 
L 1.50585 -2.01986998 1.60336004 -2.01986998 0 P 0 
L 1.50606004 -2.01886998 1.60328996 -2.01886998 0 P 0 
L 1.50633002 -2.01786998 1.60321998 -2.01786998 0 P 0 
L 1.50661998 -2.01686998 1.60315 -2.01686998 0 P 0 
L 1.50691004 -2.01586998 1.60308002 -2.01586998 0 P 0 
L 1.50726998 -2.01486998 1.603 -2.01486998 0 P 0 
L 1.50766004 -2.01386998 1.60293002 -2.01386998 0 P 0 
L 1.50808996 -2.01286998 1.60285 -2.01286998 0 P 0 
L 1.50856998 -2.01186998 1.60278002 -2.01186998 0 P 0 
L 1.50908996 -2.01086998 1.6027 -2.01086998 0 P 0 
L 1.50966004 -2.00986998 1.60261998 -2.00986998 0 P 0 
L 1.51028996 -2.00886998 1.60255 -2.00886998 0 P 0 
L 1.51096998 -2.00786998 1.60246998 -2.00786998 0 P 0 
L 1.51171998 -2.00686998 1.6024 -2.00686998 0 P 0 
L 1.51253996 -2.00586998 1.60233002 -2.00586998 0 P 0 
L 1.51343996 -2.00486998 1.60225 -2.00486998 0 P 0 
L 1.5144 -2.00386998 1.60218002 -2.00386998 0 P 0 
L 1.51551998 -2.00286998 1.6021 -2.00286998 0 P 0 
L 1.51663996 -2.00186998 1.60203002 -2.00186998 0 P 0 
L 1.51795 -2.00086998 1.60195 -2.00086998 0 P 0 
L 1.51928996 -1.99986998 1.60183996 -1.99986998 0 P 0 
L 1.52086998 -1.99886998 1.60173002 -1.99886998 0 P 0 
L 1.52258996 -1.99786998 1.60156998 -1.99786998 0 P 0 
L 1.52451004 -1.99686998 1.60138996 -1.99686998 0 P 0 
L 1.52686998 -1.99586998 1.60106998 -1.99586998 0 P 0 
L 1.52976004 -1.99486998 1.59943996 -1.99486998 0 P 0 
L 1.53283002 -1.99386998 1.59543002 -1.99386998 0 P 0 
L 1.53678996 -1.99286998 1.59003996 -1.99286998 0 P 0 
L 1.54173996 -1.99186998 1.58073996 -1.99186998 0 P 0 
L 1.55036998 -1.99086998 1.56493002 -1.99086998 0 P 0 
L 1.6036 -2.03086998 1.60413996 -2.03086998 0 P 0 
L 1.59891004 -2.02986998 1.60406998 -2.02986998 0 P 0 
L 1.59435 -2.02886998 1.604 -2.02886998 0 P 0 
L 1.58838996 -2.02786998 1.60393002 -2.02786998 0 P 0 
L 1.57981004 -2.02686998 1.60386004 -2.02686998 0 P 0 
L 1.54575 -1.98923996 1.53931998 -1.99021998 0 P 0 
L 1.53931998 -1.99021998 1.53298996 -1.99171998 0 P 0 
L 1.53298996 -1.99171998 1.52678996 -1.99373996 0 P 0 
L 1.52678996 -1.99373996 1.52376998 -1.995 0 P 0 
L 1.52376998 -1.995 1.52086998 -1.99651004 0 P 0 
L 1.52086998 -1.99651004 1.5181 -1.99826004 0 P 0 
L 1.5181 -1.99826004 1.51548002 -2.00023002 0 P 0 
L 1.51548002 -2.00023002 1.51301004 -2.00243002 0 P 0 
L 1.51301004 -2.00243002 1.51128996 -2.00423002 0 P 0 
L 1.51128996 -2.00423002 1.50971998 -2.00616004 0 P 0 
L 1.50971998 -2.00616004 1.50831004 -2.00821004 0 P 0 
L 1.50831004 -2.00821004 1.50706998 -2.01036998 0 P 0 
L 1.50706998 -2.01036998 1.50598996 -2.01261998 0 P 0 
L 1.50598996 -2.01261998 1.50508996 -2.01496998 0 P 0 
L 1.50508996 -2.01496998 1.5042 -2.01801004 0 P 0 
L 1.5042 -2.01801004 1.50355 -2.02111004 0 P 0 
L 1.50355 -2.02111004 1.50313996 -2.02426004 0 P 0 
L 1.50313996 -2.02426004 1.50298996 -2.02743002 0 P 0 
L 1.50298996 -2.02743002 1.50308996 -2.03063002 0 P 0 
L 1.50308996 -2.03063002 1.50338002 -2.03326998 0 P 0 
L 1.50338002 -2.03326998 1.50385 -2.03588002 0 P 0 
L 1.50385 -2.03588002 1.50451004 -2.03845 0 P 0 
L 1.50451004 -2.03845 1.50535 -2.04096998 0 P 0 
L 1.50535 -2.04096998 1.50633002 -2.0433 0 P 0 
L 1.50633002 -2.0433 1.5075 -2.04553002 0 P 0 
L 1.5075 -2.04553002 1.50883996 -2.04766998 0 P 0 
L 1.50883996 -2.04766998 1.51036998 -2.04968996 0 P 0 
L 1.51036998 -2.04968996 1.51323002 -2.05291998 0 P 0 
L 1.51323002 -2.05291998 1.51631998 -2.05593996 0 P 0 
L 1.51631998 -2.05593996 1.51961998 -2.05871004 0 P 0 
L 1.51961998 -2.05871004 1.53591004 -2.0706 0 P 0 
L 1.53591004 -2.0706 1.54668002 -2.07831004 0 P 0 
L 1.54668002 -2.07831004 1.54793996 -2.07933996 0 P 0 
L 1.54793996 -2.07933996 1.54911998 -2.08046998 0 P 0 
L 1.54911998 -2.08046998 1.55021004 -2.08168002 0 P 0 
L 1.55021004 -2.08168002 1.5512 -2.08298996 0 P 0 
L 1.5512 -2.08298996 1.55136004 -2.08323002 0 P 0 
L 1.55136004 -2.08323002 1.5515 -2.08348002 0 P 0 
L 1.5515 -2.08348002 1.55161004 -2.08373996 0 P 0 
L 1.55161004 -2.08373996 1.5517 -2.08401998 0 P 0 
L 1.5517 -2.08401998 1.55176998 -2.0843 0 P 0 
L 1.55176998 -2.0843 1.55181004 -2.08458002 0 P 0 
L 1.55181004 -2.08458002 1.55183002 -2.08486998 0 P 0 
L 1.55183002 -2.08486998 1.55181998 -2.08516004 0 P 0 
L 1.55181998 -2.08516004 1.55178996 -2.08545 0 P 0 
L 1.55178996 -2.08545 1.55173996 -2.08573002 0 P 0 
L 1.55173996 -2.08573002 1.55166004 -2.086 0 P 0 
L 1.55166004 -2.086 1.55156004 -2.08628002 0 P 0 
L 1.55156004 -2.08628002 1.55136998 -2.08666998 0 P 0 
L 1.55136998 -2.08666998 1.55115 -2.08703996 0 P 0 
L 1.55115 -2.08703996 1.5509 -2.08738996 0 P 0 
L 1.5509 -2.08738996 1.55063002 -2.08771998 0 P 0 
L 1.55063002 -2.08771998 1.55033002 -2.08803002 0 P 0 
L 1.55033002 -2.08803002 1.55 -2.08831004 0 P 0 
L 1.55 -2.08831004 1.54966004 -2.08856004 0 P 0 
L 1.54966004 -2.08856004 1.54928996 -2.08878996 0 P 0 
L 1.54928996 -2.08878996 1.5489 -2.08898996 0 P 0 
L 1.5489 -2.08898996 1.54786004 -2.08941004 0 P 0 
L 1.54786004 -2.08941004 1.54678996 -2.08973996 0 P 0 
L 1.54678996 -2.08973996 1.54568002 -2.08998002 0 P 0 
L 1.54568002 -2.08998002 1.54456998 -2.09011998 0 P 0 
L 1.54456998 -2.09011998 1.54343996 -2.09016998 0 P 0 
L 1.54343996 -2.09016998 1.53906998 -2.09003002 0 P 0 
L 1.53906998 -2.09003002 1.53468002 -2.08961998 0 P 0 
L 1.53468002 -2.08961998 1.52908996 -2.08878996 0 P 0 
L 1.52908996 -2.08878996 1.52351004 -2.08766004 0 P 0 
L 1.52351004 -2.08766004 1.51005 -2.08418996 0 P 0 
L 1.51005 -2.08418996 1.50631004 -2.08318002 0 P 0 
L 1.50631004 -2.08318002 1.50308002 -2.08238996 0 P 0 
L 1.50308002 -2.08238996 1.50033996 -2.08183002 0 P 0 
L 1.50033996 -2.08183002 1.5003 -2.08181998 0 P 0 
L 1.5003 -2.08181998 1.50016004 -2.08181998 0 P 0 
L 1.50016004 -2.08181998 1.50011998 -2.08183002 0 P 0 
L 1.50011998 -2.08183002 1.50006998 -2.08183996 0 P 0 
L 1.50006998 -2.08183996 1.50003002 -2.08186004 0 P 0 
L 1.50003002 -2.08186004 1.49998996 -2.08186998 0 P 0 
L 1.49998996 -2.08186998 1.49995 -2.08188996 0 P 0 
L 1.49995 -2.08188996 1.49991004 -2.08191998 0 P 0 
L 1.49991004 -2.08191998 1.49988002 -2.08195 0 P 0 
L 1.49988002 -2.08195 1.49983996 -2.08198002 0 P 0 
L 1.49983996 -2.08198002 1.4997 -2.08213996 0 P 0 
L 1.4997 -2.08213996 1.49956004 -2.08231998 0 P 0 
L 1.49956004 -2.08231998 1.49943996 -2.0825 0 P 0 
L 1.49943996 -2.0825 1.49933996 -2.0827 0 P 0 
L 1.49933996 -2.0827 1.49925 -2.0829 0 P 0 
L 1.49925 -2.0829 1.49918996 -2.08311004 0 P 0 
L 1.49918996 -2.08311004 1.49913996 -2.08333002 0 P 0 
L 1.49913996 -2.08333002 1.49911004 -2.08355 0 P 0 
L 1.49911004 -2.08355 1.4991 -2.08376998 0 P 0 
L 1.4991 -2.08376998 1.49911004 -2.08398996 0 P 0 
L 1.49911004 -2.08398996 1.50071004 -2.10395 0 P 0 
L 1.50071004 -2.10395 1.5024 -2.12403996 0 P 0 
L 1.5024 -2.12403996 1.50241998 -2.12418002 0 P 0 
L 1.50241998 -2.12418002 1.50246004 -2.12431004 0 P 0 
L 1.50246004 -2.12431004 1.50248996 -2.12445 0 P 0 
L 1.50248996 -2.12445 1.50255 -2.12456998 0 P 0 
L 1.50255 -2.12456998 1.50261004 -2.1247 0 P 0 
L 1.50261004 -2.1247 1.50276998 -2.12491998 0 P 0 
L 1.50276998 -2.12491998 1.50286004 -2.12501998 0 P 0 
L 1.50286004 -2.12501998 1.50296998 -2.12511998 0 P 0 
L 1.50296998 -2.12511998 1.50308002 -2.12521004 0 P 0 
L 1.50308002 -2.12521004 1.50318996 -2.12528002 0 P 0 
L 1.50318996 -2.12528002 1.50331998 -2.12535 0 P 0 
L 1.50331998 -2.12535 1.50343996 -2.1254 0 P 0 
L 1.50343996 -2.1254 1.50391998 -2.12556004 0 P 0 
L 1.50391998 -2.12556004 1.5044 -2.12568996 0 P 0 
L 1.5044 -2.12568996 1.50848002 -2.12648996 0 P 0 
L 1.50848002 -2.12648996 1.51328996 -2.12738002 0 P 0 
L 1.51328996 -2.12738002 1.51873996 -2.12833996 0 P 0 
L 1.51873996 -2.12833996 1.52606004 -2.12945 0 P 0 
L 1.52606004 -2.12945 1.53343996 -2.13023002 0 P 0 
L 1.53343996 -2.13023002 1.54886998 -2.13086998 0 P 0 
L 1.54886998 -2.13086998 1.56305 -2.1303 0 P 0 
L 1.56305 -2.1303 1.56666004 -2.12988996 0 P 0 
L 1.56666004 -2.12988996 1.57023002 -2.12926998 0 P 0 
L 1.57023002 -2.12926998 1.5738 -2.12843002 0 P 0 
L 1.5738 -2.12843002 1.57945 -2.12668996 0 P 0 
L 1.57945 -2.12668996 1.58498002 -2.12456998 0 P 0 
L 1.58498002 -2.12456998 1.58793996 -2.12318002 0 P 0 
L 1.58793996 -2.12318002 1.59078996 -2.12156004 0 P 0 
L 1.59078996 -2.12156004 1.59348996 -2.11971998 0 P 0 
L 1.59348996 -2.11971998 1.59525 -2.11833002 0 P 0 
L 1.59525 -2.11833002 1.5969 -2.11681998 0 P 0 
L 1.5969 -2.11681998 1.59846004 -2.11521004 0 P 0 
L 1.59846004 -2.11521004 1.59991004 -2.11348002 0 P 0 
L 1.59991004 -2.11348002 1.60175 -2.11093996 0 P 0 
L 1.60175 -2.11093996 1.60338002 -2.10826998 0 P 0 
L 1.60338002 -2.10826998 1.60481004 -2.10548002 0 P 0 
L 1.60481004 -2.10548002 1.60573002 -2.10321004 0 P 0 
L 1.60573002 -2.10321004 1.60646004 -2.10088002 0 P 0 
L 1.60646004 -2.10088002 1.60698002 -2.09848996 0 P 0 
L 1.60698002 -2.09848996 1.60756004 -2.09421998 0 P 0 
L 1.60756004 -2.09421998 1.6078 -2.08991004 0 P 0 
L 1.6078 -2.08991004 1.60768996 -2.08565 0 P 0 
L 1.60768996 -2.08565 1.60723002 -2.08141998 0 P 0 
L 1.60723002 -2.08141998 1.60691998 -2.07968002 0 P 0 
L 1.60691998 -2.07968002 1.60646998 -2.07796998 0 P 0 
L 1.60646998 -2.07796998 1.60591998 -2.0763 0 P 0 
L 1.60591998 -2.0763 1.60523002 -2.07466998 0 P 0 
L 1.60523002 -2.07466998 1.60411998 -2.07246998 0 P 0 
L 1.60411998 -2.07246998 1.60281004 -2.07038002 0 P 0 
L 1.60281004 -2.07038002 1.60131998 -2.06838996 0 P 0 
L 1.60131998 -2.06838996 1.59803996 -2.06461998 0 P 0 
L 1.59803996 -2.06461998 1.59455 -2.06101998 0 P 0 
L 1.59455 -2.06101998 1.59031998 -2.05708996 0 P 0 
L 1.59031998 -2.05708996 1.58586004 -2.05333996 0 P 0 
L 1.58586004 -2.05333996 1.57588002 -2.04598996 0 P 0 
L 1.57588002 -2.04598996 1.56685 -2.03963996 0 P 0 
L 1.56685 -2.03963996 1.56578002 -2.03878996 0 P 0 
L 1.56578002 -2.03878996 1.56476998 -2.03786004 0 P 0 
L 1.56476998 -2.03786004 1.56383002 -2.03686998 0 P 0 
L 1.56383002 -2.03686998 1.56295 -2.0358 0 P 0 
L 1.56295 -2.0358 1.56276998 -2.03555 0 P 0 
L 1.56276998 -2.03555 1.56261004 -2.03528002 0 P 0 
L 1.56261004 -2.03528002 1.56246998 -2.035 0 P 0 
L 1.56246998 -2.035 1.56236004 -2.03471998 0 P 0 
L 1.56236004 -2.03471998 1.56226998 -2.03441998 0 P 0 
L 1.56226998 -2.03441998 1.5622 -2.03411998 0 P 0 
L 1.5622 -2.03411998 1.56216004 -2.03381998 0 P 0 
L 1.56216004 -2.03381998 1.56213996 -2.03351004 0 P 0 
L 1.56213996 -2.03351004 1.56215 -2.0332 0 P 0 
L 1.56215 -2.0332 1.56218002 -2.03288996 0 P 0 
L 1.56218002 -2.03288996 1.56225 -2.03253996 0 P 0 
L 1.56225 -2.03253996 1.56233996 -2.03221004 0 P 0 
L 1.56233996 -2.03221004 1.56246004 -2.03186998 0 P 0 
L 1.56246004 -2.03186998 1.56261004 -2.03156004 0 P 0 
L 1.56261004 -2.03156004 1.56278996 -2.03125 0 P 0 
L 1.56278996 -2.03125 1.56298002 -2.03096004 0 P 0 
L 1.56298002 -2.03096004 1.56321004 -2.03068996 0 P 0 
L 1.56321004 -2.03068996 1.56345 -2.03043996 0 P 0 
L 1.56345 -2.03043996 1.56371004 -2.0302 0 P 0 
L 1.56371004 -2.0302 1.56416004 -2.02986004 0 P 0 
L 1.56416004 -2.02986004 1.56463002 -2.02955 0 P 0 
L 1.56463002 -2.02955 1.56511998 -2.02928002 0 P 0 
L 1.56511998 -2.02928002 1.56561998 -2.02903002 0 P 0 
L 1.56561998 -2.02903002 1.56611998 -2.02883996 0 P 0 
L 1.56611998 -2.02883996 1.56663996 -2.02866998 0 P 0 
L 1.56663996 -2.02866998 1.56716004 -2.02855 0 P 0 
L 1.56716004 -2.02855 1.5677 -2.02846998 0 P 0 
L 1.5677 -2.02846998 1.56926998 -2.02835 0 P 0 
L 1.56926998 -2.02835 1.57085 -2.02833996 0 P 0 
L 1.57085 -2.02833996 1.57725 -2.02866998 0 P 0 
L 1.57725 -2.02866998 1.58205 -2.02906004 0 P 0 
L 1.58205 -2.02906004 1.58746998 -2.02975 0 P 0 
L 1.58746998 -2.02975 1.59271004 -2.03056998 0 P 0 
L 1.59271004 -2.03056998 1.59681004 -2.03143002 0 P 0 
L 1.59681004 -2.03143002 1.60016004 -2.03221998 0 P 0 
L 1.60016004 -2.03221998 1.60308002 -2.03281004 0 P 0 
L 1.60308002 -2.03281004 1.60553996 -2.03323996 0 P 0 
L 1.60553996 -2.03323996 1.60568996 -2.03323996 0 P 0 
L 1.60568996 -2.03323996 1.60576998 -2.03321998 0 P 0 
L 1.60576998 -2.03321998 1.60586004 -2.03316004 0 P 0 
L 1.60586004 -2.03316004 1.6059 -2.03313996 0 P 0 
L 1.6059 -2.03313996 1.60591998 -2.03311004 0 P 0 
L 1.60591998 -2.03311004 1.60598996 -2.03303996 0 P 0 
L 1.60598996 -2.03303996 1.60605 -2.03296998 0 P 0 
L 1.60605 -2.03296998 1.6061 -2.03288996 0 P 0 
L 1.6061 -2.03288996 1.60618002 -2.03273002 0 P 0 
L 1.60618002 -2.03273002 1.60621004 -2.03263002 0 P 0 
L 1.60621004 -2.03263002 1.60623002 -2.03253996 0 P 0 
L 1.60623002 -2.03253996 1.60625 -2.03236004 0 P 0 
L 1.60625 -2.03236004 1.60623996 -2.03226004 0 P 0 
L 1.60623996 -2.03226004 1.60508002 -2.01578002 0 P 0 
L 1.60508002 -2.01578002 1.60393996 -2.00068002 0 P 0 
L 1.60393996 -2.00068002 1.60368002 -1.99833996 0 P 0 
L 1.60368002 -1.99833996 1.60326998 -1.99601004 0 P 0 
L 1.60326998 -1.99601004 1.60321004 -1.99576998 0 P 0 
L 1.60321004 -1.99576998 1.60313996 -1.99553002 0 P 0 
L 1.60313996 -1.99553002 1.60303996 -1.9953 0 P 0 
L 1.60303996 -1.9953 1.60293002 -1.99508002 0 P 0 
L 1.60293002 -1.99508002 1.60281004 -1.99486004 0 P 0 
L 1.60281004 -1.99486004 1.60261998 -1.9946 0 P 0 
L 1.60261998 -1.9946 1.60241004 -1.99435 0 P 0 
L 1.60241004 -1.99435 1.60218002 -1.99411998 0 P 0 
L 1.60218002 -1.99411998 1.60191998 -1.99391004 0 P 0 
L 1.60191998 -1.99391004 1.60161004 -1.99368996 0 P 0 
L 1.60161004 -1.99368996 1.60128996 -1.99348996 0 P 0 
L 1.60128996 -1.99348996 1.60095 -1.99331998 0 P 0 
L 1.60095 -1.99331998 1.6006 -1.99316004 0 P 0 
L 1.6006 -1.99316004 1.59966004 -1.99283002 0 P 0 
L 1.59966004 -1.99283002 1.59871004 -1.99255 0 P 0 
L 1.59871004 -1.99255 1.5933 -1.99135 0 P 0 
L 1.5933 -1.99135 1.5878 -1.9905 0 P 0 
L 1.5878 -1.9905 1.57285 -1.98915 0 P 0 
L 1.57285 -1.98915 1.55763996 -1.98861004 0 P 0 
L 1.55763996 -1.98861004 1.55171004 -1.98876004 0 P 0 
L 1.55171004 -1.98876004 1.54575 -1.98923996 0 P 0 
L 1.53011998 -2.12786998 1.5666 -2.12786998 0 P 0 
L 1.52236004 -2.12686998 1.57168002 -2.12686998 0 P 0 
L 1.51621998 -2.12586998 1.5753 -2.12586998 0 P 0 
L 1.51071004 -2.12486998 1.57856004 -2.12486998 0 P 0 
L 1.50553002 -2.12386998 1.58121004 -2.12386998 0 P 0 
L 1.50431004 -2.12286998 1.58381998 -2.12286998 0 P 0 
L 1.50423002 -2.12186998 1.58601998 -2.12186998 0 P 0 
L 1.50413996 -2.12086998 1.58796004 -2.12086998 0 P 0 
L 1.50406004 -2.11986998 1.58971004 -2.11986998 0 P 0 
L 1.50396998 -2.11886998 1.59118002 -2.11886998 0 P 0 
L 1.50388996 -2.11786998 1.5926 -2.11786998 0 P 0 
L 1.50381004 -2.11686998 1.59386004 -2.11686998 0 P 0 
L 1.50371998 -2.11586998 1.59496998 -2.11586998 0 P 0 
L 1.50363996 -2.11486998 1.59601004 -2.11486998 0 P 0 
L 1.50355 -2.11386998 1.59696998 -2.11386998 0 P 0 
L 1.50346998 -2.11286998 1.59781004 -2.11286998 0 P 0 
L 1.50338002 -2.11186998 1.5986 -2.11186998 0 P 0 
L 1.5033 -2.11086998 1.59933002 -2.11086998 0 P 0 
L 1.50321004 -2.10986998 1.60005 -2.10986998 0 P 0 
L 1.50313002 -2.10886998 1.60066998 -2.10886998 0 P 0 
L 1.50305 -2.10786998 1.60128002 -2.10786998 0 P 0 
L 1.50296004 -2.10686998 1.60185 -2.10686998 0 P 0 
L 1.50288002 -2.10586998 1.60236004 -2.10586998 0 P 0 
L 1.50278996 -2.10486998 1.60286998 -2.10486998 0 P 0 
L 1.50271004 -2.10386998 1.6033 -2.10386998 0 P 0 
L 1.50263002 -2.10286998 1.60371004 -2.10286998 0 P 0 
L 1.50255 -2.10186998 1.60405 -2.10186998 0 P 0 
L 1.50246998 -2.10086998 1.60436004 -2.10086998 0 P 0 
L 1.50238996 -2.09986998 1.60463002 -2.09986998 0 P 0 
L 1.50231004 -2.09886998 1.60485 -2.09886998 0 P 0 
L 1.50223002 -2.09786998 1.60505 -2.09786998 0 P 0 
L 1.50215 -2.09686998 1.60518002 -2.09686998 0 P 0 
L 1.50206998 -2.09586998 1.60531998 -2.09586998 0 P 0 
L 1.50198996 -2.09486998 1.60545 -2.09486998 0 P 0 
L 1.50191004 -2.09386998 1.60558002 -2.09386998 0 P 0 
L 1.50183002 -2.09286998 1.60563002 -2.09286998 0 P 0 
L 1.50175 -2.09186998 1.53725 -2.09186998 0 P 0 
L 1.54638996 -2.09186998 1.60568996 -2.09186998 0 P 0 
L 1.50166998 -2.09086998 1.5295 -2.09086998 0 P 0 
L 1.54956998 -2.09086998 1.60573996 -2.09086998 0 P 0 
L 1.50158996 -2.08986998 1.52436004 -2.08986998 0 P 0 
L 1.55125 -2.08986998 1.60578996 -2.08986998 0 P 0 
L 1.50151004 -2.08886998 1.52021004 -2.08886998 0 P 0 
L 1.55226998 -2.08886998 1.60576998 -2.08886998 0 P 0 
L 1.50143002 -2.08786998 1.51633002 -2.08786998 0 P 0 
L 1.55298002 -2.08786998 1.60573996 -2.08786998 0 P 0 
L 1.50133996 -2.08686998 1.51246004 -2.08686998 0 P 0 
L 1.55346998 -2.08686998 1.60571998 -2.08686998 0 P 0 
L 1.50126998 -2.08586998 1.50861998 -2.08586998 0 P 0 
L 1.55375 -2.08586998 1.60568996 -2.08586998 0 P 0 
L 1.50118002 -2.08486998 1.50481004 -2.08486998 0 P 0 
L 1.55383002 -2.08486998 1.60558996 -2.08486998 0 P 0 
L 1.55371998 -2.08386998 1.60548996 -2.08386998 0 P 0 
L 1.54886998 -2.12886998 1.53358996 -2.12823996 0 P 0 
L 1.53358996 -2.12823996 1.52631998 -2.12746998 0 P 0 
L 1.52631998 -2.12746998 1.51906004 -2.12636998 0 P 0 
L 1.51906004 -2.12636998 1.51363002 -2.12541004 0 P 0 
L 1.51363002 -2.12541004 1.50886998 -2.12451998 0 P 0 
L 1.50886998 -2.12451998 1.50483996 -2.12373996 0 P 0 
L 1.50483996 -2.12373996 1.50448996 -2.12365 0 P 0 
L 1.50448996 -2.12365 1.50438002 -2.12361004 0 P 0 
L 1.50438002 -2.12361004 1.5027 -2.10378002 0 P 0 
L 1.5027 -2.10378002 1.50111998 -2.08403002 0 P 0 
L 1.50111998 -2.08403002 1.50263996 -2.08433996 0 P 0 
L 1.50263996 -2.08433996 1.50581004 -2.08511004 0 P 0 
L 1.50581004 -2.08511004 1.50955 -2.08611998 0 P 0 
L 1.50955 -2.08611998 1.52306004 -2.08961004 0 P 0 
L 1.52306004 -2.08961004 1.52311004 -2.08961998 0 P 0 
L 1.52311004 -2.08961998 1.52875 -2.09076004 0 P 0 
L 1.52875 -2.09076004 1.5288 -2.09076004 0 P 0 
L 1.5288 -2.09076004 1.53443996 -2.09161004 0 P 0 
L 1.53443996 -2.09161004 1.53893996 -2.09203002 0 P 0 
L 1.53893996 -2.09203002 1.54346004 -2.09216998 0 P 0 
L 1.54346004 -2.09216998 1.54473996 -2.09211004 0 P 0 
L 1.54473996 -2.09211004 1.54603002 -2.09195 0 P 0 
L 1.54603002 -2.09195 1.54728996 -2.09166998 0 P 0 
L 1.54728996 -2.09166998 1.54853002 -2.09128996 0 P 0 
L 1.54853002 -2.09128996 1.54973002 -2.09081004 0 P 0 
L 1.54973002 -2.09081004 1.55026998 -2.09053996 0 P 0 
L 1.55026998 -2.09053996 1.55076998 -2.09023002 0 P 0 
L 1.55076998 -2.09023002 1.55118002 -2.08991998 0 P 0 
L 1.55118002 -2.08991998 1.55118002 -2.08991004 0 P 0 
L 1.55118002 -2.08991004 1.5512 -2.08991004 0 P 0 
L 1.5512 -2.08991004 1.55125 -2.08986998 0 P 0 
L 1.55125 -2.08986998 1.55131004 -2.08981998 0 P 0 
L 1.55131004 -2.08981998 1.55126998 -2.08978002 0 P 0 
L 1.55126998 -2.08978002 1.55136004 -2.08978002 0 P 0 
L 1.55136004 -2.08978002 1.5517 -2.08948996 0 P 0 
L 1.5517 -2.08948996 1.55206004 -2.08911998 0 P 0 
L 1.55206004 -2.08911998 1.55205 -2.08911004 0 P 0 
L 1.55205 -2.08911004 1.55206004 -2.08911004 0 P 0 
L 1.55206004 -2.08911004 1.55211998 -2.08906004 0 P 0 
L 1.55211998 -2.08906004 1.55248996 -2.08861004 0 P 0 
L 1.55248996 -2.08861004 1.55283996 -2.08811998 0 P 0 
L 1.55283996 -2.08811998 1.55313996 -2.08761004 0 P 0 
L 1.55313996 -2.08761004 1.5534 -2.08706998 0 P 0 
L 1.5534 -2.08706998 1.55356004 -2.08663002 0 P 0 
L 1.55356004 -2.08663002 1.55368996 -2.08618996 0 P 0 
L 1.55368996 -2.08618996 1.55376998 -2.08573996 0 P 0 
L 1.55376998 -2.08573996 1.55378002 -2.08565 0 P 0 
L 1.55378002 -2.08565 1.55381998 -2.08528002 0 P 0 
L 1.55381998 -2.08528002 1.55383002 -2.08481998 0 P 0 
L 1.55383002 -2.08481998 1.5538 -2.08436998 0 P 0 
L 1.5538 -2.08436998 1.55373002 -2.08391998 0 P 0 
L 1.55373002 -2.08391998 1.55361998 -2.08346998 0 P 0 
L 1.55361998 -2.08346998 1.55348002 -2.08303996 0 P 0 
L 1.55348002 -2.08303996 1.5533 -2.08261004 0 P 0 
L 1.5533 -2.08261004 1.55308996 -2.08221004 0 P 0 
L 1.55308996 -2.08221004 1.55283996 -2.08183002 0 P 0 
L 1.55283996 -2.08183002 1.55175 -2.0804 0 P 0 
L 1.55175 -2.0804 1.55055 -2.07908002 0 P 0 
L 1.55055 -2.07908002 1.54926004 -2.07783996 0 P 0 
L 1.54926004 -2.07783996 1.54788996 -2.07671998 0 P 0 
L 1.54788996 -2.07671998 1.53706998 -2.06898002 0 P 0 
L 1.53706998 -2.06898002 1.52085 -2.05713996 0 P 0 
L 1.52085 -2.05713996 1.51766004 -2.05445 0 P 0 
L 1.51766004 -2.05445 1.51468002 -2.05153996 0 P 0 
L 1.51468002 -2.05153996 1.51191998 -2.04841998 0 P 0 
L 1.51191998 -2.04841998 1.51048996 -2.04651998 0 P 0 
L 1.51048996 -2.04651998 1.50923002 -2.04453002 0 P 0 
L 1.50923002 -2.04453002 1.50813996 -2.04245 0 P 0 
L 1.50813996 -2.04245 1.50721998 -2.04026004 0 P 0 
L 1.50721998 -2.04026004 1.50643002 -2.03788002 0 P 0 
L 1.50643002 -2.03788002 1.50581004 -2.03545 0 P 0 
L 1.50581004 -2.03545 1.50536004 -2.03298996 0 P 0 
L 1.50536004 -2.03298996 1.50508996 -2.0305 0 P 0 
L 1.50508996 -2.0305 1.50498996 -2.02745 0 P 0 
L 1.50498996 -2.02745 1.50513996 -2.02443996 0 P 0 
L 1.50513996 -2.02443996 1.50551998 -2.02145 0 P 0 
L 1.50551998 -2.02145 1.50613996 -2.0185 0 P 0 
L 1.50613996 -2.0185 1.50698996 -2.01561004 0 P 0 
L 1.50698996 -2.01561004 1.50783002 -2.01341004 0 P 0 
L 1.50783002 -2.01341004 1.50883002 -2.0113 0 P 0 
L 1.50883002 -2.0113 1.51 -2.00928002 0 P 0 
L 1.51 -2.00928002 1.51133002 -2.00736004 0 P 0 
L 1.51133002 -2.00736004 1.5128 -2.00555 0 P 0 
L 1.5128 -2.00555 1.5144 -2.00386004 0 P 0 
L 1.5144 -2.00386004 1.51675 -2.00176998 0 P 0 
L 1.51675 -2.00176998 1.51923002 -1.9999 0 P 0 
L 1.51923002 -1.9999 1.52186004 -1.99823996 0 P 0 
L 1.52186004 -1.99823996 1.52461998 -1.99681004 0 P 0 
L 1.52461998 -1.99681004 1.52748996 -1.99561004 0 P 0 
L 1.52748996 -1.99561004 1.53353002 -1.99363996 0 P 0 
L 1.53353002 -1.99363996 1.5397 -1.99218002 0 P 0 
L 1.5397 -1.99218002 1.54598002 -1.99123002 0 P 0 
L 1.54598002 -1.99123002 1.55181004 -1.99075 0 P 0 
L 1.55181004 -1.99075 1.55763002 -1.99061998 0 P 0 
L 1.55763002 -1.99061998 1.57273002 -1.99113996 0 P 0 
L 1.57273002 -1.99113996 1.58755 -1.99248996 0 P 0 
L 1.58755 -1.99248996 1.59293002 -1.99331998 0 P 0 
L 1.59293002 -1.99331998 1.59821004 -1.99448996 0 P 0 
L 1.59821004 -1.99448996 1.59905 -1.99473002 0 P 0 
L 1.59905 -1.99473002 1.59986004 -1.99501998 0 P 0 
L 1.59986004 -1.99501998 1.60008002 -1.99511998 0 P 0 
L 1.60008002 -1.99511998 1.6003 -1.99523002 0 P 0 
L 1.6003 -1.99523002 1.60051004 -1.99536004 0 P 0 
L 1.60051004 -1.99536004 1.60071004 -1.9955 0 P 0 
L 1.60071004 -1.9955 1.60083002 -1.99561004 0 P 0 
L 1.60083002 -1.99561004 1.60093996 -1.99571004 0 P 0 
L 1.60093996 -1.99571004 1.60103996 -1.99583002 0 P 0 
L 1.60103996 -1.99583002 1.60111998 -1.99595 0 P 0 
L 1.60111998 -1.99595 1.60116998 -1.99601998 0 P 0 
L 1.60116998 -1.99601998 1.60121004 -1.99611004 0 P 0 
L 1.60121004 -1.99611004 1.60125 -1.99621004 0 P 0 
L 1.60125 -1.99621004 1.60128002 -1.9963 0 P 0 
L 1.60128002 -1.9963 1.60131004 -1.99641004 0 P 0 
L 1.60131004 -1.99641004 1.6017 -1.99861998 0 P 0 
L 1.6017 -1.99861998 1.60195 -2.00086998 0 P 0 
L 1.60195 -2.00086998 1.60308002 -2.01593002 0 P 0 
L 1.60308002 -2.01593002 1.60415 -2.03096998 0 P 0 
L 1.60415 -2.03096998 1.60345 -2.03083996 0 P 0 
L 1.60345 -2.03083996 1.60058996 -2.03026004 0 P 0 
L 1.60058996 -2.03026004 1.59723002 -2.02948002 0 P 0 
L 1.59723002 -2.02948002 1.59721998 -2.02948002 0 P 0 
L 1.59721998 -2.02948002 1.59306998 -2.0286 0 P 0 
L 1.59306998 -2.0286 1.58776004 -2.02776998 0 P 0 
L 1.58776004 -2.02776998 1.58226004 -2.02708002 0 P 0 
L 1.58226004 -2.02708002 1.57738002 -2.02666998 0 P 0 
L 1.57738002 -2.02666998 1.5709 -2.02633996 0 P 0 
L 1.5709 -2.02633996 1.56918996 -2.02635 0 P 0 
L 1.56918996 -2.02635 1.56746998 -2.02648996 0 P 0 
L 1.56746998 -2.02648996 1.56678996 -2.02658996 0 P 0 
L 1.56678996 -2.02658996 1.56611998 -2.02673996 0 P 0 
L 1.56611998 -2.02673996 1.56546004 -2.02695 0 P 0 
L 1.56546004 -2.02695 1.56481998 -2.0272 0 P 0 
L 1.56481998 -2.0272 1.56418996 -2.0275 0 P 0 
L 1.56418996 -2.0275 1.56358002 -2.02785 0 P 0 
L 1.56358002 -2.02785 1.563 -2.02823002 0 P 0 
L 1.563 -2.02823002 1.56245 -2.02865 0 P 0 
L 1.56245 -2.02865 1.56206998 -2.02898996 0 P 0 
L 1.56206998 -2.02898996 1.56171004 -2.02936004 0 P 0 
L 1.56171004 -2.02936004 1.56138002 -2.02976004 0 P 0 
L 1.56138002 -2.02976004 1.56108996 -2.03018996 0 P 0 
L 1.56108996 -2.03018996 1.56083002 -2.03063996 0 P 0 
L 1.56083002 -2.03063996 1.56061998 -2.0311 0 P 0 
L 1.56061998 -2.0311 1.56043996 -2.03158996 0 P 0 
L 1.56043996 -2.03158996 1.5603 -2.03208002 0 P 0 
L 1.5603 -2.03208002 1.5602 -2.0326 0 P 0 
L 1.5602 -2.0326 1.56015 -2.03308002 0 P 0 
L 1.56015 -2.03308002 1.56013996 -2.03353996 0 P 0 
L 1.56013996 -2.03353996 1.56016004 -2.03391004 0 P 0 
L 1.56016004 -2.03391004 1.56048002 -2.03391004 0 P 0 
L 1.56048002 -2.03391004 1.56016004 -2.03393002 0 P 0 
L 1.56016004 -2.03393002 1.56016998 -2.03401004 0 P 0 
L 1.56016998 -2.03401004 1.56023002 -2.03448002 0 P 0 
L 1.56023002 -2.03448002 1.56025 -2.03456004 0 P 0 
L 1.56025 -2.03456004 1.56033002 -2.03493002 0 P 0 
L 1.56033002 -2.03493002 1.56046998 -2.03538002 0 P 0 
L 1.56046998 -2.03538002 1.56063996 -2.03581998 0 P 0 
L 1.56063996 -2.03581998 1.56085 -2.03623996 0 P 0 
L 1.56085 -2.03623996 1.56108996 -2.03663996 0 P 0 
L 1.56108996 -2.03663996 1.56136004 -2.03701998 0 P 0 
L 1.56136004 -2.03701998 1.56233002 -2.03818996 0 P 0 
L 1.56233002 -2.03818996 1.56336998 -2.03928996 0 P 0 
L 1.56336998 -2.03928996 1.56448002 -2.04031004 0 P 0 
L 1.56448002 -2.04031004 1.56566004 -2.04123996 0 P 0 
L 1.56566004 -2.04123996 1.57471004 -2.04761998 0 P 0 
L 1.57471004 -2.04761998 1.58461998 -2.05491004 0 P 0 
L 1.58461998 -2.05491004 1.58898996 -2.05858996 0 P 0 
L 1.58898996 -2.05858996 1.59315 -2.06245 0 P 0 
L 1.59315 -2.06245 1.59656998 -2.06596998 0 P 0 
L 1.59656998 -2.06596998 1.59976004 -2.06965 0 P 0 
L 1.59976004 -2.06965 1.60116004 -2.07151004 0 P 0 
L 1.60116004 -2.07151004 1.60238002 -2.07346004 0 P 0 
L 1.60238002 -2.07346004 1.60341998 -2.0755 0 P 0 
L 1.60341998 -2.0755 1.60403996 -2.077 0 P 0 
L 1.60403996 -2.077 1.60456004 -2.07853996 0 P 0 
L 1.60456004 -2.07853996 1.60496004 -2.08011004 0 P 0 
L 1.60496004 -2.08011004 1.60525 -2.0817 0 P 0 
L 1.60525 -2.0817 1.60568996 -2.08578002 0 P 0 
L 1.60568996 -2.08578002 1.60578996 -2.08988002 0 P 0 
L 1.60578996 -2.08988002 1.60556998 -2.09403002 0 P 0 
L 1.60556998 -2.09403002 1.60501004 -2.09813996 0 P 0 
L 1.60501004 -2.09813996 1.60451998 -2.10036998 0 P 0 
L 1.60451998 -2.10036998 1.60383996 -2.10253996 0 P 0 
L 1.60383996 -2.10253996 1.60298996 -2.10465 0 P 0 
L 1.60298996 -2.10465 1.60163996 -2.1073 0 P 0 
L 1.60163996 -2.1073 1.60008002 -2.10983002 0 P 0 
L 1.60008002 -2.10983002 1.59833002 -2.11225 0 P 0 
L 1.59833002 -2.11225 1.59696998 -2.11386998 0 P 0 
L 1.59696998 -2.11386998 1.59551004 -2.11538996 0 P 0 
L 1.59551004 -2.11538996 1.59395 -2.1168 0 P 0 
L 1.59395 -2.1168 1.59231004 -2.11811004 0 P 0 
L 1.59231004 -2.11811004 1.58973002 -2.11986004 0 P 0 
L 1.58973002 -2.11986004 1.58701998 -2.1214 0 P 0 
L 1.58701998 -2.1214 1.5842 -2.12273002 0 P 0 
L 1.5842 -2.12273002 1.5788 -2.1248 0 P 0 
L 1.5788 -2.1248 1.57326998 -2.12648996 0 P 0 
L 1.57326998 -2.12648996 1.56983002 -2.12731004 0 P 0 
L 1.56983002 -2.12731004 1.56638002 -2.12791004 0 P 0 
L 1.56638002 -2.12791004 1.56288996 -2.1283 0 P 0 
L 1.56288996 -2.1283 1.54886998 -2.12886998 0 P 0 
L 1.35851998 -2.06545 1.47866004 -2.06545 0 P 0 
L 1.35936004 -2.06445 1.47871004 -2.06445 0 P 0 
L 1.36041004 -2.06345 1.47875 -2.06345 0 P 0 
L 1.36163996 -2.06245 1.4788 -2.06245 0 P 0 
L 1.36293996 -2.06145 1.47883996 -2.06145 0 P 0 
L 1.36436004 -2.06045 1.47888996 -2.06045 0 P 0 
L 1.36598002 -2.05945 1.47893996 -2.05945 0 P 0 
L 1.36776004 -2.05845 1.47898996 -2.05845 0 P 0 
L 1.36971004 -2.05745 1.47903002 -2.05745 0 P 0 
L 1.37166004 -2.05645 1.47908002 -2.05645 0 P 0 
L 1.37391004 -2.05545 1.47911998 -2.05545 0 P 0 
L 1.37616998 -2.05445 1.47916998 -2.05445 0 P 0 
L 1.37873002 -2.05345 1.47921004 -2.05345 0 P 0 
L 1.38136004 -2.05245 1.47926004 -2.05245 0 P 0 
L 1.36875 -2.03345 1.37108996 -2.03345 0 P 0 
L 1.36886004 -2.03245 1.37385 -2.03245 0 P 0 
L 1.36896998 -2.03145 1.37678002 -2.03145 0 P 0 
L 1.36908996 -2.03045 1.3797 -2.03045 0 P 0 
L 1.36921004 -2.02945 1.38261998 -2.02945 0 P 0 
L 1.36933002 -2.02845 1.38638996 -2.02845 0 P 0 
L 1.36946004 -2.02745 1.39023996 -2.02745 0 P 0 
L 1.36958002 -2.02645 1.39503002 -2.02645 0 P 0 
L 1.3697 -2.02545 1.40068002 -2.02545 0 P 0 
L 1.36981998 -2.02445 1.41053996 -2.02445 0 P 0 
L 1.36993996 -2.02345 1.47993996 -2.02345 0 P 0 
L 1.37008002 -2.02245 1.47988002 -2.02245 0 P 0 
L 1.37021004 -2.02145 1.47978002 -2.02145 0 P 0 
L 1.37033996 -2.02045 1.47968002 -2.02045 0 P 0 
L 1.37046998 -2.01945 1.47953002 -2.01945 0 P 0 
L 1.3706 -2.01845 1.47936004 -2.01845 0 P 0 
L 1.37073002 -2.01745 1.47918002 -2.01745 0 P 0 
L 1.37086004 -2.01645 1.47893002 -2.01645 0 P 0 
L 1.37098996 -2.01545 1.47868002 -2.01545 0 P 0 
L 1.37113002 -2.01445 1.4784 -2.01445 0 P 0 
L 1.37126998 -2.01345 1.47806004 -2.01345 0 P 0 
L 1.3714 -2.01245 1.47773002 -2.01245 0 P 0 
L 1.37153996 -2.01145 1.47733002 -2.01145 0 P 0 
L 1.37168002 -2.01045 1.47691004 -2.01045 0 P 0 
L 1.37181004 -2.00945 1.47641004 -2.00945 0 P 0 
L 1.37195 -2.00845 1.47588996 -2.00845 0 P 0 
L 1.37208002 -2.00745 1.47528002 -2.00745 0 P 0 
L 1.37221004 -2.00645 1.47463996 -2.00645 0 P 0 
L 1.37235 -2.00545 1.47391998 -2.00545 0 P 0 
L 1.37248996 -2.00445 1.47311004 -2.00445 0 P 0 
L 1.37261998 -2.00345 1.47225 -2.00345 0 P 0 
L 1.37276004 -2.00245 1.47126998 -2.00245 0 P 0 
L 1.3729 -2.00145 1.4702 -2.00145 0 P 0 
L 1.37303002 -2.00045 1.46903996 -2.00045 0 P 0 
L 1.37316998 -1.99945 1.46775 -1.99945 0 P 0 
L 1.3733 -1.99845 1.46625 -1.99845 0 P 0 
L 1.37343996 -1.99745 1.46455 -1.99745 0 P 0 
L 1.37356998 -1.99645 1.46253996 -1.99645 0 P 0 
L 1.37753002 -1.99545 1.46041004 -1.99545 0 P 0 
L 1.38218996 -1.99445 1.45781004 -1.99445 0 P 0 
L 1.42925 -2.08345 1.47785 -2.08345 0 P 0 
L 1.42931998 -2.08245 1.47788996 -2.08245 0 P 0 
L 1.42938002 -2.08145 1.47793002 -2.08145 0 P 0 
L 1.42945 -2.08045 1.47796998 -2.08045 0 P 0 
L 1.42951004 -2.07945 1.47801004 -2.07945 0 P 0 
L 1.42958002 -2.07845 1.47806004 -2.07845 0 P 0 
L 1.42963996 -2.07745 1.4781 -2.07745 0 P 0 
L 1.4297 -2.07645 1.47815 -2.07645 0 P 0 
L 1.42976998 -2.07545 1.4782 -2.07545 0 P 0 
L 1.42983002 -2.07445 1.47825 -2.07445 0 P 0 
L 1.4299 -2.07345 1.47828996 -2.07345 0 P 0 
L 1.42963996 -2.07245 1.47833996 -2.07245 0 P 0 
L 1.42918996 -2.07145 1.47838002 -2.07145 0 P 0 
L 1.38425 -2.05145 1.47931004 -2.05145 0 P 0 
L 1.38731998 -2.05045 1.47933996 -2.05045 0 P 0 
L 1.39088002 -2.04945 1.47938002 -2.04945 0 P 0 
L 1.3947 -2.04845 1.47941004 -2.04845 0 P 0 
L 1.39851004 -2.04745 1.47945 -2.04745 0 P 0 
L 1.40233002 -2.04645 1.47948002 -2.04645 0 P 0 
L 1.40608002 -2.04545 1.47951004 -2.04545 0 P 0 
L 1.40983002 -2.04445 1.47955 -2.04445 0 P 0 
L 1.41306998 -2.04345 1.47958996 -2.04345 0 P 0 
L 1.41591998 -2.04245 1.47961998 -2.04245 0 P 0 
L 1.41876998 -2.04145 1.47965 -2.04145 0 P 0 
L 1.42133996 -2.04045 1.47968996 -2.04045 0 P 0 
L 1.42361998 -2.03945 1.47971998 -2.03945 0 P 0 
L 1.42591004 -2.03845 1.47975 -2.03845 0 P 0 
L 1.42805 -2.03745 1.47978002 -2.03745 0 P 0 
L 1.42936004 -2.03645 1.47981004 -2.03645 0 P 0 
L 1.43003002 -2.03545 1.47983002 -2.03545 0 P 0 
L 1.43081998 -2.03445 1.47986004 -2.03445 0 P 0 
L 1.43121004 -2.03345 1.47988002 -2.03345 0 P 0 
L 1.43141998 -2.03245 1.4799 -2.03245 0 P 0 
L 1.43146998 -2.03145 1.47993002 -2.03145 0 P 0 
L 1.43136004 -2.03045 1.47996004 -2.03045 0 P 0 
L 1.43108002 -2.02945 1.47998002 -2.02945 0 P 0 
L 1.4306 -2.02845 1.48001004 -2.02845 0 P 0 
L 1.42986998 -2.02745 1.48001004 -2.02745 0 P 0 
L 1.42875 -2.02645 1.47998996 -2.02645 0 P 0 
L 1.42658996 -2.02545 1.47996998 -2.02545 0 P 0 
L 1.42203996 -2.02445 1.47996004 -2.02445 0 P 0 
L 1.38748002 -1.99345 1.45483002 -1.99345 0 P 0 
L 1.39331998 -1.99245 1.45108996 -1.99245 0 P 0 
L 1.40051004 -1.99145 1.44503002 -1.99145 0 P 0 
L 1.38096998 -2.12745 1.4051 -2.12745 0 P 0 
L 1.37671004 -2.12645 1.41113996 -2.12645 0 P 0 
L 1.3736 -2.12545 1.41238996 -2.12545 0 P 0 
L 1.37096998 -2.12445 1.41268002 -2.12445 0 P 0 
L 1.36876998 -2.12345 1.41296998 -2.12345 0 P 0 
L 1.36685 -2.12245 1.41326998 -2.12245 0 P 0 
L 1.36516004 -2.12145 1.41356004 -2.12145 0 P 0 
L 1.36366004 -2.12045 1.41385 -2.12045 0 P 0 
L 1.36225 -2.11945 1.41413996 -2.11945 0 P 0 
L 1.361 -2.11845 1.41443002 -2.11845 0 P 0 
L 1.35983002 -2.11745 1.41471998 -2.11745 0 P 0 
L 1.35876004 -2.11645 1.41501004 -2.11645 0 P 0 
L 1.42661998 -2.12445 1.47693002 -2.12445 0 P 0 
L 1.42665 -2.12345 1.47693002 -2.12345 0 P 0 
L 1.4267 -2.12245 1.47693002 -2.12245 0 P 0 
L 1.42675 -2.12145 1.47693002 -2.12145 0 P 0 
L 1.42681004 -2.12045 1.47693002 -2.12045 0 P 0 
L 1.42686998 -2.11945 1.47693002 -2.11945 0 P 0 
L 1.42691998 -2.11845 1.47693002 -2.11845 0 P 0 
L 1.42698996 -2.11745 1.47693002 -2.11745 0 P 0 
L 1.42705 -2.11645 1.47693002 -2.11645 0 P 0 
L 1.42711004 -2.11545 1.47693002 -2.11545 0 P 0 
L 1.42716998 -2.11445 1.47693002 -2.11445 0 P 0 
L 1.42723002 -2.11345 1.47693996 -2.11345 0 P 0 
L 1.4273 -2.11245 1.47695 -2.11245 0 P 0 
L 1.42736998 -2.11145 1.47696004 -2.11145 0 P 0 
L 1.42743996 -2.11045 1.47698002 -2.11045 0 P 0 
L 1.42751004 -2.10945 1.47698996 -2.10945 0 P 0 
L 1.42758002 -2.10845 1.47701004 -2.10845 0 P 0 
L 1.42765 -2.10745 1.47703002 -2.10745 0 P 0 
L 1.42771004 -2.10645 1.47703996 -2.10645 0 P 0 
L 1.42778002 -2.10545 1.47706998 -2.10545 0 P 0 
L 1.42783996 -2.10445 1.4771 -2.10445 0 P 0 
L 1.42791004 -2.10345 1.47713002 -2.10345 0 P 0 
L 1.42798002 -2.10245 1.47716004 -2.10245 0 P 0 
L 1.42805 -2.10145 1.4772 -2.10145 0 P 0 
L 1.42811004 -2.10045 1.47723002 -2.10045 0 P 0 
L 1.40953002 -2.09945 1.41973002 -2.09945 0 P 0 
L 1.42818002 -2.09945 1.47726004 -2.09945 0 P 0 
L 1.41618002 -2.09845 1.41996998 -2.09845 0 P 0 
L 1.42825 -2.09845 1.47728996 -2.09845 0 P 0 
L 1.42831998 -2.09745 1.47733002 -2.09745 0 P 0 
L 1.42838996 -2.09645 1.47736004 -2.09645 0 P 0 
L 1.42846004 -2.09545 1.47738996 -2.09545 0 P 0 
L 1.42851998 -2.09445 1.47741998 -2.09445 0 P 0 
L 1.42858996 -2.09345 1.47746004 -2.09345 0 P 0 
L 1.42866004 -2.09245 1.4775 -2.09245 0 P 0 
L 1.42873002 -2.09145 1.47753996 -2.09145 0 P 0 
L 1.42878996 -2.09045 1.47758002 -2.09045 0 P 0 
L 1.42886004 -2.08945 1.47761998 -2.08945 0 P 0 
L 1.42893002 -2.08845 1.47766004 -2.08845 0 P 0 
L 1.42898996 -2.08745 1.4777 -2.08745 0 P 0 
L 1.42906004 -2.08645 1.47773002 -2.08645 0 P 0 
L 1.42911998 -2.08545 1.47776998 -2.08545 0 P 0 
L 1.42918996 -2.08445 1.47781004 -2.08445 0 P 0 
L 1.61686004 -2.17995 1.66846004 -2.17995 0 P 0 
L 1.61591004 -2.17895 1.67158996 -2.17895 0 P 0 
L 1.61553996 -2.17795 1.67431998 -2.17795 0 P 0 
L 1.61526998 -2.17695 1.67675 -2.17695 0 P 0 
L 1.61508002 -2.17595 1.67903996 -2.17595 0 P 0 
L 1.61496998 -2.17495 1.68108002 -2.17495 0 P 0 
L 1.61491004 -2.17395 1.68295 -2.17395 0 P 0 
L 1.61485 -2.17295 1.68458996 -2.17295 0 P 0 
L 1.61478996 -2.17195 1.6861 -2.17195 0 P 0 
L 1.61473002 -2.17095 1.6875 -2.17095 0 P 0 
L 1.61466998 -2.16995 1.68876998 -2.16995 0 P 0 
L 1.61461004 -2.16895 1.68998002 -2.16895 0 P 0 
L 1.61455 -2.16795 1.69108002 -2.16795 0 P 0 
L 1.61448996 -2.16695 1.69211998 -2.16695 0 P 0 
L 1.61443002 -2.16595 1.69316004 -2.16595 0 P 0 
L 1.61436998 -2.16495 1.69411998 -2.16495 0 P 0 
L 1.61431004 -2.16395 1.69498996 -2.16395 0 P 0 
L 1.61425 -2.16295 1.69586004 -2.16295 0 P 0 
L 1.61418996 -2.16195 1.69673002 -2.16195 0 P 0 
L 1.61413002 -2.16095 1.69746998 -2.16095 0 P 0 
L 1.61406998 -2.15995 1.6982 -2.15995 0 P 0 
L 1.61401998 -2.15895 1.69893996 -2.15895 0 P 0 
L 1.61396998 -2.15795 1.69963002 -2.15795 0 P 0 
L 1.64433002 -2.18295 1.63151004 -2.18271004 0 P 0 
L 1.63151004 -2.18271004 1.62658002 -2.18226998 0 P 0 
L 1.62658002 -2.18226998 1.62168996 -2.18146998 0 P 0 
L 1.62168996 -2.18146998 1.6201 -2.1811 0 P 0 
L 1.6201 -2.1811 1.61853996 -2.18061004 0 P 0 
L 1.61853996 -2.18061004 1.61701004 -2.18001998 0 P 0 
L 1.61701004 -2.18001998 1.61686004 -2.17995 0 P 0 
L 1.61686004 -2.17995 1.61671004 -2.17986998 0 P 0 
L 1.61671004 -2.17986998 1.61656998 -2.17976998 0 P 0 
L 1.61656998 -2.17976998 1.61643996 -2.17966998 0 P 0 
L 1.61643996 -2.17966998 1.61631998 -2.17955 0 P 0 
L 1.61631998 -2.17955 1.61621004 -2.17943002 0 P 0 
L 1.61621004 -2.17943002 1.6161 -2.1793 0 P 0 
L 1.6161 -2.1793 1.61601004 -2.17915 0 P 0 
L 1.61601004 -2.17915 1.61593002 -2.179 0 P 0 
L 1.61593002 -2.179 1.61586004 -2.17885 0 P 0 
L 1.61586004 -2.17885 1.61553002 -2.17791004 0 P 0 
L 1.61553002 -2.17791004 1.61526998 -2.17696004 0 P 0 
L 1.61526998 -2.17696004 1.61508996 -2.17598996 0 P 0 
L 1.61508996 -2.17598996 1.61496998 -2.17496998 0 P 0 
L 1.61496998 -2.17496998 1.61408002 -2.16011004 0 P 0 
L 1.61408002 -2.16011004 1.61341998 -2.14758996 0 P 0 
L 1.61341998 -2.14758996 1.6202 -2.14821004 0 P 0 
L 1.6202 -2.14821004 1.62023002 -2.14821004 0 P 0 
L 1.62023002 -2.14821004 1.63216998 -2.14893996 0 P 0 
L 1.63216998 -2.14893996 1.6349 -2.14893002 0 P 0 
L 1.6349 -2.14893002 1.63761998 -2.14873002 0 P 0 
L 1.63761998 -2.14873002 1.64031998 -2.14835 0 P 0 
L 1.64031998 -2.14835 1.64198996 -2.14798996 0 P 0 
L 1.64198996 -2.14798996 1.64363002 -2.14751998 0 P 0 
L 1.64363002 -2.14751998 1.64523002 -2.14693002 0 P 0 
L 1.64523002 -2.14693002 1.64678996 -2.14623002 0 P 0 
L 1.64678996 -2.14623002 1.64888002 -2.14506998 0 P 0 
L 1.64888002 -2.14506998 1.65086998 -2.14376004 0 P 0 
L 1.65086998 -2.14376004 1.65093996 -2.14371004 0 P 0 
L 1.65093996 -2.14371004 1.65275 -2.14228996 0 P 0 
L 1.65275 -2.14228996 1.6539 -2.14123996 0 P 0 
L 1.6539 -2.14123996 1.65496004 -2.14011004 0 P 0 
L 1.65496004 -2.14011004 1.65591998 -2.13891004 0 P 0 
L 1.65591998 -2.13891004 1.65755 -2.13653996 0 P 0 
L 1.65755 -2.13653996 1.65901998 -2.13415 0 P 0 
L 1.65901998 -2.13415 1.65903002 -2.13413002 0 P 0 
L 1.65903002 -2.13413002 1.66035 -2.13171998 0 P 0 
L 1.66035 -2.13171998 1.66155 -2.12925 0 P 0 
L 1.66155 -2.12925 1.66183996 -2.12851998 0 P 0 
L 1.66183996 -2.12851998 1.66206998 -2.12776004 0 P 0 
L 1.66206998 -2.12776004 1.66223996 -2.12696998 0 P 0 
L 1.66223996 -2.12696998 1.66233996 -2.12618002 0 P 0 
L 1.66233996 -2.12618002 1.66236998 -2.12538996 0 P 0 
L 1.66236998 -2.12538996 1.66233002 -2.12436004 0 P 0 
L 1.66233002 -2.12436004 1.66221004 -2.12335 0 P 0 
L 1.66221004 -2.12335 1.662 -2.12235 0 P 0 
L 1.662 -2.12235 1.66171004 -2.12141004 0 P 0 
L 1.66171004 -2.12141004 1.64438996 -2.07113002 0 P 0 
L 1.64438996 -2.07113002 1.62871998 -2.02606004 0 P 0 
L 1.62871998 -2.02606004 1.62116004 -2.00558996 0 P 0 
L 1.62116004 -2.00558996 1.62116004 -2.00556998 0 P 0 
L 1.62116004 -2.00556998 1.61681004 -1.99443996 0 P 0 
L 1.61681004 -1.99443996 1.67163002 -1.99443996 0 P 0 
L 1.67163002 -1.99443996 1.67301004 -2.00076004 0 P 0 
L 1.67301004 -2.00076004 1.67613002 -2.01341998 0 P 0 
L 1.67613002 -2.01341998 1.68331004 -2.03931998 0 P 0 
L 1.68331004 -2.03931998 1.69153002 -2.06856998 0 P 0 
L 1.69153002 -2.06856998 1.6916 -2.06876004 0 P 0 
L 1.6916 -2.06876004 1.69168996 -2.06896998 0 P 0 
L 1.69168996 -2.06896998 1.69181004 -2.06918002 0 P 0 
L 1.69181004 -2.06918002 1.69193002 -2.06936998 0 P 0 
L 1.69193002 -2.06936998 1.69208002 -2.06956004 0 P 0 
L 1.69208002 -2.06956004 1.69223996 -2.06973002 0 P 0 
L 1.69223996 -2.06973002 1.69241998 -2.06988002 0 P 0 
L 1.69241998 -2.06988002 1.6926 -2.07001998 0 P 0 
L 1.6926 -2.07001998 1.6928 -2.07015 0 P 0 
L 1.6928 -2.07015 1.69301004 -2.07025 0 P 0 
L 1.69301004 -2.07025 1.69323002 -2.07033996 0 P 0 
L 1.69323002 -2.07033996 1.69346004 -2.07041004 0 P 0 
L 1.69346004 -2.07041004 1.69368002 -2.07045 0 P 0 
L 1.69368002 -2.07045 1.69391998 -2.07048002 0 P 0 
L 1.69391998 -2.07048002 1.69413996 -2.07048996 0 P 0 
L 1.69413996 -2.07048996 1.6944 -2.07048002 0 P 0 
L 1.6944 -2.07048002 1.69465 -2.07045 0 P 0 
L 1.69465 -2.07045 1.69488996 -2.07038996 0 P 0 
L 1.69488996 -2.07038996 1.69513996 -2.07031998 0 P 0 
L 1.69513996 -2.07031998 1.69536998 -2.07021998 0 P 0 
L 1.69536998 -2.07021998 1.69558996 -2.0701 0 P 0 
L 1.69558996 -2.0701 1.69581004 -2.06996998 0 P 0 
L 1.69581004 -2.06996998 1.69601004 -2.06981998 0 P 0 
L 1.69601004 -2.06981998 1.6962 -2.06965 0 P 0 
L 1.6962 -2.06965 1.69636998 -2.06946004 0 P 0 
L 1.69636998 -2.06946004 1.69653002 -2.06926004 0 P 0 
L 1.69653002 -2.06926004 1.69666004 -2.06905 0 P 0 
L 1.69666004 -2.06905 1.69678996 -2.06883002 0 P 0 
L 1.69678996 -2.06883002 1.69688002 -2.0686 0 P 0 
L 1.69688002 -2.0686 1.69695 -2.0684 0 P 0 
L 1.69695 -2.0684 1.70426004 -2.04365 0 P 0 
L 1.70426004 -2.04365 1.70426004 -2.04363002 0 P 0 
L 1.70426004 -2.04363002 1.71066998 -2.0213 0 P 0 
L 1.71066998 -2.0213 1.71068002 -2.02126004 0 P 0 
L 1.71068002 -2.02126004 1.71431998 -2.00693996 0 P 0 
L 1.71431998 -2.00693996 1.71706004 -1.99496998 0 P 0 
L 1.71706004 -1.99496998 1.74335 -1.9947 0 P 0 
L 1.74335 -1.9947 1.75403002 -1.99461004 0 P 0 
L 1.75403002 -1.99461004 1.76301004 -1.99465 0 P 0 
L 1.76301004 -1.99465 1.76886004 -1.99471004 0 P 0 
L 1.76886004 -1.99471004 1.76883996 -1.99476004 0 P 0 
L 1.76883996 -1.99476004 1.74021004 -2.06556004 0 P 0 
L 1.74021004 -2.06556004 1.71298002 -2.13276998 0 P 0 
L 1.71298002 -2.13276998 1.70836998 -2.14293996 0 P 0 
L 1.70836998 -2.14293996 1.70413996 -2.15076004 0 P 0 
L 1.70413996 -2.15076004 1.69941998 -2.15828996 0 P 0 
L 1.69941998 -2.15828996 1.6967 -2.16198996 0 P 0 
L 1.6967 -2.16198996 1.6937 -2.16541998 0 P 0 
L 1.6937 -2.16541998 1.69041998 -2.1686 0 P 0 
L 1.69041998 -2.1686 1.68793996 -2.17063002 0 P 0 
L 1.68793996 -2.17063002 1.68535 -2.17248002 0 P 0 
L 1.68535 -2.17248002 1.68263996 -2.17413996 0 P 0 
L 1.68263996 -2.17413996 1.67981004 -2.17561004 0 P 0 
L 1.67981004 -2.17561004 1.67525 -2.17761004 0 P 0 
L 1.67525 -2.17761004 1.6706 -2.17931998 0 P 0 
L 1.6706 -2.17931998 1.66586004 -2.18073002 0 P 0 
L 1.66586004 -2.18073002 1.66141998 -2.1817 0 P 0 
L 1.66141998 -2.1817 1.65691998 -2.18228996 0 P 0 
L 1.65691998 -2.18228996 1.64433002 -2.18295 0 P 0 
L 1.61928996 -2.00628002 1.62683996 -2.02673002 0 P 0 
L 1.62683996 -2.02673002 1.6425 -2.07178002 0 P 0 
L 1.6425 -2.07178002 1.65981004 -2.12201998 0 P 0 
L 1.65981004 -2.12201998 1.66006004 -2.12283996 0 P 0 
L 1.66006004 -2.12283996 1.66023002 -2.12368002 0 P 0 
L 1.66023002 -2.12368002 1.66033996 -2.12451998 0 P 0 
L 1.66033996 -2.12451998 1.66036998 -2.12538002 0 P 0 
L 1.66036998 -2.12538002 1.66033996 -2.12601004 0 P 0 
L 1.66033996 -2.12601004 1.66026998 -2.12663996 0 P 0 
L 1.66026998 -2.12663996 1.66013996 -2.12725 0 P 0 
L 1.66013996 -2.12725 1.65995 -2.12786004 0 P 0 
L 1.65995 -2.12786004 1.65971004 -2.12843996 0 P 0 
L 1.65971004 -2.12843996 1.65856998 -2.1308 0 P 0 
L 1.65856998 -2.1308 1.6573 -2.13313002 0 P 0 
L 1.6573 -2.13313002 1.65586998 -2.13545 0 P 0 
L 1.65586998 -2.13545 1.65431004 -2.13771998 0 P 0 
L 1.65431004 -2.13771998 1.65343996 -2.1388 0 P 0 
L 1.65343996 -2.1388 1.65248996 -2.13981998 0 P 0 
L 1.65248996 -2.13981998 1.65146004 -2.14076004 0 P 0 
L 1.65146004 -2.14076004 1.64971004 -2.14213002 0 P 0 
L 1.64971004 -2.14213002 1.64785 -2.14336004 0 P 0 
L 1.64785 -2.14336004 1.64588996 -2.14443996 0 P 0 
L 1.64588996 -2.14443996 1.64446998 -2.14508002 0 P 0 
L 1.64446998 -2.14508002 1.64301004 -2.14561998 0 P 0 
L 1.64301004 -2.14561998 1.64151004 -2.14605 0 P 0 
L 1.64151004 -2.14605 1.63996998 -2.14636998 0 P 0 
L 1.63996998 -2.14636998 1.63741004 -2.14673996 0 P 0 
L 1.63741004 -2.14673996 1.63483002 -2.14693002 0 P 0 
L 1.63483002 -2.14693002 1.63223002 -2.14693996 0 P 0 
L 1.63223002 -2.14693996 1.62036004 -2.14621998 0 P 0 
L 1.62036004 -2.14621998 1.6113 -2.14538002 0 P 0 
L 1.6113 -2.14538002 1.61208996 -2.16023002 0 P 0 
L 1.61208996 -2.16023002 1.61298002 -2.17515 0 P 0 
L 1.61298002 -2.17515 1.6131 -2.17628002 0 P 0 
L 1.6131 -2.17628002 1.61331998 -2.17741004 0 P 0 
L 1.61331998 -2.17741004 1.61361998 -2.17851004 0 P 0 
L 1.61361998 -2.17851004 1.614 -2.17958996 0 P 0 
L 1.614 -2.17958996 1.61413996 -2.17988996 0 P 0 
L 1.61413996 -2.17988996 1.61428996 -2.18018002 0 P 0 
L 1.61428996 -2.18018002 1.61446998 -2.18045 0 P 0 
L 1.61446998 -2.18045 1.61466998 -2.18071004 0 P 0 
L 1.61466998 -2.18071004 1.61488996 -2.18095 0 P 0 
L 1.61488996 -2.18095 1.61511998 -2.18116998 0 P 0 
L 1.61511998 -2.18116998 1.61538002 -2.18138002 0 P 0 
L 1.61538002 -2.18138002 1.61565 -2.18156004 0 P 0 
L 1.61565 -2.18156004 1.61593002 -2.18173002 0 P 0 
L 1.61593002 -2.18173002 1.61623002 -2.18186004 0 P 0 
L 1.61623002 -2.18186004 1.61788002 -2.1825 0 P 0 
L 1.61788002 -2.1825 1.61956998 -2.18301998 0 P 0 
L 1.61956998 -2.18301998 1.6213 -2.18343002 0 P 0 
L 1.6213 -2.18343002 1.62633002 -2.18426004 0 P 0 
L 1.62633002 -2.18426004 1.6314 -2.18471004 0 P 0 
L 1.6314 -2.18471004 1.64436004 -2.18495 0 P 0 
L 1.64436004 -2.18495 1.65711004 -2.18428002 0 P 0 
L 1.65711004 -2.18428002 1.66176998 -2.18366998 0 P 0 
L 1.66176998 -2.18366998 1.66636004 -2.18266998 0 P 0 
L 1.66636004 -2.18266998 1.67123002 -2.18121004 0 P 0 
L 1.67123002 -2.18121004 1.676 -2.17946998 0 P 0 
L 1.676 -2.17946998 1.68068002 -2.17741998 0 P 0 
L 1.68068002 -2.17741998 1.68361998 -2.17588002 0 P 0 
L 1.68361998 -2.17588002 1.68646004 -2.17415 0 P 0 
L 1.68646004 -2.17415 1.68916004 -2.17221998 0 P 0 
L 1.68916004 -2.17221998 1.69175 -2.17008996 0 P 0 
L 1.69175 -2.17008996 1.69515 -2.1668 0 P 0 
L 1.69515 -2.1668 1.69826004 -2.16323996 0 P 0 
L 1.69826004 -2.16323996 1.70108002 -2.15941998 0 P 0 
L 1.70108002 -2.15941998 1.70586004 -2.15176998 0 P 0 
L 1.70586004 -2.15176998 1.71016004 -2.14383002 0 P 0 
L 1.71016004 -2.14383002 1.71481998 -2.13356004 0 P 0 
L 1.71481998 -2.13356004 1.74206998 -2.06631004 0 P 0 
L 1.74206998 -2.06631004 1.77071004 -1.99548002 0 P 0 
L 1.77071004 -1.99548002 1.77088002 -1.99498996 0 P 0 
L 1.77088002 -1.99498996 1.77101998 -1.99448996 0 P 0 
L 1.77101998 -1.99448996 1.77111998 -1.99398996 0 P 0 
L 1.77111998 -1.99398996 1.77118002 -1.99346998 0 P 0 
L 1.77118002 -1.99346998 1.7712 -1.99295 0 P 0 
L 1.7712 -1.99295 1.7712 -1.99293002 0 P 0 
L 1.7712 -1.99293002 1.77118996 -1.99286998 0 P 0 
L 1.77118996 -1.99286998 1.77118002 -1.99286004 0 P 0 
L 1.77118002 -1.99286004 1.77118002 -1.99283996 0 P 0 
L 1.77118002 -1.99283996 1.77111004 -1.99276998 0 P 0 
L 1.77111004 -1.99276998 1.77106998 -1.99275 0 P 0 
L 1.77106998 -1.99275 1.77106004 -1.99273996 0 P 0 
L 1.77106004 -1.99273996 1.771 -1.99273002 0 P 0 
L 1.771 -1.99273002 1.77098002 -1.99273002 0 P 0 
L 1.77098002 -1.99273002 1.76301004 -1.99265 0 P 0 
L 1.76301004 -1.99265 1.75401998 -1.99261004 0 P 0 
L 1.75401998 -1.99261004 1.74333002 -1.9927 0 P 0 
L 1.74333002 -1.9927 1.71546004 -1.99298996 0 P 0 
L 1.71546004 -1.99298996 1.71236998 -2.00646998 0 P 0 
L 1.71236998 -2.00646998 1.70873996 -2.02078002 0 P 0 
L 1.70873996 -2.02078002 1.70233996 -2.04308002 0 P 0 
L 1.70233996 -2.04308002 1.69505 -2.0678 0 P 0 
L 1.69505 -2.0678 1.69501998 -2.06788002 0 P 0 
L 1.69501998 -2.06788002 1.69498996 -2.06795 0 P 0 
L 1.69498996 -2.06795 1.69495 -2.06801998 0 P 0 
L 1.69495 -2.06801998 1.69485 -2.06816004 0 P 0 
L 1.69485 -2.06816004 1.69478996 -2.06821998 0 P 0 
L 1.69478996 -2.06821998 1.69466998 -2.06831998 0 P 0 
L 1.69466998 -2.06831998 1.69453002 -2.0684 0 P 0 
L 1.69453002 -2.0684 1.69445 -2.06843002 0 P 0 
L 1.69445 -2.06843002 1.69438002 -2.06846004 0 P 0 
L 1.69438002 -2.06846004 1.69428996 -2.06846998 0 P 0 
L 1.69428996 -2.06846998 1.69421004 -2.06848996 0 P 0 
L 1.69421004 -2.06848996 1.69406998 -2.06848996 0 P 0 
L 1.69406998 -2.06848996 1.69395 -2.06846998 0 P 0 
L 1.69395 -2.06846998 1.69383002 -2.06843002 0 P 0 
L 1.69383002 -2.06843002 1.69373002 -2.06836998 0 P 0 
L 1.69373002 -2.06836998 1.69363002 -2.06828996 0 P 0 
L 1.69363002 -2.06828996 1.69358996 -2.06823996 0 P 0 
L 1.69358996 -2.06823996 1.69355 -2.0682 0 P 0 
L 1.69355 -2.0682 1.69351998 -2.06815 0 P 0 
L 1.69351998 -2.06815 1.69346004 -2.06803996 0 P 0 
L 1.69346004 -2.06803996 1.69343996 -2.06798002 0 P 0 
L 1.69343996 -2.06798002 1.68523002 -2.03878002 0 P 0 
L 1.68523002 -2.03878002 1.67806998 -2.01291998 0 P 0 
L 1.67806998 -2.01291998 1.67496004 -2.00031004 0 P 0 
L 1.67496004 -2.00031004 1.67323002 -1.99243996 0 P 0 
L 1.67323002 -1.99243996 1.61388002 -1.99243996 0 P 0 
L 1.61388002 -1.99243996 1.61928996 -2.00628002 0 P 0 
L 1.35018002 -2.08345 1.39488996 -2.08345 0 P 0 
L 1.35026004 -2.08245 1.39586004 -2.08245 0 P 0 
L 1.35041004 -2.08145 1.39708996 -2.08145 0 P 0 
L 1.35058996 -2.08045 1.39853002 -2.08045 0 P 0 
L 1.35083996 -2.07945 1.40031998 -2.07945 0 P 0 
L 1.35116998 -2.07845 1.40271004 -2.07845 0 P 0 
L 1.35158002 -2.07745 1.40561998 -2.07745 0 P 0 
L 1.35203002 -2.07645 1.4092 -2.07645 0 P 0 
L 1.35248002 -2.07545 1.41288996 -2.07545 0 P 0 
L 1.35293002 -2.07445 1.4164 -2.07445 0 P 0 
L 1.35338996 -2.07345 1.41975 -2.07345 0 P 0 
L 1.35393996 -2.07245 1.42293996 -2.07245 0 P 0 
L 1.35448996 -2.07145 1.42606998 -2.07145 0 P 0 
L 1.35505 -2.07045 1.47843002 -2.07045 0 P 0 
L 1.3557 -2.06945 1.47846998 -2.06945 0 P 0 
L 1.35635 -2.06845 1.47851998 -2.06845 0 P 0 
L 1.35701998 -2.06745 1.47856998 -2.06745 0 P 0 
L 1.35776998 -2.06645 1.47861004 -2.06645 0 P 0 
L 1.29346998 -2.00516004 1.33388996 -2.00516004 0 P 0 
L 1.29448996 -2.00416004 1.33385 -2.00416004 0 P 0 
L 1.29551004 -2.00316004 1.33381004 -2.00316004 0 P 0 
L 1.29653996 -2.00216004 1.33376004 -2.00216004 0 P 0 
L 1.29756004 -2.00116004 1.33371004 -2.00116004 0 P 0 
L 1.29861998 -2.00016004 1.33366004 -2.00016004 0 P 0 
L 1.29973002 -1.99916004 1.3336 -1.99916004 0 P 0 
L 1.30101004 -1.99816004 1.33355 -1.99816004 0 P 0 
L 1.30238996 -1.99716004 1.3335 -1.99716004 0 P 0 
L 1.30393996 -1.99616004 1.33345 -1.99616004 0 P 0 
L 1.30571004 -1.99516004 1.33338996 -1.99516004 0 P 0 
L 1.3077 -1.99416004 1.33333002 -1.99416004 0 P 0 
L 1.31001004 -1.99316004 1.33328002 -1.99316004 0 P 0 
L 1.31288002 -1.99216004 1.33321998 -1.99216004 0 P 0 
L 1.31688996 -1.99116004 1.33316004 -1.99116004 0 P 0 
L 1.39798996 -1.98971998 1.39326998 -1.99043002 0 P 0 
L 1.39326998 -1.99043002 1.38806998 -1.9913 0 P 0 
L 1.38806998 -1.9913 1.38316004 -1.9922 0 P 0 
L 1.38316004 -1.9922 1.37946004 -1.99296998 0 P 0 
L 1.37946004 -1.99296998 1.3718 -1.99466998 0 P 0 
L 1.3718 -1.99466998 1.36896004 -2.01553996 0 P 0 
L 1.36896004 -2.01553996 1.36791004 -2.02358996 0 P 0 
L 1.36791004 -2.02358996 1.36708002 -2.03043002 0 P 0 
L 1.36708002 -2.03043002 1.36638996 -2.03646004 0 P 0 
L 1.36638996 -2.03646004 1.36638002 -2.03648996 0 P 0 
L 1.36638002 -2.03648996 1.36638996 -2.03653002 0 P 0 
L 1.36638996 -2.03653002 1.36638996 -2.03656998 0 P 0 
L 1.36638996 -2.03656998 1.3664 -2.03663996 0 P 0 
L 1.3664 -2.03663996 1.36641998 -2.03666998 0 P 0 
L 1.36641998 -2.03666998 1.36643002 -2.03671004 0 P 0 
L 1.36643002 -2.03671004 1.36648996 -2.0368 0 P 0 
L 1.36648996 -2.0368 1.36656004 -2.03686004 0 P 0 
L 1.36656004 -2.03686004 1.3666 -2.03688996 0 P 0 
L 1.3666 -2.03688996 1.36663002 -2.03691004 0 P 0 
L 1.36663002 -2.03691004 1.36666004 -2.03691004 0 P 0 
L 1.36666004 -2.03691004 1.36671004 -2.03693002 0 P 0 
L 1.36671004 -2.03693002 1.36676998 -2.03693002 0 P 0 
L 1.36676998 -2.03693002 1.36685 -2.03691998 0 P 0 
L 1.36685 -2.03691998 1.36895 -2.03628002 0 P 0 
L 1.36895 -2.03628002 1.37143002 -2.03545 0 P 0 
L 1.37143002 -2.03545 1.37428996 -2.03441004 0 P 0 
L 1.37428996 -2.03441004 1.38346004 -2.03126998 0 P 0 
L 1.38346004 -2.03126998 1.39251998 -2.02891998 0 P 0 
L 1.39251998 -2.02891998 1.40156004 -2.02731998 0 P 0 
L 1.40156004 -2.02731998 1.41068002 -2.02643996 0 P 0 
L 1.41068002 -2.02643996 1.41566998 -2.02628002 0 P 0 
L 1.41566998 -2.02628002 1.42066004 -2.02633996 0 P 0 
L 1.42066004 -2.02633996 1.42221004 -2.02646998 0 P 0 
L 1.42221004 -2.02646998 1.42375 -2.02671998 0 P 0 
L 1.42375 -2.02671998 1.42525 -2.0271 0 P 0 
L 1.42525 -2.0271 1.42671998 -2.02761004 0 P 0 
L 1.42671998 -2.02761004 1.42706004 -2.02776004 0 P 0 
L 1.42706004 -2.02776004 1.42738002 -2.02793002 0 P 0 
L 1.42738002 -2.02793002 1.42768002 -2.02813996 0 P 0 
L 1.42768002 -2.02813996 1.42796998 -2.02836004 0 P 0 
L 1.42796998 -2.02836004 1.42823002 -2.02861004 0 P 0 
L 1.42823002 -2.02861004 1.42848002 -2.02888996 0 P 0 
L 1.42848002 -2.02888996 1.4287 -2.02918002 0 P 0 
L 1.4287 -2.02918002 1.42888996 -2.02948996 0 P 0 
L 1.42888996 -2.02948996 1.42906004 -2.02981004 0 P 0 
L 1.42906004 -2.02981004 1.4292 -2.03015 0 P 0 
L 1.4292 -2.03015 1.42931998 -2.0305 0 P 0 
L 1.42931998 -2.0305 1.4294 -2.03086004 0 P 0 
L 1.4294 -2.03086004 1.42945 -2.03121998 0 P 0 
L 1.42945 -2.03121998 1.42946998 -2.03158002 0 P 0 
L 1.42946998 -2.03158002 1.42946004 -2.03195 0 P 0 
L 1.42946004 -2.03195 1.42941998 -2.03231004 0 P 0 
L 1.42941998 -2.03231004 1.42935 -2.03266998 0 P 0 
L 1.42935 -2.03266998 1.42925 -2.03301998 0 P 0 
L 1.42925 -2.03301998 1.42911998 -2.03336004 0 P 0 
L 1.42911998 -2.03336004 1.42896004 -2.03368996 0 P 0 
L 1.42896004 -2.03368996 1.42875 -2.03405 0 P 0 
L 1.42875 -2.03405 1.42851004 -2.03438996 0 P 0 
L 1.42851004 -2.03438996 1.42825 -2.03471004 0 P 0 
L 1.42825 -2.03471004 1.42796004 -2.03501004 0 P 0 
L 1.42796004 -2.03501004 1.42765 -2.03528996 0 P 0 
L 1.42765 -2.03528996 1.42731998 -2.03553996 0 P 0 
L 1.42731998 -2.03553996 1.42696998 -2.03576004 0 P 0 
L 1.42696998 -2.03576004 1.4266 -2.03596004 0 P 0 
L 1.4266 -2.03596004 1.41951004 -2.03906004 0 P 0 
L 1.41951004 -2.03906004 1.4109 -2.04208996 0 P 0 
L 1.4109 -2.04208996 1.40178002 -2.04451998 0 P 0 
L 1.40178002 -2.04451998 1.3878 -2.04818996 0 P 0 
L 1.3878 -2.04818996 1.38176998 -2.05015 0 P 0 
L 1.38176998 -2.05015 1.3758 -2.05243002 0 P 0 
L 1.3758 -2.05243002 1.37086998 -2.0546 0 P 0 
L 1.37086998 -2.0546 1.36603996 -2.05708002 0 P 0 
L 1.36603996 -2.05708002 1.36356004 -2.05856004 0 P 0 
L 1.36356004 -2.05856004 1.36118996 -2.06023002 0 P 0 
L 1.36118996 -2.06023002 1.35895 -2.06206004 0 P 0 
L 1.35895 -2.06206004 1.35805 -2.06291004 0 P 0 
L 1.35805 -2.06291004 1.35721998 -2.06385 0 P 0 
L 1.35721998 -2.06385 1.35518996 -2.06655 0 P 0 
L 1.35518996 -2.06655 1.3532 -2.06961998 0 P 0 
L 1.3532 -2.06961998 1.35156004 -2.07263002 0 P 0 
L 1.35156004 -2.07263002 1.34951004 -2.07718002 0 P 0 
L 1.34951004 -2.07718002 1.34911004 -2.07825 0 P 0 
L 1.34911004 -2.07825 1.34878996 -2.07935 0 P 0 
L 1.34878996 -2.07935 1.34853002 -2.08046998 0 P 0 
L 1.34853002 -2.08046998 1.34825 -2.08238002 0 P 0 
L 1.34825 -2.08238002 1.34811998 -2.08431004 0 P 0 
L 1.34811998 -2.08431004 1.348 -2.09128996 0 P 0 
L 1.348 -2.09128996 1.3481 -2.09761004 0 P 0 
L 1.3481 -2.09761004 1.34823002 -2.09961004 0 P 0 
L 1.34823002 -2.09961004 1.34846998 -2.10161004 0 P 0 
L 1.34846998 -2.10161004 1.34876998 -2.10321998 0 P 0 
L 1.34876998 -2.10321998 1.3492 -2.10478996 0 P 0 
L 1.3492 -2.10478996 1.3498 -2.10648996 0 P 0 
L 1.3498 -2.10648996 1.3505 -2.10815 0 P 0 
L 1.3505 -2.10815 1.35178996 -2.11066004 0 P 0 
L 1.35178996 -2.11066004 1.35328002 -2.11305 0 P 0 
L 1.35328002 -2.11305 1.35496998 -2.1153 0 P 0 
L 1.35496998 -2.1153 1.35685 -2.1174 0 P 0 
L 1.35685 -2.1174 1.35891998 -2.11933996 0 P 0 
L 1.35891998 -2.11933996 1.36126998 -2.12121998 0 P 0 
L 1.36126998 -2.12121998 1.36373996 -2.12293002 0 P 0 
L 1.36373996 -2.12293002 1.36633002 -2.12446004 0 P 0 
L 1.36633002 -2.12446004 1.36901004 -2.1258 0 P 0 
L 1.36901004 -2.1258 1.3718 -2.12695 0 P 0 
L 1.3718 -2.12695 1.37578996 -2.12828002 0 P 0 
L 1.37578996 -2.12828002 1.37986998 -2.12928996 0 P 0 
L 1.37986998 -2.12928996 1.38401998 -2.12998996 0 P 0 
L 1.38401998 -2.12998996 1.3882 -2.13036004 0 P 0 
L 1.3882 -2.13036004 1.39443002 -2.13045 0 P 0 
L 1.39443002 -2.13045 1.40066004 -2.13006998 0 P 0 
L 1.40066004 -2.13006998 1.40685 -2.12923002 0 P 0 
L 1.40685 -2.12923002 1.41371004 -2.12801998 0 P 0 
L 1.41371004 -2.12801998 1.41583002 -2.12081004 0 P 0 
L 1.41583002 -2.12081004 1.41953996 -2.10798996 0 P 0 
L 1.41953996 -2.10798996 1.42135 -2.10126998 0 P 0 
L 1.42135 -2.10126998 1.42236998 -2.097 0 P 0 
L 1.42236998 -2.097 1.42238996 -2.09691004 0 P 0 
L 1.42238996 -2.09691004 1.4224 -2.09681998 0 P 0 
L 1.4224 -2.09681998 1.4224 -2.09673996 0 P 0 
L 1.4224 -2.09673996 1.42238002 -2.09656004 0 P 0 
L 1.42238002 -2.09656004 1.42235 -2.09648002 0 P 0 
L 1.42235 -2.09648002 1.42233002 -2.09638996 0 P 0 
L 1.42233002 -2.09638996 1.42225 -2.09623002 0 P 0 
L 1.42225 -2.09623002 1.4222 -2.09616004 0 P 0 
L 1.4222 -2.09616004 1.42213996 -2.09608996 0 P 0 
L 1.42213996 -2.09608996 1.42208996 -2.09601998 0 P 0 
L 1.42208996 -2.09601998 1.42203996 -2.09598996 0 P 0 
L 1.42203996 -2.09598996 1.42198996 -2.09595 0 P 0 
L 1.42198996 -2.09595 1.42188996 -2.09588996 0 P 0 
L 1.42188996 -2.09588996 1.42183002 -2.09586004 0 P 0 
L 1.42183002 -2.09586004 1.42178002 -2.09585 0 P 0 
L 1.42178002 -2.09585 1.42171998 -2.09583002 0 P 0 
L 1.42171998 -2.09583002 1.42166004 -2.09581998 0 P 0 
L 1.42166004 -2.09581998 1.42153996 -2.09581998 0 P 0 
L 1.42153996 -2.09581998 1.41978002 -2.09591004 0 P 0 
L 1.41978002 -2.09591004 1.41763996 -2.09615 0 P 0 
L 1.41763996 -2.09615 1.41521998 -2.09658002 0 P 0 
L 1.41521998 -2.09658002 1.4107 -2.09733002 0 P 0 
L 1.4107 -2.09733002 1.40613002 -2.09775 0 P 0 
L 1.40613002 -2.09775 1.40481004 -2.09778002 0 P 0 
L 1.40481004 -2.09778002 1.40348996 -2.09771998 0 P 0 
L 1.40348996 -2.09771998 1.40216998 -2.09756004 0 P 0 
L 1.40216998 -2.09756004 1.40086998 -2.0973 0 P 0 
L 1.40086998 -2.0973 1.39958996 -2.09695 0 P 0 
L 1.39958996 -2.09695 1.39895 -2.09671998 0 P 0 
L 1.39895 -2.09671998 1.39831998 -2.09643002 0 P 0 
L 1.39831998 -2.09643002 1.39773002 -2.0961 0 P 0 
L 1.39773002 -2.0961 1.39716004 -2.09571004 0 P 0 
L 1.39716004 -2.09571004 1.39663002 -2.09528002 0 P 0 
L 1.39663002 -2.09528002 1.39613996 -2.0948 0 P 0 
L 1.39613996 -2.0948 1.39568002 -2.09428002 0 P 0 
L 1.39568002 -2.09428002 1.39533996 -2.09381998 0 P 0 
L 1.39533996 -2.09381998 1.39505 -2.09333996 0 P 0 
L 1.39505 -2.09333996 1.39478996 -2.09281998 0 P 0 
L 1.39478996 -2.09281998 1.39456998 -2.09228996 0 P 0 
L 1.39456998 -2.09228996 1.3944 -2.09173996 0 P 0 
L 1.3944 -2.09173996 1.39428002 -2.09118996 0 P 0 
L 1.39428002 -2.09118996 1.39421004 -2.09061998 0 P 0 
L 1.39421004 -2.09061998 1.39418002 -2.09003996 0 P 0 
L 1.39418002 -2.09003996 1.39421004 -2.08943002 0 P 0 
L 1.39421004 -2.08943002 1.39428002 -2.08883002 0 P 0 
L 1.39428002 -2.08883002 1.39441004 -2.08823002 0 P 0 
L 1.39441004 -2.08823002 1.3946 -2.08765 0 P 0 
L 1.3946 -2.08765 1.39483002 -2.08708002 0 P 0 
L 1.39483002 -2.08708002 1.39511004 -2.08653996 0 P 0 
L 1.39511004 -2.08653996 1.39555 -2.08583996 0 P 0 
L 1.39555 -2.08583996 1.39603996 -2.08518002 0 P 0 
L 1.39603996 -2.08518002 1.39658002 -2.08456004 0 P 0 
L 1.39658002 -2.08456004 1.39716004 -2.08396998 0 P 0 
L 1.39716004 -2.08396998 1.39778002 -2.08343002 0 P 0 
L 1.39778002 -2.08343002 1.39878996 -2.08266998 0 P 0 
L 1.39878996 -2.08266998 1.39985 -2.08196998 0 P 0 
L 1.39985 -2.08196998 1.40096004 -2.08135 0 P 0 
L 1.40096004 -2.08135 1.40211998 -2.08081004 0 P 0 
L 1.40211998 -2.08081004 1.40503002 -2.07971004 0 P 0 
L 1.40503002 -2.07971004 1.40801998 -2.07881998 0 P 0 
L 1.40801998 -2.07881998 1.41128996 -2.07796004 0 P 0 
L 1.41128996 -2.07796004 1.41506004 -2.07691998 0 P 0 
L 1.41506004 -2.07691998 1.41871998 -2.07585 0 P 0 
L 1.41871998 -2.07585 1.42165 -2.07495 0 P 0 
L 1.42165 -2.07495 1.42791998 -2.07295 0 P 0 
L 1.42791998 -2.07295 1.42731998 -2.08241004 0 P 0 
L 1.42731998 -2.08241004 1.42701004 -2.08708002 0 P 0 
L 1.42701004 -2.08708002 1.42658002 -2.09353996 0 P 0 
L 1.42658002 -2.09353996 1.4261 -2.10055 0 P 0 
L 1.4261 -2.10055 1.42566998 -2.10706004 0 P 0 
L 1.42566998 -2.10706004 1.42525 -2.11306004 0 P 0 
L 1.42525 -2.11306004 1.42491998 -2.11851998 0 P 0 
L 1.42491998 -2.11851998 1.42466004 -2.1231 0 P 0 
L 1.42466004 -2.1231 1.42461004 -2.12471004 0 P 0 
L 1.42461004 -2.12471004 1.4246 -2.12716004 0 P 0 
L 1.4246 -2.12716004 1.47893002 -2.12716004 0 P 0 
L 1.47893002 -2.12716004 1.47893002 -2.11358002 0 P 0 
L 1.47893002 -2.11358002 1.47905 -2.10616998 0 P 0 
L 1.47905 -2.10616998 1.47943996 -2.09385 0 P 0 
L 1.47943996 -2.09385 1.48 -2.07968996 0 P 0 
L 1.48 -2.07968996 1.48066004 -2.0655 0 P 0 
L 1.48066004 -2.0655 1.4813 -2.05168996 0 P 0 
L 1.4813 -2.05168996 1.48175 -2.03873996 0 P 0 
L 1.48175 -2.03873996 1.48201998 -2.02785 0 P 0 
L 1.48201998 -2.02785 1.48191998 -2.02286004 0 P 0 
L 1.48191998 -2.02286004 1.48165 -2.01995 0 P 0 
L 1.48165 -2.01995 1.48115 -2.01708002 0 P 0 
L 1.48115 -2.01708002 1.48043996 -2.01425 0 P 0 
L 1.48043996 -2.01425 1.47951004 -2.01146998 0 P 0 
L 1.47951004 -2.01146998 1.47866998 -2.00946998 0 P 0 
L 1.47866998 -2.00946998 1.47768002 -2.00753996 0 P 0 
L 1.47768002 -2.00753996 1.47655 -2.00568002 0 P 0 
L 1.47655 -2.00568002 1.47528002 -2.00391998 0 P 0 
L 1.47528002 -2.00391998 1.47388002 -2.00225 0 P 0 
L 1.47388002 -2.00225 1.47228996 -2.00063002 0 P 0 
L 1.47228996 -2.00063002 1.4706 -1.99911998 0 P 0 
L 1.4706 -1.99911998 1.4688 -1.99773002 0 P 0 
L 1.4688 -1.99773002 1.46691004 -1.99648002 0 P 0 
L 1.46691004 -1.99648002 1.46491998 -1.99535 0 P 0 
L 1.46491998 -1.99535 1.46098996 -1.99351004 0 P 0 
L 1.46098996 -1.99351004 1.45693002 -1.99196998 0 P 0 
L 1.45693002 -1.99196998 1.45276004 -1.99076004 0 P 0 
L 1.45276004 -1.99076004 1.44953996 -1.99006004 0 P 0 
L 1.44953996 -1.99006004 1.44628996 -1.98956004 0 P 0 
L 1.44628996 -1.98956004 1.44298002 -1.98923996 0 P 0 
L 1.44298002 -1.98923996 1.42695 -1.98856998 0 P 0 
L 1.42695 -1.98856998 1.41038996 -1.98865 0 P 0 
L 1.41038996 -1.98865 1.4042 -1.98901004 0 P 0 
L 1.4042 -1.98901004 1.39798996 -1.98971998 0 P 0 
L 1.35778996 -2.11545 1.4153 -2.11545 0 P 0 
L 1.35688996 -2.11445 1.41558996 -2.11445 0 P 0 
L 1.35608002 -2.11345 1.41588002 -2.11345 0 P 0 
L 1.35533002 -2.11245 1.41616998 -2.11245 0 P 0 
L 1.35463996 -2.11145 1.41646004 -2.11145 0 P 0 
L 1.35401004 -2.11045 1.41675 -2.11045 0 P 0 
L 1.35341004 -2.10945 1.41703996 -2.10945 0 P 0 
L 1.3529 -2.10845 1.41733002 -2.10845 0 P 0 
L 1.35238002 -2.10745 1.41761998 -2.10745 0 P 0 
L 1.35195 -2.10645 1.41788002 -2.10645 0 P 0 
L 1.35155 -2.10545 1.41816004 -2.10545 0 P 0 
L 1.3512 -2.10445 1.41841998 -2.10445 0 P 0 
L 1.35091004 -2.10345 1.41868996 -2.10345 0 P 0 
L 1.35066004 -2.10245 1.41896004 -2.10245 0 P 0 
L 1.35046998 -2.10145 1.41923002 -2.10145 0 P 0 
L 1.35033996 -2.10045 1.41948996 -2.10045 0 P 0 
L 1.35021998 -2.09945 1.40141004 -2.09945 0 P 0 
L 1.35016004 -2.09845 1.39791004 -2.09845 0 P 0 
L 1.3501 -2.09745 1.39616004 -2.09745 0 P 0 
L 1.35008002 -2.09645 1.39496004 -2.09645 0 P 0 
L 1.35006998 -2.09545 1.39406004 -2.09545 0 P 0 
L 1.35005 -2.09445 1.39338002 -2.09445 0 P 0 
L 1.35003996 -2.09345 1.39288002 -2.09345 0 P 0 
L 1.35001998 -2.09245 1.39253002 -2.09245 0 P 0 
L 1.35001004 -2.09145 1.3923 -2.09145 0 P 0 
L 1.35001998 -2.09045 1.3922 -2.09045 0 P 0 
L 1.35003002 -2.08945 1.3922 -2.08945 0 P 0 
L 1.35005 -2.08845 1.39231998 -2.08845 0 P 0 
L 1.35006998 -2.08745 1.39256004 -2.08745 0 P 0 
L 1.35008002 -2.08645 1.39293002 -2.08645 0 P 0 
L 1.3501 -2.08545 1.39343002 -2.08545 0 P 0 
L 1.35011004 -2.08445 1.39408996 -2.08445 0 P 0 
L 1.39438002 -2.12845 1.3883 -2.12836004 0 P 0 
L 1.3883 -2.12836004 1.38426998 -2.128 0 P 0 
L 1.38426998 -2.128 1.38028002 -2.12733002 0 P 0 
L 1.38028002 -2.12733002 1.37635 -2.12636004 0 P 0 
L 1.37635 -2.12636004 1.37248996 -2.12508002 0 P 0 
L 1.37248996 -2.12508002 1.36983996 -2.12398002 0 P 0 
L 1.36983996 -2.12398002 1.36728996 -2.1227 0 P 0 
L 1.36728996 -2.1227 1.36481998 -2.12123996 0 P 0 
L 1.36481998 -2.12123996 1.36246004 -2.11961004 0 P 0 
L 1.36246004 -2.11961004 1.36023002 -2.11781998 0 P 0 
L 1.36023002 -2.11781998 1.35828996 -2.116 0 P 0 
L 1.35828996 -2.116 1.35651998 -2.11403002 0 P 0 
L 1.35651998 -2.11403002 1.35493002 -2.11191004 0 P 0 
L 1.35493002 -2.11191004 1.35353002 -2.10966998 0 P 0 
L 1.35353002 -2.10966998 1.35231004 -2.10731004 0 P 0 
L 1.35231004 -2.10731004 1.35166998 -2.10576998 0 P 0 
L 1.35166998 -2.10576998 1.35111004 -2.1042 0 P 0 
L 1.35111004 -2.1042 1.35071998 -2.10276004 0 P 0 
L 1.35071998 -2.10276004 1.35045 -2.1013 0 P 0 
L 1.35045 -2.1013 1.35021998 -2.09943002 0 P 0 
L 1.35021998 -2.09943002 1.3501 -2.09753002 0 P 0 
L 1.3501 -2.09753002 1.35001004 -2.09128002 0 P 0 
L 1.35001004 -2.09128002 1.35011998 -2.0844 0 P 0 
L 1.35011998 -2.0844 1.35023996 -2.08258996 0 P 0 
L 1.35023996 -2.08258996 1.3505 -2.08083996 0 P 0 
L 1.3505 -2.08083996 1.35071998 -2.07985 0 P 0 
L 1.35071998 -2.07985 1.35101004 -2.07888002 0 P 0 
L 1.35101004 -2.07888002 1.35136004 -2.07793002 0 P 0 
L 1.35136004 -2.07793002 1.35335 -2.07351998 0 P 0 
L 1.35335 -2.07351998 1.35491998 -2.07065 0 P 0 
L 1.35491998 -2.07065 1.35683002 -2.0677 0 P 0 
L 1.35683002 -2.0677 1.35876998 -2.06511004 0 P 0 
L 1.35876998 -2.06511004 1.35948996 -2.0643 0 P 0 
L 1.35948996 -2.0643 1.36026998 -2.06356004 0 P 0 
L 1.36026998 -2.06356004 1.3624 -2.06181998 0 P 0 
L 1.3624 -2.06181998 1.36465 -2.06023996 0 P 0 
L 1.36465 -2.06023996 1.36701004 -2.05883002 0 P 0 
L 1.36701004 -2.05883002 1.37173002 -2.05641004 0 P 0 
L 1.37173002 -2.05641004 1.37656004 -2.05426998 0 P 0 
L 1.37656004 -2.05426998 1.38243002 -2.05203996 0 P 0 
L 1.38243002 -2.05203996 1.38836004 -2.0501 0 P 0 
L 1.38836004 -2.0501 1.4023 -2.04645 0 P 0 
L 1.4023 -2.04645 1.41148996 -2.044 0 P 0 
L 1.41148996 -2.044 1.42016998 -2.04095 0 P 0 
L 1.42016998 -2.04095 1.42016998 -2.04093996 0 P 0 
L 1.42016998 -2.04093996 1.42021004 -2.04093996 0 P 0 
L 1.42021004 -2.04093996 1.42023996 -2.04093002 0 P 0 
L 1.42023996 -2.04093002 1.42746998 -2.03776004 0 P 0 
L 1.42746998 -2.03776004 1.42753002 -2.03773002 0 P 0 
L 1.42753002 -2.03773002 1.42796998 -2.03748996 0 P 0 
L 1.42796998 -2.03748996 1.42846004 -2.03718996 0 P 0 
L 1.42846004 -2.03718996 1.42891998 -2.03683996 0 P 0 
L 1.42891998 -2.03683996 1.42935 -2.03646004 0 P 0 
L 1.42935 -2.03646004 1.42975 -2.03603996 0 P 0 
L 1.42975 -2.03603996 1.43011004 -2.0356 0 P 0 
L 1.43011004 -2.0356 1.43016004 -2.03553002 0 P 0 
L 1.43016004 -2.03553002 1.4299 -2.03535 0 P 0 
L 1.4299 -2.03535 1.43028002 -2.03535 0 P 0 
L 1.43028002 -2.03535 1.43043996 -2.03513002 0 P 0 
L 1.43043996 -2.03513002 1.43048002 -2.03506004 0 P 0 
L 1.43048002 -2.03506004 1.43041998 -2.03501998 0 P 0 
L 1.43041998 -2.03501998 1.4305 -2.03501998 0 P 0 
L 1.4305 -2.03501998 1.43073002 -2.03463002 0 P 0 
L 1.43073002 -2.03463002 1.43096004 -2.03415 0 P 0 
L 1.43096004 -2.03415 1.43115 -2.03365 0 P 0 
L 1.43115 -2.03365 1.4313 -2.03313002 0 P 0 
L 1.4313 -2.03313002 1.4314 -2.03261004 0 P 0 
L 1.4314 -2.03261004 1.43146004 -2.03208002 0 P 0 
L 1.43146004 -2.03208002 1.43146998 -2.03155 0 P 0 
L 1.43146998 -2.03155 1.43143996 -2.03101004 0 P 0 
L 1.43143996 -2.03101004 1.43143002 -2.03093002 0 P 0 
L 1.43143002 -2.03093002 1.43136004 -2.03048996 0 P 0 
L 1.43136004 -2.03048996 1.43125 -2.02996998 0 P 0 
L 1.43125 -2.02996998 1.43108002 -2.02946004 0 P 0 
L 1.43108002 -2.02946004 1.43086998 -2.02896004 0 P 0 
L 1.43086998 -2.02896004 1.43063002 -2.02848996 0 P 0 
L 1.43063002 -2.02848996 1.43033996 -2.02803996 0 P 0 
L 1.43033996 -2.02803996 1.43001998 -2.02761004 0 P 0 
L 1.43001998 -2.02761004 1.42966004 -2.02721004 0 P 0 
L 1.42966004 -2.02721004 1.42928002 -2.02685 0 P 0 
L 1.42928002 -2.02685 1.42886004 -2.02651998 0 P 0 
L 1.42886004 -2.02651998 1.42841998 -2.02623002 0 P 0 
L 1.42841998 -2.02623002 1.42795 -2.02596998 0 P 0 
L 1.42795 -2.02596998 1.42746004 -2.02575 0 P 0 
L 1.42746004 -2.02575 1.42583002 -2.02518002 0 P 0 
L 1.42583002 -2.02518002 1.42416004 -2.02476004 0 P 0 
L 1.42416004 -2.02476004 1.42245 -2.02448002 0 P 0 
L 1.42245 -2.02448002 1.42075 -2.02435 0 P 0 
L 1.42075 -2.02435 1.41565 -2.02428002 0 P 0 
L 1.41565 -2.02428002 1.4156 -2.02428002 0 P 0 
L 1.4156 -2.02428002 1.41055 -2.02445 0 P 0 
L 1.41055 -2.02445 1.41048002 -2.02445 0 P 0 
L 1.41048002 -2.02445 1.40128996 -2.02533996 0 P 0 
L 1.40128996 -2.02533996 1.39208996 -2.02696998 0 P 0 
L 1.39208996 -2.02696998 1.38288002 -2.02936004 0 P 0 
L 1.38288002 -2.02936004 1.37363002 -2.03251998 0 P 0 
L 1.37363002 -2.03251998 1.37076998 -2.03356004 0 P 0 
L 1.37076998 -2.03356004 1.36865 -2.03426998 0 P 0 
L 1.36865 -2.03426998 1.36906004 -2.03066998 0 P 0 
L 1.36906004 -2.03066998 1.36988996 -2.02383996 0 P 0 
L 1.36988996 -2.02383996 1.37095 -2.01581004 0 P 0 
L 1.37095 -2.01581004 1.37358996 -1.99631998 0 P 0 
L 1.37358996 -1.99631998 1.37988002 -1.99491998 0 P 0 
L 1.37988002 -1.99491998 1.38353996 -1.99416998 0 P 0 
L 1.38353996 -1.99416998 1.38841998 -1.99326998 0 P 0 
L 1.38841998 -1.99326998 1.39358002 -1.9924 0 P 0 
L 1.39358002 -1.9924 1.39825 -1.9917 0 P 0 
L 1.39825 -1.9917 1.40436998 -1.991 0 P 0 
L 1.40436998 -1.991 1.41045 -1.99065 0 P 0 
L 1.41045 -1.99065 1.42691004 -1.99056998 0 P 0 
L 1.42691004 -1.99056998 1.44283996 -1.99123996 0 P 0 
L 1.44283996 -1.99123996 1.44603996 -1.99153996 0 P 0 
L 1.44603996 -1.99153996 1.44918002 -1.99203002 0 P 0 
L 1.44918002 -1.99203002 1.45226004 -1.9927 0 P 0 
L 1.45226004 -1.9927 1.4563 -1.99386998 0 P 0 
L 1.4563 -1.99386998 1.46021004 -1.99535 0 P 0 
L 1.46021004 -1.99535 1.464 -1.99713002 0 P 0 
L 1.464 -1.99713002 1.46586004 -1.99818996 0 P 0 
L 1.46586004 -1.99818996 1.46763996 -1.99936004 0 P 0 
L 1.46763996 -1.99936004 1.46931998 -2.00066004 0 P 0 
L 1.46931998 -2.00066004 1.47091004 -2.00206998 0 P 0 
L 1.47091004 -2.00206998 1.47238996 -2.00358996 0 P 0 
L 1.47238996 -2.00358996 1.4737 -2.00515 0 P 0 
L 1.4737 -2.00515 1.47488002 -2.00678996 0 P 0 
L 1.47488002 -2.00678996 1.47593996 -2.00851004 0 P 0 
L 1.47593996 -2.00851004 1.47686004 -2.01031004 0 P 0 
L 1.47686004 -2.01031004 1.47763996 -2.01216998 0 P 0 
L 1.47763996 -2.01216998 1.47851998 -2.01481004 0 P 0 
L 1.47851998 -2.01481004 1.47918996 -2.01748996 0 P 0 
L 1.47918996 -2.01748996 1.47966004 -2.02021998 0 P 0 
L 1.47966004 -2.02021998 1.47993002 -2.02296998 0 P 0 
L 1.47993002 -2.02296998 1.48001998 -2.02783996 0 P 0 
L 1.48001998 -2.02783996 1.47975 -2.03868996 0 P 0 
L 1.47975 -2.03868996 1.4793 -2.05161004 0 P 0 
L 1.4793 -2.05161004 1.47866004 -2.06543002 0 P 0 
L 1.47866004 -2.06543002 1.47801004 -2.07961004 0 P 0 
L 1.47801004 -2.07961004 1.47743996 -2.09378996 0 P 0 
L 1.47743996 -2.09378996 1.47705 -2.10613002 0 P 0 
L 1.47705 -2.10613002 1.47693002 -2.11356004 0 P 0 
L 1.47693002 -2.11356004 1.47693002 -2.12516004 0 P 0 
L 1.47693002 -2.12516004 1.42661004 -2.12516004 0 P 0 
L 1.42661004 -2.12516004 1.42661004 -2.12473996 0 P 0 
L 1.42661004 -2.12473996 1.42666004 -2.12318002 0 P 0 
L 1.42666004 -2.12318002 1.42691004 -2.11863996 0 P 0 
L 1.42691004 -2.11863996 1.42725 -2.1132 0 P 0 
L 1.42725 -2.1132 1.42766004 -2.1072 0 P 0 
L 1.42766004 -2.1072 1.42766004 -2.10718996 0 P 0 
L 1.42766004 -2.10718996 1.4281 -2.10068996 0 P 0 
L 1.4281 -2.10068996 1.42858002 -2.09368002 0 P 0 
L 1.42858002 -2.09368002 1.42901004 -2.08721004 0 P 0 
L 1.42901004 -2.08721004 1.42901004 -2.0872 0 P 0 
L 1.42901004 -2.0872 1.42931004 -2.08256004 0 P 0 
L 1.42931004 -2.08256004 1.42991998 -2.07308002 0 P 0 
L 1.42991998 -2.07308002 1.42916004 -2.07136998 0 P 0 
L 1.42916004 -2.07136998 1.42731998 -2.07105 0 P 0 
L 1.42731998 -2.07105 1.42105 -2.07303996 0 P 0 
L 1.42105 -2.07303996 1.41815 -2.07393002 0 P 0 
L 1.41815 -2.07393002 1.41451004 -2.075 0 P 0 
L 1.41451004 -2.075 1.41076004 -2.07603002 0 P 0 
L 1.41076004 -2.07603002 1.40748002 -2.0769 0 P 0 
L 1.40748002 -2.0769 1.40438996 -2.07781004 0 P 0 
L 1.40438996 -2.07781004 1.40431998 -2.07783996 0 P 0 
L 1.40431998 -2.07783996 1.40133996 -2.07896998 0 P 0 
L 1.40133996 -2.07896998 1.40005 -2.07956998 0 P 0 
L 1.40005 -2.07956998 1.39881998 -2.08026004 0 P 0 
L 1.39881998 -2.08026004 1.39763996 -2.08103002 0 P 0 
L 1.39763996 -2.08103002 1.39651998 -2.08188002 0 P 0 
L 1.39651998 -2.08188002 1.39578996 -2.08251004 0 P 0 
L 1.39578996 -2.08251004 1.39573996 -2.08256004 0 P 0 
L 1.39573996 -2.08256004 1.3951 -2.08318996 0 P 0 
L 1.3951 -2.08318996 1.39446998 -2.08393002 0 P 0 
L 1.39446998 -2.08393002 1.3939 -2.08471004 0 P 0 
L 1.3939 -2.08471004 1.39336998 -2.08553996 0 P 0 
L 1.39336998 -2.08553996 1.39301004 -2.08623996 0 P 0 
L 1.39301004 -2.08623996 1.39271004 -2.08696998 0 P 0 
L 1.39271004 -2.08696998 1.39248002 -2.08771998 0 P 0 
L 1.39248002 -2.08771998 1.39231004 -2.08848996 0 P 0 
L 1.39231004 -2.08848996 1.39221004 -2.08926004 0 P 0 
L 1.39221004 -2.08926004 1.39218002 -2.09003996 0 P 0 
L 1.39218002 -2.09003996 1.39221004 -2.0908 0 P 0 
L 1.39221004 -2.0908 1.39231004 -2.09153002 0 P 0 
L 1.39231004 -2.09153002 1.39246998 -2.09226004 0 P 0 
L 1.39246998 -2.09226004 1.39268996 -2.09296998 0 P 0 
L 1.39268996 -2.09296998 1.39296004 -2.09365 0 P 0 
L 1.39296004 -2.09365 1.3933 -2.09431004 0 P 0 
L 1.3933 -2.09431004 1.39368996 -2.09493996 0 P 0 
L 1.39368996 -2.09493996 1.39411998 -2.09553996 0 P 0 
L 1.39411998 -2.09553996 1.39468996 -2.09618002 0 P 0 
L 1.39468996 -2.09618002 1.3953 -2.09678002 0 P 0 
L 1.3953 -2.09678002 1.39596004 -2.09731998 0 P 0 
L 1.39596004 -2.09731998 1.39666998 -2.0978 0 P 0 
L 1.39666998 -2.0978 1.39673996 -2.09783996 0 P 0 
L 1.39673996 -2.09783996 1.39741004 -2.09821998 0 P 0 
L 1.39741004 -2.09821998 1.39748996 -2.09825 0 P 0 
L 1.39748996 -2.09825 1.39818996 -2.09856998 0 P 0 
L 1.39818996 -2.09856998 1.39898996 -2.09886004 0 P 0 
L 1.39898996 -2.09886004 1.39906998 -2.09888002 0 P 0 
L 1.39906998 -2.09888002 1.40043996 -2.09888002 0 P 0 
L 1.40043996 -2.09888002 1.40033996 -2.09923002 0 P 0 
L 1.40033996 -2.09923002 1.40041998 -2.09925 0 P 0 
L 1.40041998 -2.09925 1.40186004 -2.09953002 0 P 0 
L 1.40186004 -2.09953002 1.40331004 -2.09971004 0 P 0 
L 1.40331004 -2.09971004 1.40478002 -2.09978002 0 P 0 
L 1.40478002 -2.09978002 1.40625 -2.09975 0 P 0 
L 1.40625 -2.09975 1.41096004 -2.09931004 0 P 0 
L 1.41096004 -2.09931004 1.41556998 -2.09855 0 P 0 
L 1.41556998 -2.09855 1.41791998 -2.09813002 0 P 0 
L 1.41791998 -2.09813002 1.41995 -2.09791004 0 P 0 
L 1.41995 -2.09791004 1.4201 -2.0979 0 P 0 
L 1.4201 -2.0979 1.41941004 -2.10078002 0 P 0 
L 1.41941004 -2.10078002 1.41761004 -2.10745 0 P 0 
L 1.41761004 -2.10745 1.41391004 -2.12025 0 P 0 
L 1.41391004 -2.12025 1.41215 -2.12626998 0 P 0 
L 1.41215 -2.12626998 1.40655 -2.12725 0 P 0 
L 1.40655 -2.12725 1.40046004 -2.12808002 0 P 0 
L 1.40046004 -2.12808002 1.39438002 -2.12845 0 P 0 
L 1.15303002 -2.08283002 1.20788996 -2.08283002 0 P 0 
L 1.15398996 -2.08183002 1.20795 -2.08183002 0 P 0 
L 1.15483002 -2.08083002 1.208 -2.08083002 0 P 0 
L 1.15555 -2.07983002 1.20805 -2.07983002 0 P 0 
L 1.15621998 -2.07883002 1.2081 -2.07883002 0 P 0 
L 1.15681998 -2.07783002 1.20816004 -2.07783002 0 P 0 
L 1.15733002 -2.07683002 1.20821004 -2.07683002 0 P 0 
L 1.15778996 -2.07583002 1.20826004 -2.07583002 0 P 0 
L 1.15818002 -2.07483002 1.20831004 -2.07483002 0 P 0 
L 1.15853996 -2.07383002 1.20836998 -2.07383002 0 P 0 
L 1.15881998 -2.07283002 1.20841998 -2.07283002 0 P 0 
L 1.1591 -2.07183002 1.20846998 -2.07183002 0 P 0 
L 1.15938002 -2.07083002 1.20853002 -2.07083002 0 P 0 
L 1.1596 -2.06983002 1.20858002 -2.06983002 0 P 0 
L 1.15981004 -2.06883002 1.20863996 -2.06883002 0 P 0 
L 1.16001004 -2.06783002 1.20868996 -2.06783002 0 P 0 
L 1.1602 -2.06683002 1.20875 -2.06683002 0 P 0 
L 1.16033996 -2.06583002 1.2088 -2.06583002 0 P 0 
L 1.16048996 -2.06483002 1.20886004 -2.06483002 0 P 0 
L 1.16063996 -2.06383002 1.20891998 -2.06383002 0 P 0 
L 1.16078002 -2.06283002 1.20896998 -2.06283002 0 P 0 
L 1.16088996 -2.06183002 1.20903002 -2.06183002 0 P 0 
L 1.16098996 -2.06083002 1.20908002 -2.06083002 0 P 0 
L 1.16108996 -2.05983002 1.20913996 -2.05983002 0 P 0 
L 1.16118002 -2.05883002 1.20918996 -2.05883002 0 P 0 
L 1.16128002 -2.05783002 1.20925 -2.05783002 0 P 0 
L 1.16133996 -2.05683002 1.2093 -2.05683002 0 P 0 
L 1.1614 -2.05583002 1.20936004 -2.05583002 0 P 0 
L 1.16146004 -2.05483002 1.20941004 -2.05483002 0 P 0 
L 1.16151998 -2.05383002 1.20946998 -2.05383002 0 P 0 
L 1.16158002 -2.05283002 1.20951998 -2.05283002 0 P 0 
L 1.16163996 -2.05183002 1.20958002 -2.05183002 0 P 0 
L 1.1617 -2.05083002 1.20963996 -2.05083002 0 P 0 
L 1.16175 -2.04983002 1.2097 -2.04983002 0 P 0 
L 1.16181004 -2.04883002 1.20975 -2.04883002 0 P 0 
L 1.16186998 -2.04783002 1.20981004 -2.04783002 0 P 0 
L 1.16193002 -2.04683002 1.20986998 -2.04683002 0 P 0 
L 1.16198996 -2.04583002 1.20993002 -2.04583002 0 P 0 
L 1.16205 -2.04483002 1.20998996 -2.04483002 0 P 0 
L 1.16211004 -2.04383002 1.21005 -2.04383002 0 P 0 
L 1.16215 -2.04283002 1.2101 -2.04283002 0 P 0 
L 1.1622 -2.04183002 1.21016004 -2.04183002 0 P 0 
L 1.16225 -2.04083002 1.21021998 -2.04083002 0 P 0 
L 1.16228996 -2.03983002 1.21028002 -2.03983002 0 P 0 
L 1.16233996 -2.03883002 1.21033996 -2.03883002 0 P 0 
L 1.16238002 -2.03783002 1.2104 -2.03783002 0 P 0 
L 1.16243002 -2.03683002 1.21046004 -2.03683002 0 P 0 
L 1.16246998 -2.03583002 1.21051004 -2.03583002 0 P 0 
L 1.16251998 -2.03483002 1.21056998 -2.03483002 0 P 0 
L 1.16256998 -2.03383002 1.21063996 -2.03383002 0 P 0 
L 1.16261004 -2.03283002 1.2107 -2.03283002 0 P 0 
L 1.16266004 -2.03183002 1.21076004 -2.03183002 0 P 0 
L 1.1627 -2.03083002 1.21083002 -2.03083002 0 P 0 
L 1.16015 -1.97631004 1.17066004 -1.97631004 0 P 0 
L 1.15961998 -1.97531004 1.17026004 -1.97531004 0 P 0 
L 1.1591 -1.97431004 1.16986998 -1.97431004 0 P 0 
L 1.15856998 -1.97331004 1.16946998 -1.97331004 0 P 0 
L 1.15803996 -1.97231004 1.16903002 -1.97231004 0 P 0 
L 1.15746998 -1.97131004 1.16858996 -1.97131004 0 P 0 
L 1.1569 -1.97031004 1.16815 -1.97031004 0 P 0 
L 1.15631998 -1.96931004 1.16771004 -1.96931004 0 P 0 
L 1.15573996 -1.96831004 1.16726998 -1.96831004 0 P 0 
L 1.15516004 -1.96731004 1.16681998 -1.96731004 0 P 0 
L 1.15458996 -1.96631004 1.16638002 -1.96631004 0 P 0 
L 1.15398002 -1.96531004 1.16593996 -1.96531004 0 P 0 
L 1.1533 -1.96431004 1.16548996 -1.96431004 0 P 0 
L 1.15261998 -1.96331004 1.16503002 -1.96331004 0 P 0 
L 1.15193996 -1.96231004 1.16448002 -1.96231004 0 P 0 
L 1.15126004 -1.96131004 1.16393002 -1.96131004 0 P 0 
L 1.15058002 -1.96031004 1.16338002 -1.96031004 0 P 0 
L 1.1499 -1.95931004 1.16283002 -1.95931004 0 P 0 
L 1.1491 -1.95831004 1.16228996 -1.95831004 0 P 0 
L 1.14831004 -1.95731004 1.16173996 -1.95731004 0 P 0 
L 1.14751004 -1.95631004 1.16118996 -1.95631004 0 P 0 
L 1.14671004 -1.95531004 1.16063996 -1.95531004 0 P 0 
L 1.14591998 -1.95431004 1.16008996 -1.95431004 0 P 0 
L 1.14511998 -1.95331004 1.15943996 -1.95331004 0 P 0 
L 1.1442 -1.95231004 1.15878002 -1.95231004 0 P 0 
L 1.14326998 -1.95131004 1.15811004 -1.95131004 0 P 0 
L 1.14233996 -1.95031004 1.15745 -1.95031004 0 P 0 
L 1.14141004 -1.94931004 1.15678002 -1.94931004 0 P 0 
L 1.14048996 -1.94831004 1.15611998 -1.94831004 0 P 0 
L 1.1395 -1.94731004 1.15545 -1.94731004 0 P 0 
L 1.13843002 -1.94631004 1.15478996 -1.94631004 0 P 0 
L 1.13736004 -1.94531004 1.15411998 -1.94531004 0 P 0 
L 1.13628996 -1.94431004 1.15333002 -1.94431004 0 P 0 
L 1.13521004 -1.94331004 1.15253002 -1.94331004 0 P 0 
L 1.13413996 -1.94231004 1.15173996 -1.94231004 0 P 0 
L 1.13306998 -1.94131004 1.15093996 -1.94131004 0 P 0 
L 1.132 -1.94031004 1.15013996 -1.94031004 0 P 0 
L 1.13081004 -1.93931004 1.14935 -1.93931004 0 P 0 
L 1.12958002 -1.93831004 1.14855 -1.93831004 0 P 0 
L 1.12833996 -1.93731004 1.14775 -1.93731004 0 P 0 
L 1.1271 -1.93631004 1.14688996 -1.93631004 0 P 0 
L 1.12586004 -1.93531004 1.14593996 -1.93531004 0 P 0 
L 1.12461998 -1.93431004 1.14498996 -1.93431004 0 P 0 
L 1.12338002 -1.93331004 1.14405 -1.93331004 0 P 0 
L 1.12203002 -1.93231004 1.1431 -1.93231004 0 P 0 
L 1.1206 -1.93131004 1.14216004 -1.93131004 0 P 0 
L 1.11916004 -1.93031004 1.14121004 -1.93031004 0 P 0 
L 1.11771998 -1.92931004 1.14026998 -1.92931004 0 P 0 
L 1.11628996 -1.92831004 1.13931998 -1.92831004 0 P 0 
L 1.11483996 -1.92731004 1.13838002 -1.92731004 0 P 0 
L 1.11338996 -1.92631004 1.13743002 -1.92631004 0 P 0 
L 1.11171998 -1.92531004 1.13648996 -1.92531004 0 P 0 
L 1.11005 -1.92431004 1.13538002 -1.92431004 0 P 0 
L 1.10838002 -1.92331004 1.13426998 -1.92331004 0 P 0 
L 1.1067 -1.92231004 1.13315 -1.92231004 0 P 0 
L 1.10503002 -1.92131004 1.13203002 -1.92131004 0 P 0 
L 1.10336004 -1.92031004 1.13091998 -1.92031004 0 P 0 
L 1.1015 -1.91931004 1.1298 -1.91931004 0 P 0 
L 1.09955 -1.91831004 1.12868002 -1.91831004 0 P 0 
L 1.16275 -2.02983002 1.21088996 -2.02983002 0 P 0 
L 1.16278996 -2.02883002 1.21095 -2.02883002 0 P 0 
L 1.16283996 -2.02783002 1.21101004 -2.02783002 0 P 0 
L 1.16226998 -2.02683002 1.21108002 -2.02683002 0 P 0 
L 1.16153996 -2.02583002 1.21113996 -2.02583002 0 P 0 
L 1.15846004 -2.02483002 1.2112 -2.02483002 0 P 0 
L 1.10036004 -2.00383002 1.21255 -2.00383002 0 P 0 
L 1.10226004 -2.00283002 1.2126 -2.00283002 0 P 0 
L 1.10433996 -2.00183002 1.21266998 -2.00183002 0 P 0 
L 1.1065 -2.00083002 1.21273002 -2.00083002 0 P 0 
L 1.10886998 -1.99983002 1.21278996 -1.99983002 0 P 0 
L 1.11138002 -1.99883002 1.21285 -1.99883002 0 P 0 
L 1.11436998 -1.99783002 1.21288002 -1.99783002 0 P 0 
L 1.11748996 -1.99683002 1.21255 -1.99683002 0 P 0 
L 1.12061998 -1.99583002 1.2089 -1.99583002 0 P 0 
L 1.12433996 -1.99483002 1.2036 -1.99483002 0 P 0 
L 1.12863996 -1.99383002 1.19728002 -1.99383002 0 P 0 
L 1.13295 -1.99283002 1.19096998 -1.99283002 0 P 0 
L 1.13985 -1.99183002 1.18111998 -1.99183002 0 P 0 
L 1.14948002 -1.99083002 1.1651 -1.99083002 0 P 0 
L 1.24218002 -2.08316004 1.29143996 -2.08316004 0 P 0 
L 1.24223002 -2.08216004 1.29151004 -2.08216004 0 P 0 
L 1.24228002 -2.08116004 1.29158996 -2.08116004 0 P 0 
L 1.24233996 -2.08016004 1.29166004 -2.08016004 0 P 0 
L 1.24238996 -2.07916004 1.29173002 -2.07916004 0 P 0 
L 1.24245 -2.07816004 1.29181004 -2.07816004 0 P 0 
L 1.2425 -2.07716004 1.29188002 -2.07716004 0 P 0 
L 1.24256004 -2.07616004 1.29195 -2.07616004 0 P 0 
L 1.24261004 -2.07516004 1.29203002 -2.07516004 0 P 0 
L 1.24266998 -2.07416004 1.2921 -2.07416004 0 P 0 
L 1.24271998 -2.07316004 1.29216998 -2.07316004 0 P 0 
L 1.24278002 -2.07216004 1.29223996 -2.07216004 0 P 0 
L 1.24283002 -2.07116004 1.29231998 -2.07116004 0 P 0 
L 1.24288002 -2.07016004 1.29238996 -2.07016004 0 P 0 
L 1.24293002 -2.06916004 1.29246004 -2.06916004 0 P 0 
L 1.24296998 -2.06816004 1.29253002 -2.06816004 0 P 0 
L 1.24301998 -2.06716004 1.29261004 -2.06716004 0 P 0 
L 1.24306004 -2.06616004 1.2927 -2.06616004 0 P 0 
L 1.24311004 -2.06516004 1.29281004 -2.06516004 0 P 0 
L 1.24315 -2.06416004 1.29291998 -2.06416004 0 P 0 
L 1.2432 -2.06316004 1.29303002 -2.06316004 0 P 0 
L 1.24323996 -2.06216004 1.29315 -2.06216004 0 P 0 
L 1.24328996 -2.06116004 1.29331998 -2.06116004 0 P 0 
L 1.24333002 -2.06016004 1.2935 -2.06016004 0 P 0 
L 1.24338002 -2.05916004 1.29366998 -2.05916004 0 P 0 
L 1.24341998 -2.05816004 1.29385 -2.05816004 0 P 0 
L 1.24346998 -2.05716004 1.29408996 -2.05716004 0 P 0 
L 1.24351004 -2.05616004 1.29433996 -2.05616004 0 P 0 
L 1.24355 -2.05516004 1.29458996 -2.05516004 0 P 0 
L 1.2436 -2.05416004 1.29485 -2.05416004 0 P 0 
L 1.24363996 -2.05316004 1.29516998 -2.05316004 0 P 0 
L 1.24368996 -2.05216004 1.29551998 -2.05216004 0 P 0 
L 1.24373002 -2.05116004 1.29586004 -2.05116004 0 P 0 
L 1.24378002 -2.05016004 1.29621004 -2.05016004 0 P 0 
L 1.24383002 -2.04916004 1.29663996 -2.04916004 0 P 0 
L 1.24386998 -2.04816004 1.29708002 -2.04816004 0 P 0 
L 1.24391004 -2.04716004 1.29753002 -2.04716004 0 P 0 
L 1.24396004 -2.04616004 1.29796998 -2.04616004 0 P 0 
L 1.244 -2.04516004 1.29851004 -2.04516004 0 P 0 
L 1.24405 -2.04416004 1.2991 -2.04416004 0 P 0 
L 1.24408996 -2.04316004 1.29975 -2.04316004 0 P 0 
L 1.24413996 -2.04216004 1.3005 -2.04216004 0 P 0 
L 1.24418002 -2.04116004 1.30131998 -2.04116004 0 P 0 
L 1.24423002 -2.04016004 1.30223002 -2.04016004 0 P 0 
L 1.24426998 -2.03916004 1.30326998 -2.03916004 0 P 0 
L 1.24431998 -2.03816004 1.30446004 -2.03816004 0 P 0 
L 1.24436004 -2.03716004 1.30581998 -2.03716004 0 P 0 
L 1.24441004 -2.03616004 1.30738002 -2.03616004 0 P 0 
L 1.24445 -2.03516004 1.30923002 -2.03516004 0 P 0 
L 1.24448996 -2.03416004 1.31156004 -2.03416004 0 P 0 
L 1.24453996 -2.03316004 1.31478996 -2.03316004 0 P 0 
L 1.24458996 -2.03216004 1.32013002 -2.03216004 0 P 0 
L 1.24461998 -2.03116004 1.33481004 -2.03116004 0 P 0 
L 1.24463996 -2.03016004 1.33478002 -2.03016004 0 P 0 
L 1.24466004 -2.02916004 1.33473996 -2.02916004 0 P 0 
L 1.24468002 -2.02816004 1.33471004 -2.02816004 0 P 0 
L 1.2447 -2.02716004 1.33468002 -2.02716004 0 P 0 
L 1.24471998 -2.02616004 1.33463996 -2.02616004 0 P 0 
L 1.24473996 -2.02516004 1.3346 -2.02516004 0 P 0 
L 1.24476004 -2.02416004 1.33456998 -2.02416004 0 P 0 
L 1.24478002 -2.02316004 1.33453002 -2.02316004 0 P 0 
L 1.2448 -2.02216004 1.3345 -2.02216004 0 P 0 
L 1.24481998 -2.02116004 1.33446998 -2.02116004 0 P 0 
L 1.24483996 -2.02016004 1.33443002 -2.02016004 0 P 0 
L 1.24486004 -2.01916004 1.3344 -2.01916004 0 P 0 
L 1.24488002 -2.01816004 1.33436004 -2.01816004 0 P 0 
L 1.2449 -2.01716004 1.33433002 -2.01716004 0 P 0 
L 1.24491998 -2.01616004 1.33428996 -2.01616004 0 P 0 
L 1.24493996 -2.01516004 1.33426004 -2.01516004 0 P 0 
L 1.24496004 -2.01416004 1.33421998 -2.01416004 0 P 0 
L 1.24498002 -2.01316004 1.33418996 -2.01316004 0 P 0 
L 1.245 -2.01216004 1.33415 -2.01216004 0 P 0 
L 1.24501998 -2.01116004 1.33411998 -2.01116004 0 P 0 
L 1.24503996 -2.01016004 1.33408002 -2.01016004 0 P 0 
L 1.24506004 -2.00916004 1.33403996 -2.00916004 0 P 0 
L 1.24508002 -2.00816004 1.334 -2.00816004 0 P 0 
L 1.2451 -2.00716004 1.33396004 -2.00716004 0 P 0 
L 1.24511998 -2.00616004 1.33393002 -2.00616004 0 P 0 
L 1.24513996 -2.00516004 1.29098996 -2.00516004 0 P 0 
L 1.24513996 -2.00416004 1.29033002 -2.00416004 0 P 0 
L 1.24513996 -2.00316004 1.29005 -2.00316004 0 P 0 
L 1.24513996 -2.00216004 1.29005 -2.00216004 0 P 0 
L 1.24513996 -2.00116004 1.29005 -2.00116004 0 P 0 
L 1.24515 -2.00016004 1.29005 -2.00016004 0 P 0 
L 1.24515 -1.99916004 1.29005 -1.99916004 0 P 0 
L 1.24515 -1.99816004 1.29005 -1.99816004 0 P 0 
L 1.24515 -1.99716004 1.29005 -1.99716004 0 P 0 
L 1.24515 -1.99616004 1.29005 -1.99616004 0 P 0 
L 1.24515 -1.99516004 1.29005 -1.99516004 0 P 0 
L 1.16085 -2.02753002 1.1601 -2.04393002 0 P 0 
L 1.1601 -2.04393002 1.15928996 -2.05771998 0 P 0 
L 1.15928996 -2.05771998 1.15883996 -2.06228002 0 P 0 
L 1.15883996 -2.06228002 1.15818002 -2.06681998 0 P 0 
L 1.15818002 -2.06681998 1.15751004 -2.07006998 0 P 0 
L 1.15751004 -2.07006998 1.15661004 -2.07328996 0 P 0 
L 1.15661004 -2.07328996 1.15616004 -2.07453996 0 P 0 
L 1.15616004 -2.07453996 1.15563002 -2.07576998 0 P 0 
L 1.15563002 -2.07576998 1.15501998 -2.07696004 0 P 0 
L 1.15501998 -2.07696004 1.15433002 -2.0781 0 P 0 
L 1.15433002 -2.0781 1.1534 -2.07941998 0 P 0 
L 1.1534 -2.07941998 1.15236004 -2.08066004 0 P 0 
L 1.15236004 -2.08066004 1.15123002 -2.08181998 0 P 0 
L 1.15123002 -2.08181998 1.15001004 -2.08286998 0 P 0 
L 1.15001004 -2.08286998 1.14871004 -2.08383002 0 P 0 
L 1.14871004 -2.08383002 1.14733002 -2.08468002 0 P 0 
L 1.14733002 -2.08468002 1.14591004 -2.0854 0 P 0 
L 1.14591004 -2.0854 1.14443996 -2.086 0 P 0 
L 1.14443996 -2.086 1.14291004 -2.08648002 0 P 0 
L 1.14291004 -2.08648002 1.14136004 -2.08683002 0 P 0 
L 1.14136004 -2.08683002 1.13976998 -2.08703996 0 P 0 
L 1.13976998 -2.08703996 1.13816004 -2.08713002 0 P 0 
L 1.13816004 -2.08713002 1.13656998 -2.08708002 0 P 0 
L 1.13656998 -2.08708002 1.13498996 -2.0869 0 P 0 
L 1.13498996 -2.0869 1.13341998 -2.08658996 0 P 0 
L 1.13341998 -2.08658996 1.13188996 -2.08615 0 P 0 
L 1.13188996 -2.08615 1.1304 -2.08558996 0 P 0 
L 1.1304 -2.08558996 1.12895 -2.08488996 0 P 0 
L 1.12895 -2.08488996 1.12756998 -2.08408002 0 P 0 
L 1.12756998 -2.08408002 1.12625 -2.08315 0 P 0 
L 1.12625 -2.08315 1.12501004 -2.08211998 0 P 0 
L 1.12501004 -2.08211998 1.12386004 -2.081 0 P 0 
L 1.12386004 -2.081 1.12281004 -2.07978002 0 P 0 
L 1.12281004 -2.07978002 1.12183996 -2.07846998 0 P 0 
L 1.12183996 -2.07846998 1.1211 -2.07726004 0 P 0 
L 1.1211 -2.07726004 1.12046998 -2.07598996 0 P 0 
L 1.12046998 -2.07598996 1.11996004 -2.07466998 0 P 0 
L 1.11996004 -2.07466998 1.11955 -2.07331004 0 P 0 
L 1.11955 -2.07331004 1.11926998 -2.07191004 0 P 0 
L 1.11926998 -2.07191004 1.11868002 -2.06693996 0 P 0 
L 1.11868002 -2.06693996 1.11848002 -2.06191004 0 P 0 
L 1.11848002 -2.06191004 1.11871004 -2.05668002 0 P 0 
L 1.11871004 -2.05668002 1.11936004 -2.05148002 0 P 0 
L 1.11936004 -2.05148002 1.11978996 -2.04936998 0 P 0 
L 1.11978996 -2.04936998 1.12036998 -2.0473 0 P 0 
L 1.12036998 -2.0473 1.12108996 -2.04528002 0 P 0 
L 1.12108996 -2.04528002 1.12196004 -2.04331998 0 P 0 
L 1.12196004 -2.04331998 1.1229 -2.04153996 0 P 0 
L 1.1229 -2.04153996 1.12396998 -2.03985 0 P 0 
L 1.12396998 -2.03985 1.12516998 -2.03823002 0 P 0 
L 1.12516998 -2.03823002 1.12735 -2.03573996 0 P 0 
L 1.12735 -2.03573996 1.12973002 -2.03345 0 P 0 
L 1.12973002 -2.03345 1.13223996 -2.03141998 0 P 0 
L 1.13223996 -2.03141998 1.13491998 -2.02961004 0 P 0 
L 1.13491998 -2.02961004 1.13611004 -2.02893002 0 P 0 
L 1.13611004 -2.02893002 1.13735 -2.02833996 0 P 0 
L 1.13735 -2.02833996 1.13861998 -2.02781998 0 P 0 
L 1.13861998 -2.02781998 1.13993996 -2.0274 0 P 0 
L 1.13993996 -2.0274 1.14191004 -2.02693002 0 P 0 
L 1.14191004 -2.02693002 1.14391004 -2.02663002 0 P 0 
L 1.14391004 -2.02663002 1.14935 -2.02626004 0 P 0 
L 1.14935 -2.02626004 1.15471004 -2.0263 0 P 0 
L 1.15471004 -2.0263 1.15591004 -2.02638996 0 P 0 
L 1.15591004 -2.02638996 1.1571 -2.02656998 0 P 0 
L 1.1571 -2.02656998 1.15828002 -2.02683996 0 P 0 
L 1.15828002 -2.02683996 1.16085 -2.02753002 0 P 0 
L 1.13876998 -2.14783002 1.20233002 -2.14783002 0 P 0 
L 1.14236998 -2.14683002 1.20266004 -2.14683002 0 P 0 
L 1.14481004 -2.14583002 1.20296004 -2.14583002 0 P 0 
L 1.1467 -2.14483002 1.20325 -2.14483002 0 P 0 
L 1.14826004 -2.14383002 1.20353002 -2.14383002 0 P 0 
L 1.1496 -2.14283002 1.20373996 -2.14283002 0 P 0 
L 1.15078996 -2.14183002 1.20395 -2.14183002 0 P 0 
L 1.15186004 -2.14083002 1.20415 -2.14083002 0 P 0 
L 1.15278996 -2.13983002 1.20431998 -2.13983002 0 P 0 
L 1.15361998 -2.13883002 1.20446004 -2.13883002 0 P 0 
L 1.15436004 -2.13783002 1.20458002 -2.13783002 0 P 0 
L 1.155 -2.13683002 1.20466998 -2.13683002 0 P 0 
L 1.15556998 -2.13583002 1.20475 -2.13583002 0 P 0 
L 1.15608996 -2.13483002 1.20481998 -2.13483002 0 P 0 
L 1.15653996 -2.13383002 1.20488996 -2.13383002 0 P 0 
L 1.15691004 -2.13283002 1.20496004 -2.13283002 0 P 0 
L 1.15723996 -2.13183002 1.20503002 -2.13183002 0 P 0 
L 1.15751998 -2.13083002 1.2051 -2.13083002 0 P 0 
L 1.15773002 -2.12983002 1.20516004 -2.12983002 0 P 0 
L 1.15793002 -2.12883002 1.20523002 -2.12883002 0 P 0 
L 1.15806004 -2.12783002 1.2053 -2.12783002 0 P 0 
L 1.15816998 -2.12683002 1.20536998 -2.12683002 0 P 0 
L 1.15821004 -2.12583002 1.20543996 -2.12583002 0 P 0 
L 1.11716004 -2.12483002 1.12726004 -2.12483002 0 P 0 
L 1.15823996 -2.12483002 1.20551004 -2.12483002 0 P 0 
L 1.10911998 -2.12383002 1.1352 -2.12383002 0 P 0 
L 1.15821998 -2.12383002 1.20556998 -2.12383002 0 P 0 
L 1.10468996 -2.12283002 1.14018996 -2.12283002 0 P 0 
L 1.1582 -2.12283002 1.20563996 -2.12283002 0 P 0 
L 1.10131004 -2.12183002 1.14366998 -2.12183002 0 P 0 
L 1.15818002 -2.12183002 1.2057 -2.12183002 0 P 0 
L 1.15808996 -2.12083002 1.20576004 -2.12083002 0 P 0 
L 1.15781004 -2.11983002 1.20583002 -2.11983002 0 P 0 
L 1.15721004 -2.11883002 1.20588002 -2.11883002 0 P 0 
L 1.14146004 -2.08883002 1.20758002 -2.08883002 0 P 0 
L 1.14525 -2.08783002 1.20763002 -2.08783002 0 P 0 
L 1.14751004 -2.08683002 1.20768002 -2.08683002 0 P 0 
L 1.14928002 -2.08583002 1.20773002 -2.08583002 0 P 0 
L 1.15073002 -2.08483002 1.20778996 -2.08483002 0 P 0 
L 1.15196004 -2.08383002 1.20783996 -2.08383002 0 P 0 
L 1.13818996 -2.08913002 1.13826998 -2.08913002 0 P 0 
L 1.13826998 -2.08913002 1.13988002 -2.08903996 0 P 0 
L 1.13988002 -2.08903996 1.13996004 -2.08903996 0 P 0 
L 1.13996004 -2.08903996 1.14001004 -2.08903002 0 P 0 
L 1.14001004 -2.08903002 1.14005 -2.08901998 0 P 0 
L 1.14005 -2.08901998 1.14163002 -2.08881004 0 P 0 
L 1.14163002 -2.08881004 1.14166998 -2.0888 0 P 0 
L 1.14166998 -2.0888 1.14171004 -2.0888 0 P 0 
L 1.14171004 -2.0888 1.14178996 -2.08878002 0 P 0 
L 1.14178996 -2.08878002 1.14335 -2.08843002 0 P 0 
L 1.14335 -2.08843002 1.14351004 -2.08838996 0 P 0 
L 1.14351004 -2.08838996 1.14503002 -2.08791004 0 P 0 
L 1.14503002 -2.08791004 1.14511004 -2.08788996 0 P 0 
L 1.14511004 -2.08788996 1.14515 -2.08786998 0 P 0 
L 1.14515 -2.08786998 1.14518996 -2.08786004 0 P 0 
L 1.14518996 -2.08786004 1.14666004 -2.08725 0 P 0 
L 1.14666004 -2.08725 1.14673996 -2.08721998 0 P 0 
L 1.14673996 -2.08721998 1.14678002 -2.0872 0 P 0 
L 1.14678002 -2.0872 1.14681998 -2.08718996 0 P 0 
L 1.14681998 -2.08718996 1.14823996 -2.08646998 0 P 0 
L 1.14823996 -2.08646998 1.14826998 -2.08645 0 P 0 
L 1.14826998 -2.08645 1.14835 -2.08641004 0 P 0 
L 1.14835 -2.08641004 1.14838002 -2.08638002 0 P 0 
L 1.14838002 -2.08638002 1.14976004 -2.08553002 0 P 0 
L 1.14976004 -2.08553002 1.14978996 -2.08551004 0 P 0 
L 1.14978996 -2.08551004 1.14983002 -2.08548996 0 P 0 
L 1.14983002 -2.08548996 1.14988996 -2.08543996 0 P 0 
L 1.14988996 -2.08543996 1.1512 -2.08448996 0 P 0 
L 1.1512 -2.08448996 1.15126004 -2.08443996 0 P 0 
L 1.15126004 -2.08443996 1.15128996 -2.08441004 0 P 0 
L 1.15128996 -2.08441004 1.15131998 -2.08438996 0 P 0 
L 1.15131998 -2.08438996 1.15253996 -2.08333002 0 P 0 
L 1.15253996 -2.08333002 1.15256998 -2.0833 0 P 0 
L 1.15256998 -2.0833 1.1526 -2.08328002 0 P 0 
L 1.1526 -2.08328002 1.15263002 -2.08323996 0 P 0 
L 1.15263002 -2.08323996 1.15266004 -2.08321998 0 P 0 
L 1.15266004 -2.08321998 1.15378996 -2.08206004 0 P 0 
L 1.15378996 -2.08206004 1.15376004 -2.08203996 0 P 0 
L 1.15376004 -2.08203996 1.15381998 -2.08203996 0 P 0 
L 1.15381998 -2.08203996 1.15383996 -2.082 0 P 0 
L 1.15383996 -2.082 1.15386998 -2.08196998 0 P 0 
L 1.15386998 -2.08196998 1.1539 -2.08195 0 P 0 
L 1.1539 -2.08195 1.15493002 -2.08071004 0 P 0 
L 1.15493002 -2.08071004 1.15493002 -2.0807 0 P 0 
L 1.15493002 -2.0807 1.15496004 -2.08066998 0 P 0 
L 1.15496004 -2.08066998 1.15498002 -2.08063996 0 P 0 
L 1.15498002 -2.08063996 1.15501004 -2.08061004 0 P 0 
L 1.15501004 -2.08061004 1.15503002 -2.08058002 0 P 0 
L 1.15503002 -2.08058002 1.15596004 -2.07926004 0 P 0 
L 1.15596004 -2.07926004 1.15603996 -2.07913996 0 P 0 
L 1.15603996 -2.07913996 1.15673002 -2.07798996 0 P 0 
L 1.15673002 -2.07798996 1.15676998 -2.07793002 0 P 0 
L 1.15676998 -2.07793002 1.15678996 -2.07786998 0 P 0 
L 1.15678996 -2.07786998 1.15741004 -2.07668996 0 P 0 
L 1.15741004 -2.07668996 1.15743996 -2.07663002 0 P 0 
L 1.15743996 -2.07663002 1.15746004 -2.07656998 0 P 0 
L 1.15746004 -2.07656998 1.15746998 -2.07656998 0 P 0 
L 1.15746998 -2.07656998 1.158 -2.07533996 0 P 0 
L 1.158 -2.07533996 1.15801004 -2.07531004 0 P 0 
L 1.15801004 -2.07531004 1.15803002 -2.07528002 0 P 0 
L 1.15803002 -2.07528002 1.15805 -2.07521998 0 P 0 
L 1.15805 -2.07521998 1.15848996 -2.07396004 0 P 0 
L 1.15848996 -2.07396004 1.15841004 -2.07393002 0 P 0 
L 1.15841004 -2.07393002 1.15851004 -2.07393002 0 P 0 
L 1.15851004 -2.07393002 1.15851998 -2.0739 0 P 0 
L 1.15851998 -2.0739 1.15853002 -2.07386004 0 P 0 
L 1.15853002 -2.07386004 1.15853996 -2.07383002 0 P 0 
L 1.15853996 -2.07383002 1.15943996 -2.07061004 0 P 0 
L 1.15943996 -2.07061004 1.15945 -2.07058002 0 P 0 
L 1.15945 -2.07058002 1.15946004 -2.07053996 0 P 0 
L 1.15946004 -2.07053996 1.15946998 -2.07051004 0 P 0 
L 1.15946998 -2.07051004 1.15946998 -2.07046998 0 P 0 
L 1.15946998 -2.07046998 1.16013996 -2.06723002 0 P 0 
L 1.16013996 -2.06723002 1.16013996 -2.0672 0 P 0 
L 1.16013996 -2.0672 1.16016004 -2.06713996 0 P 0 
L 1.16016004 -2.06713996 1.16016004 -2.06711004 0 P 0 
L 1.16016004 -2.06711004 1.16081998 -2.06256004 0 P 0 
L 1.16081998 -2.06256004 1.16081998 -2.06253996 0 P 0 
L 1.16081998 -2.06253996 1.16083002 -2.0625 0 P 0 
L 1.16083002 -2.0625 1.16083002 -2.06246998 0 P 0 
L 1.16083002 -2.06246998 1.16126998 -2.05791004 0 P 0 
L 1.16126998 -2.05791004 1.16128002 -2.0579 0 P 0 
L 1.16128002 -2.0579 1.16128002 -2.05783996 0 P 0 
L 1.16128002 -2.05783996 1.1621 -2.04405 0 P 0 
L 1.1621 -2.04405 1.1621 -2.04401998 0 P 0 
L 1.1621 -2.04401998 1.16285 -2.02761998 0 P 0 
L 1.16285 -2.02761998 1.16136998 -2.0256 0 P 0 
L 1.16136998 -2.0256 1.15878996 -2.02491004 0 P 0 
L 1.15878996 -2.02491004 1.15878002 -2.0249 0 P 0 
L 1.15878002 -2.0249 1.15871998 -2.02488996 0 P 0 
L 1.15871998 -2.02488996 1.15755 -2.02461998 0 P 0 
L 1.15755 -2.02461998 1.15746998 -2.0246 0 P 0 
L 1.15746998 -2.0246 1.1574 -2.0246 0 P 0 
L 1.1574 -2.0246 1.15621004 -2.02441004 0 P 0 
L 1.15621004 -2.02441004 1.15616998 -2.02441004 0 P 0 
L 1.15616998 -2.02441004 1.1561 -2.0244 0 P 0 
L 1.1561 -2.0244 1.15606004 -2.02438996 0 P 0 
L 1.15606004 -2.02438996 1.15486004 -2.0243 0 P 0 
L 1.15486004 -2.0243 1.15471998 -2.0243 0 P 0 
L 1.15471998 -2.0243 1.14936004 -2.02426004 0 P 0 
L 1.14936004 -2.02426004 1.14928996 -2.02426004 0 P 0 
L 1.14928996 -2.02426004 1.14925 -2.02426998 0 P 0 
L 1.14925 -2.02426998 1.14921004 -2.02426998 0 P 0 
L 1.14921004 -2.02426998 1.14376998 -2.02463996 0 P 0 
L 1.14376998 -2.02463996 1.1437 -2.02463996 0 P 0 
L 1.1437 -2.02463996 1.14365 -2.02465 0 P 0 
L 1.14365 -2.02465 1.14361004 -2.02465 0 P 0 
L 1.14361004 -2.02465 1.14161998 -2.02495 0 P 0 
L 1.14161998 -2.02495 1.14161004 -2.02495 0 P 0 
L 1.14161004 -2.02495 1.14153002 -2.02496998 0 P 0 
L 1.14153002 -2.02496998 1.14148996 -2.02496998 0 P 0 
L 1.14148996 -2.02496998 1.14143996 -2.02498996 0 P 0 
L 1.14143996 -2.02498996 1.13946998 -2.02545 0 P 0 
L 1.13946998 -2.02545 1.13943996 -2.02546998 0 P 0 
L 1.13943996 -2.02546998 1.1394 -2.02546998 0 P 0 
L 1.1394 -2.02546998 1.13933002 -2.0255 0 P 0 
L 1.13933002 -2.0255 1.13801004 -2.02591998 0 P 0 
L 1.13801004 -2.02591998 1.13798002 -2.02593002 0 P 0 
L 1.13798002 -2.02593002 1.13793996 -2.02593996 0 P 0 
L 1.13793996 -2.02593996 1.13788002 -2.02596998 0 P 0 
L 1.13788002 -2.02596998 1.1366 -2.02648002 0 P 0 
L 1.1366 -2.02648002 1.13653996 -2.0265 0 P 0 
L 1.13653996 -2.0265 1.13648002 -2.02653002 0 P 0 
L 1.13648002 -2.02653002 1.13523996 -2.02713002 0 P 0 
L 1.13523996 -2.02713002 1.13518002 -2.02716004 0 P 0 
L 1.13518002 -2.02716004 1.13515 -2.02716998 0 P 0 
L 1.13515 -2.02716998 1.13511998 -2.02718996 0 P 0 
L 1.13511998 -2.02718996 1.13393002 -2.02786998 0 P 0 
L 1.13393002 -2.02786998 1.13388996 -2.02788996 0 P 0 
L 1.13388996 -2.02788996 1.1338 -2.02795 0 P 0 
L 1.1338 -2.02795 1.13111998 -2.02976004 0 P 0 
L 1.13111998 -2.02976004 1.13105 -2.02981004 0 P 0 
L 1.13105 -2.02981004 1.13101004 -2.02983996 0 P 0 
L 1.13101004 -2.02983996 1.13098002 -2.02986004 0 P 0 
L 1.13098002 -2.02986004 1.12846998 -2.03188996 0 P 0 
L 1.12846998 -2.03188996 1.12838002 -2.03198002 0 P 0 
L 1.12838002 -2.03198002 1.12833996 -2.03201004 0 P 0 
L 1.12833996 -2.03201004 1.12596004 -2.0343 0 P 0 
L 1.12596004 -2.0343 1.12593996 -2.03433002 0 P 0 
L 1.12593996 -2.03433002 1.1259 -2.03436004 0 P 0 
L 1.1259 -2.03436004 1.12588002 -2.03438996 0 P 0 
L 1.12588002 -2.03438996 1.12585 -2.03443002 0 P 0 
L 1.12585 -2.03443002 1.12366998 -2.03691004 0 P 0 
L 1.12366998 -2.03691004 1.12363996 -2.03695 0 P 0 
L 1.12363996 -2.03695 1.12361998 -2.03698002 0 P 0 
L 1.12361998 -2.03698002 1.12358996 -2.03701004 0 P 0 
L 1.12358996 -2.03701004 1.12356998 -2.03703996 0 P 0 
L 1.12356998 -2.03703996 1.12236998 -2.03865 0 P 0 
L 1.12236998 -2.03865 1.12233996 -2.03868996 0 P 0 
L 1.12233996 -2.03868996 1.12233002 -2.03871004 0 P 0 
L 1.12233002 -2.03871004 1.12228996 -2.03878002 0 P 0 
L 1.12228996 -2.03878002 1.12121004 -2.04046998 0 P 0 
L 1.12121004 -2.04046998 1.12118996 -2.0405 0 P 0 
L 1.12118996 -2.0405 1.12116998 -2.04053996 0 P 0 
L 1.12116998 -2.04053996 1.12115 -2.04056998 0 P 0 
L 1.12115 -2.04056998 1.12113996 -2.04061004 0 P 0 
L 1.12113996 -2.04061004 1.12018996 -2.04238002 0 P 0 
L 1.12018996 -2.04238002 1.12016004 -2.04245 0 P 0 
L 1.12016004 -2.04245 1.12013996 -2.04248002 0 P 0 
L 1.12013996 -2.04248002 1.12013002 -2.04251004 0 P 0 
L 1.12013002 -2.04251004 1.11926004 -2.04446998 0 P 0 
L 1.11926004 -2.04446998 1.11925 -2.0445 0 P 0 
L 1.11925 -2.0445 1.11923002 -2.04453996 0 P 0 
L 1.11923002 -2.04453996 1.11921998 -2.04458002 0 P 0 
L 1.11921998 -2.04458002 1.11921004 -2.04461004 0 P 0 
L 1.11921004 -2.04461004 1.11848002 -2.04663002 0 P 0 
L 1.11848002 -2.04663002 1.11846998 -2.04666004 0 P 0 
L 1.11846998 -2.04666004 1.11846004 -2.0467 0 P 0 
L 1.11846004 -2.0467 1.11843996 -2.04676998 0 P 0 
L 1.11843996 -2.04676998 1.11786004 -2.04883996 0 P 0 
L 1.11786004 -2.04883996 1.11785 -2.04886998 0 P 0 
L 1.11785 -2.04886998 1.11783996 -2.04891004 0 P 0 
L 1.11783996 -2.04891004 1.11783996 -2.04893996 0 P 0 
L 1.11783996 -2.04893996 1.11783002 -2.04896998 0 P 0 
L 1.11783002 -2.04896998 1.11783002 -2.04898002 0 P 0 
L 1.11783002 -2.04898002 1.1174 -2.05108002 0 P 0 
L 1.1174 -2.05108002 1.1174 -2.05111998 0 P 0 
L 1.1174 -2.05111998 1.11738996 -2.05116004 0 P 0 
L 1.11738996 -2.05116004 1.11738002 -2.05118996 0 P 0 
L 1.11738002 -2.05118996 1.11738002 -2.05123002 0 P 0 
L 1.11738002 -2.05123002 1.11673002 -2.05643002 0 P 0 
L 1.11673002 -2.05643002 1.11671998 -2.05646998 0 P 0 
L 1.11671998 -2.05646998 1.11671998 -2.05655 0 P 0 
L 1.11671998 -2.05655 1.11671004 -2.05658996 0 P 0 
L 1.11671004 -2.05658996 1.11648996 -2.06181998 0 P 0 
L 1.11648996 -2.06181998 1.11648002 -2.06186998 0 P 0 
L 1.11648002 -2.06186998 1.11648002 -2.06195 0 P 0 
L 1.11648002 -2.06195 1.11648996 -2.06198996 0 P 0 
L 1.11648996 -2.06198996 1.11668002 -2.06696998 0 P 0 
L 1.11668002 -2.06696998 1.11768002 -2.06696998 0 P 0 
L 1.11768002 -2.06696998 1.11668002 -2.06701004 0 P 0 
L 1.11668002 -2.06701004 1.11668002 -2.06713002 0 P 0 
L 1.11668002 -2.06713002 1.11668996 -2.06716998 0 P 0 
L 1.11668996 -2.06716998 1.11728002 -2.07215 0 P 0 
L 1.11728002 -2.07215 1.11728996 -2.07218996 0 P 0 
L 1.11728996 -2.07218996 1.11728996 -2.07223002 0 P 0 
L 1.11728996 -2.07223002 1.11731004 -2.07231004 0 P 0 
L 1.11731004 -2.07231004 1.11758996 -2.07371004 0 P 0 
L 1.11758996 -2.07371004 1.1176 -2.07375 0 P 0 
L 1.1176 -2.07375 1.11761004 -2.0738 0 P 0 
L 1.11761004 -2.0738 1.11761998 -2.07383996 0 P 0 
L 1.11761998 -2.07383996 1.11763996 -2.07388002 0 P 0 
L 1.11763996 -2.07388002 1.11803996 -2.07523996 0 P 0 
L 1.11803996 -2.07523996 1.11806004 -2.07531998 0 P 0 
L 1.11806004 -2.07531998 1.11808002 -2.07536004 0 P 0 
L 1.11808002 -2.07536004 1.11808996 -2.07541004 0 P 0 
L 1.11808996 -2.07541004 1.11861004 -2.07673002 0 P 0 
L 1.11861004 -2.07673002 1.11863996 -2.07681004 0 P 0 
L 1.11863996 -2.07681004 1.11866004 -2.07683996 0 P 0 
L 1.11866004 -2.07683996 1.11868002 -2.07688002 0 P 0 
L 1.11868002 -2.07688002 1.11931004 -2.07815 0 P 0 
L 1.11931004 -2.07815 1.11935 -2.07823002 0 P 0 
L 1.11935 -2.07823002 1.1194 -2.0783 0 P 0 
L 1.1194 -2.0783 1.12013996 -2.07951998 0 P 0 
L 1.12013996 -2.07951998 1.12021004 -2.07961998 0 P 0 
L 1.12021004 -2.07961998 1.12023002 -2.07965 0 P 0 
L 1.12023002 -2.07965 1.12023002 -2.07966004 0 P 0 
L 1.12023002 -2.07966004 1.1212 -2.08096998 0 P 0 
L 1.1212 -2.08096998 1.12123996 -2.08103002 0 P 0 
L 1.12123996 -2.08103002 1.12126998 -2.08106004 0 P 0 
L 1.12126998 -2.08106004 1.12128996 -2.08108996 0 P 0 
L 1.12128996 -2.08108996 1.12235 -2.08231004 0 P 0 
L 1.12235 -2.08231004 1.12238002 -2.08233996 0 P 0 
L 1.12238002 -2.08233996 1.1224 -2.08236998 0 P 0 
L 1.1224 -2.08236998 1.12246004 -2.08243002 0 P 0 
L 1.12246004 -2.08243002 1.12361004 -2.08355 0 P 0 
L 1.12361004 -2.08355 1.12366998 -2.08361004 0 P 0 
L 1.12366998 -2.08361004 1.1237 -2.08363002 0 P 0 
L 1.1237 -2.08363002 1.12373002 -2.08366004 0 P 0 
L 1.12373002 -2.08366004 1.12496998 -2.08468996 0 P 0 
L 1.12496998 -2.08468996 1.125 -2.08471004 0 P 0 
L 1.125 -2.08471004 1.12503002 -2.08473996 0 P 0 
L 1.12503002 -2.08473996 1.12506998 -2.08476004 0 P 0 
L 1.12506998 -2.08476004 1.1251 -2.08478996 0 P 0 
L 1.1251 -2.08478996 1.12641998 -2.08571004 0 P 0 
L 1.12641998 -2.08571004 1.12645 -2.08573002 0 P 0 
L 1.12645 -2.08573002 1.12648002 -2.08576004 0 P 0 
L 1.12648002 -2.08576004 1.12651004 -2.08578002 0 P 0 
L 1.12651004 -2.08578002 1.12655 -2.0858 0 P 0 
L 1.12655 -2.0858 1.12793996 -2.08661004 0 P 0 
L 1.12793996 -2.08661004 1.12801004 -2.08665 0 P 0 
L 1.12801004 -2.08665 1.12805 -2.08666998 0 P 0 
L 1.12805 -2.08666998 1.12808002 -2.08668996 0 P 0 
L 1.12808002 -2.08668996 1.12808996 -2.08668996 0 P 0 
L 1.12808996 -2.08668996 1.12953996 -2.08738996 0 P 0 
L 1.12953996 -2.08738996 1.12961998 -2.08743002 0 P 0 
L 1.12961998 -2.08743002 1.12965 -2.08743996 0 P 0 
L 1.12965 -2.08743996 1.1297 -2.08746004 0 P 0 
L 1.1297 -2.08746004 1.13118002 -2.08801998 0 P 0 
L 1.13118002 -2.08801998 1.13133996 -2.08808002 0 P 0 
L 1.13133996 -2.08808002 1.13286998 -2.08851004 0 P 0 
L 1.13286998 -2.08851004 1.13295 -2.08853996 0 P 0 
L 1.13295 -2.08853996 1.13303996 -2.08855 0 P 0 
L 1.13303996 -2.08855 1.1346 -2.08886004 0 P 0 
L 1.1346 -2.08886004 1.13471998 -2.08888996 0 P 0 
L 1.13471998 -2.08888996 1.13476004 -2.08888996 0 P 0 
L 1.13476004 -2.08888996 1.13633996 -2.08906998 0 P 0 
L 1.13633996 -2.08906998 1.13638996 -2.08908002 0 P 0 
L 1.13638996 -2.08908002 1.13651004 -2.08908002 0 P 0 
L 1.13651004 -2.08908002 1.1381 -2.08913002 0 P 0 
L 1.1381 -2.08913002 1.13818996 -2.08913002 0 P 0 
L 1.31623996 -1.98923996 1.3135 -1.98988002 0 P 0 
L 1.3135 -1.98988002 1.31078996 -1.99071004 0 P 0 
L 1.31078996 -1.99071004 1.30813002 -1.99175 0 P 0 
L 1.30813002 -1.99175 1.30553996 -1.99296998 0 P 0 
L 1.30553996 -1.99296998 1.30308996 -1.99431998 0 P 0 
L 1.30308996 -1.99431998 1.30073996 -1.99585 0 P 0 
L 1.30073996 -1.99585 1.29863996 -1.99746004 0 P 0 
L 1.29863996 -1.99746004 1.29666004 -1.99923996 0 P 0 
L 1.29666004 -1.99923996 1.29205 -2.00375 0 P 0 
L 1.29205 -2.00375 1.29205 -1.99243996 0 P 0 
L 1.29205 -1.99243996 1.24316004 -1.99243996 0 P 0 
L 1.24316004 -1.99243996 1.24313996 -2.00521004 0 P 0 
L 1.24313996 -2.00521004 1.24261004 -2.03151004 0 P 0 
L 1.24261004 -2.03151004 1.24086998 -2.07046004 0 P 0 
L 1.24086998 -2.07046004 1.23873996 -2.10921004 0 P 0 
L 1.23873996 -2.10921004 1.23811998 -2.11641998 0 P 0 
L 1.23811998 -2.11641998 1.23711998 -2.12361998 0 P 0 
L 1.23711998 -2.12361998 1.23655 -2.12716004 0 P 0 
L 1.23655 -2.12716004 1.29205 -2.12716004 0 P 0 
L 1.29205 -2.12716004 1.29206998 -2.11766004 0 P 0 
L 1.29206998 -2.11766004 1.29238996 -2.10283996 0 P 0 
L 1.29238996 -2.10283996 1.29336004 -2.08431004 0 P 0 
L 1.29336004 -2.08431004 1.29463996 -2.06673002 0 P 0 
L 1.29463996 -2.06673002 1.29511004 -2.06253002 0 P 0 
L 1.29511004 -2.06253002 1.29583996 -2.05836004 0 P 0 
L 1.29583996 -2.05836004 1.29683002 -2.05446998 0 P 0 
L 1.29683002 -2.05446998 1.29813996 -2.05068996 0 P 0 
L 1.29813996 -2.05068996 1.29978002 -2.04701998 0 P 0 
L 1.29978002 -2.04701998 1.30056998 -2.04556998 0 P 0 
L 1.30056998 -2.04556998 1.30146998 -2.04418996 0 P 0 
L 1.30146998 -2.04418996 1.30246998 -2.04288002 0 P 0 
L 1.30246998 -2.04288002 1.30356998 -2.04165 0 P 0 
L 1.30356998 -2.04165 1.30475 -2.0405 0 P 0 
L 1.30475 -2.0405 1.30603996 -2.03945 0 P 0 
L 1.30603996 -2.03945 1.30773996 -2.03826004 0 P 0 
L 1.30773996 -2.03826004 1.30953002 -2.03723002 0 P 0 
L 1.30953002 -2.03723002 1.31141004 -2.03635 0 P 0 
L 1.31141004 -2.03635 1.31335 -2.03563002 0 P 0 
L 1.31335 -2.03563002 1.31535 -2.03508002 0 P 0 
L 1.31535 -2.03508002 1.31973996 -2.03423002 0 P 0 
L 1.31973996 -2.03423002 1.32416004 -2.03366998 0 P 0 
L 1.32416004 -2.03366998 1.32863002 -2.0334 0 P 0 
L 1.32863002 -2.0334 1.33688002 -2.03318002 0 P 0 
L 1.33688002 -2.03318002 1.33613002 -2.01151004 0 P 0 
L 1.33613002 -2.01151004 1.33581004 -2.00315 0 P 0 
L 1.33581004 -2.00315 1.33543996 -1.99596004 0 P 0 
L 1.33543996 -1.99596004 1.33508002 -1.98971004 0 P 0 
L 1.33508002 -1.98971004 1.33503996 -1.98945 0 P 0 
L 1.33503996 -1.98945 1.335 -1.98931998 0 P 0 
L 1.335 -1.98931998 1.33496004 -1.9892 0 P 0 
L 1.33496004 -1.9892 1.3349 -1.98908002 0 P 0 
L 1.3349 -1.98908002 1.33483996 -1.98896998 0 P 0 
L 1.33483996 -1.98896998 1.33476998 -1.98886004 0 P 0 
L 1.33476998 -1.98886004 1.33468996 -1.98876004 0 P 0 
L 1.33468996 -1.98876004 1.3346 -1.98866998 0 P 0 
L 1.3346 -1.98866998 1.33451004 -1.98858996 0 P 0 
L 1.33451004 -1.98858996 1.3344 -1.98851998 0 P 0 
L 1.3344 -1.98851998 1.3343 -1.98845 0 P 0 
L 1.3343 -1.98845 1.33418002 -1.98838996 0 P 0 
L 1.33418002 -1.98838996 1.33406998 -1.98833996 0 P 0 
L 1.33406998 -1.98833996 1.33395 -1.9883 0 P 0 
L 1.33395 -1.9883 1.33383002 -1.98828002 0 P 0 
L 1.33383002 -1.98828002 1.3337 -1.98826004 0 P 0 
L 1.3337 -1.98826004 1.33356998 -1.98825 0 P 0 
L 1.33356998 -1.98825 1.32756998 -1.98823002 0 P 0 
L 1.32756998 -1.98823002 1.32135 -1.98853996 0 P 0 
L 1.32135 -1.98853996 1.31878996 -1.98881998 0 P 0 
L 1.31878996 -1.98881998 1.31623996 -1.98923996 0 P 0 
L 1.2389 -2.12516004 1.29006004 -2.12516004 0 P 0 
L 1.23906998 -2.12416004 1.29006004 -2.12416004 0 P 0 
L 1.23921004 -2.12316004 1.29006004 -2.12316004 0 P 0 
L 1.23933996 -2.12216004 1.29006004 -2.12216004 0 P 0 
L 1.23948996 -2.12116004 1.29006004 -2.12116004 0 P 0 
L 1.23961998 -2.12016004 1.29006998 -2.12016004 0 P 0 
L 1.23976004 -2.11916004 1.29006998 -2.11916004 0 P 0 
L 1.2399 -2.11816004 1.29006998 -2.11816004 0 P 0 
L 1.24003996 -2.11716004 1.29008002 -2.11716004 0 P 0 
L 1.24015 -2.11616004 1.2901 -2.11616004 0 P 0 
L 1.24023996 -2.11516004 1.29011998 -2.11516004 0 P 0 
L 1.24033002 -2.11416004 1.29013996 -2.11416004 0 P 0 
L 1.24041004 -2.11316004 1.29016004 -2.11316004 0 P 0 
L 1.24048996 -2.11216004 1.29018996 -2.11216004 0 P 0 
L 1.24058002 -2.11116004 1.29021004 -2.11116004 0 P 0 
L 1.24066998 -2.11016004 1.29023002 -2.11016004 0 P 0 
L 1.24075 -2.10916004 1.29025 -2.10916004 0 P 0 
L 1.2408 -2.10816004 1.29026998 -2.10816004 0 P 0 
L 1.24086004 -2.10716004 1.29028996 -2.10716004 0 P 0 
L 1.24091004 -2.10616004 1.29031998 -2.10616004 0 P 0 
L 1.24096998 -2.10516004 1.29033996 -2.10516004 0 P 0 
L 1.24101998 -2.10416004 1.29036004 -2.10416004 0 P 0 
L 1.24108002 -2.10316004 1.29038002 -2.10316004 0 P 0 
L 1.24113002 -2.10216004 1.29041998 -2.10216004 0 P 0 
L 1.24118002 -2.10116004 1.29046998 -2.10116004 0 P 0 
L 1.24123996 -2.10016004 1.29053002 -2.10016004 0 P 0 
L 1.24128996 -2.09916004 1.29058002 -2.09916004 0 P 0 
L 1.24135 -2.09816004 1.29063002 -2.09816004 0 P 0 
L 1.2414 -2.09716004 1.29068002 -2.09716004 0 P 0 
L 1.24146004 -2.09616004 1.29073996 -2.09616004 0 P 0 
L 1.24151004 -2.09516004 1.29078996 -2.09516004 0 P 0 
L 1.24156998 -2.09416004 1.29083996 -2.09416004 0 P 0 
L 1.24161998 -2.09316004 1.2909 -2.09316004 0 P 0 
L 1.24168002 -2.09216004 1.29095 -2.09216004 0 P 0 
L 1.24173002 -2.09116004 1.291 -2.09116004 0 P 0 
L 1.24178996 -2.09016004 1.29105 -2.09016004 0 P 0 
L 1.24183996 -2.08916004 1.2911 -2.08916004 0 P 0 
L 1.2419 -2.08816004 1.29116004 -2.08816004 0 P 0 
L 1.24196004 -2.08716004 1.29121004 -2.08716004 0 P 0 
L 1.24201004 -2.08616004 1.29126998 -2.08616004 0 P 0 
L 1.24206998 -2.08516004 1.29131998 -2.08516004 0 P 0 
L 1.24211998 -2.08416004 1.29136998 -2.08416004 0 P 0 
L 1.2389 -2.12516004 1.2391 -2.12393002 0 P 0 
L 1.2391 -2.12393002 1.2391 -2.1239 0 P 0 
L 1.2391 -2.1239 1.24011004 -2.11665 0 P 0 
L 1.24011004 -2.11665 1.24073002 -2.10935 0 P 0 
L 1.24073002 -2.10935 1.24073996 -2.10931998 0 P 0 
L 1.24073996 -2.10931998 1.24286004 -2.07056004 0 P 0 
L 1.24286004 -2.07056004 1.24461004 -2.03158002 0 P 0 
L 1.24461004 -2.03158002 1.24513996 -2.00523002 0 P 0 
L 1.24513996 -2.00523002 1.24515 -1.99443996 0 P 0 
L 1.24515 -1.99443996 1.29005 -1.99443996 0 P 0 
L 1.29005 -1.99443996 1.29005 -2.00375 0 P 0 
L 1.29005 -2.00375 1.29128002 -2.0056 0 P 0 
L 1.29128002 -2.0056 1.29345 -2.00518002 0 P 0 
L 1.29345 -2.00518002 1.29803002 -2.0007 0 P 0 
L 1.29803002 -2.0007 1.29991998 -1.999 0 P 0 
L 1.29991998 -1.999 1.30188996 -1.99748996 0 P 0 
L 1.30188996 -1.99748996 1.30411998 -1.99603996 0 P 0 
L 1.30411998 -1.99603996 1.30645 -1.99475 0 P 0 
L 1.30645 -1.99475 1.30891998 -1.99358996 0 P 0 
L 1.30891998 -1.99358996 1.31145 -1.9926 0 P 0 
L 1.31145 -1.9926 1.31401998 -1.99181004 0 P 0 
L 1.31401998 -1.99181004 1.31663996 -1.9912 0 P 0 
L 1.31663996 -1.9912 1.31906004 -1.9908 0 P 0 
L 1.31906004 -1.9908 1.32151004 -1.99053002 0 P 0 
L 1.32151004 -1.99053002 1.32761998 -1.99023002 0 P 0 
L 1.32761998 -1.99023002 1.3331 -1.99025 0 P 0 
L 1.3331 -1.99025 1.33345 -1.99608002 0 P 0 
L 1.33345 -1.99608002 1.33381004 -2.00323002 0 P 0 
L 1.33381004 -2.00323002 1.33413002 -2.01158996 0 P 0 
L 1.33413002 -2.01158996 1.33413002 -2.0116 0 P 0 
L 1.33413002 -2.0116 1.33481998 -2.03123002 0 P 0 
L 1.33481998 -2.03123002 1.32853996 -2.0314 0 P 0 
L 1.32853996 -2.0314 1.32398002 -2.03166998 0 P 0 
L 1.32398002 -2.03166998 1.31941998 -2.03225 0 P 0 
L 1.31941998 -2.03225 1.31488996 -2.03313002 0 P 0 
L 1.31488996 -2.03313002 1.31273996 -2.03373002 0 P 0 
L 1.31273996 -2.03373002 1.31063996 -2.0345 0 P 0 
L 1.31063996 -2.0345 1.3086 -2.03545 0 P 0 
L 1.3086 -2.03545 1.30666004 -2.03656998 0 P 0 
L 1.30666004 -2.03656998 1.30658996 -2.03661998 0 P 0 
L 1.30658996 -2.03661998 1.30483002 -2.03786004 0 P 0 
L 1.30483002 -2.03786004 1.30341998 -2.03901004 0 P 0 
L 1.30341998 -2.03901004 1.30336998 -2.03906004 0 P 0 
L 1.30336998 -2.03906004 1.30211998 -2.04026004 0 P 0 
L 1.30211998 -2.04026004 1.30093002 -2.0416 0 P 0 
L 1.30093002 -2.0416 1.29983002 -2.04303996 0 P 0 
L 1.29983002 -2.04303996 1.29978996 -2.0431 0 P 0 
L 1.29978996 -2.0431 1.29885 -2.04453996 0 P 0 
L 1.29885 -2.04453996 1.29798996 -2.04613002 0 P 0 
L 1.29798996 -2.04613002 1.29631998 -2.04986998 0 P 0 
L 1.29631998 -2.04986998 1.29628002 -2.04995 0 P 0 
L 1.29628002 -2.04995 1.29625 -2.05003002 0 P 0 
L 1.29625 -2.05003002 1.29491998 -2.0539 0 P 0 
L 1.29491998 -2.0539 1.29388996 -2.05793996 0 P 0 
L 1.29388996 -2.05793996 1.29386998 -2.05801998 0 P 0 
L 1.29386998 -2.05801998 1.29313996 -2.06221004 0 P 0 
L 1.29313996 -2.06221004 1.29313002 -2.06223996 0 P 0 
L 1.29313002 -2.06223996 1.29311998 -2.0623 0 P 0 
L 1.29311998 -2.0623 1.29265 -2.06655 0 P 0 
L 1.29265 -2.06655 1.29136998 -2.08418996 0 P 0 
L 1.29136998 -2.08418996 1.29038996 -2.10276998 0 P 0 
L 1.29038996 -2.10276998 1.29006998 -2.11763002 0 P 0 
L 1.29006998 -2.11763002 1.29006004 -2.12516004 0 P 0 
L 1.29006004 -2.12516004 1.2389 -2.12516004 0 P 0 
L 1.09846998 -2.00483002 1.21248002 -2.00483002 0 P 0 
L 1.09838002 -2.12083002 1.14708002 -2.12083002 0 P 0 
L 1.11933002 -2.18283002 1.15161998 -2.18283002 0 P 0 
L 1.11001998 -2.18183002 1.15838002 -2.18183002 0 P 0 
L 1.10246998 -2.18083002 1.16333996 -2.18083002 0 P 0 
L 1.04061004 -1.89731004 1.09978002 -1.89731004 0 P 0 
L 1.03565 -1.89631004 1.09821004 -1.89631004 0 P 0 
L 1.03068996 -1.89531004 1.09661004 -1.89531004 0 P 0 
L 1.02573002 -1.89431004 1.09475 -1.89431004 0 P 0 
L 1.019 -1.89331004 1.09288002 -1.89331004 0 P 0 
L 1.01163996 -1.89231004 1.09101998 -1.89231004 0 P 0 
L 0.99518996 -1.89131004 1.08916004 -1.89131004 0 P 0 
L 0.87011998 -1.88331004 1.07278996 -1.88331004 0 P 0 
L 0.86963996 -1.88231004 1.07053002 -1.88231004 0 P 0 
L 0.86916004 -1.88131004 1.06828002 -1.88131004 0 P 0 
L 0.86863002 -1.88031004 1.06603002 -1.88031004 0 P 0 
L 0.86806998 -1.87931004 1.06351004 -1.87931004 0 P 0 
L 0.8675 -1.87831004 1.06076998 -1.87831004 0 P 0 
L 0.86693002 -1.87731004 1.05803996 -1.87731004 0 P 0 
L 0.86631004 -1.87631004 1.05531004 -1.87631004 0 P 0 
L 0.86563996 -1.87531004 1.05256998 -1.87531004 0 P 0 
L 0.86498002 -1.87431004 1.04983996 -1.87431004 0 P 0 
L 0.86431998 -1.87331004 1.0471 -1.87331004 0 P 0 
L 0.86356004 -1.87231004 1.04376004 -1.87231004 0 P 0 
L 0.86278996 -1.87131004 1.04041998 -1.87131004 0 P 0 
L 0.86203002 -1.87031004 1.03708002 -1.87031004 0 P 0 
L 0.86118996 -1.86931004 1.03373996 -1.86931004 0 P 0 
L 0.8603 -1.86831004 1.0304 -1.86831004 0 P 0 
L 0.85941004 -1.86731004 1.02656998 -1.86731004 0 P 0 
L 0.8585 -1.86631004 1.02231998 -1.86631004 0 P 0 
L 0.85756998 -1.86531004 1.01806998 -1.86531004 0 P 0 
L 0.85663002 -1.86431004 1.01381998 -1.86431004 0 P 0 
L 0.85568996 -1.86331004 1.00931998 -1.86331004 0 P 0 
L 0.85481004 -1.86231004 1.00335 -1.86231004 0 P 0 
L 0.85916998 -1.86131004 0.99738002 -1.86131004 0 P 0 
L 0.86716998 -1.86031004 0.99141998 -1.86031004 0 P 0 
L 0.87476998 -1.89731004 0.89943002 -1.89731004 0 P 0 
L 0.87453996 -1.89631004 0.90426004 -1.89631004 0 P 0 
L 0.87431004 -1.89531004 0.9097 -1.89531004 0 P 0 
L 0.87406998 -1.89431004 0.91608002 -1.89431004 0 P 0 
L 0.87383002 -1.89331004 0.92246004 -1.89331004 0 P 0 
L 0.87355 -1.89231004 0.93086004 -1.89231004 0 P 0 
L 0.87323002 -1.89131004 0.95553002 -1.89131004 0 P 0 
L 0.87291004 -1.89031004 1.08728996 -1.89031004 0 P 0 
L 0.87258996 -1.88931004 1.08543002 -1.88931004 0 P 0 
L 0.87223002 -1.88831004 1.08356998 -1.88831004 0 P 0 
L 0.87183002 -1.88731004 1.0817 -1.88731004 0 P 0 
L 0.87143002 -1.88631004 1.07955 -1.88631004 0 P 0 
L 0.87103002 -1.88531004 1.07728996 -1.88531004 0 P 0 
L 0.8706 -1.88431004 1.07503996 -1.88431004 0 P 0 
L 0.87525 -1.85931004 0.98545 -1.85931004 0 P 0 
L 0.88421004 -1.85831004 0.97621004 -1.85831004 0 P 0 
L 0.89393002 -1.85731004 0.96606998 -1.85731004 0 P 0 
L 0.9106 -1.85631004 0.95203002 -1.85631004 0 P 0 
L 1.08716004 -1.91231004 1.12151004 -1.91231004 0 P 0 
L 1.08486004 -1.91131004 1.12018996 -1.91131004 0 P 0 
L 1.08256004 -1.91031004 1.11886004 -1.91031004 0 P 0 
L 1.08023002 -1.90931004 1.11753996 -1.90931004 0 P 0 
L 1.07738002 -1.90831004 1.11621004 -1.90831004 0 P 0 
L 1.07453002 -1.90731004 1.11488996 -1.90731004 0 P 0 
L 1.07168996 -1.90631004 1.11356998 -1.90631004 0 P 0 
L 1.06883996 -1.90531004 1.11223996 -1.90531004 0 P 0 
L 1.066 -1.90431004 1.11076998 -1.90431004 0 P 0 
L 1.06315 -1.90331004 1.1092 -1.90331004 0 P 0 
L 1.0599 -1.90231004 1.10763002 -1.90231004 0 P 0 
L 1.05611998 -1.90131004 1.10606004 -1.90131004 0 P 0 
L 1.05235 -1.90031004 1.10448996 -1.90031004 0 P 0 
L 1.04856998 -1.89931004 1.10291998 -1.89931004 0 P 0 
L 1.04478996 -1.89831004 1.10135 -1.89831004 0 P 0 
L 0.98815 -2.08316004 1.03726998 -2.08316004 0 P 0 
L 0.98818002 -2.08216004 1.03731004 -2.08216004 0 P 0 
L 0.98821998 -2.08116004 1.03735 -2.08116004 0 P 0 
L 0.98825 -2.08016004 1.03738996 -2.08016004 0 P 0 
L 0.98828002 -2.07916004 1.03743002 -2.07916004 0 P 0 
L 0.98831998 -2.07816004 1.03746998 -2.07816004 0 P 0 
L 0.98835 -2.07716004 1.03751004 -2.07716004 0 P 0 
L 0.98838002 -2.07616004 1.03755 -2.07616004 0 P 0 
L 0.98841998 -2.07516004 1.03758002 -2.07516004 0 P 0 
L 0.98845 -2.07416004 1.03761004 -2.07416004 0 P 0 
L 0.98848002 -2.07316004 1.03763996 -2.07316004 0 P 0 
L 0.98851004 -2.07216004 1.03768002 -2.07216004 0 P 0 
L 0.98855 -2.07116004 1.03771004 -2.07116004 0 P 0 
L 0.98858002 -2.07016004 1.03773996 -2.07016004 0 P 0 
L 0.98858996 -2.06916004 1.03776998 -2.06916004 0 P 0 
L 0.98858996 -2.06816004 1.0378 -2.06816004 0 P 0 
L 0.98858996 -2.06716004 1.03783002 -2.06716004 0 P 0 
L 0.98858002 -2.06616004 1.03786004 -2.06616004 0 P 0 
L 0.98856998 -2.06516004 1.0379 -2.06516004 0 P 0 
L 0.98856998 -2.06416004 1.03793002 -2.06416004 0 P 0 
L 0.98856998 -2.06316004 1.03796004 -2.06316004 0 P 0 
L 0.98856004 -2.06216004 1.03798996 -2.06216004 0 P 0 
L 0.98855 -2.06116004 1.03801998 -2.06116004 0 P 0 
L 0.98855 -2.06016004 1.03805 -2.06016004 0 P 0 
L 0.98853996 -2.05916004 1.03808002 -2.05916004 0 P 0 
L 0.98853996 -2.05816004 1.0381 -2.05816004 0 P 0 
L 0.98853002 -2.05716004 1.03811998 -2.05716004 0 P 0 
L 0.98848002 -2.05616004 1.03815 -2.05616004 0 P 0 
L 0.98841004 -2.05516004 1.03818002 -2.05516004 0 P 0 
L 0.98835 -2.05416004 1.0382 -2.05416004 0 P 0 
L 0.98828002 -2.05316004 1.03821998 -2.05316004 0 P 0 
L 0.98821004 -2.05216004 1.03825 -2.05216004 0 P 0 
L 0.98815 -2.05116004 1.03826998 -2.05116004 0 P 0 
L 0.98808996 -2.05016004 1.03828996 -2.05016004 0 P 0 
L 0.98801998 -2.04916004 1.03831998 -2.04916004 0 P 0 
L 0.98796004 -2.04816004 1.03833996 -2.04816004 0 P 0 
L 0.98788996 -2.04716004 1.03836004 -2.04716004 0 P 0 
L 0.98783002 -2.04616004 1.03838996 -2.04616004 0 P 0 
L 0.98768996 -2.04516004 1.0384 -2.04516004 0 P 0 
L 0.98756004 -2.04416004 1.03841004 -2.04416004 0 P 0 
L 0.98738002 -2.04316004 1.03841998 -2.04316004 0 P 0 
L 0.98716004 -2.04216004 1.03843002 -2.04216004 0 P 0 
L 0.98691998 -2.04116004 1.03843996 -2.04116004 0 P 0 
L 0.98661998 -2.04016004 1.03845 -2.04016004 0 P 0 
L 0.98631998 -2.03916004 1.03846004 -2.03916004 0 P 0 
L 0.98593996 -2.03816004 1.03846998 -2.03816004 0 P 0 
L 0.98546998 -2.03716004 1.03848002 -2.03716004 0 P 0 
L 0.98491004 -2.03616004 1.03846998 -2.03616004 0 P 0 
L 0.98425 -2.03516004 1.03846004 -2.03516004 0 P 0 
L 0.98346004 -2.03416004 1.03846004 -2.03416004 0 P 0 
L 0.98251998 -2.03316004 1.03843996 -2.03316004 0 P 0 
L 0.98138002 -2.03216004 1.03843002 -2.03216004 0 P 0 
L 0.97998996 -2.03116004 1.03841998 -2.03116004 0 P 0 
L 0.97813996 -2.03016004 1.03841004 -2.03016004 0 P 0 
L 0.97491004 -2.02916004 1.0384 -2.02916004 0 P 0 
L 0.94763996 -2.00716004 1.03293996 -2.00716004 0 P 0 
L 0.94978996 -2.00616004 1.03231998 -2.00616004 0 P 0 
L 0.95081004 -2.00516004 1.0317 -2.00516004 0 P 0 
L 0.95183002 -2.00416004 1.03098002 -2.00416004 0 P 0 
L 0.95285 -2.00316004 1.03023002 -2.00316004 0 P 0 
L 0.95388996 -2.00216004 1.02936004 -2.00216004 0 P 0 
L 0.95498002 -2.00116004 1.02841998 -2.00116004 0 P 0 
L 0.95621998 -2.00016004 1.02738996 -2.00016004 0 P 0 
L 0.95761998 -1.99916004 1.0262 -1.99916004 0 P 0 
L 0.9592 -1.99816004 1.02486004 -1.99816004 0 P 0 
L 0.96083996 -1.99716004 1.02335 -1.99716004 0 P 0 
L 0.9627 -1.99616004 1.02161004 -1.99616004 0 P 0 
L 0.96468996 -1.99516004 1.01951998 -1.99516004 0 P 0 
L 0.96685 -1.99416004 1.01683002 -1.99416004 0 P 0 
L 0.96936998 -1.99316004 1.01378002 -1.99316004 0 P 0 
L 0.97236998 -1.99216004 1.00981004 -1.99216004 0 P 0 
L 0.97676004 -1.99116004 1.00456998 -1.99116004 0 P 0 
L 1.06713996 -2.08283002 1.12288002 -2.08283002 0 P 0 
L 1.06698996 -2.08183002 1.12193996 -2.08183002 0 P 0 
L 1.06686004 -2.08083002 1.12108996 -2.08083002 0 P 0 
L 1.06673996 -2.07983002 1.12036004 -2.07983002 0 P 0 
L 1.06661998 -2.07883002 1.11971998 -2.07883002 0 P 0 
L 1.06653002 -2.07783002 1.11916004 -2.07783002 0 P 0 
L 1.06648002 -2.07683002 1.11866004 -2.07683002 0 P 0 
L 1.06641998 -2.07583002 1.11826004 -2.07583002 0 P 0 
L 1.06636998 -2.07483002 1.11791998 -2.07483002 0 P 0 
L 1.06631998 -2.07383002 1.11761998 -2.07383002 0 P 0 
L 1.06626004 -2.07283002 1.11741998 -2.07283002 0 P 0 
L 1.06621004 -2.07183002 1.11723996 -2.07183002 0 P 0 
L 1.06616004 -2.07083002 1.11711998 -2.07083002 0 P 0 
L 1.06616004 -2.06983002 1.11701004 -2.06983002 0 P 0 
L 1.06616004 -2.06883002 1.11688996 -2.06883002 0 P 0 
L 1.06616998 -2.06783002 1.11676998 -2.06783002 0 P 0 
L 1.06618002 -2.06683002 1.11666998 -2.06683002 0 P 0 
L 1.06618996 -2.06583002 1.11663002 -2.06583002 0 P 0 
L 1.0662 -2.06483002 1.11658996 -2.06483002 0 P 0 
L 1.06621004 -2.06383002 1.11656004 -2.06383002 0 P 0 
L 1.06623002 -2.06283002 1.11651998 -2.06283002 0 P 0 
L 1.06631004 -2.06183002 1.11648996 -2.06183002 0 P 0 
L 1.06638002 -2.06083002 1.11653002 -2.06083002 0 P 0 
L 1.06645 -2.05983002 1.11656998 -2.05983002 0 P 0 
L 1.06651998 -2.05883002 1.11661998 -2.05883002 0 P 0 
L 1.06658996 -2.05783002 1.11666004 -2.05783002 0 P 0 
L 1.06666998 -2.05683002 1.11671004 -2.05683002 0 P 0 
L 1.06673996 -2.05583002 1.11681004 -2.05583002 0 P 0 
L 1.06686004 -2.05483002 1.11693002 -2.05483002 0 P 0 
L 1.067 -2.05383002 1.11705 -2.05383002 0 P 0 
L 1.06713996 -2.05283002 1.11718002 -2.05283002 0 P 0 
L 1.06728002 -2.05183002 1.11731004 -2.05183002 0 P 0 
L 1.06741998 -2.05083002 1.11746004 -2.05083002 0 P 0 
L 1.06756004 -2.04983002 1.11766004 -2.04983002 0 P 0 
L 1.0677 -2.04883002 1.11786004 -2.04883002 0 P 0 
L 1.06786004 -2.04783002 1.11813996 -2.04783002 0 P 0 
L 1.06806998 -2.04683002 1.11841998 -2.04683002 0 P 0 
L 1.06828002 -2.04583002 1.11876998 -2.04583002 0 P 0 
L 1.06848996 -2.04483002 1.11913002 -2.04483002 0 P 0 
L 1.06871004 -2.04383002 1.11955 -2.04383002 0 P 0 
L 1.06898996 -2.04283002 1.11998996 -2.04283002 0 P 0 
L 1.06928002 -2.04183002 1.12048002 -2.04183002 0 P 0 
L 1.06956004 -2.04083002 1.12101004 -2.04083002 0 P 0 
L 1.06985 -2.03983002 1.12161998 -2.03983002 0 P 0 
L 1.07021004 -2.03883002 1.12225 -2.03883002 0 P 0 
L 1.07056998 -2.03783002 1.12298002 -2.03783002 0 P 0 
L 1.07093002 -2.03683002 1.12373996 -2.03683002 0 P 0 
L 1.07128996 -2.03583002 1.12461998 -2.03583002 0 P 0 
L 1.07173002 -2.03483002 1.12548996 -2.03483002 0 P 0 
L 1.07216998 -2.03383002 1.12646004 -2.03383002 0 P 0 
L 1.07261998 -2.03283002 1.12748996 -2.03283002 0 P 0 
L 1.07308002 -2.03183002 1.12855 -2.03183002 0 P 0 
L 1.07361998 -2.03083002 1.12978996 -2.03083002 0 P 0 
L 1.09761004 -1.91731004 1.12756998 -1.91731004 0 P 0 
L 1.09566004 -1.91631004 1.12645 -1.91631004 0 P 0 
L 1.09371004 -1.91531004 1.12533002 -1.91531004 0 P 0 
L 1.09176004 -1.91431004 1.12416004 -1.91431004 0 P 0 
L 1.08946004 -1.91331004 1.12283996 -1.91331004 0 P 0 
L 1.07415 -2.02983002 1.13101998 -2.02983002 0 P 0 
L 1.07468996 -2.02883002 1.13248996 -2.02883002 0 P 0 
L 1.07528996 -2.02783002 1.134 -2.02783002 0 P 0 
L 1.07591998 -2.02683002 1.13586004 -2.02683002 0 P 0 
L 1.07656004 -2.02583002 1.13828996 -2.02583002 0 P 0 
L 1.07721004 -2.02483002 1.14243002 -2.02483002 0 P 0 
L 1.07795 -2.02383002 1.21126998 -2.02383002 0 P 0 
L 1.07868002 -2.02283002 1.21133002 -2.02283002 0 P 0 
L 1.07941998 -2.02183002 1.2114 -2.02183002 0 P 0 
L 1.08021004 -2.02083002 1.21146004 -2.02083002 0 P 0 
L 1.08103996 -2.01983002 1.21153002 -2.01983002 0 P 0 
L 1.08186998 -2.01883002 1.2116 -2.01883002 0 P 0 
L 1.08273002 -2.01783002 1.21166004 -2.01783002 0 P 0 
L 1.08366998 -2.01683002 1.21173002 -2.01683002 0 P 0 
L 1.0846 -2.01583002 1.2118 -2.01583002 0 P 0 
L 1.08555 -2.01483002 1.21186004 -2.01483002 0 P 0 
L 1.08661004 -2.01383002 1.21193002 -2.01383002 0 P 0 
L 1.08766998 -2.01283002 1.21198996 -2.01283002 0 P 0 
L 1.08873002 -2.01183002 1.21205 -2.01183002 0 P 0 
L 1.0898 -2.01083002 1.21211998 -2.01083002 0 P 0 
L 1.09098996 -2.00983002 1.21218002 -2.00983002 0 P 0 
L 1.09225 -2.00883002 1.21223996 -2.00883002 0 P 0 
L 1.09358996 -2.00783002 1.2123 -2.00783002 0 P 0 
L 1.09506998 -2.00683002 1.21236004 -2.00683002 0 P 0 
L 1.09668996 -2.00583002 1.21241998 -2.00583002 0 P 0 
L 0.98546998 -2.12516004 1.03548996 -2.12516004 0 P 0 
L 0.98558996 -2.12416004 1.03553996 -2.12416004 0 P 0 
L 0.9857 -2.12316004 1.03558002 -2.12316004 0 P 0 
L 0.98581004 -2.12216004 1.03561998 -2.12216004 0 P 0 
L 0.98591004 -2.12116004 1.03566998 -2.12116004 0 P 0 
L 0.98598996 -2.12016004 1.03571004 -2.12016004 0 P 0 
L 0.98608002 -2.11916004 1.03575 -2.11916004 0 P 0 
L 0.98616998 -2.11816004 1.0358 -2.11816004 0 P 0 
L 0.98625 -2.11716004 1.03583996 -2.11716004 0 P 0 
L 0.98633996 -2.11616004 1.03588002 -2.11616004 0 P 0 
L 0.98641998 -2.11516004 1.03593002 -2.11516004 0 P 0 
L 0.98651004 -2.11416004 1.03596998 -2.11416004 0 P 0 
L 0.9866 -2.11316004 1.03601004 -2.11316004 0 P 0 
L 0.98668002 -2.11216004 1.03605 -2.11216004 0 P 0 
L 0.98676998 -2.11116004 1.0361 -2.11116004 0 P 0 
L 0.98685 -2.11016004 1.03613996 -2.11016004 0 P 0 
L 0.98693996 -2.10916004 1.03618002 -2.10916004 0 P 0 
L 0.987 -2.10816004 1.03623002 -2.10816004 0 P 0 
L 0.98705 -2.10716004 1.03626998 -2.10716004 0 P 0 
L 0.9871 -2.10616004 1.03631004 -2.10616004 0 P 0 
L 0.98716004 -2.10516004 1.03636004 -2.10516004 0 P 0 
L 0.9872 -2.10416004 1.0364 -2.10416004 0 P 0 
L 0.98725 -2.10316004 1.03643996 -2.10316004 0 P 0 
L 0.98731004 -2.10216004 1.03648002 -2.10216004 0 P 0 
L 0.98735 -2.10116004 1.03653002 -2.10116004 0 P 0 
L 0.9874 -2.10016004 1.03656998 -2.10016004 0 P 0 
L 0.98746004 -2.09916004 1.03661004 -2.09916004 0 P 0 
L 0.98751004 -2.09816004 1.03666004 -2.09816004 0 P 0 
L 0.98755 -2.09716004 1.0367 -2.09716004 0 P 0 
L 0.9876 -2.09616004 1.03673996 -2.09616004 0 P 0 
L 0.98766004 -2.09516004 1.03678996 -2.09516004 0 P 0 
L 0.9877 -2.09416004 1.03683002 -2.09416004 0 P 0 
L 0.98775 -2.09316004 1.03686998 -2.09316004 0 P 0 
L 0.98781004 -2.09216004 1.03691998 -2.09216004 0 P 0 
L 0.98785 -2.09116004 1.03696004 -2.09116004 0 P 0 
L 0.9879 -2.09016004 1.037 -2.09016004 0 P 0 
L 0.98796004 -2.08916004 1.03703996 -2.08916004 0 P 0 
L 0.98798996 -2.08816004 1.03706998 -2.08816004 0 P 0 
L 0.98801998 -2.08716004 1.03711004 -2.08716004 0 P 0 
L 0.98805 -2.08616004 1.03715 -2.08616004 0 P 0 
L 0.98808996 -2.08516004 1.03718996 -2.08516004 0 P 0 
L 0.98811998 -2.08416004 1.03723002 -2.08416004 0 P 0 
L 1.08216998 -2.15683002 1.19803996 -2.15683002 0 P 0 
L 1.0821 -2.15583002 1.19861004 -2.15583002 0 P 0 
L 1.08201998 -2.15483002 1.19918002 -2.15483002 0 P 0 
L 1.08195 -2.15383002 1.1997 -2.15383002 0 P 0 
L 1.08188996 -2.15283002 1.20018002 -2.15283002 0 P 0 
L 1.08183002 -2.15183002 1.20066004 -2.15183002 0 P 0 
L 1.08176998 -2.15083002 1.20113996 -2.15083002 0 P 0 
L 1.08171998 -2.14983002 1.20153996 -2.14983002 0 P 0 
L 1.08166004 -2.14883002 1.20193002 -2.14883002 0 P 0 
L 1.0816 -2.14783002 1.11538996 -2.14783002 0 P 0 
L 1.08155 -2.14683002 1.10903002 -2.14683002 0 P 0 
L 1.0815 -2.14583002 1.10415 -2.14583002 0 P 0 
L 1.08146004 -2.14483002 1.09953002 -2.14483002 0 P 0 
L 1.08141004 -2.14383002 1.09563996 -2.14383002 0 P 0 
L 1.08136004 -2.14283002 1.09183996 -2.14283002 0 P 0 
L 1.08131004 -2.14183002 1.08821004 -2.14183002 0 P 0 
L 1.08133002 -2.14083002 1.08471998 -2.14083002 0 P 0 
L 1.09586998 -2.11983002 1.14965 -2.11983002 0 P 0 
L 1.09361998 -2.11883002 1.15221998 -2.11883002 0 P 0 
L 1.09158996 -2.11783002 1.20595 -2.11783002 0 P 0 
L 1.08988002 -2.11683002 1.20601004 -2.11683002 0 P 0 
L 1.08823996 -2.11583002 1.20606998 -2.11583002 0 P 0 
L 1.08678996 -2.11483002 1.20613002 -2.11483002 0 P 0 
L 1.08541004 -2.11383002 1.20618996 -2.11383002 0 P 0 
L 1.08416998 -2.11283002 1.20625 -2.11283002 0 P 0 
L 1.08295 -2.11183002 1.20631004 -2.11183002 0 P 0 
L 1.08188002 -2.11083002 1.20638002 -2.11083002 0 P 0 
L 1.08081998 -2.10983002 1.20643996 -2.10983002 0 P 0 
L 1.07986004 -2.10883002 1.2065 -2.10883002 0 P 0 
L 1.07895 -2.10783002 1.20656004 -2.10783002 0 P 0 
L 1.07803002 -2.10683002 1.20661998 -2.10683002 0 P 0 
L 1.07723996 -2.10583002 1.20666998 -2.10583002 0 P 0 
L 1.07646004 -2.10483002 1.20671998 -2.10483002 0 P 0 
L 1.07568002 -2.10383002 1.20678002 -2.10383002 0 P 0 
L 1.075 -2.10283002 1.20683002 -2.10283002 0 P 0 
L 1.07433002 -2.10183002 1.20688002 -2.10183002 0 P 0 
L 1.07366998 -2.10083002 1.20693996 -2.10083002 0 P 0 
L 1.07308996 -2.09983002 1.20698996 -2.09983002 0 P 0 
L 1.07253002 -2.09883002 1.20705 -2.09883002 0 P 0 
L 1.07198002 -2.09783002 1.2071 -2.09783002 0 P 0 
L 1.07146998 -2.09683002 1.20715 -2.09683002 0 P 0 
L 1.07101998 -2.09583002 1.2072 -2.09583002 0 P 0 
L 1.07056998 -2.09483002 1.20726004 -2.09483002 0 P 0 
L 1.07013002 -2.09383002 1.20731004 -2.09383002 0 P 0 
L 1.06976998 -2.09283002 1.20736004 -2.09283002 0 P 0 
L 1.06941998 -2.09183002 1.20741998 -2.09183002 0 P 0 
L 1.06906004 -2.09083002 1.20746998 -2.09083002 0 P 0 
L 1.06876004 -2.08983002 1.20753002 -2.08983002 0 P 0 
L 1.06848996 -2.08883002 1.13443002 -2.08883002 0 P 0 
L 1.06821998 -2.08783002 1.13068002 -2.08783002 0 P 0 
L 1.06795 -2.08683002 1.12836998 -2.08683002 0 P 0 
L 1.06771998 -2.08583002 1.1266 -2.08583002 0 P 0 
L 1.06753002 -2.08483002 1.12516004 -2.08483002 0 P 0 
L 1.06733002 -2.08383002 1.12393996 -2.08383002 0 P 0 
L 0.90273996 -1.85456998 0.89068996 -1.85558002 0 P 0 
L 0.89068996 -1.85558002 0.87421004 -1.85741998 0 P 0 
L 0.87421004 -1.85741998 0.85783002 -1.85946998 0 P 0 
L 0.85783002 -1.85946998 0.85526998 -1.8599 0 P 0 
L 0.85526998 -1.8599 0.85276004 -1.86055 0 P 0 
L 0.85276004 -1.86055 0.85255 -1.86063996 0 P 0 
L 0.85255 -1.86063996 0.85248996 -1.86068996 0 P 0 
L 0.85248996 -1.86068996 0.85243002 -1.86073002 0 P 0 
L 0.85243002 -1.86073002 0.85238002 -1.86078002 0 P 0 
L 0.85238002 -1.86078002 0.85233002 -1.86083996 0 P 0 
L 0.85233002 -1.86083996 0.85225 -1.86096004 0 P 0 
L 0.85225 -1.86096004 0.85218002 -1.8611 0 P 0 
L 0.85218002 -1.8611 0.85216004 -1.86116998 0 P 0 
L 0.85216004 -1.86116998 0.85215 -1.86123996 0 P 0 
L 0.85215 -1.86123996 0.85213996 -1.86136998 0 P 0 
L 0.85213996 -1.86136998 0.85213002 -1.86148996 0 P 0 
L 0.85213002 -1.86148996 0.85213996 -1.86161998 0 P 0 
L 0.85213996 -1.86161998 0.85215 -1.86173996 0 P 0 
L 0.85215 -1.86173996 0.85218002 -1.86186998 0 P 0 
L 0.85218002 -1.86186998 0.85221004 -1.86198996 0 P 0 
L 0.85221004 -1.86198996 0.85225 -1.8621 0 P 0 
L 0.85225 -1.8621 0.85231004 -1.86221998 0 P 0 
L 0.85231004 -1.86221998 0.85236998 -1.86233002 0 P 0 
L 0.85236998 -1.86233002 0.85281998 -1.863 0 P 0 
L 0.85281998 -1.863 0.8533 -1.86363996 0 P 0 
L 0.8533 -1.86363996 0.85383002 -1.86425 0 P 0 
L 0.85383002 -1.86425 0.85736004 -1.86801998 0 P 0 
L 0.85736004 -1.86801998 0.86013002 -1.87113002 0 P 0 
L 0.86013002 -1.87113002 0.86266004 -1.87443002 0 P 0 
L 0.86266004 -1.87443002 0.86501004 -1.87798996 0 P 0 
L 0.86501004 -1.87798996 0.86711998 -1.88171004 0 P 0 
L 0.86711998 -1.88171004 0.86896998 -1.88553996 0 P 0 
L 0.86896998 -1.88553996 0.87055 -1.8895 0 P 0 
L 0.87055 -1.8895 0.8718 -1.89343002 0 P 0 
L 0.8718 -1.89343002 0.87276004 -1.89745 0 P 0 
L 0.87276004 -1.89745 0.87371004 -1.90195 0 P 0 
L 0.87371004 -1.90195 0.87383002 -1.90236004 0 P 0 
L 0.87383002 -1.90236004 0.87396998 -1.90276004 0 P 0 
L 0.87396998 -1.90276004 0.87416004 -1.90313996 0 P 0 
L 0.87416004 -1.90313996 0.87436998 -1.90351004 0 P 0 
L 0.87436998 -1.90351004 0.87443002 -1.9036 0 P 0 
L 0.87443002 -1.9036 0.87456998 -1.90376004 0 P 0 
L 0.87456998 -1.90376004 0.87465 -1.90381998 0 P 0 
L 0.87465 -1.90381998 0.87473002 -1.90388996 0 P 0 
L 0.87473002 -1.90388996 0.87481998 -1.90393996 0 P 0 
L 0.87481998 -1.90393996 0.87491998 -1.90398996 0 P 0 
L 0.87491998 -1.90398996 0.87501004 -1.90403002 0 P 0 
L 0.87501004 -1.90403002 0.87521004 -1.90408996 0 P 0 
L 0.87521004 -1.90408996 0.87531998 -1.9041 0 P 0 
L 0.87531998 -1.9041 0.87573002 -1.90413002 0 P 0 
L 0.87573002 -1.90413002 0.87613996 -1.90411998 0 P 0 
L 0.87613996 -1.90411998 0.87653996 -1.90408002 0 P 0 
L 0.87653996 -1.90408002 0.87695 -1.90401004 0 P 0 
L 0.87695 -1.90401004 0.90756004 -1.89766998 0 P 0 
L 0.90756004 -1.89766998 0.92603996 -1.89478002 0 P 0 
L 0.92603996 -1.89478002 0.93486004 -1.89393996 0 P 0 
L 0.93486004 -1.89393996 0.94371004 -1.8935 0 P 0 
L 0.94371004 -1.8935 0.97045 -1.89308002 0 P 0 
L 0.97045 -1.89308002 0.99468996 -1.89328996 0 P 0 
L 0.99468996 -1.89328996 1.01021004 -1.89413996 0 P 0 
L 1.01021004 -1.89413996 1.0241 -1.89601998 0 P 0 
L 1.0241 -1.89601998 1.04188002 -1.89961004 0 P 0 
L 1.04188002 -1.89961004 1.06095 -1.90466004 0 P 0 
L 1.06095 -1.90466004 1.07963996 -1.91123002 0 P 0 
L 1.07963996 -1.91123002 1.09093996 -1.91613002 0 P 0 
L 1.09093996 -1.91613002 1.10186998 -1.92175 0 P 0 
L 1.10186998 -1.92175 1.11243996 -1.92806998 0 P 0 
L 1.11243996 -1.92806998 1.12163002 -1.93446998 0 P 0 
L 1.12163002 -1.93446998 1.13033002 -1.94148996 0 P 0 
L 1.13033002 -1.94148996 1.1385 -1.94911004 0 P 0 
L 1.1385 -1.94911004 1.14358996 -1.9546 0 P 0 
L 1.14358996 -1.9546 1.14825 -1.96045 0 P 0 
L 1.14825 -1.96045 1.15246998 -1.96663002 0 P 0 
L 1.15246998 -1.96663002 1.15623002 -1.97316004 0 P 0 
L 1.15623002 -1.97316004 1.15895 -1.97831004 0 P 0 
L 1.15895 -1.97831004 1.17358996 -1.97831004 0 P 0 
L 1.17358996 -1.97831004 1.17135 -1.9726 0 P 0 
L 1.17135 -1.9726 1.16696004 -1.96266998 0 P 0 
L 1.16696004 -1.96266998 1.16171998 -1.95313002 0 P 0 
L 1.16171998 -1.95313002 1.1557 -1.94406998 0 P 0 
L 1.1557 -1.94406998 1.14885 -1.93548002 0 P 0 
L 1.14885 -1.93548002 1.13778996 -1.92378002 0 P 0 
L 1.13778996 -1.92378002 1.12576998 -1.91301998 0 P 0 
L 1.12576998 -1.91301998 1.11283996 -1.90326004 0 P 0 
L 1.11283996 -1.90326004 1.09783002 -1.89368996 0 P 0 
L 1.09783002 -1.89368996 1.08213002 -1.88526998 0 P 0 
L 1.08213002 -1.88526998 1.06576998 -1.87801004 0 P 0 
L 1.06576998 -1.87801004 1.04776004 -1.87141998 0 P 0 
L 1.04776004 -1.87141998 1.02938002 -1.86591998 0 P 0 
L 1.02938002 -1.86591998 1.01058002 -1.8615 0 P 0 
L 1.01058002 -1.8615 0.98441998 -1.85711004 0 P 0 
L 0.98441998 -1.85711004 0.95781004 -1.85448996 0 P 0 
L 0.95781004 -1.85448996 0.93061004 -1.85366004 0 P 0 
L 0.93061004 -1.85366004 0.90273996 -1.85456998 0 P 0 
L 1.16015 -1.97631004 1.15798002 -1.97218996 0 P 0 
L 1.15798002 -1.97218996 1.15796004 -1.97216004 0 P 0 
L 1.15796004 -1.97216004 1.15416004 -1.96556998 0 P 0 
L 1.15416004 -1.96556998 1.15411998 -1.96551004 0 P 0 
L 1.15411998 -1.96551004 1.14986004 -1.95926004 0 P 0 
L 1.14986004 -1.95926004 1.14981998 -1.95921004 0 P 0 
L 1.14981998 -1.95921004 1.14511004 -1.9533 0 P 0 
L 1.14511004 -1.9533 1.13991998 -1.9477 0 P 0 
L 1.13991998 -1.9477 1.13986004 -1.94765 0 P 0 
L 1.13986004 -1.94765 1.13163996 -1.93998002 0 P 0 
L 1.13163996 -1.93998002 1.12283002 -1.93286004 0 P 0 
L 1.12283002 -1.93286004 1.11351998 -1.92638996 0 P 0 
L 1.11351998 -1.92638996 1.10283996 -1.92 0 P 0 
L 1.10283996 -1.92 1.0918 -1.91433002 0 P 0 
L 1.0918 -1.91433002 1.08036998 -1.90936004 0 P 0 
L 1.08036998 -1.90936004 1.06153002 -1.90273996 0 P 0 
L 1.06153002 -1.90273996 1.06146004 -1.90273002 0 P 0 
L 1.06146004 -1.90273002 1.04233002 -1.89766004 0 P 0 
L 1.04233002 -1.89766004 1.02443002 -1.89405 0 P 0 
L 1.02443002 -1.89405 1.0104 -1.89213996 0 P 0 
L 1.0104 -1.89213996 0.99475 -1.89128996 0 P 0 
L 0.99475 -1.89128996 0.97045 -1.89108002 0 P 0 
L 0.97045 -1.89108002 0.94365 -1.8915 0 P 0 
L 0.94365 -1.8915 0.94361998 -1.8915 0 P 0 
L 0.94361998 -1.8915 0.93471998 -1.89195 0 P 0 
L 0.93471998 -1.89195 0.92578996 -1.89278996 0 P 0 
L 0.92578996 -1.89278996 0.9072 -1.89571004 0 P 0 
L 0.9072 -1.89571004 0.87656998 -1.90203996 0 P 0 
L 0.87656998 -1.90203996 0.87626998 -1.9021 0 P 0 
L 0.87626998 -1.9021 0.87601998 -1.90211998 0 P 0 
L 0.87601998 -1.90211998 0.87588996 -1.90213002 0 P 0 
L 0.87588996 -1.90213002 0.87583002 -1.90198996 0 P 0 
L 0.87583002 -1.90198996 0.87573002 -1.90175 0 P 0 
L 0.87573002 -1.90175 0.87566004 -1.90146998 0 P 0 
L 0.87566004 -1.90146998 0.87471004 -1.89701004 0 P 0 
L 0.87471004 -1.89701004 0.8747 -1.89698996 0 P 0 
L 0.8747 -1.89698996 0.87373002 -1.89288996 0 P 0 
L 0.87373002 -1.89288996 0.87243002 -1.88881998 0 P 0 
L 0.87243002 -1.88881998 0.8724 -1.88876004 0 P 0 
L 0.8724 -1.88876004 0.8708 -1.88473996 0 P 0 
L 0.8708 -1.88473996 0.8689 -1.88078002 0 P 0 
L 0.8689 -1.88078002 0.86671998 -1.87693996 0 P 0 
L 0.86671998 -1.87693996 0.86428996 -1.87326004 0 P 0 
L 0.86428996 -1.87326004 0.86166998 -1.86985 0 P 0 
L 0.86166998 -1.86985 0.85883996 -1.86668002 0 P 0 
L 0.85883996 -1.86668002 0.85883002 -1.86666004 0 P 0 
L 0.85883002 -1.86666004 0.85531998 -1.86291004 0 P 0 
L 0.85531998 -1.86291004 0.85486004 -1.86238002 0 P 0 
L 0.85486004 -1.86238002 0.85466004 -1.86211998 0 P 0 
L 0.85466004 -1.86211998 0.8557 -1.86186004 0 P 0 
L 0.8557 -1.86186004 0.85811998 -1.86145 0 P 0 
L 0.85811998 -1.86145 0.87443996 -1.85941004 0 P 0 
L 0.87443996 -1.85941004 0.89088996 -1.85756998 0 P 0 
L 0.89088996 -1.85756998 0.90286004 -1.85656998 0 P 0 
L 0.90286004 -1.85656998 0.93061004 -1.85566004 0 P 0 
L 0.93061004 -1.85566004 0.95768002 -1.85648996 0 P 0 
L 0.95768002 -1.85648996 0.98416004 -1.8591 0 P 0 
L 0.98416004 -1.8591 1.01018996 -1.86346004 0 P 0 
L 1.01018996 -1.86346004 1.02886004 -1.86785 0 P 0 
L 1.02886004 -1.86785 1.04711998 -1.87331998 0 P 0 
L 1.04711998 -1.87331998 1.06501004 -1.87986004 0 P 0 
L 1.06501004 -1.87986004 1.08125 -1.88706998 0 P 0 
L 1.08125 -1.88706998 1.09681004 -1.89541998 0 P 0 
L 1.09681004 -1.89541998 1.1117 -1.9049 0 P 0 
L 1.1117 -1.9049 1.1245 -1.91456998 0 P 0 
L 1.1245 -1.91456998 1.13638996 -1.92521004 0 P 0 
L 1.13638996 -1.92521004 1.14733996 -1.93678996 0 P 0 
L 1.14733996 -1.93678996 1.15408002 -1.94525 0 P 0 
L 1.15408002 -1.94525 1.16001004 -1.95416998 0 P 0 
L 1.16001004 -1.95416998 1.16516004 -1.96355 0 P 0 
L 1.16516004 -1.96355 1.1695 -1.97336998 0 P 0 
L 1.1695 -1.97336998 1.17066004 -1.97631004 0 P 0 
L 1.17066004 -1.97631004 1.16015 -1.97631004 0 P 0 
L 0.87563002 -1.90131004 0.8801 -1.90131004 0 P 0 
L 0.87541004 -1.90031004 0.88493996 -1.90031004 0 P 0 
L 0.8752 -1.89931004 0.88976998 -1.89931004 0 P 0 
L 0.87498996 -1.89831004 0.8946 -1.89831004 0 P 0 
L 0.89423002 -2.08316004 0.94355 -2.08316004 0 P 0 
L 0.89428996 -2.08216004 0.9436 -2.08216004 0 P 0 
L 0.89435 -2.08116004 0.94365 -2.08116004 0 P 0 
L 0.89441004 -2.08016004 0.9437 -2.08016004 0 P 0 
L 0.89446004 -2.07916004 0.94375 -2.07916004 0 P 0 
L 0.89451998 -2.07816004 0.94378996 -2.07816004 0 P 0 
L 0.89458002 -2.07716004 0.94383996 -2.07716004 0 P 0 
L 0.89463996 -2.07616004 0.94388996 -2.07616004 0 P 0 
L 0.8947 -2.07516004 0.94393996 -2.07516004 0 P 0 
L 0.89475 -2.07416004 0.94398002 -2.07416004 0 P 0 
L 0.89481004 -2.07316004 0.94403002 -2.07316004 0 P 0 
L 0.89486998 -2.07216004 0.94408002 -2.07216004 0 P 0 
L 0.89493002 -2.07116004 0.94415 -2.07116004 0 P 0 
L 0.89498996 -2.07016004 0.94426004 -2.07016004 0 P 0 
L 0.89505 -2.06916004 0.94436998 -2.06916004 0 P 0 
L 0.8951 -2.06816004 0.94448002 -2.06816004 0 P 0 
L 0.89516004 -2.06716004 0.94458996 -2.06716004 0 P 0 
L 0.89521998 -2.06616004 0.9447 -2.06616004 0 P 0 
L 0.89526998 -2.06516004 0.94481004 -2.06516004 0 P 0 
L 0.89531004 -2.06416004 0.94491998 -2.06416004 0 P 0 
L 0.89535 -2.06316004 0.94503002 -2.06316004 0 P 0 
L 0.8954 -2.06216004 0.94513996 -2.06216004 0 P 0 
L 0.89543996 -2.06116004 0.94531998 -2.06116004 0 P 0 
L 0.89548996 -2.06016004 0.94551004 -2.06016004 0 P 0 
L 0.89553002 -2.05916004 0.9457 -2.05916004 0 P 0 
L 0.89558002 -2.05816004 0.94588996 -2.05816004 0 P 0 
L 0.89561998 -2.05716004 0.94608002 -2.05716004 0 P 0 
L 0.89566998 -2.05616004 0.94626998 -2.05616004 0 P 0 
L 0.89571004 -2.05516004 0.94646998 -2.05516004 0 P 0 
L 0.89575 -2.05416004 0.94666004 -2.05416004 0 P 0 
L 0.8958 -2.05316004 0.94685 -2.05316004 0 P 0 
L 0.89583996 -2.05216004 0.94708002 -2.05216004 0 P 0 
L 0.89588996 -2.05116004 0.94735 -2.05116004 0 P 0 
L 0.89593996 -2.05016004 0.94761998 -2.05016004 0 P 0 
L 0.89598002 -2.04916004 0.9479 -2.04916004 0 P 0 
L 0.89601998 -2.04816004 0.94825 -2.04816004 0 P 0 
L 0.89606998 -2.04716004 0.94858996 -2.04716004 0 P 0 
L 0.89611004 -2.04616004 0.94893002 -2.04616004 0 P 0 
L 0.89616004 -2.04516004 0.94935 -2.04516004 0 P 0 
L 0.8962 -2.04416004 0.94976998 -2.04416004 0 P 0 
L 0.89625 -2.04316004 0.9502 -2.04316004 0 P 0 
L 0.89628002 -2.04216004 0.95068996 -2.04216004 0 P 0 
L 0.89631004 -2.04116004 0.95118996 -2.04116004 0 P 0 
L 0.89633996 -2.04016004 0.95168996 -2.04016004 0 P 0 
L 0.89638002 -2.03916004 0.95228002 -2.03916004 0 P 0 
L 0.89641004 -2.03816004 0.95291004 -2.03816004 0 P 0 
L 0.89643996 -2.03716004 0.95363002 -2.03716004 0 P 0 
L 0.89646998 -2.03616004 0.95445 -2.03616004 0 P 0 
L 0.89651004 -2.03516004 0.95535 -2.03516004 0 P 0 
L 0.89653996 -2.03416004 0.95636998 -2.03416004 0 P 0 
L 0.89656998 -2.03316004 0.95756998 -2.03316004 0 P 0 
L 0.8966 -2.03216004 0.95893996 -2.03216004 0 P 0 
L 0.89663996 -2.03116004 0.96055 -2.03116004 0 P 0 
L 0.89666998 -2.03016004 0.96278002 -2.03016004 0 P 0 
L 0.8967 -2.02916004 0.96676004 -2.02916004 0 P 0 
L 0.89673996 -2.02816004 1.03838996 -2.02816004 0 P 0 
L 0.89676998 -2.02716004 1.03838002 -2.02716004 0 P 0 
L 0.8968 -2.02616004 1.03833996 -2.02616004 0 P 0 
L 0.89683996 -2.02516004 1.03828996 -2.02516004 0 P 0 
L 0.89686998 -2.02416004 1.03823002 -2.02416004 0 P 0 
L 0.8969 -2.02316004 1.03816004 -2.02316004 0 P 0 
L 0.89693996 -2.02216004 1.0381 -2.02216004 0 P 0 
L 0.89696998 -2.02116004 1.03803996 -2.02116004 0 P 0 
L 0.897 -2.02016004 1.0379 -2.02016004 0 P 0 
L 0.89703002 -2.01916004 1.03773996 -2.01916004 0 P 0 
L 0.89706004 -2.01816004 1.03751998 -2.01816004 0 P 0 
L 0.89708996 -2.01716004 1.03728002 -2.01716004 0 P 0 
L 0.89711998 -2.01616004 1.03698996 -2.01616004 0 P 0 
L 0.89713996 -2.01516004 1.03668002 -2.01516004 0 P 0 
L 0.89716998 -2.01416004 1.03631004 -2.01416004 0 P 0 
L 0.8972 -2.01316004 1.03591998 -2.01316004 0 P 0 
L 0.89721998 -2.01216004 1.03548996 -2.01216004 0 P 0 
L 0.89725 -2.01116004 1.03505 -2.01116004 0 P 0 
L 0.89726998 -2.01016004 1.03458002 -2.01016004 0 P 0 
L 0.8973 -2.00916004 1.03405 -2.00916004 0 P 0 
L 0.89733002 -2.00816004 1.03351998 -2.00816004 0 P 0 
L 0.89736004 -2.00716004 0.94676004 -2.00716004 0 P 0 
L 0.89738002 -2.00616004 0.9461 -2.00616004 0 P 0 
L 0.89741004 -2.00516004 0.94563996 -2.00516004 0 P 0 
L 0.89743996 -2.00416004 0.94563996 -2.00416004 0 P 0 
L 0.89746004 -2.00316004 0.94563996 -2.00316004 0 P 0 
L 0.89748996 -2.00216004 0.94563996 -2.00216004 0 P 0 
L 0.89751004 -2.00116004 0.94563996 -2.00116004 0 P 0 
L 0.89753996 -2.00016004 0.94563996 -2.00016004 0 P 0 
L 0.89756998 -1.99916004 0.94563996 -1.99916004 0 P 0 
L 0.8976 -1.99816004 0.94563996 -1.99816004 0 P 0 
L 0.89761998 -1.99716004 0.94563996 -1.99716004 0 P 0 
L 0.89765 -1.99616004 0.94563996 -1.99616004 0 P 0 
L 0.89768002 -1.99516004 0.94563996 -1.99516004 0 P 0 
L 0.97546998 -1.98933996 0.97236998 -1.99006004 0 P 0 
L 0.97236998 -1.99006004 0.96931998 -1.99103002 0 P 0 
L 0.96931998 -1.99103002 0.96603002 -1.99233002 0 P 0 
L 0.96603002 -1.99233002 0.96281004 -1.99383002 0 P 0 
L 0.96281004 -1.99383002 0.95976004 -1.99546998 0 P 0 
L 0.95976004 -1.99546998 0.95681004 -1.99728996 0 P 0 
L 0.95681004 -1.99728996 0.95521004 -1.99841004 0 P 0 
L 0.95521004 -1.99841004 0.95368996 -1.99963002 0 P 0 
L 0.95368996 -1.99963002 0.95223996 -2.00095 0 P 0 
L 0.95223996 -2.00095 0.94763996 -2.00546998 0 P 0 
L 0.94763996 -2.00546998 0.94763996 -1.99243996 0 P 0 
L 0.94763996 -1.99243996 0.89575 -1.99243996 0 P 0 
L 0.89575 -1.99243996 0.89505 -2.01878002 0 P 0 
L 0.89505 -2.01878002 0.89423996 -2.04316004 0 P 0 
L 0.89423996 -2.04316004 0.89321998 -2.0661 0 P 0 
L 0.89321998 -2.0661 0.89198996 -2.08728996 0 P 0 
L 0.89198996 -2.08728996 0.89055 -2.1063 0 P 0 
L 0.89055 -2.1063 0.88993996 -2.11358002 0 P 0 
L 0.88993996 -2.11358002 0.88943002 -2.11988002 0 P 0 
L 0.88943002 -2.11988002 0.88898996 -2.12533996 0 P 0 
L 0.88898996 -2.12533996 0.88896004 -2.12613002 0 P 0 
L 0.88896004 -2.12613002 0.88896998 -2.12621004 0 P 0 
L 0.88896998 -2.12621004 0.88898002 -2.12625 0 P 0 
L 0.88898002 -2.12625 0.88898996 -2.12628002 0 P 0 
L 0.88898996 -2.12628002 0.88901998 -2.12636004 0 P 0 
L 0.88901998 -2.12636004 0.88903996 -2.12638996 0 P 0 
L 0.88903996 -2.12638996 0.88906998 -2.12641998 0 P 0 
L 0.88906998 -2.12641998 0.88908996 -2.12645 0 P 0 
L 0.88908996 -2.12645 0.88911998 -2.12646998 0 P 0 
L 0.88911998 -2.12646998 0.88915 -2.1265 0 P 0 
L 0.88915 -2.1265 0.88921004 -2.12653996 0 P 0 
L 0.88921004 -2.12653996 0.88925 -2.12655 0 P 0 
L 0.88925 -2.12655 0.88928002 -2.12656004 0 P 0 
L 0.88928002 -2.12656004 0.88931998 -2.12658002 0 P 0 
L 0.88931998 -2.12658002 0.8894 -2.12658002 0 P 0 
L 0.8894 -2.12658002 0.89648002 -2.12686998 0 P 0 
L 0.89648002 -2.12686998 0.90518996 -2.1271 0 P 0 
L 0.90518996 -2.1271 0.9165 -2.12716004 0 P 0 
L 0.9165 -2.12716004 0.94403996 -2.12716004 0 P 0 
L 0.94403996 -2.12716004 0.94468996 -2.10135 0 P 0 
L 0.94468996 -2.10135 0.9461 -2.07171998 0 P 0 
L 0.9461 -2.07171998 0.94713002 -2.06233002 0 P 0 
L 0.94713002 -2.06233002 0.9489 -2.05308002 0 P 0 
L 0.9489 -2.05308002 0.94975 -2.04995 0 P 0 
L 0.94975 -2.04995 0.9508 -2.04688996 0 P 0 
L 0.9508 -2.04688996 0.95205 -2.0439 0 P 0 
L 0.95205 -2.0439 0.95351004 -2.041 0 P 0 
L 0.95351004 -2.041 0.9544 -2.03951004 0 P 0 
L 0.9544 -2.03951004 0.95541998 -2.03811004 0 P 0 
L 0.95541998 -2.03811004 0.95655 -2.03678996 0 P 0 
L 0.95655 -2.03678996 0.95778996 -2.03556998 0 P 0 
L 0.95778996 -2.03556998 0.95911998 -2.03446998 0 P 0 
L 0.95911998 -2.03446998 0.96056998 -2.03346998 0 P 0 
L 0.96056998 -2.03346998 0.96151004 -2.03291004 0 P 0 
L 0.96151004 -2.03291004 0.96248996 -2.03243002 0 P 0 
L 0.96248996 -2.03243002 0.96351004 -2.03201998 0 P 0 
L 0.96351004 -2.03201998 0.96455 -2.03168996 0 P 0 
L 0.96455 -2.03168996 0.96613002 -2.0313 0 P 0 
L 0.96613002 -2.0313 0.96773002 -2.03101998 0 P 0 
L 0.96773002 -2.03101998 0.96935 -2.03086004 0 P 0 
L 0.96935 -2.03086004 0.97095 -2.03081004 0 P 0 
L 0.97095 -2.03081004 0.97255 -2.03086998 0 P 0 
L 0.97255 -2.03086998 0.97413002 -2.03105 0 P 0 
L 0.97413002 -2.03105 0.97513002 -2.03123996 0 P 0 
L 0.97513002 -2.03123996 0.9761 -2.03151004 0 P 0 
L 0.9761 -2.03151004 0.97706004 -2.03186004 0 P 0 
L 0.97706004 -2.03186004 0.97796998 -2.0323 0 P 0 
L 0.97796998 -2.0323 0.97885 -2.0328 0 P 0 
L 0.97885 -2.0328 0.97968002 -2.03336998 0 P 0 
L 0.97968002 -2.03336998 0.98046998 -2.03398996 0 P 0 
L 0.98046998 -2.03398996 0.98121998 -2.03468002 0 P 0 
L 0.98121998 -2.03468002 0.98191004 -2.03541998 0 P 0 
L 0.98191004 -2.03541998 0.98253996 -2.0362 0 P 0 
L 0.98253996 -2.0362 0.9831 -2.03703002 0 P 0 
L 0.9831 -2.03703002 0.9836 -2.03788996 0 P 0 
L 0.9836 -2.03788996 0.98403996 -2.0388 0 P 0 
L 0.98403996 -2.0388 0.9844 -2.03973996 0 P 0 
L 0.9844 -2.03973996 0.98505 -2.04188996 0 P 0 
L 0.98505 -2.04188996 0.98553002 -2.04408002 0 P 0 
L 0.98553002 -2.04408002 0.98583002 -2.0463 0 P 0 
L 0.98583002 -2.0463 0.98653002 -2.05705 0 P 0 
L 0.98653002 -2.05705 0.9866 -2.06961004 0 P 0 
L 0.9866 -2.06961004 0.98596004 -2.08908002 0 P 0 
L 0.98596004 -2.08908002 0.98498002 -2.10858002 0 P 0 
L 0.98498002 -2.10858002 0.98388002 -2.12146998 0 P 0 
L 0.98388002 -2.12146998 0.98323002 -2.12716004 0 P 0 
L 0.98323002 -2.12716004 1.03741004 -2.12716004 0 P 0 
L 1.03741004 -2.12716004 1.03896004 -2.09103002 0 P 0 
L 1.03896004 -2.09103002 1.03956004 -2.0759 0 P 0 
L 1.03956004 -2.0759 1.04005 -2.06025 0 P 0 
L 1.04005 -2.06025 1.04038996 -2.04626004 0 P 0 
L 1.04038996 -2.04626004 1.04048002 -2.03698996 0 P 0 
L 1.04048002 -2.03698996 1.04036998 -2.02651998 0 P 0 
L 1.04036998 -2.02651998 1.04003996 -2.02096998 0 P 0 
L 1.04003996 -2.02096998 1.03975 -2.01895 0 P 0 
L 1.03975 -2.01895 1.0393 -2.01693996 0 P 0 
L 1.0393 -2.01693996 1.03868996 -2.01483996 0 P 0 
L 1.03868996 -2.01483996 1.03793996 -2.01278002 0 P 0 
L 1.03793996 -2.01278002 1.03658996 -2.00968002 0 P 0 
L 1.03658996 -2.00968002 1.03501004 -2.00668996 0 P 0 
L 1.03501004 -2.00668996 1.0332 -2.0038 0 P 0 
L 1.0332 -2.0038 1.03186998 -2.002 0 P 0 
L 1.03186998 -2.002 1.0304 -2.0003 0 P 0 
L 1.0304 -2.0003 1.0288 -1.99873002 0 P 0 
L 1.0288 -1.99873002 1.02708002 -1.99728996 0 P 0 
L 1.02708002 -1.99728996 1.02518002 -1.99593002 0 P 0 
L 1.02518002 -1.99593002 1.02318002 -1.99471998 0 P 0 
L 1.02318002 -1.99471998 1.0211 -1.99365 0 P 0 
L 1.0211 -1.99365 1.01893002 -1.99273996 0 P 0 
L 1.01893002 -1.99273996 1.01358996 -1.99098996 0 P 0 
L 1.01358996 -1.99098996 1.0081 -1.98971004 0 P 0 
L 1.0081 -1.98971004 1.00428996 -1.98908996 0 P 0 
L 1.00428996 -1.98908996 1.00043996 -1.98868002 0 P 0 
L 1.00043996 -1.98868002 0.99138002 -1.98826004 0 P 0 
L 0.99138002 -1.98826004 0.98251998 -1.98846998 0 P 0 
L 0.98251998 -1.98846998 0.97898996 -1.98878996 0 P 0 
L 0.97898996 -1.98878996 0.97546998 -1.98933996 0 P 0 
L 0.91651004 -2.12516004 0.94208996 -2.12516004 0 P 0 
L 0.8911 -2.12416004 0.94211004 -2.12416004 0 P 0 
L 0.89118002 -2.12316004 0.94213996 -2.12316004 0 P 0 
L 0.89125 -2.12216004 0.94216004 -2.12216004 0 P 0 
L 0.89133002 -2.12116004 0.94218996 -2.12116004 0 P 0 
L 0.89141004 -2.12016004 0.94221004 -2.12016004 0 P 0 
L 0.89148996 -2.11916004 0.94223996 -2.11916004 0 P 0 
L 0.89156998 -2.11816004 0.94226998 -2.11816004 0 P 0 
L 0.89166004 -2.11716004 0.94228996 -2.11716004 0 P 0 
L 0.89173996 -2.11616004 0.94231004 -2.11616004 0 P 0 
L 0.89181998 -2.11516004 0.94233996 -2.11516004 0 P 0 
L 0.8919 -2.11416004 0.94236004 -2.11416004 0 P 0 
L 0.89198002 -2.11316004 0.94238996 -2.11316004 0 P 0 
L 0.89206998 -2.11216004 0.94241998 -2.11216004 0 P 0 
L 0.89215 -2.11116004 0.94243996 -2.11116004 0 P 0 
L 0.89223002 -2.11016004 0.94246998 -2.11016004 0 P 0 
L 0.89231998 -2.10916004 0.94248996 -2.10916004 0 P 0 
L 0.8924 -2.10816004 0.94251998 -2.10816004 0 P 0 
L 0.89248002 -2.10716004 0.94255 -2.10716004 0 P 0 
L 0.89256998 -2.10616004 0.94256998 -2.10616004 0 P 0 
L 0.89263996 -2.10516004 0.94258996 -2.10516004 0 P 0 
L 0.89271004 -2.10416004 0.94261998 -2.10416004 0 P 0 
L 0.89278996 -2.10316004 0.94263996 -2.10316004 0 P 0 
L 0.89286998 -2.10216004 0.94266998 -2.10216004 0 P 0 
L 0.89293996 -2.10116004 0.9427 -2.10116004 0 P 0 
L 0.89301998 -2.10016004 0.94275 -2.10016004 0 P 0 
L 0.89308996 -2.09916004 0.94278996 -2.09916004 0 P 0 
L 0.89316998 -2.09816004 0.94283996 -2.09816004 0 P 0 
L 0.89325 -2.09716004 0.94288996 -2.09716004 0 P 0 
L 0.89331998 -2.09616004 0.94293996 -2.09616004 0 P 0 
L 0.8934 -2.09516004 0.94298002 -2.09516004 0 P 0 
L 0.89346998 -2.09416004 0.94303002 -2.09416004 0 P 0 
L 0.89355 -2.09316004 0.94308002 -2.09316004 0 P 0 
L 0.89361998 -2.09216004 0.94313002 -2.09216004 0 P 0 
L 0.8937 -2.09116004 0.94318002 -2.09116004 0 P 0 
L 0.89378002 -2.09016004 0.94321998 -2.09016004 0 P 0 
L 0.89385 -2.08916004 0.94326998 -2.08916004 0 P 0 
L 0.89393002 -2.08816004 0.94331998 -2.08816004 0 P 0 
L 0.894 -2.08716004 0.94336004 -2.08716004 0 P 0 
L 0.89406004 -2.08616004 0.94341004 -2.08616004 0 P 0 
L 0.89411998 -2.08516004 0.94346004 -2.08516004 0 P 0 
L 0.89418002 -2.08416004 0.94351004 -2.08416004 0 P 0 
L 0.91651004 -2.12516004 0.90521998 -2.1251 0 P 0 
L 0.90521998 -2.1251 0.89655 -2.12486998 0 P 0 
L 0.89655 -2.12486998 0.89106004 -2.12465 0 P 0 
L 0.89106004 -2.12465 0.89141998 -2.12003996 0 P 0 
L 0.89141998 -2.12003996 0.89193996 -2.11373996 0 P 0 
L 0.89193996 -2.11373996 0.89253996 -2.10645 0 P 0 
L 0.89253996 -2.10645 0.89398002 -2.08741998 0 P 0 
L 0.89398002 -2.08741998 0.89521998 -2.06621998 0 P 0 
L 0.89521998 -2.06621998 0.89521998 -2.06618996 0 P 0 
L 0.89521998 -2.06618996 0.89623996 -2.04323002 0 P 0 
L 0.89623996 -2.04323002 0.89703996 -2.01883002 0 P 0 
L 0.89703996 -2.01883002 0.8977 -1.99443996 0 P 0 
L 0.8977 -1.99443996 0.94563996 -1.99443996 0 P 0 
L 0.94563996 -1.99443996 0.94563996 -2.00546998 0 P 0 
L 0.94563996 -2.00546998 0.94686004 -2.00731004 0 P 0 
L 0.94686004 -2.00731004 0.94903002 -2.00688996 0 P 0 
L 0.94903002 -2.00688996 0.95361998 -2.00241004 0 P 0 
L 0.95361998 -2.00241004 0.95498996 -2.00115 0 P 0 
L 0.95498996 -2.00115 0.95641998 -2.00001004 0 P 0 
L 0.95641998 -2.00001004 0.9579 -1.99896004 0 P 0 
L 0.9579 -1.99896004 0.96076004 -1.9972 0 P 0 
L 0.96076004 -1.9972 0.9637 -1.99561998 0 P 0 
L 0.9637 -1.99561998 0.96683002 -1.99416998 0 P 0 
L 0.96683002 -1.99416998 0.96998996 -1.99291998 0 P 0 
L 0.96998996 -1.99291998 0.9729 -1.99198996 0 P 0 
L 0.9729 -1.99198996 0.97586004 -1.9913 0 P 0 
L 0.97586004 -1.9913 0.97923002 -1.99076998 0 P 0 
L 0.97923002 -1.99076998 0.98263002 -1.99046998 0 P 0 
L 0.98263002 -1.99046998 0.99136004 -1.99026004 0 P 0 
L 0.99136004 -1.99026004 1.00028996 -1.99066998 0 P 0 
L 1.00028996 -1.99066998 1.00403002 -1.99108002 0 P 0 
L 1.00403002 -1.99108002 1.00771004 -1.99166998 0 P 0 
L 1.00771004 -1.99166998 1.01305 -1.99291998 0 P 0 
L 1.01305 -1.99291998 1.01823002 -1.99461998 0 P 0 
L 1.01823002 -1.99461998 1.02026004 -1.99546998 0 P 0 
L 1.02026004 -1.99546998 1.02221004 -1.99646998 0 P 0 
L 1.02221004 -1.99646998 1.02408002 -1.9976 0 P 0 
L 1.02408002 -1.9976 1.02585 -1.99886998 0 P 0 
L 1.02585 -1.99886998 1.02746004 -2.00021004 0 P 0 
L 1.02746004 -2.00021004 1.02893996 -2.00166998 0 P 0 
L 1.02893996 -2.00166998 1.03031004 -2.00325 0 P 0 
L 1.03031004 -2.00325 1.03155 -2.00493002 0 P 0 
L 1.03155 -2.00493002 1.03326998 -2.00768002 0 P 0 
L 1.03326998 -2.00768002 1.03478002 -2.01055 0 P 0 
L 1.03478002 -2.01055 1.03608002 -2.01351998 0 P 0 
L 1.03608002 -2.01351998 1.03678996 -2.01546998 0 P 0 
L 1.03678996 -2.01546998 1.03736004 -2.01743002 0 P 0 
L 1.03736004 -2.01743002 1.03778002 -2.0193 0 P 0 
L 1.03778002 -2.0193 1.03805 -2.02116998 0 P 0 
L 1.03805 -2.02116998 1.03836998 -2.02658996 0 P 0 
L 1.03836998 -2.02658996 1.03848002 -2.03698996 0 P 0 
L 1.03848002 -2.03698996 1.03838996 -2.04623002 0 P 0 
L 1.03838996 -2.04623002 1.03805 -2.06018996 0 P 0 
L 1.03805 -2.06018996 1.03756004 -2.07583002 0 P 0 
L 1.03756004 -2.07583002 1.03696998 -2.09095 0 P 0 
L 1.03696998 -2.09095 1.03548996 -2.12516004 0 P 0 
L 1.03548996 -2.12516004 0.98546998 -2.12516004 0 P 0 
L 0.98546998 -2.12516004 0.98586998 -2.12166004 0 P 0 
L 0.98586998 -2.12166004 0.98696998 -2.10871998 0 P 0 
L 0.98696998 -2.10871998 0.98796004 -2.08916004 0 P 0 
L 0.98796004 -2.08916004 0.9886 -2.06963002 0 P 0 
L 0.9886 -2.06963002 0.98853002 -2.05698002 0 P 0 
L 0.98853002 -2.05698002 0.98781998 -2.0461 0 P 0 
L 0.98781998 -2.0461 0.9875 -2.04373002 0 P 0 
L 0.9875 -2.04373002 0.98748002 -2.04365 0 P 0 
L 0.98748002 -2.04365 0.98698996 -2.04138996 0 P 0 
L 0.98698996 -2.04138996 0.9863 -2.03908002 0 P 0 
L 0.9863 -2.03908002 0.98588002 -2.038 0 P 0 
L 0.98588002 -2.038 0.98538002 -2.03696004 0 P 0 
L 0.98538002 -2.03696004 0.9848 -2.03596004 0 P 0 
L 0.9848 -2.03596004 0.98413996 -2.03501004 0 P 0 
L 0.98413996 -2.03501004 0.98341998 -2.03411004 0 P 0 
L 0.98341998 -2.03411004 0.98336998 -2.03405 0 P 0 
L 0.98336998 -2.03405 0.98263002 -2.03326004 0 P 0 
L 0.98263002 -2.03326004 0.98176998 -2.03246998 0 P 0 
L 0.98176998 -2.03246998 0.98086998 -2.03175 0 P 0 
L 0.98086998 -2.03175 0.97991004 -2.0311 0 P 0 
L 0.97991004 -2.0311 0.9789 -2.03051998 0 P 0 
L 0.9789 -2.03051998 0.97783002 -2.03001998 0 P 0 
L 0.97783002 -2.03001998 0.97673002 -2.02961004 0 P 0 
L 0.97673002 -2.02961004 0.97663996 -2.02958002 0 P 0 
L 0.97663996 -2.02958002 0.97558996 -2.02928996 0 P 0 
L 0.97558996 -2.02928996 0.97443002 -2.02906998 0 P 0 
L 0.97443002 -2.02906998 0.9727 -2.02888002 0 P 0 
L 0.9727 -2.02888002 0.97261998 -2.02886998 0 P 0 
L 0.97261998 -2.02886998 0.97096004 -2.02881004 0 P 0 
L 0.97096004 -2.02881004 0.96921004 -2.02886004 0 P 0 
L 0.96921004 -2.02886004 0.96745 -2.02903996 0 P 0 
L 0.96745 -2.02903996 0.96571004 -2.02933996 0 P 0 
L 0.96571004 -2.02933996 0.964 -2.02976004 0 P 0 
L 0.964 -2.02976004 0.96283002 -2.03013996 0 P 0 
L 0.96283002 -2.03013996 0.96168002 -2.0306 0 P 0 
L 0.96168002 -2.0306 0.96056998 -2.03115 0 P 0 
L 0.96056998 -2.03115 0.95948996 -2.03178002 0 P 0 
L 0.95948996 -2.03178002 0.95791004 -2.03286998 0 P 0 
L 0.95791004 -2.03286998 0.95645 -2.03408996 0 P 0 
L 0.95645 -2.03408996 0.95508996 -2.03541998 0 P 0 
L 0.95508996 -2.03541998 0.95383996 -2.03686998 0 P 0 
L 0.95383996 -2.03686998 0.9538 -2.03693002 0 P 0 
L 0.9538 -2.03693002 0.95273002 -2.03841004 0 P 0 
L 0.95273002 -2.03841004 0.95175 -2.04003996 0 P 0 
L 0.95175 -2.04003996 0.95023002 -2.04306004 0 P 0 
L 0.95023002 -2.04306004 0.94896004 -2.04611004 0 P 0 
L 0.94896004 -2.04611004 0.94893002 -2.04616998 0 P 0 
L 0.94893002 -2.04616998 0.94783002 -2.04936004 0 P 0 
L 0.94783002 -2.04936004 0.94695 -2.05263002 0 P 0 
L 0.94695 -2.05263002 0.94515 -2.06203002 0 P 0 
L 0.94515 -2.06203002 0.9441 -2.07156004 0 P 0 
L 0.9441 -2.07156004 0.9427 -2.10128002 0 P 0 
L 0.9427 -2.10128002 0.94208996 -2.12516004 0 P 0 
L 0.94208996 -2.12516004 0.91651004 -2.12516004 0 P 0 
L 0.93143002 -2.21261998 1.00578996 -2.21261998 0 P 0 
L 0.94051004 -2.21161998 1.00803002 -2.21161998 0 P 0 
L 0.94941998 -2.21061998 1.01026004 -2.21061998 0 P 0 
L 0.9555 -2.20961998 1.0125 -2.20961998 0 P 0 
L 0.96158002 -2.20861998 1.01473996 -2.20861998 0 P 0 
L 0.96766004 -2.20761998 1.01696998 -2.20761998 0 P 0 
L 0.97373002 -2.20661998 1.01921004 -2.20661998 0 P 0 
L 0.97981004 -2.20561998 1.02145 -2.20561998 0 P 0 
L 0.98498996 -2.20461998 1.02368996 -2.20461998 0 P 0 
L 0.98973996 -2.20361998 1.02591998 -2.20361998 0 P 0 
L 0.99448996 -2.20261998 1.02816004 -2.20261998 0 P 0 
L 0.99923996 -2.20161998 1.0304 -2.20161998 0 P 0 
L 1.00398996 -2.20061998 1.03243996 -2.20061998 0 P 0 
L 1.00875 -2.19961998 1.0344 -2.19961998 0 P 0 
L 1.01348996 -2.19861998 1.03636998 -2.19861998 0 P 0 
L 1.0178 -2.19761998 1.03833996 -2.19761998 0 P 0 
L 1.02168996 -2.19661998 1.04031004 -2.19661998 0 P 0 
L 1.02558002 -2.19561998 1.04228002 -2.19561998 0 P 0 
L 1.02946998 -2.19461998 1.04415 -2.19461998 0 P 0 
L 1.03336004 -2.19361998 1.04596998 -2.19361998 0 P 0 
L 1.03725 -2.19261998 1.04778996 -2.19261998 0 P 0 
L 1.04113996 -2.19161998 1.0496 -2.19161998 0 P 0 
L 1.14356998 -1.98926998 1.13261004 -1.99086004 0 P 0 
L 1.13261004 -1.99086004 1.12165 -1.9934 0 P 0 
L 1.12165 -1.9934 1.11125 -1.99673002 0 P 0 
L 1.11125 -1.99673002 1.10658002 -1.99858996 0 P 0 
L 1.10658002 -1.99858996 1.10198996 -2.00071004 0 P 0 
L 1.10198996 -2.00071004 1.09653002 -2.00358996 0 P 0 
L 1.09653002 -2.00358996 1.09436998 -2.00488996 0 P 0 
L 1.09436998 -2.00488996 1.09226004 -2.00631004 0 P 0 
L 1.09226004 -2.00631004 1.09028002 -2.00781004 0 P 0 
L 1.09028002 -2.00781004 1.08836998 -2.00941998 0 P 0 
L 1.08836998 -2.00941998 1.08405 -2.0135 0 P 0 
L 1.08405 -2.0135 1.08096998 -2.01678996 0 P 0 
L 1.08096998 -2.01678996 1.07808002 -2.02026998 0 P 0 
L 1.07808002 -2.02026998 1.0754 -2.02393002 0 P 0 
L 1.0754 -2.02393002 1.07313996 -2.02748002 0 P 0 
L 1.07313996 -2.02748002 1.07116004 -2.03118996 0 P 0 
L 1.07116004 -2.03118996 1.06943996 -2.03505 0 P 0 
L 1.06943996 -2.03505 1.06795 -2.03918996 0 P 0 
L 1.06795 -2.03918996 1.06673996 -2.04343996 0 P 0 
L 1.06673996 -2.04343996 1.06583002 -2.04778002 0 P 0 
L 1.06583002 -2.04778002 1.06476998 -2.05538996 0 P 0 
L 1.06476998 -2.05538996 1.06421004 -2.06306004 0 P 0 
L 1.06421004 -2.06306004 1.06415 -2.07076004 0 P 0 
L 1.06415 -2.07076004 1.06456998 -2.0785 0 P 0 
L 1.06456998 -2.0785 1.06508996 -2.08276004 0 P 0 
L 1.06508996 -2.08276004 1.06591004 -2.08696004 0 P 0 
L 1.06591004 -2.08696004 1.06703002 -2.09108002 0 P 0 
L 1.06703002 -2.09108002 1.06833002 -2.09473002 0 P 0 
L 1.06833002 -2.09473002 1.06991998 -2.09823996 0 P 0 
L 1.06991998 -2.09823996 1.0718 -2.10161998 0 P 0 
L 1.0718 -2.10161998 1.07398002 -2.10491998 0 P 0 
L 1.07398002 -2.10491998 1.07641998 -2.10803002 0 P 0 
L 1.07641998 -2.10803002 1.07908996 -2.11095 0 P 0 
L 1.07908996 -2.11095 1.08175 -2.11345 0 P 0 
L 1.08175 -2.11345 1.08458996 -2.11573996 0 P 0 
L 1.08458996 -2.11573996 1.08758996 -2.1178 0 P 0 
L 1.08758996 -2.1178 1.09073002 -2.11963996 0 P 0 
L 1.09073002 -2.11963996 1.094 -2.12123996 0 P 0 
L 1.094 -2.12123996 1.0986 -2.12306998 0 P 0 
L 1.0986 -2.12306998 1.10331004 -2.12456004 0 P 0 
L 1.10331004 -2.12456004 1.10811004 -2.12568996 0 P 0 
L 1.10811004 -2.12568996 1.11298002 -2.12646998 0 P 0 
L 1.11298002 -2.12646998 1.1182 -2.12693002 0 P 0 
L 1.1182 -2.12693002 1.12343996 -2.12703002 0 P 0 
L 1.12343996 -2.12703002 1.12866998 -2.12676004 0 P 0 
L 1.12866998 -2.12676004 1.13388002 -2.12613002 0 P 0 
L 1.13388002 -2.12613002 1.14086004 -2.12473996 0 P 0 
L 1.14086004 -2.12473996 1.1477 -2.12273996 0 P 0 
L 1.1477 -2.12273996 1.15433996 -2.12015 0 P 0 
L 1.15433996 -2.12015 1.1545 -2.12008996 0 P 0 
L 1.1545 -2.12008996 1.15466004 -2.12003996 0 P 0 
L 1.15466004 -2.12003996 1.15483002 -2.12001004 0 P 0 
L 1.15483002 -2.12001004 1.15498996 -2.11998996 0 P 0 
L 1.15498996 -2.11998996 1.15533002 -2.11998996 0 P 0 
L 1.15533002 -2.11998996 1.15538996 -2.12 0 P 0 
L 1.15538996 -2.12 1.15545 -2.12001998 0 P 0 
L 1.15545 -2.12001998 1.15551004 -2.12003002 0 P 0 
L 1.15551004 -2.12003002 1.15556004 -2.12006004 0 P 0 
L 1.15556004 -2.12006004 1.15561004 -2.12008002 0 P 0 
L 1.15561004 -2.12008002 1.15566004 -2.12011004 0 P 0 
L 1.15566004 -2.12011004 1.15571004 -2.12015 0 P 0 
L 1.15571004 -2.12015 1.15575 -2.12018996 0 P 0 
L 1.15575 -2.12018996 1.15578996 -2.12023996 0 P 0 
L 1.15578996 -2.12023996 1.15583002 -2.12028002 0 P 0 
L 1.15583002 -2.12028002 1.15586004 -2.12033996 0 P 0 
L 1.15586004 -2.12033996 1.15588002 -2.12038996 0 P 0 
L 1.15588002 -2.12038996 1.15591004 -2.12043996 0 P 0 
L 1.15591004 -2.12043996 1.15601998 -2.12076004 0 P 0 
L 1.15601998 -2.12076004 1.1561 -2.12108002 0 P 0 
L 1.1561 -2.12108002 1.15616004 -2.12141998 0 P 0 
L 1.15616004 -2.12141998 1.15618002 -2.12175 0 P 0 
L 1.15618002 -2.12175 1.15623996 -2.12505 0 P 0 
L 1.15623996 -2.12505 1.15616004 -2.12688002 0 P 0 
L 1.15616004 -2.12688002 1.15593002 -2.12871004 0 P 0 
L 1.15593002 -2.12871004 1.15553996 -2.13051998 0 P 0 
L 1.15553996 -2.13051998 1.15516004 -2.1318 0 P 0 
L 1.15516004 -2.1318 1.1547 -2.13305 0 P 0 
L 1.1547 -2.13305 1.15415 -2.13426004 0 P 0 
L 1.15415 -2.13426004 1.15351004 -2.13545 0 P 0 
L 1.15351004 -2.13545 1.15278996 -2.1366 0 P 0 
L 1.15278996 -2.1366 1.15198002 -2.13768996 0 P 0 
L 1.15198002 -2.13768996 1.15111004 -2.13873002 0 P 0 
L 1.15111004 -2.13873002 1.15016004 -2.13971004 0 P 0 
L 1.15016004 -2.13971004 1.14876004 -2.14096004 0 P 0 
L 1.14876004 -2.14096004 1.14726004 -2.1421 0 P 0 
L 1.14726004 -2.1421 1.14566998 -2.14311004 0 P 0 
L 1.14566998 -2.14311004 1.144 -2.144 0 P 0 
L 1.144 -2.144 1.14226004 -2.14476004 0 P 0 
L 1.14226004 -2.14476004 1.14046004 -2.14536998 0 P 0 
L 1.14046004 -2.14536998 1.13863002 -2.14583002 0 P 0 
L 1.13863002 -2.14583002 1.13676004 -2.14613996 0 P 0 
L 1.13676004 -2.14613996 1.13041998 -2.14663996 0 P 0 
L 1.13041998 -2.14663996 1.12403996 -2.1466 0 P 0 
L 1.12403996 -2.1466 1.11621998 -2.14593996 0 P 0 
L 1.11621998 -2.14593996 1.10843996 -2.14471004 0 P 0 
L 1.10843996 -2.14471004 1.09946998 -2.14276998 0 P 0 
L 1.09946998 -2.14276998 1.0905 -2.14041004 0 P 0 
L 1.0905 -2.14041004 1.07963996 -2.13728996 0 P 0 
L 1.07963996 -2.13728996 1.07936004 -2.1401 0 P 0 
L 1.07936004 -2.1401 1.07931004 -2.14103996 0 P 0 
L 1.07931004 -2.14103996 1.07931998 -2.14198002 0 P 0 
L 1.07931998 -2.14198002 1.07956998 -2.14735 0 P 0 
L 1.07956998 -2.14735 1.07993996 -2.15375 0 P 0 
L 1.07993996 -2.15375 1.08045 -2.16081998 0 P 0 
L 1.08045 -2.16081998 1.08181004 -2.17873002 0 P 0 
L 1.08181004 -2.17873002 1.08996004 -2.18061004 0 P 0 
L 1.08996004 -2.18061004 1.09951004 -2.18246004 0 P 0 
L 1.09951004 -2.18246004 1.11243996 -2.18416998 0 P 0 
L 1.11243996 -2.18416998 1.1254 -2.18543002 0 P 0 
L 1.1254 -2.18543002 1.13508002 -2.18583002 0 P 0 
L 1.13508002 -2.18583002 1.14765 -2.18528996 0 P 0 
L 1.14765 -2.18528996 1.15368002 -2.18461004 0 P 0 
L 1.15368002 -2.18461004 1.15971004 -2.18363996 0 P 0 
L 1.15971004 -2.18363996 1.16521004 -2.18248002 0 P 0 
L 1.16521004 -2.18248002 1.17063996 -2.18103002 0 P 0 
L 1.17063996 -2.18103002 1.17528996 -2.17946998 0 P 0 
L 1.17528996 -2.17946998 1.17978002 -2.17753996 0 P 0 
L 1.17978002 -2.17753996 1.18216998 -2.1763 0 P 0 
L 1.18216998 -2.1763 1.18446004 -2.17488996 0 P 0 
L 1.18446004 -2.17488996 1.18663996 -2.17331004 0 P 0 
L 1.18663996 -2.17331004 1.18871004 -2.17156004 0 P 0 
L 1.18871004 -2.17156004 1.19161004 -2.16871998 0 P 0 
L 1.19161004 -2.16871998 1.19431004 -2.16568996 0 P 0 
L 1.19431004 -2.16568996 1.19678996 -2.16246998 0 P 0 
L 1.19678996 -2.16246998 1.19908996 -2.15901998 0 P 0 
L 1.19908996 -2.15901998 1.20113996 -2.15543996 0 P 0 
L 1.20113996 -2.15543996 1.20295 -2.15171004 0 P 0 
L 1.20295 -2.15171004 1.20435 -2.14815 0 P 0 
L 1.20435 -2.14815 1.20543996 -2.14448996 0 P 0 
L 1.20543996 -2.14448996 1.20621004 -2.14073996 0 P 0 
L 1.20621004 -2.14073996 1.20651998 -2.13855 0 P 0 
L 1.20651998 -2.13855 1.20671998 -2.13633996 0 P 0 
L 1.20671998 -2.13633996 1.20761998 -2.12321004 0 P 0 
L 1.20761998 -2.12321004 1.20858002 -2.10753996 0 P 0 
L 1.20858002 -2.10753996 1.20951004 -2.09021998 0 P 0 
L 1.20951004 -2.09021998 1.21048002 -2.07166004 0 P 0 
L 1.21048002 -2.07166004 1.21156004 -2.05228002 0 P 0 
L 1.21156004 -2.05228002 1.21258002 -2.03478996 0 P 0 
L 1.21258002 -2.03478996 1.21333002 -2.02286004 0 P 0 
L 1.21333002 -2.02286004 1.21393996 -2.01373996 0 P 0 
L 1.21393996 -2.01373996 1.21443996 -2.00568996 0 P 0 
L 1.21443996 -2.00568996 1.21485 -1.99883996 0 P 0 
L 1.21485 -1.99883996 1.2149 -1.99721004 0 P 0 
L 1.2149 -1.99721004 1.21488996 -1.99703996 0 P 0 
L 1.21488996 -1.99703996 1.21486998 -1.99686004 0 P 0 
L 1.21486998 -1.99686004 1.21483996 -1.99668996 0 P 0 
L 1.21483996 -1.99668996 1.21478996 -1.99653002 0 P 0 
L 1.21478996 -1.99653002 1.21473002 -1.99636998 0 P 0 
L 1.21473002 -1.99636998 1.21466004 -1.99621004 0 P 0 
L 1.21466004 -1.99621004 1.21458002 -1.99606004 0 P 0 
L 1.21458002 -1.99606004 1.21448002 -1.99591004 0 P 0 
L 1.21448002 -1.99591004 1.21433002 -1.99571998 0 P 0 
L 1.21433002 -1.99571998 1.21416998 -1.99553996 0 P 0 
L 1.21416998 -1.99553996 1.21398996 -1.99538002 0 P 0 
L 1.21398996 -1.99538002 1.21378996 -1.99523996 0 P 0 
L 1.21378996 -1.99523996 1.21358002 -1.99511004 0 P 0 
L 1.21358002 -1.99511004 1.21336004 -1.995 0 P 0 
L 1.21336004 -1.995 1.21261004 -1.99468996 0 P 0 
L 1.21261004 -1.99468996 1.21183996 -1.99443996 0 P 0 
L 1.21183996 -1.99443996 1.21105 -1.99423002 0 P 0 
L 1.21105 -1.99423002 1.20593996 -1.99318002 0 P 0 
L 1.20593996 -1.99318002 1.18996998 -1.99065 0 P 0 
L 1.18996998 -1.99065 1.17318996 -1.98908002 0 P 0 
L 1.17318996 -1.98908002 1.15718996 -1.98858002 0 P 0 
L 1.15718996 -1.98858002 1.1504 -1.98876004 0 P 0 
L 1.1504 -1.98876004 1.14356998 -1.98926998 0 P 0 
L 1.04503996 -2.19061998 1.05141998 -2.19061998 0 P 0 
L 1.04893002 -2.18961998 1.05323002 -2.18961998 0 P 0 
L 1.05263002 -2.18861998 1.05503996 -2.18861998 0 P 0 
L 1.05628996 -2.18761998 1.05676004 -2.18761998 0 P 0 
L 1.09645 -2.17983002 1.16738002 -2.17983002 0 P 0 
L 1.09126004 -2.17883002 1.17091004 -2.17883002 0 P 0 
L 1.0868 -2.17783002 1.17386998 -2.17783002 0 P 0 
L 1.08368002 -2.17683002 1.17636004 -2.17683002 0 P 0 
L 1.0836 -2.17583002 1.1787 -2.17583002 0 P 0 
L 1.08351998 -2.17483002 1.18066998 -2.17483002 0 P 0 
L 1.08345 -2.17383002 1.18236998 -2.17383002 0 P 0 
L 1.08336998 -2.17283002 1.1839 -2.17283002 0 P 0 
L 1.08328996 -2.17183002 1.18526998 -2.17183002 0 P 0 
L 1.08321998 -2.17083002 1.18646998 -2.17083002 0 P 0 
L 1.08313996 -2.16983002 1.18761998 -2.16983002 0 P 0 
L 1.08306998 -2.16883002 1.18863996 -2.16883002 0 P 0 
L 1.08298996 -2.16783002 1.18966004 -2.16783002 0 P 0 
L 1.08291998 -2.16683002 1.19061004 -2.16683002 0 P 0 
L 1.08283996 -2.16583002 1.1915 -2.16583002 0 P 0 
L 1.08276004 -2.16483002 1.19238996 -2.16483002 0 P 0 
L 1.08268996 -2.16383002 1.19321004 -2.16383002 0 P 0 
L 1.08261004 -2.16283002 1.19398002 -2.16283002 0 P 0 
L 1.08253002 -2.16183002 1.19476004 -2.16183002 0 P 0 
L 1.08246004 -2.16083002 1.19548002 -2.16083002 0 P 0 
L 1.08238002 -2.15983002 1.19613996 -2.15983002 0 P 0 
L 1.08231004 -2.15883002 1.19681004 -2.15883002 0 P 0 
L 1.08223996 -2.15783002 1.19746004 -2.15783002 0 P 0 
L 1.13506998 -2.18383002 1.12553002 -2.18343996 0 P 0 
L 1.12553002 -2.18343996 1.11266004 -2.18218002 0 P 0 
L 1.11266004 -2.18218002 1.09983002 -2.18048002 0 P 0 
L 1.09983002 -2.18048002 1.09036998 -2.17866004 0 P 0 
L 1.09036998 -2.17866004 1.0837 -2.17711004 0 P 0 
L 1.0837 -2.17711004 1.08245 -2.16066998 0 P 0 
L 1.08245 -2.16066998 1.08193996 -2.15361998 0 P 0 
L 1.08193996 -2.15361998 1.08156998 -2.14726004 0 P 0 
L 1.08156998 -2.14726004 1.08131998 -2.14191004 0 P 0 
L 1.08131998 -2.14191004 1.08131004 -2.14108996 0 P 0 
L 1.08131004 -2.14108996 1.08136004 -2.14026004 0 P 0 
L 1.08136004 -2.14026004 1.0814 -2.13986998 0 P 0 
L 1.0814 -2.13986998 1.08996004 -2.14233002 0 P 0 
L 1.08996004 -2.14233002 1.08996998 -2.14233996 0 P 0 
L 1.08996998 -2.14233996 1.08998996 -2.14233996 0 P 0 
L 1.08998996 -2.14233996 1.099 -2.14471998 0 P 0 
L 1.099 -2.14471998 1.10806998 -2.14668002 0 P 0 
L 1.10806998 -2.14668002 1.11598002 -2.14791998 0 P 0 
L 1.11598002 -2.14791998 1.12395 -2.1486 0 P 0 
L 1.12395 -2.1486 1.13048996 -2.14863996 0 P 0 
L 1.13048996 -2.14863996 1.137 -2.14811998 0 P 0 
L 1.137 -2.14811998 1.13903002 -2.14778996 0 P 0 
L 1.13903002 -2.14778996 1.14103002 -2.14728996 0 P 0 
L 1.14103002 -2.14728996 1.14298002 -2.14661998 0 P 0 
L 1.14298002 -2.14661998 1.14486998 -2.14581004 0 P 0 
L 1.14486998 -2.14581004 1.14668002 -2.14483996 0 P 0 
L 1.14668002 -2.14483996 1.1484 -2.14373996 0 P 0 
L 1.1484 -2.14373996 1.15003002 -2.1425 0 P 0 
L 1.15003002 -2.1425 1.15155 -2.14115 0 P 0 
L 1.15155 -2.14115 1.1526 -2.14006998 0 P 0 
L 1.1526 -2.14006998 1.15263996 -2.14001998 0 P 0 
L 1.15263996 -2.14001998 1.15356004 -2.13893002 0 P 0 
L 1.15356004 -2.13893002 1.15443996 -2.13771998 0 P 0 
L 1.15443996 -2.13771998 1.15523002 -2.13646004 0 P 0 
L 1.15523002 -2.13646004 1.15593996 -2.13515 0 P 0 
L 1.15593996 -2.13515 1.15655 -2.13381004 0 P 0 
L 1.15655 -2.13381004 1.15706004 -2.13243002 0 P 0 
L 1.15706004 -2.13243002 1.15748002 -2.13101004 0 P 0 
L 1.15748002 -2.13101004 1.1579 -2.12905 0 P 0 
L 1.1579 -2.12905 1.15816004 -2.12706004 0 P 0 
L 1.15816004 -2.12706004 1.15825 -2.12506998 0 P 0 
L 1.15825 -2.12506998 1.15818002 -2.12165 0 P 0 
L 1.15818002 -2.12165 1.15813996 -2.12118002 0 P 0 
L 1.15813996 -2.12118002 1.15813002 -2.1211 0 P 0 
L 1.15813002 -2.1211 1.15806004 -2.12068002 0 P 0 
L 1.15806004 -2.12068002 1.15793996 -2.12018996 0 P 0 
L 1.15793996 -2.12018996 1.15778002 -2.11973002 0 P 0 
L 1.15778002 -2.11973002 1.1577 -2.11953002 0 P 0 
L 1.1577 -2.11953002 1.15758996 -2.11933002 0 P 0 
L 1.15758996 -2.11933002 1.15746998 -2.11913996 0 P 0 
L 1.15746998 -2.11913996 1.15733002 -2.11895 0 P 0 
L 1.15733002 -2.11895 1.15716998 -2.11878002 0 P 0 
L 1.15716998 -2.11878002 1.157 -2.11863002 0 P 0 
L 1.157 -2.11863002 1.15681998 -2.11848996 0 P 0 
L 1.15681998 -2.11848996 1.15663002 -2.11836004 0 P 0 
L 1.15663002 -2.11836004 1.15641998 -2.11825 0 P 0 
L 1.15641998 -2.11825 1.15621004 -2.11816004 0 P 0 
L 1.15621004 -2.11816004 1.15598996 -2.11808996 0 P 0 
L 1.15598996 -2.11808996 1.15576998 -2.11803996 0 P 0 
L 1.15576998 -2.11803996 1.15553002 -2.118 0 P 0 
L 1.15553002 -2.118 1.15518002 -2.11798002 0 P 0 
L 1.15518002 -2.11798002 1.15483996 -2.11798996 0 P 0 
L 1.15483996 -2.11798996 1.15451004 -2.11803002 0 P 0 
L 1.15451004 -2.11803002 1.15418002 -2.1181 0 P 0 
L 1.15418002 -2.1181 1.15386004 -2.1182 0 P 0 
L 1.15386004 -2.1182 1.15361004 -2.11828996 0 P 0 
L 1.15361004 -2.11828996 1.14705 -2.12083996 0 P 0 
L 1.14705 -2.12083996 1.14038996 -2.12278996 0 P 0 
L 1.14038996 -2.12278996 1.13356004 -2.12416004 0 P 0 
L 1.13356004 -2.12416004 1.1285 -2.12476998 0 P 0 
L 1.1285 -2.12476998 1.12341004 -2.12501998 0 P 0 
L 1.12341004 -2.12501998 1.11831004 -2.12493002 0 P 0 
L 1.11831004 -2.12493002 1.11323002 -2.12448996 0 P 0 
L 1.11323002 -2.12448996 1.10848996 -2.12373002 0 P 0 
L 1.10848996 -2.12373002 1.10383996 -2.12263002 0 P 0 
L 1.10383996 -2.12263002 1.09926998 -2.12118996 0 P 0 
L 1.09926998 -2.12118996 1.09481004 -2.11941004 0 P 0 
L 1.09481004 -2.11941004 1.09168002 -2.11788002 0 P 0 
L 1.09168002 -2.11788002 1.08866004 -2.11611998 0 P 0 
L 1.08866004 -2.11611998 1.08578002 -2.11413002 0 P 0 
L 1.08578002 -2.11413002 1.08306998 -2.11193996 0 P 0 
L 1.08306998 -2.11193996 1.08051998 -2.10955 0 P 0 
L 1.08051998 -2.10955 1.07793996 -2.10673002 0 P 0 
L 1.07793996 -2.10673002 1.07561004 -2.10373996 0 P 0 
L 1.07561004 -2.10373996 1.07351004 -2.10058002 0 P 0 
L 1.07351004 -2.10058002 1.07171004 -2.09733996 0 P 0 
L 1.07171004 -2.09733996 1.07018002 -2.09396998 0 P 0 
L 1.07018002 -2.09396998 1.06893996 -2.09048002 0 P 0 
L 1.06893996 -2.09048002 1.06786004 -2.0865 0 P 0 
L 1.06786004 -2.0865 1.06706004 -2.08243996 0 P 0 
L 1.06706004 -2.08243996 1.06656004 -2.07833002 0 P 0 
L 1.06656004 -2.07833002 1.06615 -2.07071004 0 P 0 
L 1.06615 -2.07071004 1.06621004 -2.06313996 0 P 0 
L 1.06621004 -2.06313996 1.06675 -2.0556 0 P 0 
L 1.06675 -2.0556 1.0678 -2.04813002 0 P 0 
L 1.0678 -2.04813002 1.06868996 -2.04391998 0 P 0 
L 1.06868996 -2.04391998 1.06985 -2.03981004 0 P 0 
L 1.06985 -2.03981004 1.0713 -2.03578996 0 P 0 
L 1.0713 -2.03578996 1.07296004 -2.03206998 0 P 0 
L 1.07296004 -2.03206998 1.07486998 -2.02848996 0 P 0 
L 1.07486998 -2.02848996 1.07705 -2.02506004 0 P 0 
L 1.07705 -2.02506004 1.07966004 -2.0215 0 P 0 
L 1.07966004 -2.0215 1.08246998 -2.01811004 0 P 0 
L 1.08246998 -2.01811004 1.08546998 -2.01491004 0 P 0 
L 1.08546998 -2.01491004 1.0897 -2.01091004 0 P 0 
L 1.0897 -2.01091004 1.09153002 -2.00936998 0 P 0 
L 1.09153002 -2.00936998 1.09341998 -2.00793996 0 P 0 
L 1.09341998 -2.00793996 1.09545 -2.00658002 0 P 0 
L 1.09545 -2.00658002 1.09751004 -2.00533996 0 P 0 
L 1.09751004 -2.00533996 1.10288002 -2.0025 0 P 0 
L 1.10288002 -2.0025 1.10736998 -2.00043002 0 P 0 
L 1.10736998 -2.00043002 1.11193002 -1.99861004 0 P 0 
L 1.11193002 -1.99861004 1.12218002 -1.99533002 0 P 0 
L 1.12218002 -1.99533002 1.13298002 -1.99281998 0 P 0 
L 1.13298002 -1.99281998 1.14378996 -1.99126004 0 P 0 
L 1.14378996 -1.99126004 1.1505 -1.99075 0 P 0 
L 1.1505 -1.99075 1.15718002 -1.99058996 0 P 0 
L 1.15718002 -1.99058996 1.17306998 -1.99108002 0 P 0 
L 1.17306998 -1.99108002 1.18971998 -1.99263002 0 P 0 
L 1.18971998 -1.99263002 1.20558002 -1.99515 0 P 0 
L 1.20558002 -1.99515 1.21058996 -1.99618002 0 P 0 
L 1.21058996 -1.99618002 1.21126998 -1.99636004 0 P 0 
L 1.21126998 -1.99636004 1.21191998 -1.99656998 0 P 0 
L 1.21191998 -1.99656998 1.21253002 -1.99681998 0 P 0 
L 1.21253002 -1.99681998 1.21261004 -1.99686004 0 P 0 
L 1.21261004 -1.99686004 1.21266004 -1.99688996 0 P 0 
L 1.21266004 -1.99688996 1.21271998 -1.99693002 0 P 0 
L 1.21271998 -1.99693002 1.21281998 -1.99703002 0 P 0 
L 1.21281998 -1.99703002 1.21286004 -1.99708996 0 P 0 
L 1.21286004 -1.99708996 1.21288002 -1.99711004 0 P 0 
L 1.21288002 -1.99711004 1.21288002 -1.99711998 0 P 0 
L 1.21288002 -1.99711998 1.21288996 -1.99715 0 P 0 
L 1.21288996 -1.99715 1.2129 -1.99716998 0 P 0 
L 1.2129 -1.99716998 1.2129 -1.99721998 0 P 0 
L 1.2129 -1.99721998 1.21285 -1.99875 0 P 0 
L 1.21285 -1.99875 1.21243996 -2.00556998 0 P 0 
L 1.21243996 -2.00556998 1.21193996 -2.01361004 0 P 0 
L 1.21193996 -2.01361004 1.21133996 -2.02273002 0 P 0 
L 1.21133996 -2.02273002 1.21133996 -2.02273996 0 P 0 
L 1.21133996 -2.02273996 1.21058996 -2.03468002 0 P 0 
L 1.21058996 -2.03468002 1.20956004 -2.05216998 0 P 0 
L 1.20956004 -2.05216998 1.20848996 -2.07156004 0 P 0 
L 1.20848996 -2.07156004 1.20848996 -2.07156998 0 P 0 
L 1.20848996 -2.07156998 1.20751004 -2.09011004 0 P 0 
L 1.20751004 -2.09011004 1.20658996 -2.10743996 0 P 0 
L 1.20658996 -2.10743996 1.20561998 -2.12308996 0 P 0 
L 1.20561998 -2.12308996 1.20473002 -2.13618996 0 P 0 
L 1.20473002 -2.13618996 1.20453002 -2.13831998 0 P 0 
L 1.20453002 -2.13831998 1.20423996 -2.14041004 0 P 0 
L 1.20423996 -2.14041004 1.2035 -2.144 0 P 0 
L 1.2035 -2.144 1.20246004 -2.1475 0 P 0 
L 1.20246004 -2.1475 1.20111998 -2.1509 0 P 0 
L 1.20111998 -2.1509 1.19936998 -2.1545 0 P 0 
L 1.19936998 -2.1545 1.19738002 -2.15796998 0 P 0 
L 1.19738002 -2.15796998 1.19516004 -2.1613 0 P 0 
L 1.19516004 -2.1613 1.19276998 -2.16441004 0 P 0 
L 1.19276998 -2.16441004 1.19016004 -2.16733996 0 P 0 
L 1.19016004 -2.16733996 1.18736004 -2.17008002 0 P 0 
L 1.18736004 -2.17008002 1.1854 -2.17173996 0 P 0 
L 1.1854 -2.17173996 1.18335 -2.17323002 0 P 0 
L 1.18335 -2.17323002 1.18118002 -2.17456004 0 P 0 
L 1.18118002 -2.17456004 1.17893002 -2.17573002 0 P 0 
L 1.17893002 -2.17573002 1.17456998 -2.1776 0 P 0 
L 1.17456998 -2.1776 1.17006998 -2.17911998 0 P 0 
L 1.17006998 -2.17911998 1.16473996 -2.18053002 0 P 0 
L 1.16473996 -2.18053002 1.15935 -2.18166998 0 P 0 
L 1.15935 -2.18166998 1.15341998 -2.18263002 0 P 0 
L 1.15341998 -2.18263002 1.1475 -2.18328996 0 P 0 
L 1.1475 -2.18328996 1.13506998 -2.18383002 0 P 0 
L 0.90491998 -2.21461998 1.00131004 -2.21461998 0 P 0 
L 0.92235 -2.21361998 1.00355 -2.21361998 0 P 0 
L 0.76925 -1.8965 0.85586998 -1.8965 0 P 0 
L 0.76958996 -1.8955 0.85556004 -1.8955 0 P 0 
L 0.76995 -1.8945 0.85521004 -1.8945 0 P 0 
L 0.77031004 -1.8935 0.85486004 -1.8935 0 P 0 
L 0.77071004 -1.8925 0.85443996 -1.8925 0 P 0 
L 0.77115 -1.8915 0.85401004 -1.8915 0 P 0 
L 0.7716 -1.8905 0.85355 -1.8905 0 P 0 
L 0.77206004 -1.8895 0.85303002 -1.8895 0 P 0 
L 0.7726 -1.8885 0.85251004 -1.8885 0 P 0 
L 0.77313996 -1.8875 0.85198996 -1.8875 0 P 0 
L 0.77368996 -1.8865 0.85138002 -1.8865 0 P 0 
L 0.77433002 -1.8855 0.85073996 -1.8855 0 P 0 
L 0.77496004 -1.8845 0.85011004 -1.8845 0 P 0 
L 0.77561998 -1.8835 0.84943002 -1.8835 0 P 0 
L 0.77636004 -1.8825 0.84866998 -1.8825 0 P 0 
L 0.77711004 -1.8815 0.84791004 -1.8815 0 P 0 
L 0.7779 -1.8805 0.84713002 -1.8805 0 P 0 
L 0.77876998 -1.8795 0.84623002 -1.8795 0 P 0 
L 0.77963996 -1.8785 0.84533002 -1.8785 0 P 0 
L 0.7806 -1.8775 0.8444 -1.8775 0 P 0 
L 0.78161004 -1.8765 0.84335 -1.8765 0 P 0 
L 0.78265 -1.8755 0.84228996 -1.8755 0 P 0 
L 0.78381998 -1.8745 0.84108996 -1.8745 0 P 0 
L 0.78498996 -1.8735 0.83986998 -1.8735 0 P 0 
L 0.78635 -1.8725 0.83848002 -1.8725 0 P 0 
L 0.78773002 -1.8715 0.83706004 -1.8715 0 P 0 
L 0.78933002 -1.8705 0.83541998 -1.8705 0 P 0 
L 0.791 -1.8695 0.83366004 -1.8695 0 P 0 
L 0.793 -1.8685 0.83171998 -1.8685 0 P 0 
L 0.79525 -1.8675 0.82941998 -1.8675 0 P 0 
L 0.79791998 -1.8665 0.82671004 -1.8665 0 P 0 
L 0.80143996 -1.8655 0.82328996 -1.8655 0 P 0 
L 0.80705 -1.8645 0.81776004 -1.8645 0 P 0 
L 0.74543002 -1.89661998 0.75033002 -1.89661998 0 P 0 
L 0.74751004 -1.89561998 0.75058996 -1.89561998 0 P 0 
L 0.74958996 -1.89461998 0.75086004 -1.89461998 0 P 0 
L 0.76733996 -1.9125 0.85751998 -1.9125 0 P 0 
L 0.76728996 -1.9115 0.85756004 -1.9115 0 P 0 
L 0.76723996 -1.9105 0.85758996 -1.9105 0 P 0 
L 0.76721998 -1.9095 0.85763002 -1.9095 0 P 0 
L 0.76725 -1.9085 0.85761004 -1.9085 0 P 0 
L 0.76728002 -1.9075 0.85756998 -1.9075 0 P 0 
L 0.76731004 -1.9065 0.85753002 -1.9065 0 P 0 
L 0.76741998 -1.9055 0.85748996 -1.9055 0 P 0 
L 0.76753996 -1.9045 0.85738002 -1.9045 0 P 0 
L 0.76766004 -1.9035 0.85726004 -1.9035 0 P 0 
L 0.76781998 -1.9025 0.85713996 -1.9025 0 P 0 
L 0.76801998 -1.9015 0.85701004 -1.9015 0 P 0 
L 0.76821004 -1.9005 0.85683002 -1.9005 0 P 0 
L 0.76841998 -1.8995 0.85661998 -1.8995 0 P 0 
L 0.7687 -1.8985 0.85641004 -1.8985 0 P 0 
L 0.76896998 -1.8975 0.85613996 -1.8975 0 P 0 
L 0.76751004 -2.08325 0.8416 -2.08325 0 P 0 
L 0.76761998 -2.08225 0.84161998 -2.08225 0 P 0 
L 0.76773996 -2.08125 0.84166998 -2.08125 0 P 0 
L 0.76786004 -2.08025 0.84171998 -2.08025 0 P 0 
L 0.76796998 -2.07925 0.84176998 -2.07925 0 P 0 
L 0.76808002 -2.07825 0.84181004 -2.07825 0 P 0 
L 0.76818002 -2.07725 0.84186004 -2.07725 0 P 0 
L 0.76828996 -2.07625 0.8419 -2.07625 0 P 0 
L 0.76838996 -2.07525 0.84195 -2.07525 0 P 0 
L 0.76848996 -2.07425 0.842 -2.07425 0 P 0 
L 0.7686 -2.07325 0.84205 -2.07325 0 P 0 
L 0.7687 -2.07225 0.84208996 -2.07225 0 P 0 
L 0.7688 -2.07125 0.84213996 -2.07125 0 P 0 
L 0.7689 -2.07025 0.84218002 -2.07025 0 P 0 
L 0.76901004 -2.06925 0.84223002 -2.06925 0 P 0 
L 0.76911004 -2.06825 0.84228002 -2.06825 0 P 0 
L 0.76921004 -2.06725 0.84233002 -2.06725 0 P 0 
L 0.76931998 -2.06625 0.84236998 -2.06625 0 P 0 
L 0.76941998 -2.06525 0.84241998 -2.06525 0 P 0 
L 0.76948996 -2.06425 0.84246004 -2.06425 0 P 0 
L 0.76956004 -2.06325 0.84251004 -2.06325 0 P 0 
L 0.76963002 -2.06225 0.84256004 -2.06225 0 P 0 
L 0.7697 -2.06125 0.8426 -2.06125 0 P 0 
L 0.76976998 -2.06025 0.84265 -2.06025 0 P 0 
L 0.76983996 -2.05925 0.8427 -2.05925 0 P 0 
L 0.76991004 -2.05825 0.84273996 -2.05825 0 P 0 
L 0.76996998 -2.05725 0.84278996 -2.05725 0 P 0 
L 0.77001004 -2.05625 0.84283996 -2.05625 0 P 0 
L 0.77003996 -2.05525 0.84288002 -2.05525 0 P 0 
L 0.77008002 -2.05425 0.84295 -2.05425 0 P 0 
L 0.77011998 -2.05325 0.84303996 -2.05325 0 P 0 
L 0.77016004 -2.05225 0.84311998 -2.05225 0 P 0 
L 0.77018996 -2.05125 0.84321004 -2.05125 0 P 0 
L 0.77023002 -2.05025 0.8433 -2.05025 0 P 0 
L 0.77026998 -2.04925 0.84338002 -2.04925 0 P 0 
L 0.77031004 -2.04825 0.84346998 -2.04825 0 P 0 
L 0.77033996 -2.04725 0.84356004 -2.04725 0 P 0 
L 0.77038002 -2.04625 0.84363996 -2.04625 0 P 0 
L 0.77041004 -2.04525 0.84373002 -2.04525 0 P 0 
L 0.77043996 -2.04425 0.84381004 -2.04425 0 P 0 
L 0.77046004 -2.04325 0.8439 -2.04325 0 P 0 
L 0.77048002 -2.04225 0.84398996 -2.04225 0 P 0 
L 0.77051004 -2.04125 0.84406998 -2.04125 0 P 0 
L 0.77053002 -2.04025 0.84416004 -2.04025 0 P 0 
L 0.77055 -2.03925 0.84425 -2.03925 0 P 0 
L 0.77058002 -2.03825 0.84433002 -2.03825 0 P 0 
L 0.7706 -2.03725 0.84441998 -2.03725 0 P 0 
L 0.77061998 -2.03625 0.84451004 -2.03625 0 P 0 
L 0.77065 -2.03525 0.84458996 -2.03525 0 P 0 
L 0.77066998 -2.03425 0.84468002 -2.03425 0 P 0 
L 0.7707 -2.03325 0.84476998 -2.03325 0 P 0 
L 0.77071998 -2.03225 0.84485 -2.03225 0 P 0 
L 0.77073002 -2.03125 0.84493996 -2.03125 0 P 0 
L 0.77073996 -2.03025 0.84503002 -2.03025 0 P 0 
L 0.79986004 -1.8638 0.79643996 -1.86486998 0 P 0 
L 0.79643996 -1.86486998 0.79311998 -1.86621004 0 P 0 
L 0.79311998 -1.86621004 0.78991004 -1.86781004 0 P 0 
L 0.78991004 -1.86781004 0.78683996 -1.86966998 0 P 0 
L 0.78683996 -1.86966998 0.78391998 -1.87178002 0 P 0 
L 0.78391998 -1.87178002 0.78111998 -1.87416998 0 P 0 
L 0.78111998 -1.87416998 0.7785 -1.87676004 0 P 0 
L 0.7785 -1.87676004 0.77608002 -1.87953996 0 P 0 
L 0.77608002 -1.87953996 0.77386998 -1.8825 0 P 0 
L 0.77386998 -1.8825 0.77188002 -1.88561998 0 P 0 
L 0.77188002 -1.88561998 0.77013996 -1.88886004 0 P 0 
L 0.77013996 -1.88886004 0.76863996 -1.89221004 0 P 0 
L 0.76863996 -1.89221004 0.7674 -1.89566998 0 P 0 
L 0.7674 -1.89566998 0.76643002 -1.89921004 0 P 0 
L 0.76643002 -1.89921004 0.76571004 -1.90283996 0 P 0 
L 0.76571004 -1.90283996 0.76531004 -1.90636004 0 P 0 
L 0.76531004 -1.90636004 0.7652 -1.90991004 0 P 0 
L 0.7652 -1.90991004 0.76538996 -1.91345 0 P 0 
L 0.76538996 -1.91345 0.76586998 -1.91696998 0 P 0 
L 0.76586998 -1.91696998 0.76663996 -1.92046004 0 P 0 
L 0.76663996 -1.92046004 0.76803002 -1.92493996 0 P 0 
L 0.76803002 -1.92493996 0.76978002 -1.9293 0 P 0 
L 0.76978002 -1.9293 0.77106998 -1.93193996 0 P 0 
L 0.77106998 -1.93193996 0.77253002 -1.93448002 0 P 0 
L 0.77253002 -1.93448002 0.77416004 -1.93693996 0 P 0 
L 0.77416004 -1.93693996 0.77593002 -1.93923002 0 P 0 
L 0.77593002 -1.93923002 0.77783996 -1.94141004 0 P 0 
L 0.77783996 -1.94141004 0.77988996 -1.94345 0 P 0 
L 0.77988996 -1.94345 0.78216004 -1.94545 0 P 0 
L 0.78216004 -1.94545 0.78453996 -1.9473 0 P 0 
L 0.78453996 -1.9473 0.78703002 -1.94901998 0 P 0 
L 0.78703002 -1.94901998 0.79016998 -1.95088002 0 P 0 
L 0.79016998 -1.95088002 0.79343996 -1.95248996 0 P 0 
L 0.79343996 -1.95248996 0.79683002 -1.95383996 0 P 0 
L 0.79683002 -1.95383996 0.80031998 -1.95491998 0 P 0 
L 0.80031998 -1.95491998 0.80391004 -1.95573996 0 P 0 
L 0.80391004 -1.95573996 0.80751998 -1.95626004 0 P 0 
L 0.80751998 -1.95626004 0.81116004 -1.9565 0 P 0 
L 0.81116004 -1.9565 0.81481004 -1.95646004 0 P 0 
L 0.81481004 -1.95646004 0.81843996 -1.95613002 0 P 0 
L 0.81843996 -1.95613002 0.82205 -1.95551004 0 P 0 
L 0.82205 -1.95551004 0.82561998 -1.95461004 0 P 0 
L 0.82561998 -1.95461004 0.82911004 -1.95345 0 P 0 
L 0.82911004 -1.95345 0.83248996 -1.95201004 0 P 0 
L 0.83248996 -1.95201004 0.83576004 -1.95031998 0 P 0 
L 0.83576004 -1.95031998 0.83891998 -1.94836004 0 P 0 
L 0.83891998 -1.94836004 0.84191998 -1.94616998 0 P 0 
L 0.84191998 -1.94616998 0.84475 -1.94375 0 P 0 
L 0.84475 -1.94375 0.84738996 -1.94113996 0 P 0 
L 0.84738996 -1.94113996 0.84983002 -1.93833996 0 P 0 
L 0.84983002 -1.93833996 0.85206998 -1.93533996 0 P 0 
L 0.85206998 -1.93533996 0.8536 -1.93291998 0 P 0 
L 0.8536 -1.93291998 0.85496004 -1.93041004 0 P 0 
L 0.85496004 -1.93041004 0.85613996 -1.9278 0 P 0 
L 0.85613996 -1.9278 0.85711998 -1.92511004 0 P 0 
L 0.85711998 -1.92511004 0.85823002 -1.92123002 0 P 0 
L 0.85823002 -1.92123002 0.85901998 -1.91726998 0 P 0 
L 0.85901998 -1.91726998 0.85948996 -1.91323996 0 P 0 
L 0.85948996 -1.91323996 0.85963996 -1.90918002 0 P 0 
L 0.85963996 -1.90918002 0.85946998 -1.90513002 0 P 0 
L 0.85946998 -1.90513002 0.85898002 -1.9011 0 P 0 
L 0.85898002 -1.9011 0.85841998 -1.89826004 0 P 0 
L 0.85841998 -1.89826004 0.85766004 -1.89546004 0 P 0 
L 0.85766004 -1.89546004 0.85671004 -1.89273002 0 P 0 
L 0.85671004 -1.89273002 0.85556998 -1.89006004 0 P 0 
L 0.85556998 -1.89006004 0.85361998 -1.88631004 0 P 0 
L 0.85361998 -1.88631004 0.85136004 -1.88273996 0 P 0 
L 0.85136004 -1.88273996 0.84881004 -1.87938002 0 P 0 
L 0.84881004 -1.87938002 0.84596998 -1.87623002 0 P 0 
L 0.84596998 -1.87623002 0.84355 -1.87393996 0 P 0 
L 0.84355 -1.87393996 0.84096998 -1.87181998 0 P 0 
L 0.84096998 -1.87181998 0.83826004 -1.86988996 0 P 0 
L 0.83826004 -1.86988996 0.83541004 -1.86815 0 P 0 
L 0.83541004 -1.86815 0.83243996 -1.86661004 0 P 0 
L 0.83243996 -1.86661004 0.82938996 -1.86531004 0 P 0 
L 0.82938996 -1.86531004 0.82625 -1.86423002 0 P 0 
L 0.82625 -1.86423002 0.82303996 -1.86336004 0 P 0 
L 0.82303996 -1.86336004 0.81978002 -1.86273002 0 P 0 
L 0.81978002 -1.86273002 0.81646998 -1.86233002 0 P 0 
L 0.81646998 -1.86233002 0.81228996 -1.86215 0 P 0 
L 0.81228996 -1.86215 0.80811004 -1.86233996 0 P 0 
L 0.80811004 -1.86233996 0.80396004 -1.86288996 0 P 0 
L 0.80396004 -1.86288996 0.79986004 -1.8638 0 P 0 
L 0.80308996 -1.9535 0.82186004 -1.9535 0 P 0 
L 0.79926004 -1.9525 0.82563996 -1.9525 0 P 0 
L 0.79636004 -1.9515 0.82856998 -1.9515 0 P 0 
L 0.79393002 -1.9505 0.83093996 -1.9505 0 P 0 
L 0.7919 -1.9495 0.83298996 -1.9495 0 P 0 
L 0.79008002 -1.9485 0.8349 -1.9485 0 P 0 
L 0.78838996 -1.9475 0.83651004 -1.9475 0 P 0 
L 0.7869 -1.9465 0.83806998 -1.9465 0 P 0 
L 0.78548002 -1.9455 0.83943996 -1.9455 0 P 0 
L 0.7842 -1.9445 0.84078996 -1.9445 0 P 0 
L 0.78298002 -1.9435 0.84196998 -1.9435 0 P 0 
L 0.78183996 -1.9425 0.84313996 -1.9425 0 P 0 
L 0.78076998 -1.9415 0.84418996 -1.9415 0 P 0 
L 0.77976004 -1.9405 0.8452 -1.9405 0 P 0 
L 0.77883002 -1.9395 0.84616998 -1.9395 0 P 0 
L 0.77793996 -1.9385 0.84703996 -1.9385 0 P 0 
L 0.77711998 -1.9375 0.84791004 -1.9375 0 P 0 
L 0.77635 -1.9365 0.84871004 -1.9365 0 P 0 
L 0.77561004 -1.9355 0.84945 -1.9355 0 P 0 
L 0.77493996 -1.9345 0.8502 -1.9345 0 P 0 
L 0.77428002 -1.9335 0.85086998 -1.9335 0 P 0 
L 0.7737 -1.9325 0.8515 -1.9325 0 P 0 
L 0.77311998 -1.9315 0.8521 -1.9315 0 P 0 
L 0.77258996 -1.9305 0.85263996 -1.9305 0 P 0 
L 0.7721 -1.9295 0.85318002 -1.9295 0 P 0 
L 0.77161004 -1.9285 0.85363002 -1.9285 0 P 0 
L 0.77121004 -1.9275 0.85408002 -1.9275 0 P 0 
L 0.77081004 -1.9265 0.85448002 -1.9265 0 P 0 
L 0.77041004 -1.9255 0.85485 -1.9255 0 P 0 
L 0.77001004 -1.9245 0.85521998 -1.9245 0 P 0 
L 0.76968002 -1.9235 0.8555 -1.9235 0 P 0 
L 0.76936998 -1.9225 0.85578996 -1.9225 0 P 0 
L 0.76906004 -1.9215 0.85606998 -1.9215 0 P 0 
L 0.76875 -1.9205 0.85633002 -1.9205 0 P 0 
L 0.76848002 -1.9195 0.85653002 -1.9195 0 P 0 
L 0.76826004 -1.9185 0.85673002 -1.9185 0 P 0 
L 0.76803002 -1.9175 0.85693002 -1.9175 0 P 0 
L 0.76783002 -1.9165 0.85708996 -1.9165 0 P 0 
L 0.76768996 -1.9155 0.85721004 -1.9155 0 P 0 
L 0.76755 -1.9145 0.85733002 -1.9145 0 P 0 
L 0.76741998 -1.9135 0.85745 -1.9135 0 P 0 
L 0.81121004 -1.9545 0.80773002 -1.95426998 0 P 0 
L 0.80773002 -1.95426998 0.80426998 -1.95376998 0 P 0 
L 0.80426998 -1.95376998 0.80083996 -1.95298996 0 P 0 
L 0.80083996 -1.95298996 0.7975 -1.95195 0 P 0 
L 0.7975 -1.95195 0.79426004 -1.95066004 0 P 0 
L 0.79426004 -1.95066004 0.79111998 -1.94911998 0 P 0 
L 0.79111998 -1.94911998 0.78811004 -1.94733002 0 P 0 
L 0.78811004 -1.94733002 0.78573002 -1.94568996 0 P 0 
L 0.78573002 -1.94568996 0.78343996 -1.9439 0 P 0 
L 0.78343996 -1.9439 0.78126004 -1.94198996 0 P 0 
L 0.78126004 -1.94198996 0.7793 -1.94003996 0 P 0 
L 0.7793 -1.94003996 0.77746998 -1.93796004 0 P 0 
L 0.77746998 -1.93796004 0.77578996 -1.93576998 0 P 0 
L 0.77578996 -1.93576998 0.77423002 -1.93343002 0 P 0 
L 0.77423002 -1.93343002 0.77283996 -1.931 0 P 0 
L 0.77283996 -1.931 0.77161004 -1.92848996 0 P 0 
L 0.77161004 -1.92848996 0.76991998 -1.92426998 0 P 0 
L 0.76991998 -1.92426998 0.76858002 -1.91993996 0 P 0 
L 0.76858002 -1.91993996 0.76783996 -1.91661998 0 P 0 
L 0.76783996 -1.91661998 0.76738002 -1.91326998 0 P 0 
L 0.76738002 -1.91326998 0.76721004 -1.90988996 0 P 0 
L 0.76721004 -1.90988996 0.76731004 -1.90651004 0 P 0 
L 0.76731004 -1.90651004 0.7677 -1.90315 0 P 0 
L 0.7677 -1.90315 0.76838002 -1.89966998 0 P 0 
L 0.76838002 -1.89966998 0.76931004 -1.89626998 0 P 0 
L 0.76931004 -1.89626998 0.7705 -1.89296004 0 P 0 
L 0.7705 -1.89296004 0.77193996 -1.88973996 0 P 0 
L 0.77193996 -1.88973996 0.7736 -1.88663996 0 P 0 
L 0.7736 -1.88663996 0.77551004 -1.88363996 0 P 0 
L 0.77551004 -1.88363996 0.77763002 -1.8808 0 P 0 
L 0.77763002 -1.8808 0.77996004 -1.87813002 0 P 0 
L 0.77996004 -1.87813002 0.78246998 -1.87565 0 P 0 
L 0.78246998 -1.87565 0.78516004 -1.87336004 0 P 0 
L 0.78516004 -1.87336004 0.78795 -1.87133996 0 P 0 
L 0.78795 -1.87133996 0.79088002 -1.86956004 0 P 0 
L 0.79088002 -1.86956004 0.79393996 -1.86803002 0 P 0 
L 0.79393996 -1.86803002 0.79711004 -1.86675 0 P 0 
L 0.79711004 -1.86675 0.80038002 -1.86573002 0 P 0 
L 0.80038002 -1.86573002 0.80431004 -1.86486004 0 P 0 
L 0.80431004 -1.86486004 0.80828996 -1.86433996 0 P 0 
L 0.80828996 -1.86433996 0.8123 -1.86416004 0 P 0 
L 0.8123 -1.86416004 0.81631004 -1.86431998 0 P 0 
L 0.81631004 -1.86431998 0.81946998 -1.86471004 0 P 0 
L 0.81946998 -1.86471004 0.82258996 -1.86531004 0 P 0 
L 0.82258996 -1.86531004 0.82566004 -1.86613996 0 P 0 
L 0.82566004 -1.86613996 0.82866998 -1.86718002 0 P 0 
L 0.82866998 -1.86718002 0.83158996 -1.86843002 0 P 0 
L 0.83158996 -1.86843002 0.83443002 -1.86988996 0 P 0 
L 0.83443002 -1.86988996 0.83716004 -1.87156004 0 P 0 
L 0.83716004 -1.87156004 0.83976004 -1.87341004 0 P 0 
L 0.83976004 -1.87341004 0.84223002 -1.87543996 0 P 0 
L 0.84223002 -1.87543996 0.84453996 -1.87763002 0 P 0 
L 0.84453996 -1.87763002 0.84726998 -1.88065 0 P 0 
L 0.84726998 -1.88065 0.84971998 -1.88388002 0 P 0 
L 0.84971998 -1.88388002 0.85188996 -1.88731004 0 P 0 
L 0.85188996 -1.88731004 0.85376004 -1.89091004 0 P 0 
L 0.85376004 -1.89091004 0.85483996 -1.89345 0 P 0 
L 0.85483996 -1.89345 0.85575 -1.89605 0 P 0 
L 0.85575 -1.89605 0.85646998 -1.89871004 0 P 0 
L 0.85646998 -1.89871004 0.857 -1.90141004 0 P 0 
L 0.857 -1.90141004 0.85748002 -1.9053 0 P 0 
L 0.85748002 -1.9053 0.85763996 -1.90918996 0 P 0 
L 0.85763996 -1.90918996 0.8575 -1.91308002 0 P 0 
L 0.8575 -1.91308002 0.85703996 -1.91696004 0 P 0 
L 0.85703996 -1.91696004 0.85628002 -1.92076004 0 P 0 
L 0.85628002 -1.92076004 0.85521998 -1.92448996 0 P 0 
L 0.85521998 -1.92448996 0.85428002 -1.92705 0 P 0 
L 0.85428002 -1.92705 0.85316998 -1.92951998 0 P 0 
L 0.85316998 -1.92951998 0.85188002 -1.93191004 0 P 0 
L 0.85188002 -1.93191004 0.85041998 -1.9342 0 P 0 
L 0.85041998 -1.9342 0.84826998 -1.93708002 0 P 0 
L 0.84826998 -1.93708002 0.84593002 -1.93976998 0 P 0 
L 0.84593002 -1.93976998 0.8434 -1.94228002 0 P 0 
L 0.8434 -1.94228002 0.84068002 -1.9446 0 P 0 
L 0.84068002 -1.9446 0.8378 -1.9467 0 P 0 
L 0.8378 -1.9467 0.83476998 -1.94858002 0 P 0 
L 0.83476998 -1.94858002 0.83163996 -1.9502 0 P 0 
L 0.83163996 -1.9502 0.8284 -1.95158002 0 P 0 
L 0.8284 -1.95158002 0.82506004 -1.95268996 0 P 0 
L 0.82506004 -1.95268996 0.82163996 -1.95356004 0 P 0 
L 0.82163996 -1.95356004 0.81818002 -1.95413996 0 P 0 
L 0.81818002 -1.95413996 0.8147 -1.95446004 0 P 0 
L 0.8147 -1.95446004 0.81121004 -1.9545 0 P 0 
L 0.77075 -2.02925 0.84511004 -2.02925 0 P 0 
L 0.77076004 -2.02825 0.8452 -2.02825 0 P 0 
L 0.77076998 -2.02725 0.84528996 -2.02725 0 P 0 
L 0.77078002 -2.02625 0.84536998 -2.02625 0 P 0 
L 0.77078996 -2.02525 0.84548996 -2.02525 0 P 0 
L 0.7708 -2.02425 0.84561998 -2.02425 0 P 0 
L 0.77081004 -2.02325 0.84575 -2.02325 0 P 0 
L 0.77081998 -2.02225 0.84588002 -2.02225 0 P 0 
L 0.77083002 -2.02125 0.84601004 -2.02125 0 P 0 
L 0.77083996 -2.02025 0.84613996 -2.02025 0 P 0 
L 0.77085 -2.01925 0.84626004 -2.01925 0 P 0 
L 0.77085 -2.01825 0.84638996 -2.01825 0 P 0 
L 0.77085 -2.01725 0.84651998 -2.01725 0 P 0 
L 0.77086004 -2.01625 0.84663996 -2.01625 0 P 0 
L 0.77086004 -2.01525 0.84676998 -2.01525 0 P 0 
L 0.77086004 -2.01425 0.8469 -2.01425 0 P 0 
L 0.77086004 -2.01325 0.84703002 -2.01325 0 P 0 
L 0.77086004 -2.01225 0.84716004 -2.01225 0 P 0 
L 0.77086004 -2.01125 0.84728996 -2.01125 0 P 0 
L 0.77086004 -2.01025 0.84741004 -2.01025 0 P 0 
L 0.77086998 -2.00925 0.84753996 -2.00925 0 P 0 
L 0.77086998 -2.00825 0.84766998 -2.00825 0 P 0 
L 0.77086998 -2.00725 0.84778996 -2.00725 0 P 0 
L 0.77086998 -2.00625 0.84791998 -2.00625 0 P 0 
L 0.77086998 -2.00525 0.84805 -2.00525 0 P 0 
L 0.77086998 -2.00425 0.84818002 -2.00425 0 P 0 
L 0.77088002 -2.00325 0.84831004 -2.00325 0 P 0 
L 0.77088002 -2.00225 0.84843996 -2.00225 0 P 0 
L 0.77088002 -2.00125 0.84856004 -2.00125 0 P 0 
L 0.77088002 -2.00025 0.84868996 -2.00025 0 P 0 
L 0.77088002 -1.99925 0.84881998 -1.99925 0 P 0 
L 0.77088002 -1.99825 0.84896004 -1.99825 0 P 0 
L 0.77088002 -1.99725 0.84911004 -1.99725 0 P 0 
L 0.77088996 -1.99625 0.84926998 -1.99625 0 P 0 
L 0.77088996 -1.99525 0.84941998 -1.99525 0 P 0 
L 0.77088996 -1.99425 0.84956998 -1.99425 0 P 0 
L 0.77088996 -1.99325 0.84971998 -1.99325 0 P 0 
L 0.77088996 -1.99225 0.84986998 -1.99225 0 P 0 
L 0.77088996 -1.99125 0.85003002 -1.99125 0 P 0 
L 0.7709 -1.99025 0.85018002 -1.99025 0 P 0 
L 0.7709 -1.98925 0.85033002 -1.98925 0 P 0 
L 0.76885 -2.01878002 0.76871998 -2.03201998 0 P 0 
L 0.76871998 -2.03201998 0.7684 -2.04553996 0 P 0 
L 0.7684 -2.04553996 0.76796004 -2.05751004 0 P 0 
L 0.76796004 -2.05751004 0.76741004 -2.06523002 0 P 0 
L 0.76741004 -2.06523002 0.76596004 -2.07933996 0 P 0 
L 0.76596004 -2.07933996 0.7636 -2.09918002 0 P 0 
L 0.7636 -2.09918002 0.76116004 -2.119 0 P 0 
L 0.76116004 -2.119 0.76011998 -2.12526004 0 P 0 
L 0.76011998 -2.12526004 0.75948996 -2.12825 0 P 0 
L 0.75948996 -2.12825 0.84418002 -2.12825 0 P 0 
L 0.84418002 -2.12825 0.84361998 -2.10788002 0 P 0 
L 0.84361998 -2.10788002 0.8436 -2.08276004 0 P 0 
L 0.8436 -2.08276004 0.8449 -2.05491998 0 P 0 
L 0.8449 -2.05491998 0.84736004 -2.02641004 0 P 0 
L 0.84736004 -2.02641004 0.85083996 -1.99923002 0 P 0 
L 0.85083996 -1.99923002 0.85268996 -1.987 0 P 0 
L 0.85268996 -1.987 0.7689 -1.987 0 P 0 
L 0.7689 -1.987 0.76885 -2.01878002 0 P 0 
L 0.76195 -2.12625 0.84211998 -2.12625 0 P 0 
L 0.76213996 -2.12525 0.8421 -2.12525 0 P 0 
L 0.76231004 -2.12425 0.84206998 -2.12425 0 P 0 
L 0.76248002 -2.12325 0.84203996 -2.12325 0 P 0 
L 0.76263996 -2.12225 0.84201004 -2.12225 0 P 0 
L 0.76281004 -2.12125 0.84198996 -2.12125 0 P 0 
L 0.76296998 -2.12025 0.84196004 -2.12025 0 P 0 
L 0.76313996 -2.11925 0.84193002 -2.11925 0 P 0 
L 0.76326998 -2.11825 0.8419 -2.11825 0 P 0 
L 0.76338996 -2.11725 0.84188002 -2.11725 0 P 0 
L 0.76351004 -2.11625 0.84185 -2.11625 0 P 0 
L 0.76363996 -2.11525 0.84181998 -2.11525 0 P 0 
L 0.76376004 -2.11425 0.84178996 -2.11425 0 P 0 
L 0.76388002 -2.11325 0.84176998 -2.11325 0 P 0 
L 0.76401004 -2.11225 0.84173996 -2.11225 0 P 0 
L 0.76413002 -2.11125 0.84171004 -2.11125 0 P 0 
L 0.76425 -2.11025 0.84168002 -2.11025 0 P 0 
L 0.76438002 -2.10925 0.84166004 -2.10925 0 P 0 
L 0.7645 -2.10825 0.84163002 -2.10825 0 P 0 
L 0.76461998 -2.10725 0.84161998 -2.10725 0 P 0 
L 0.76475 -2.10625 0.84161998 -2.10625 0 P 0 
L 0.76486998 -2.10525 0.84161998 -2.10525 0 P 0 
L 0.76498996 -2.10425 0.84161998 -2.10425 0 P 0 
L 0.76511998 -2.10325 0.84161998 -2.10325 0 P 0 
L 0.76523996 -2.10225 0.84161998 -2.10225 0 P 0 
L 0.76536004 -2.10125 0.84161998 -2.10125 0 P 0 
L 0.76548996 -2.10025 0.84161998 -2.10025 0 P 0 
L 0.76561004 -2.09925 0.84161998 -2.09925 0 P 0 
L 0.76573002 -2.09825 0.84161004 -2.09825 0 P 0 
L 0.76583996 -2.09725 0.84161004 -2.09725 0 P 0 
L 0.76596998 -2.09625 0.84161004 -2.09625 0 P 0 
L 0.76608996 -2.09525 0.84161004 -2.09525 0 P 0 
L 0.7662 -2.09425 0.84161004 -2.09425 0 P 0 
L 0.76631998 -2.09325 0.84161004 -2.09325 0 P 0 
L 0.76643996 -2.09225 0.84161004 -2.09225 0 P 0 
L 0.76656004 -2.09125 0.84161004 -2.09125 0 P 0 
L 0.76668002 -2.09025 0.84161004 -2.09025 0 P 0 
L 0.76678996 -2.08925 0.84161004 -2.08925 0 P 0 
L 0.76691998 -2.08825 0.84161004 -2.08825 0 P 0 
L 0.76703002 -2.08725 0.84161004 -2.08725 0 P 0 
L 0.76715 -2.08625 0.8416 -2.08625 0 P 0 
L 0.76726998 -2.08525 0.8416 -2.08525 0 P 0 
L 0.76738996 -2.08425 0.8416 -2.08425 0 P 0 
L 0.76195 -2.12625 0.76208002 -2.12561998 0 P 0 
L 0.76208002 -2.12561998 0.76313996 -2.11928996 0 P 0 
L 0.76313996 -2.11928996 0.76558996 -2.09941998 0 P 0 
L 0.76558996 -2.09941998 0.76558996 -2.09941004 0 P 0 
L 0.76558996 -2.09941004 0.76793996 -2.07956004 0 P 0 
L 0.76793996 -2.07956004 0.7694 -2.0654 0 P 0 
L 0.7694 -2.0654 0.76941004 -2.06536004 0 P 0 
L 0.76941004 -2.06536004 0.76996004 -2.05761998 0 P 0 
L 0.76996004 -2.05761998 0.76996004 -2.05758996 0 P 0 
L 0.76996004 -2.05758996 0.7704 -2.0456 0 P 0 
L 0.7704 -2.0456 0.77071998 -2.03206004 0 P 0 
L 0.77071998 -2.03206004 0.77085 -2.01878002 0 P 0 
L 0.77085 -2.01878002 0.7709 -1.989 0 P 0 
L 0.7709 -1.989 0.85036004 -1.989 0 P 0 
L 0.85036004 -1.989 0.84886004 -1.99895 0 P 0 
L 0.84886004 -1.99895 0.84538002 -2.02618996 0 P 0 
L 0.84538002 -2.02618996 0.8429 -2.05478996 0 P 0 
L 0.8429 -2.05478996 0.8416 -2.08271004 0 P 0 
L 0.8416 -2.08271004 0.84161998 -2.10791004 0 P 0 
L 0.84161998 -2.10791004 0.84211998 -2.12625 0 P 0 
L 0.84211998 -2.12625 0.76195 -2.12625 0 P 0 
L 0.71628996 -1.91261998 0.74938002 -1.91261998 0 P 0 
L 0.71783002 -1.91161998 0.74933002 -1.91161998 0 P 0 
L 0.71953002 -1.91061998 0.74931004 -1.91061998 0 P 0 
L 0.72133002 -1.90961998 0.74928996 -1.90961998 0 P 0 
L 0.72313996 -1.90861998 0.74926998 -1.90861998 0 P 0 
L 0.72493996 -1.90761998 0.74928996 -1.90761998 0 P 0 
L 0.72673996 -1.90661998 0.74931998 -1.90661998 0 P 0 
L 0.72855 -1.90561998 0.74935 -1.90561998 0 P 0 
L 0.73035 -1.90461998 0.74938996 -1.90461998 0 P 0 
L 0.73215 -1.90361998 0.74946998 -1.90361998 0 P 0 
L 0.73396004 -1.90261998 0.74953996 -1.90261998 0 P 0 
L 0.73576004 -1.90161998 0.74961998 -1.90161998 0 P 0 
L 0.73756998 -1.90061998 0.74973996 -1.90061998 0 P 0 
L 0.73943002 -1.89961998 0.74986004 -1.89961998 0 P 0 
L 0.74141998 -1.89861998 0.74998996 -1.89861998 0 P 0 
L 0.74341004 -1.89761998 0.75015 -1.89761998 0 P 0 
L 0.59843002 -2.08361998 0.6754 -2.08361998 0 P 0 
L 0.59846004 -2.08261998 0.67538996 -2.08261998 0 P 0 
L 0.59848002 -2.08161998 0.67538002 -2.08161998 0 P 0 
L 0.59851004 -2.08061998 0.67538002 -2.08061998 0 P 0 
L 0.59853002 -2.07961998 0.67546004 -2.07961998 0 P 0 
L 0.59856004 -2.07861998 0.67553996 -2.07861998 0 P 0 
L 0.59861998 -2.07761998 0.67561004 -2.07761998 0 P 0 
L 0.5987 -2.07661998 0.67568996 -2.07661998 0 P 0 
L 0.59878002 -2.07561998 0.67576004 -2.07561998 0 P 0 
L 0.59885 -2.07461998 0.67583996 -2.07461998 0 P 0 
L 0.59893002 -2.07361998 0.67591998 -2.07361998 0 P 0 
L 0.59901004 -2.07261998 0.67598996 -2.07261998 0 P 0 
L 0.59908002 -2.07161998 0.67606998 -2.07161998 0 P 0 
L 0.59916004 -2.07061998 0.67613996 -2.07061998 0 P 0 
L 0.59923002 -2.06961998 0.67621004 -2.06961998 0 P 0 
L 0.59936004 -2.06861998 0.6763 -2.06861998 0 P 0 
L 0.59948996 -2.06761998 0.67645 -2.06761998 0 P 0 
L 0.59963002 -2.06661998 0.6766 -2.06661998 0 P 0 
L 0.59976998 -2.06561998 0.67676004 -2.06561998 0 P 0 
L 0.5999 -2.06461998 0.67691998 -2.06461998 0 P 0 
L 0.60003002 -2.06361998 0.67706998 -2.06361998 0 P 0 
L 0.60016998 -2.06261998 0.6773 -2.06261998 0 P 0 
L 0.60031004 -2.06161998 0.67753002 -2.06161998 0 P 0 
L 0.60051004 -2.06061998 0.67776004 -2.06061998 0 P 0 
L 0.60071004 -2.05961998 0.67798996 -2.05961998 0 P 0 
L 0.60091998 -2.05861998 0.67823002 -2.05861998 0 P 0 
L 0.60111998 -2.05761998 0.67853002 -2.05761998 0 P 0 
L 0.60133002 -2.05661998 0.67883996 -2.05661998 0 P 0 
L 0.60153996 -2.05561998 0.67913996 -2.05561998 0 P 0 
L 0.60173996 -2.05461998 0.67945 -2.05461998 0 P 0 
L 0.60195 -2.05361998 0.67975 -2.05361998 0 P 0 
L 0.60223002 -2.05261998 0.68006004 -2.05261998 0 P 0 
L 0.60251004 -2.05161998 0.68036004 -2.05161998 0 P 0 
L 0.60278996 -2.05061998 0.68066998 -2.05061998 0 P 0 
L 0.60306004 -2.04961998 0.68096998 -2.04961998 0 P 0 
L 0.60333996 -2.04861998 0.68135 -2.04861998 0 P 0 
L 0.60361998 -2.04761998 0.68173002 -2.04761998 0 P 0 
L 0.6039 -2.04661998 0.68211004 -2.04661998 0 P 0 
L 0.60418002 -2.04561998 0.68248996 -2.04561998 0 P 0 
L 0.60453002 -2.04461998 0.68288002 -2.04461998 0 P 0 
L 0.60488002 -2.04361998 0.68326004 -2.04361998 0 P 0 
L 0.60523002 -2.04261998 0.68363996 -2.04261998 0 P 0 
L 0.60556998 -2.04161998 0.68401998 -2.04161998 0 P 0 
L 0.60591998 -2.04061998 0.6844 -2.04061998 0 P 0 
L 0.60626998 -2.03961998 0.68486004 -2.03961998 0 P 0 
L 0.60661998 -2.03861998 0.68531998 -2.03861998 0 P 0 
L 0.60698996 -2.03761998 0.68578002 -2.03761998 0 P 0 
L 0.60743002 -2.03661998 0.68623996 -2.03661998 0 P 0 
L 0.60786004 -2.03561998 0.6867 -2.03561998 0 P 0 
L 0.60828996 -2.03461998 0.68716004 -2.03461998 0 P 0 
L 0.60873002 -2.03361998 0.68761998 -2.03361998 0 P 0 
L 0.60916004 -2.03261998 0.68808996 -2.03261998 0 P 0 
L 0.60958996 -2.03161998 0.68856998 -2.03161998 0 P 0 
L 0.61003002 -2.03061998 0.68911004 -2.03061998 0 P 0 
L 0.61046004 -2.02961998 0.68965 -2.02961998 0 P 0 
L 0.61088996 -2.02861998 0.69018996 -2.02861998 0 P 0 
L 0.61133002 -2.02761998 0.69073002 -2.02761998 0 P 0 
L 0.61176004 -2.02661998 0.69126998 -2.02661998 0 P 0 
L 0.6122 -2.02561998 0.69181004 -2.02561998 0 P 0 
L 0.61263002 -2.02461998 0.69235 -2.02461998 0 P 0 
L 0.61306004 -2.02361998 0.69288002 -2.02361998 0 P 0 
L 0.61348996 -2.02261998 0.69346998 -2.02261998 0 P 0 
L 0.61393002 -2.02161998 0.69408996 -2.02161998 0 P 0 
L 0.61436004 -2.02061998 0.6947 -2.02061998 0 P 0 
L 0.61478996 -2.01961998 0.69531998 -2.01961998 0 P 0 
L 0.61531004 -2.01861998 0.69593996 -2.01861998 0 P 0 
L 0.61583996 -2.01761998 0.69656004 -2.01761998 0 P 0 
L 0.61636004 -2.01661998 0.69718002 -2.01661998 0 P 0 
L 0.61688002 -2.01561998 0.69778996 -2.01561998 0 P 0 
L 0.6174 -2.01461998 0.69841998 -2.01461998 0 P 0 
L 0.61791998 -2.01361998 0.69911998 -2.01361998 0 P 0 
L 0.61843996 -2.01261998 0.69981998 -2.01261998 0 P 0 
L 0.61896004 -2.01161998 0.70051998 -2.01161998 0 P 0 
L 0.61948002 -2.01061998 0.70123002 -2.01061998 0 P 0 
L 0.62 -2.00961998 0.70193002 -2.00961998 0 P 0 
L 0.62051998 -2.00861998 0.70263002 -2.00861998 0 P 0 
L 0.62103996 -2.00761998 0.70333002 -2.00761998 0 P 0 
L 0.62163996 -2.00661998 0.70403996 -2.00661998 0 P 0 
L 0.62225 -2.00561998 0.70483002 -2.00561998 0 P 0 
L 0.62285 -2.00461998 0.70565 -2.00461998 0 P 0 
L 0.62346004 -2.00361998 0.70646004 -2.00361998 0 P 0 
L 0.62406004 -2.00261998 0.70726998 -2.00261998 0 P 0 
L 0.62466004 -2.00161998 0.70808996 -2.00161998 0 P 0 
L 0.62526998 -2.00061998 0.7089 -2.00061998 0 P 0 
L 0.62586998 -1.99961998 0.70971004 -1.99961998 0 P 0 
L 0.62648002 -1.99861998 0.71053002 -1.99861998 0 P 0 
L 0.62708002 -1.99761998 0.71133996 -1.99761998 0 P 0 
L 0.62768996 -1.99661998 0.71216004 -1.99661998 0 P 0 
L 0.62831998 -1.99561998 0.71296998 -1.99561998 0 P 0 
L 0.62901004 -1.99461998 0.71378996 -1.99461998 0 P 0 
L 0.62971004 -1.99361998 0.71466004 -1.99361998 0 P 0 
L 0.6304 -1.99261998 0.71561004 -1.99261998 0 P 0 
L 0.6311 -1.99161998 0.71656998 -1.99161998 0 P 0 
L 0.63178996 -1.99061998 0.71753002 -1.99061998 0 P 0 
L 0.63248996 -1.98961998 0.71848996 -1.98961998 0 P 0 
L 0.63318002 -1.98861998 0.71945 -1.98861998 0 P 0 
L 0.63388002 -1.98761998 0.72041004 -1.98761998 0 P 0 
L 0.63456998 -1.98661998 0.72136998 -1.98661998 0 P 0 
L 0.63526998 -1.98561998 0.72233002 -1.98561998 0 P 0 
L 0.63598002 -1.98461998 0.72328996 -1.98461998 0 P 0 
L 0.63678996 -1.98361998 0.72425 -1.98361998 0 P 0 
L 0.6376 -1.98261998 0.72521004 -1.98261998 0 P 0 
L 0.63841004 -1.98161998 0.72628002 -1.98161998 0 P 0 
L 0.63921998 -1.98061998 0.72738996 -1.98061998 0 P 0 
L 0.64003002 -1.97961998 0.7285 -1.97961998 0 P 0 
L 0.64083996 -1.97861998 0.72961004 -1.97861998 0 P 0 
L 0.64165 -1.97761998 0.73071004 -1.97761998 0 P 0 
L 0.64246004 -1.97661998 0.73181998 -1.97661998 0 P 0 
L 0.64326998 -1.97561998 0.73293002 -1.97561998 0 P 0 
L 0.64406998 -1.97461998 0.73403996 -1.97461998 0 P 0 
L 0.64488002 -1.97361998 0.73515 -1.97361998 0 P 0 
L 0.64568996 -1.97261998 0.73625 -1.97261998 0 P 0 
L 0.6465 -1.97161998 0.73736004 -1.97161998 0 P 0 
L 0.64731004 -1.97061998 0.73848002 -1.97061998 0 P 0 
L 0.64811998 -1.96961998 0.73973002 -1.96961998 0 P 0 
L 0.64893002 -1.96861998 0.74098996 -1.96861998 0 P 0 
L 0.64981004 -1.96761998 0.74225 -1.96761998 0 P 0 
L 0.65076004 -1.96661998 0.74351004 -1.96661998 0 P 0 
L 0.65171004 -1.96561998 0.74476998 -1.96561998 0 P 0 
L 0.65266998 -1.96461998 0.74603002 -1.96461998 0 P 0 
L 0.65361998 -1.96361998 0.74728996 -1.96361998 0 P 0 
L 0.65458002 -1.96261998 0.74855 -1.96261998 0 P 0 
L 0.65553002 -1.96161998 0.74981004 -1.96161998 0 P 0 
L 0.65648996 -1.96061998 0.75106004 -1.96061998 0 P 0 
L 0.65743996 -1.95961998 0.75233996 -1.95961998 0 P 0 
L 0.6584 -1.95861998 0.7537 -1.95861998 0 P 0 
L 0.65935 -1.95761998 0.75506004 -1.95761998 0 P 0 
L 0.66031004 -1.95661998 0.75641998 -1.95661998 0 P 0 
L 0.66126004 -1.95561998 0.75778996 -1.95561998 0 P 0 
L 0.66221004 -1.95461998 0.75916004 -1.95461998 0 P 0 
L 0.66316998 -1.95361998 0.76053996 -1.95361998 0 P 0 
L 0.66411998 -1.95261998 0.76193996 -1.95261998 0 P 0 
L 0.66523002 -1.95161998 0.76333996 -1.95161998 0 P 0 
L 0.66636004 -1.95061998 0.76406998 -1.95061998 0 P 0 
L 0.66746998 -1.94961998 0.76355 -1.94961998 0 P 0 
L 0.6686 -1.94861998 0.76291998 -1.94861998 0 P 0 
L 0.66971004 -1.94761998 0.76226998 -1.94761998 0 P 0 
L 0.67083996 -1.94661998 0.76161998 -1.94661998 0 P 0 
L 0.67196004 -1.94561998 0.76096998 -1.94561998 0 P 0 
L 0.67306998 -1.94461998 0.76033002 -1.94461998 0 P 0 
L 0.6742 -1.94361998 0.75968996 -1.94361998 0 P 0 
L 0.67531004 -1.94261998 0.75905 -1.94261998 0 P 0 
L 0.67643996 -1.94161998 0.75846004 -1.94161998 0 P 0 
L 0.67755 -1.94061998 0.75788996 -1.94061998 0 P 0 
L 0.67868002 -1.93961998 0.75731998 -1.93961998 0 P 0 
L 0.67978996 -1.93861998 0.75676998 -1.93861998 0 P 0 
L 0.68091998 -1.93761998 0.75626998 -1.93761998 0 P 0 
L 0.68221004 -1.93661998 0.75576998 -1.93661998 0 P 0 
L 0.68353002 -1.93561998 0.75528002 -1.93561998 0 P 0 
L 0.68483996 -1.93461998 0.75483996 -1.93461998 0 P 0 
L 0.68616004 -1.93361998 0.75441004 -1.93361998 0 P 0 
L 0.68746998 -1.93261998 0.75398002 -1.93261998 0 P 0 
L 0.68878002 -1.93161998 0.7536 -1.93161998 0 P 0 
L 0.6901 -1.93061998 0.75323996 -1.93061998 0 P 0 
L 0.69141004 -1.92961998 0.75286998 -1.92961998 0 P 0 
L 0.69271998 -1.92861998 0.75253996 -1.92861998 0 P 0 
L 0.69403002 -1.92761998 0.75223002 -1.92761998 0 P 0 
L 0.69535 -1.92661998 0.75193002 -1.92661998 0 P 0 
L 0.69666004 -1.92561998 0.75163002 -1.92561998 0 P 0 
L 0.69796998 -1.92461998 0.75138002 -1.92461998 0 P 0 
L 0.69936998 -1.92361998 0.75113996 -1.92361998 0 P 0 
L 0.70091004 -1.92261998 0.75088996 -1.92261998 0 P 0 
L 0.70243996 -1.92161998 0.75066004 -1.92161998 0 P 0 
L 0.70398002 -1.92061998 0.75046004 -1.92061998 0 P 0 
L 0.70551998 -1.91961998 0.75026004 -1.91961998 0 P 0 
L 0.70706004 -1.91861998 0.75006998 -1.91861998 0 P 0 
L 0.7086 -1.91761998 0.7499 -1.91761998 0 P 0 
L 0.71013996 -1.91661998 0.74976998 -1.91661998 0 P 0 
L 0.71166998 -1.91561998 0.74961998 -1.91561998 0 P 0 
L 0.71321004 -1.91461998 0.74951998 -1.91461998 0 P 0 
L 0.71475 -1.91361998 0.74945 -1.91361998 0 P 0 
L 0.61556998 -2.15661998 0.70655 -2.15661998 0 P 0 
L 0.61503002 -2.15561998 0.7056 -2.15561998 0 P 0 
L 0.61448996 -2.15461998 0.70465 -2.15461998 0 P 0 
L 0.61395 -2.15361998 0.7037 -2.15361998 0 P 0 
L 0.61341004 -2.15261998 0.70273996 -2.15261998 0 P 0 
L 0.61286998 -2.15161998 0.70178996 -2.15161998 0 P 0 
L 0.61233002 -2.15061998 0.70095 -2.15061998 0 P 0 
L 0.61188002 -2.14961998 0.70015 -2.14961998 0 P 0 
L 0.61143002 -2.14861998 0.69935 -2.14861998 0 P 0 
L 0.61098002 -2.14761998 0.69855 -2.14761998 0 P 0 
L 0.61053002 -2.14661998 0.69775 -2.14661998 0 P 0 
L 0.61008002 -2.14561998 0.69695 -2.14561998 0 P 0 
L 0.60963002 -2.14461998 0.69615 -2.14461998 0 P 0 
L 0.60918002 -2.14361998 0.69535 -2.14361998 0 P 0 
L 0.60873002 -2.14261998 0.69455 -2.14261998 0 P 0 
L 0.60831004 -2.14161998 0.69381998 -2.14161998 0 P 0 
L 0.60793996 -2.14061998 0.69315 -2.14061998 0 P 0 
L 0.60756998 -2.13961998 0.69248002 -2.13961998 0 P 0 
L 0.60721004 -2.13861998 0.69181004 -2.13861998 0 P 0 
L 0.60683996 -2.13761998 0.69115 -2.13761998 0 P 0 
L 0.60646998 -2.13661998 0.69048002 -2.13661998 0 P 0 
L 0.60611004 -2.13561998 0.68981004 -2.13561998 0 P 0 
L 0.60573996 -2.13461998 0.68918002 -2.13461998 0 P 0 
L 0.60538002 -2.13361998 0.68863002 -2.13361998 0 P 0 
L 0.60503996 -2.13261998 0.68808002 -2.13261998 0 P 0 
L 0.60476004 -2.13161998 0.68753002 -2.13161998 0 P 0 
L 0.60446998 -2.13061998 0.68698002 -2.13061998 0 P 0 
L 0.60418002 -2.12961998 0.68643002 -2.12961998 0 P 0 
L 0.6039 -2.12861998 0.68588002 -2.12861998 0 P 0 
L 0.60361004 -2.12761998 0.68533002 -2.12761998 0 P 0 
L 0.60331998 -2.12661998 0.68486004 -2.12661998 0 P 0 
L 0.60303002 -2.12561998 0.68441998 -2.12561998 0 P 0 
L 0.60275 -2.12461998 0.68396998 -2.12461998 0 P 0 
L 0.60246004 -2.12361998 0.68353002 -2.12361998 0 P 0 
L 0.60218002 -2.12261998 0.68308996 -2.12261998 0 P 0 
L 0.60188996 -2.12161998 0.68263996 -2.12161998 0 P 0 
L 0.60166998 -2.12061998 0.6822 -2.12061998 0 P 0 
L 0.60145 -2.11961998 0.68176004 -2.11961998 0 P 0 
L 0.60123002 -2.11861998 0.68138996 -2.11861998 0 P 0 
L 0.60101004 -2.11761998 0.68105 -2.11761998 0 P 0 
L 0.60078002 -2.11661998 0.68071004 -2.11661998 0 P 0 
L 0.6006 -2.11561998 0.68036004 -2.11561998 0 P 0 
L 0.60043002 -2.11461998 0.68001998 -2.11461998 0 P 0 
L 0.60025 -2.11361998 0.67968002 -2.11361998 0 P 0 
L 0.60008002 -2.11261998 0.67933002 -2.11261998 0 P 0 
L 0.59991004 -2.11161998 0.67898996 -2.11161998 0 P 0 
L 0.59976004 -2.11061998 0.6787 -2.11061998 0 P 0 
L 0.59963996 -2.10961998 0.67845 -2.10961998 0 P 0 
L 0.59951004 -2.10861998 0.6782 -2.10861998 0 P 0 
L 0.59938002 -2.10761998 0.67795 -2.10761998 0 P 0 
L 0.59925 -2.10661998 0.6777 -2.10661998 0 P 0 
L 0.59913002 -2.10561998 0.67746004 -2.10561998 0 P 0 
L 0.59905 -2.10461998 0.67721004 -2.10461998 0 P 0 
L 0.59896998 -2.10361998 0.67696004 -2.10361998 0 P 0 
L 0.59888002 -2.10261998 0.67671004 -2.10261998 0 P 0 
L 0.5988 -2.10161998 0.67653996 -2.10161998 0 P 0 
L 0.59871998 -2.10061998 0.67638002 -2.10061998 0 P 0 
L 0.59866998 -2.09961998 0.67621004 -2.09961998 0 P 0 
L 0.59863996 -2.09861998 0.67605 -2.09861998 0 P 0 
L 0.59861004 -2.09761998 0.67588996 -2.09761998 0 P 0 
L 0.59858996 -2.09661998 0.6758 -2.09661998 0 P 0 
L 0.59856004 -2.09561998 0.67571004 -2.09561998 0 P 0 
L 0.59853002 -2.09461998 0.67563002 -2.09461998 0 P 0 
L 0.5985 -2.09361998 0.67553996 -2.09361998 0 P 0 
L 0.59846998 -2.09261998 0.67546004 -2.09261998 0 P 0 
L 0.59843996 -2.09161998 0.67546004 -2.09161998 0 P 0 
L 0.59841998 -2.09061998 0.67545 -2.09061998 0 P 0 
L 0.59838002 -2.08961998 0.67543996 -2.08961998 0 P 0 
L 0.59836004 -2.08861998 0.67543002 -2.08861998 0 P 0 
L 0.59833002 -2.08761998 0.67543002 -2.08761998 0 P 0 
L 0.59835 -2.08661998 0.67541998 -2.08661998 0 P 0 
L 0.59836998 -2.08561998 0.67541004 -2.08561998 0 P 0 
L 0.5984 -2.08461998 0.67541004 -2.08461998 0 P 0 
L 0.80005 -2.25161998 0.85543996 -2.25161998 0 P 0 
L 0.78651998 -2.25061998 0.86596004 -2.25061998 0 P 0 
L 0.77878996 -2.24961998 0.87636004 -2.24961998 0 P 0 
L 0.77106004 -2.24861998 0.88285 -2.24861998 0 P 0 
L 0.76398996 -2.24761998 0.88933996 -2.24761998 0 P 0 
L 0.75891998 -2.24661998 0.89583996 -2.24661998 0 P 0 
L 0.73781004 -1.8982 0.71738996 -1.90951998 0 P 0 
L 0.71738996 -1.90951998 0.69766998 -1.92233996 0 P 0 
L 0.69766998 -1.92233996 0.67971004 -1.93601998 0 P 0 
L 0.67971004 -1.93601998 0.66278996 -1.95113002 0 P 0 
L 0.66278996 -1.95113002 0.64786998 -1.96675 0 P 0 
L 0.64786998 -1.96675 0.63423996 -1.98358996 0 P 0 
L 0.63423996 -1.98358996 0.62643996 -1.99483002 0 P 0 
L 0.62643996 -1.99483002 0.61933996 -2.00655 0 P 0 
L 0.61933996 -2.00655 0.61298996 -2.01873996 0 P 0 
L 0.61298996 -2.01873996 0.60503002 -2.03713002 0 P 0 
L 0.60503002 -2.03713002 0.60225 -2.04506004 0 P 0 
L 0.60225 -2.04506004 0.59998996 -2.05323002 0 P 0 
L 0.59998996 -2.05323002 0.59833996 -2.0612 0 P 0 
L 0.59833996 -2.0612 0.59725 -2.06928996 0 P 0 
L 0.59725 -2.06928996 0.59656998 -2.07833996 0 P 0 
L 0.59656998 -2.07833996 0.59633002 -2.0875 0 P 0 
L 0.59633002 -2.0875 0.59668996 -2.10036998 0 P 0 
L 0.59668996 -2.10036998 0.59715 -2.10596004 0 P 0 
L 0.59715 -2.10596004 0.59786004 -2.11151004 0 P 0 
L 0.59786004 -2.11151004 0.59878996 -2.11686998 0 P 0 
L 0.59878996 -2.11686998 0.59996998 -2.1222 0 P 0 
L 0.59996998 -2.1222 0.60326998 -2.13368996 0 P 0 
L 0.60326998 -2.13368996 0.60656998 -2.1427 0 P 0 
L 0.60656998 -2.1427 0.6105 -2.15143996 0 P 0 
L 0.6105 -2.15143996 0.61505 -2.15988002 0 P 0 
L 0.61505 -2.15988002 0.62023996 -2.16803996 0 P 0 
L 0.62023996 -2.16803996 0.62828996 -2.17873002 0 P 0 
L 0.62828996 -2.17873002 0.63718996 -2.18871004 0 P 0 
L 0.63718996 -2.18871004 0.64693002 -2.19795 0 P 0 
L 0.64693002 -2.19795 0.6582 -2.20701998 0 P 0 
L 0.6582 -2.20701998 0.67011004 -2.21518996 0 P 0 
L 0.67011004 -2.21518996 0.68261004 -2.22243002 0 P 0 
L 0.68261004 -2.22243002 0.69673996 -2.22936004 0 P 0 
L 0.69673996 -2.22936004 0.71123002 -2.23543996 0 P 0 
L 0.71123002 -2.23543996 0.72611998 -2.24066998 0 P 0 
L 0.72611998 -2.24066998 0.74536004 -2.24598996 0 P 0 
L 0.74536004 -2.24598996 0.76493002 -2.24985 0 P 0 
L 0.76493002 -2.24985 0.78671998 -2.25266998 0 P 0 
L 0.78671998 -2.25266998 0.80863002 -2.25425 0 P 0 
L 0.80863002 -2.25425 0.83146004 -2.25463002 0 P 0 
L 0.83146004 -2.25463002 0.85418002 -2.25375 0 P 0 
L 0.85418002 -2.25375 0.87641004 -2.25163996 0 P 0 
L 0.87641004 -2.25163996 0.89853002 -2.24823002 0 P 0 
L 0.89853002 -2.24823002 0.93045 -2.24101998 0 P 0 
L 0.93045 -2.24101998 0.96466004 -2.23063002 0 P 0 
L 0.96466004 -2.23063002 0.99911004 -2.2178 0 P 0 
L 0.99911004 -2.2178 1.03183002 -2.20318002 0 P 0 
L 1.03183002 -2.20318002 1.04391998 -2.19703002 0 P 0 
L 1.04391998 -2.19703002 1.05581004 -2.19048996 0 P 0 
L 1.05581004 -2.19048996 1.06676004 -2.18411998 0 P 0 
L 1.06676004 -2.18411998 1.06681004 -2.18408996 0 P 0 
L 1.06681004 -2.18408996 1.06685 -2.18405 0 P 0 
L 1.06685 -2.18405 1.0669 -2.18401004 0 P 0 
L 1.0669 -2.18401004 1.06693996 -2.18396998 0 P 0 
L 1.06693996 -2.18396998 1.06696998 -2.18391998 0 P 0 
L 1.06696998 -2.18391998 1.06701004 -2.18386998 0 P 0 
L 1.06701004 -2.18386998 1.06703002 -2.18381998 0 P 0 
L 1.06703002 -2.18381998 1.06706004 -2.18376004 0 P 0 
L 1.06706004 -2.18376004 1.06706998 -2.18371004 0 P 0 
L 1.06706998 -2.18371004 1.06708996 -2.18365 0 P 0 
L 1.06708996 -2.18365 1.06708996 -2.18358996 0 P 0 
L 1.06708996 -2.18358996 1.0671 -2.18353002 0 P 0 
L 1.0671 -2.18353002 1.0671 -2.18346998 0 P 0 
L 1.0671 -2.18346998 1.06708996 -2.18341004 0 P 0 
L 1.06708996 -2.18341004 1.06706998 -2.18336004 0 P 0 
L 1.06706998 -2.18336004 1.06706004 -2.1833 0 P 0 
L 1.06706004 -2.1833 1.06703002 -2.18323996 0 P 0 
L 1.06703002 -2.18323996 1.06701004 -2.18318996 0 P 0 
L 1.06701004 -2.18318996 1.06696998 -2.18313996 0 P 0 
L 1.06696998 -2.18313996 1.06693996 -2.18308996 0 P 0 
L 1.06693996 -2.18308996 1.06688002 -2.18303002 0 P 0 
L 1.06688002 -2.18303002 1.06678996 -2.18296998 0 P 0 
L 1.06678996 -2.18296998 1.06673002 -2.18295 0 P 0 
L 1.06673002 -2.18295 1.0667 -2.18295 0 P 0 
L 1.0667 -2.18295 1.06666004 -2.18293996 0 P 0 
L 1.06666004 -2.18293996 1.0666 -2.18293996 0 P 0 
L 1.0666 -2.18293996 1.06656998 -2.18295 0 P 0 
L 1.06656998 -2.18295 1.06653002 -2.18295 0 P 0 
L 1.06653002 -2.18295 1.06153002 -2.1842 0 P 0 
L 1.06153002 -2.1842 1.05583996 -2.18566998 0 P 0 
L 1.05583996 -2.18566998 1.04916998 -2.1875 0 P 0 
L 1.04916998 -2.1875 1.0153 -2.1962 0 P 0 
L 1.0153 -2.1962 0.9814 -2.20333996 0 P 0 
L 0.9814 -2.20333996 0.94881998 -2.2087 0 P 0 
L 0.94881998 -2.2087 0.9189 -2.21198996 0 P 0 
L 0.9189 -2.21198996 0.90113996 -2.21278996 0 P 0 
L 0.90113996 -2.21278996 0.87738002 -2.21265 0 P 0 
L 0.87738002 -2.21265 0.854 -2.21183002 0 P 0 
L 0.854 -2.21183002 0.83788996 -2.21033996 0 P 0 
L 0.83788996 -2.21033996 0.8174 -2.20693002 0 P 0 
L 0.8174 -2.20693002 0.79708996 -2.2023 0 P 0 
L 0.79708996 -2.2023 0.7769 -2.19641004 0 P 0 
L 0.7769 -2.19641004 0.76433002 -2.19183996 0 P 0 
L 0.76433002 -2.19183996 0.75208996 -2.18638002 0 P 0 
L 0.75208996 -2.18638002 0.74026998 -2.18006998 0 P 0 
L 0.74026998 -2.18006998 0.72886998 -2.17291004 0 P 0 
L 0.72886998 -2.17291004 0.71961998 -2.16603002 0 P 0 
L 0.71961998 -2.16603002 0.71098996 -2.15838996 0 P 0 
L 0.71098996 -2.15838996 0.70303002 -2.15003002 0 P 0 
L 0.70303002 -2.15003002 0.6958 -2.14098996 0 P 0 
L 0.6958 -2.14098996 0.69106998 -2.1339 0 P 0 
L 0.69106998 -2.1339 0.68696004 -2.12643002 0 P 0 
L 0.68696004 -2.12643002 0.68351004 -2.11863002 0 P 0 
L 0.68351004 -2.11863002 0.68073996 -2.11056004 0 P 0 
L 0.68073996 -2.11056004 0.67866004 -2.10218996 0 P 0 
L 0.67866004 -2.10218996 0.67788002 -2.09741998 0 P 0 
L 0.67788002 -2.09741998 0.67746004 -2.0926 0 P 0 
L 0.67746004 -2.0926 0.67738002 -2.08076004 0 P 0 
L 0.67738002 -2.08076004 0.67828002 -2.06891004 0 P 0 
L 0.67828002 -2.06891004 0.67903002 -2.06403996 0 P 0 
L 0.67903002 -2.06403996 0.68013002 -2.05923996 0 P 0 
L 0.68013002 -2.05923996 0.68288002 -2.05021998 0 P 0 
L 0.68288002 -2.05021998 0.68623996 -2.04141004 0 P 0 
L 0.68623996 -2.04141004 0.69018002 -2.03286004 0 P 0 
L 0.69018002 -2.03286004 0.69486004 -2.02418002 0 P 0 
L 0.69486004 -2.02418002 0.70003996 -2.0158 0 P 0 
L 0.70003996 -2.0158 0.70573002 -2.00768996 0 P 0 
L 0.70573002 -2.00768996 0.7158 -1.99531998 0 P 0 
L 0.7158 -1.99531998 0.72681004 -1.98385 0 P 0 
L 0.72681004 -1.98385 0.73971004 -1.9722 0 P 0 
L 0.73971004 -1.9722 0.7533 -1.9614 0 P 0 
L 0.7533 -1.9614 0.75753996 -1.95828002 0 P 0 
L 0.75753996 -1.95828002 0.76138002 -1.95548002 0 P 0 
L 0.76138002 -1.95548002 0.76463002 -1.95316004 0 P 0 
L 0.76463002 -1.95316004 0.76516004 -1.95281004 0 P 0 
L 0.76516004 -1.95281004 0.7657 -1.95248996 0 P 0 
L 0.7657 -1.95248996 0.76578002 -1.95243996 0 P 0 
L 0.76578002 -1.95243996 0.76586004 -1.95238002 0 P 0 
L 0.76586004 -1.95238002 0.76593002 -1.95231998 0 P 0 
L 0.76593002 -1.95231998 0.766 -1.95223996 0 P 0 
L 0.766 -1.95223996 0.76606004 -1.95216998 0 P 0 
L 0.76606004 -1.95216998 0.76616004 -1.95201004 0 P 0 
L 0.76616004 -1.95201004 0.7662 -1.95191998 0 P 0 
L 0.7662 -1.95191998 0.76626004 -1.95173996 0 P 0 
L 0.76626004 -1.95173996 0.76628002 -1.95163996 0 P 0 
L 0.76628002 -1.95163996 0.7663 -1.95143002 0 P 0 
L 0.7663 -1.95143002 0.7663 -1.95121004 0 P 0 
L 0.7663 -1.95121004 0.76628996 -1.951 0 P 0 
L 0.76628996 -1.951 0.76625 -1.95078996 0 P 0 
L 0.76625 -1.95078996 0.7662 -1.95058002 0 P 0 
L 0.7662 -1.95058002 0.76613002 -1.95036998 0 P 0 
L 0.76613002 -1.95036998 0.76583002 -1.94966998 0 P 0 
L 0.76583002 -1.94966998 0.76548996 -1.94896998 0 P 0 
L 0.76548996 -1.94896998 0.76508996 -1.9483 0 P 0 
L 0.76508996 -1.9483 0.76253002 -1.94436004 0 P 0 
L 0.76253002 -1.94436004 0.76056998 -1.94126998 0 P 0 
L 0.76056998 -1.94126998 0.75871998 -1.93806004 0 P 0 
L 0.75871998 -1.93806004 0.75716998 -1.93496998 0 P 0 
L 0.75716998 -1.93496998 0.7558 -1.93178002 0 P 0 
L 0.7558 -1.93178002 0.7546 -1.92853996 0 P 0 
L 0.7546 -1.92853996 0.75358996 -1.92521004 0 P 0 
L 0.75358996 -1.92521004 0.7527 -1.92161998 0 P 0 
L 0.7527 -1.92161998 0.75196998 -1.91796004 0 P 0 
L 0.75196998 -1.91796004 0.75155 -1.91496004 0 P 0 
L 0.75155 -1.91496004 0.75133002 -1.91193002 0 P 0 
L 0.75133002 -1.91193002 0.75126998 -1.9085 0 P 0 
L 0.75126998 -1.9085 0.75136004 -1.90506004 0 P 0 
L 0.75136004 -1.90506004 0.75161004 -1.90181998 0 P 0 
L 0.75161004 -1.90181998 0.752 -1.8986 0 P 0 
L 0.752 -1.8986 0.75228996 -1.89701998 0 P 0 
L 0.75228996 -1.89701998 0.75268996 -1.89546998 0 P 0 
L 0.75268996 -1.89546998 0.7532 -1.89395 0 P 0 
L 0.7532 -1.89395 0.75358996 -1.89281998 0 P 0 
L 0.75358996 -1.89281998 0.75373002 -1.89231998 0 P 0 
L 0.75373002 -1.89231998 0.75383996 -1.8918 0 P 0 
L 0.75383996 -1.8918 0.75391998 -1.89138996 0 P 0 
L 0.75391998 -1.89138996 0.75396998 -1.89098996 0 P 0 
L 0.75396998 -1.89098996 0.75396998 -1.89086004 0 P 0 
L 0.75396998 -1.89086004 0.75393996 -1.89076998 0 P 0 
L 0.75393996 -1.89076998 0.7539 -1.89071004 0 P 0 
L 0.7539 -1.89071004 0.75386004 -1.89066998 0 P 0 
L 0.75386004 -1.89066998 0.75381004 -1.89063002 0 P 0 
L 0.75381004 -1.89063002 0.75378996 -1.89061004 0 P 0 
L 0.75378996 -1.89061004 0.75373002 -1.89058996 0 P 0 
L 0.75373002 -1.89058996 0.75368002 -1.89056998 0 P 0 
L 0.75368002 -1.89056998 0.75356004 -1.89056998 0 P 0 
L 0.75356004 -1.89056998 0.75346998 -1.8906 0 P 0 
L 0.75346998 -1.8906 0.74898002 -1.8927 0 P 0 
L 0.74898002 -1.8927 0.74383002 -1.89518002 0 P 0 
L 0.74383002 -1.89518002 0.73781004 -1.8982 0 P 0 
L 0.69776998 -2.22761998 0.96701004 -2.22761998 0 P 0 
L 0.6957 -2.22661998 0.96968996 -2.22661998 0 P 0 
L 0.69366998 -2.22561998 0.97238002 -2.22561998 0 P 0 
L 0.69163002 -2.22461998 0.97506004 -2.22461998 0 P 0 
L 0.68958996 -2.22361998 0.97775 -2.22361998 0 P 0 
L 0.68756004 -2.22261998 0.98043002 -2.22261998 0 P 0 
L 0.68551998 -2.22161998 0.98311004 -2.22161998 0 P 0 
L 0.68348996 -2.22061998 0.9858 -2.22061998 0 P 0 
L 0.68176998 -2.21961998 0.98848002 -2.21961998 0 P 0 
L 0.68003996 -2.21861998 0.99116998 -2.21861998 0 P 0 
L 0.67831004 -2.21761998 0.99385 -2.21761998 0 P 0 
L 0.67658002 -2.21661998 0.99653996 -2.21661998 0 P 0 
L 0.67485 -2.21561998 0.99908002 -2.21561998 0 P 0 
L 0.67311998 -2.21461998 0.87665 -2.21461998 0 P 0 
L 0.6714 -2.21361998 0.85166004 -2.21361998 0 P 0 
L 0.6699 -2.21261998 0.84083002 -2.21261998 0 P 0 
L 0.66845 -2.21161998 0.8334 -2.21161998 0 P 0 
L 0.66698996 -2.21061998 0.8274 -2.21061998 0 P 0 
L 0.66553002 -2.20961998 0.82138996 -2.20961998 0 P 0 
L 0.66406998 -2.20861998 0.81583002 -2.20861998 0 P 0 
L 0.66261998 -2.20761998 0.81143996 -2.20761998 0 P 0 
L 0.66116004 -2.20661998 0.80706004 -2.20661998 0 P 0 
L 0.6597 -2.20561998 0.80266998 -2.20561998 0 P 0 
L 0.65841004 -2.20461998 0.79828996 -2.20461998 0 P 0 
L 0.65716998 -2.20361998 0.79448996 -2.20361998 0 P 0 
L 0.65593002 -2.20261998 0.79106004 -2.20261998 0 P 0 
L 0.65468996 -2.20161998 0.78763996 -2.20161998 0 P 0 
L 0.83143002 -2.25261998 0.80871998 -2.25225 0 P 0 
L 0.80871998 -2.25225 0.78691998 -2.25066998 0 P 0 
L 0.78691998 -2.25066998 0.76525 -2.24786998 0 P 0 
L 0.76525 -2.24786998 0.74581998 -2.24403996 0 P 0 
L 0.74581998 -2.24403996 0.72671004 -2.23876004 0 P 0 
L 0.72671004 -2.23876004 0.71196004 -2.23356998 0 P 0 
L 0.71196004 -2.23356998 0.69756998 -2.22753996 0 P 0 
L 0.69756998 -2.22753996 0.68355 -2.22066004 0 P 0 
L 0.68355 -2.22066004 0.67118002 -2.2135 0 P 0 
L 0.67118002 -2.2135 0.65938996 -2.20541004 0 P 0 
L 0.65938996 -2.20541004 0.64825 -2.19643996 0 P 0 
L 0.64825 -2.19643996 0.63861998 -2.18731998 0 P 0 
L 0.63861998 -2.18731998 0.62983002 -2.17746998 0 P 0 
L 0.62983002 -2.17746998 0.62188996 -2.1669 0 P 0 
L 0.62188996 -2.1669 0.61678002 -2.15886998 0 P 0 
L 0.61678002 -2.15886998 0.6123 -2.15056004 0 P 0 
L 0.6123 -2.15056004 0.60841998 -2.14193996 0 P 0 
L 0.60841998 -2.14193996 0.60516998 -2.13306998 0 P 0 
L 0.60516998 -2.13306998 0.60191004 -2.12171004 0 P 0 
L 0.60191004 -2.12171004 0.60075 -2.11648002 0 P 0 
L 0.60075 -2.11648002 0.59983996 -2.11121004 0 P 0 
L 0.59983996 -2.11121004 0.59913996 -2.10576004 0 P 0 
L 0.59913996 -2.10576004 0.59868996 -2.10026004 0 P 0 
L 0.59868996 -2.10026004 0.59833002 -2.0875 0 P 0 
L 0.59833002 -2.0875 0.59856998 -2.07843996 0 P 0 
L 0.59856998 -2.07843996 0.59923996 -2.0695 0 P 0 
L 0.59923996 -2.0695 0.60031998 -2.06153996 0 P 0 
L 0.60031998 -2.06153996 0.60193002 -2.05368996 0 P 0 
L 0.60193002 -2.05368996 0.60416004 -2.04566004 0 P 0 
L 0.60416004 -2.04566004 0.60688996 -2.03786004 0 P 0 
L 0.60688996 -2.03786004 0.6148 -2.01961004 0 P 0 
L 0.6148 -2.01961004 0.62108996 -2.00753002 0 P 0 
L 0.62108996 -2.00753002 0.62811998 -1.99591998 0 P 0 
L 0.62811998 -1.99591998 0.63583996 -1.98478996 0 P 0 
L 0.63583996 -1.98478996 0.64936998 -1.96808002 0 P 0 
L 0.64936998 -1.96808002 0.66418002 -1.95256998 0 P 0 
L 0.66418002 -1.95256998 0.68098002 -1.93756004 0 P 0 
L 0.68098002 -1.93756004 0.69881998 -1.92398002 0 P 0 
L 0.69881998 -1.92398002 0.71841998 -1.91123996 0 P 0 
L 0.71841998 -1.91123996 0.73875 -1.89996998 0 P 0 
L 0.73875 -1.89996998 0.74471004 -1.89696998 0 P 0 
L 0.74471004 -1.89696998 0.74983002 -1.89451004 0 P 0 
L 0.74983002 -1.89451004 0.7511 -1.89391004 0 P 0 
L 0.7511 -1.89391004 0.75076998 -1.89488996 0 P 0 
L 0.75076998 -1.89488996 0.75033996 -1.89658996 0 P 0 
L 0.75033996 -1.89658996 0.75003002 -1.8983 0 P 0 
L 0.75003002 -1.8983 0.74961998 -1.90161998 0 P 0 
L 0.74961998 -1.90161998 0.74936004 -1.90496004 0 P 0 
L 0.74936004 -1.90496004 0.74926998 -1.9085 0 P 0 
L 0.74926998 -1.9085 0.74933002 -1.91201998 0 P 0 
L 0.74933002 -1.91201998 0.74956004 -1.91516998 0 P 0 
L 0.74956004 -1.91516998 0.75 -1.91828996 0 P 0 
L 0.75 -1.91828996 0.75075 -1.92205 0 P 0 
L 0.75075 -1.92205 0.75166004 -1.92573996 0 P 0 
L 0.75166004 -1.92573996 0.7527 -1.92916998 0 P 0 
L 0.7527 -1.92916998 0.75393996 -1.93253002 0 P 0 
L 0.75393996 -1.93253002 0.75536004 -1.93581998 0 P 0 
L 0.75536004 -1.93581998 0.75696004 -1.939 0 P 0 
L 0.75696004 -1.939 0.75885 -1.94231004 0 P 0 
L 0.75885 -1.94231004 0.76083996 -1.94543996 0 P 0 
L 0.76083996 -1.94543996 0.76338996 -1.94933996 0 P 0 
L 0.76338996 -1.94933996 0.76371998 -1.94991998 0 P 0 
L 0.76371998 -1.94991998 0.76401004 -1.9505 0 P 0 
L 0.76401004 -1.9505 0.76423996 -1.95103002 0 P 0 
L 0.76423996 -1.95103002 0.76408996 -1.95111004 0 P 0 
L 0.76408996 -1.95111004 0.76348996 -1.95151004 0 P 0 
L 0.76348996 -1.95151004 0.76021004 -1.95386004 0 P 0 
L 0.76021004 -1.95386004 0.7602 -1.95386998 0 P 0 
L 0.7602 -1.95386998 0.75636998 -1.95666004 0 P 0 
L 0.75636998 -1.95666004 0.75636004 -1.95666998 0 P 0 
L 0.75636004 -1.95666998 0.75635 -1.95666998 0 P 0 
L 0.75635 -1.95666998 0.75208996 -1.95981004 0 P 0 
L 0.75208996 -1.95981004 0.73841004 -1.97066998 0 P 0 
L 0.73841004 -1.97066998 0.72541004 -1.98241004 0 P 0 
L 0.72541004 -1.98241004 0.7143 -1.994 0 P 0 
L 0.7143 -1.994 0.71425 -1.99406004 0 P 0 
L 0.71425 -1.99406004 0.70413996 -2.00648002 0 P 0 
L 0.70413996 -2.00648002 0.69836998 -2.01468996 0 P 0 
L 0.69836998 -2.01468996 0.69313002 -2.02318002 0 P 0 
L 0.69313002 -2.02318002 0.68838996 -2.03196004 0 P 0 
L 0.68838996 -2.03196004 0.68438996 -2.04063996 0 P 0 
L 0.68438996 -2.04063996 0.68098996 -2.04958002 0 P 0 
L 0.68098996 -2.04958002 0.6782 -2.05873002 0 P 0 
L 0.6782 -2.05873002 0.67706004 -2.06366004 0 P 0 
L 0.67706004 -2.06366004 0.67628996 -2.06866998 0 P 0 
L 0.67628996 -2.06866998 0.67538002 -2.08068996 0 P 0 
L 0.67538002 -2.08068996 0.67546004 -2.09268996 0 P 0 
L 0.67546004 -2.09268996 0.67588996 -2.09766998 0 P 0 
L 0.67588996 -2.09766998 0.6767 -2.10258996 0 P 0 
L 0.6767 -2.10258996 0.67881998 -2.11111998 0 P 0 
L 0.67881998 -2.11111998 0.68163996 -2.11936004 0 P 0 
L 0.68163996 -2.11936004 0.68516004 -2.12731998 0 P 0 
L 0.68516004 -2.12731998 0.68935 -2.13493996 0 P 0 
L 0.68935 -2.13493996 0.69418002 -2.14216998 0 P 0 
L 0.69418002 -2.14216998 0.70153002 -2.15135 0 P 0 
L 0.70153002 -2.15135 0.7096 -2.15983002 0 P 0 
L 0.7096 -2.15983002 0.71836004 -2.16758996 0 P 0 
L 0.71836004 -2.16758996 0.71843002 -2.16763996 0 P 0 
L 0.71843002 -2.16763996 0.72773996 -2.17456004 0 P 0 
L 0.72773996 -2.17456004 0.73926998 -2.1818 0 P 0 
L 0.73926998 -2.1818 0.75121004 -2.18818002 0 P 0 
L 0.75121004 -2.18818002 0.75128002 -2.18821004 0 P 0 
L 0.75128002 -2.18821004 0.76358002 -2.19368996 0 P 0 
L 0.76358002 -2.19368996 0.77628002 -2.19831004 0 P 0 
L 0.77628002 -2.19831004 0.79658996 -2.20423996 0 P 0 
L 0.79658996 -2.20423996 0.81701004 -2.20888996 0 P 0 
L 0.81701004 -2.20888996 0.83763996 -2.21233002 0 P 0 
L 0.83763996 -2.21233002 0.85388002 -2.21383002 0 P 0 
L 0.85388002 -2.21383002 0.87733996 -2.21465 0 P 0 
L 0.87733996 -2.21465 0.90118002 -2.21478996 0 P 0 
L 0.90118002 -2.21478996 0.91906004 -2.21398996 0 P 0 
L 0.91906004 -2.21398996 0.94908996 -2.21068002 0 P 0 
L 0.94908996 -2.21068002 0.98176998 -2.2053 0 P 0 
L 0.98176998 -2.2053 1.01575 -2.19815 0 P 0 
L 1.01575 -2.19815 1.04968002 -2.18943002 0 P 0 
L 1.04968002 -2.18943002 1.05633996 -2.18761004 0 P 0 
L 1.05633996 -2.18761004 1.05713996 -2.1874 0 P 0 
L 1.05713996 -2.1874 1.05483002 -2.18875 0 P 0 
L 1.05483002 -2.18875 1.04298996 -2.19526004 0 P 0 
L 1.04298996 -2.19526004 1.03096998 -2.20136998 0 P 0 
L 1.03096998 -2.20136998 0.99835 -2.21595 0 P 0 
L 0.99835 -2.21595 0.96401998 -2.22873996 0 P 0 
L 0.96401998 -2.22873996 0.92993996 -2.23908002 0 P 0 
L 0.92993996 -2.23908002 0.89816004 -2.24626004 0 P 0 
L 0.89816004 -2.24626004 0.87616004 -2.24965 0 P 0 
L 0.87616004 -2.24965 0.85405 -2.25176004 0 P 0 
L 0.85405 -2.25176004 0.83143002 -2.25261998 0 P 0 
L 0.65345 -2.20061998 0.78421004 -2.20061998 0 P 0 
L 0.65221004 -2.19961998 0.78078002 -2.19961998 0 P 0 
L 0.65096004 -2.19861998 0.77735 -2.19861998 0 P 0 
L 0.64971998 -2.19761998 0.77438996 -2.19761998 0 P 0 
L 0.64848002 -2.19661998 0.77163996 -2.19661998 0 P 0 
L 0.64738996 -2.19561998 0.76888996 -2.19561998 0 P 0 
L 0.64633996 -2.19461998 0.76613996 -2.19461998 0 P 0 
L 0.64528002 -2.19361998 0.76343002 -2.19361998 0 P 0 
L 0.64421998 -2.19261998 0.76118996 -2.19261998 0 P 0 
L 0.64316998 -2.19161998 0.75893996 -2.19161998 0 P 0 
L 0.64211004 -2.19061998 0.7567 -2.19061998 0 P 0 
L 0.64106004 -2.18961998 0.75446004 -2.18961998 0 P 0 
L 0.64 -2.18861998 0.75221004 -2.18861998 0 P 0 
L 0.63895 -2.18761998 0.75018002 -2.18761998 0 P 0 
L 0.63801004 -2.18661998 0.74831004 -2.18661998 0 P 0 
L 0.63711004 -2.18561998 0.74643002 -2.18561998 0 P 0 
L 0.63621998 -2.18461998 0.74456004 -2.18461998 0 P 0 
L 0.63533002 -2.18361998 0.74268002 -2.18361998 0 P 0 
L 0.63443996 -2.18261998 0.74081004 -2.18261998 0 P 0 
L 0.63353996 -2.18161998 0.73898996 -2.18161998 0 P 0 
L 0.63265 -2.18061998 0.73738996 -2.18061998 0 P 0 
L 0.63176004 -2.17961998 0.7358 -2.17961998 0 P 0 
L 0.63086998 -2.17861998 0.73421004 -2.17861998 0 P 0 
L 0.62996998 -2.17761998 0.73261998 -2.17761998 0 P 0 
L 0.6292 -2.17661998 0.73103002 -2.17661998 0 P 0 
L 0.62845 -2.17561998 0.72943996 -2.17561998 0 P 0 
L 0.6277 -2.17461998 0.72783996 -2.17461998 0 P 0 
L 0.62693996 -2.17361998 0.72648002 -2.17361998 0 P 0 
L 0.62618996 -2.17261998 0.72513996 -2.17261998 0 P 0 
L 0.62543996 -2.17161998 0.72378996 -2.17161998 0 P 0 
L 0.62468996 -2.17061998 0.72245 -2.17061998 0 P 0 
L 0.62393996 -2.16961998 0.7211 -2.16961998 0 P 0 
L 0.62318002 -2.16861998 0.71976004 -2.16861998 0 P 0 
L 0.62243996 -2.16761998 0.71841004 -2.16761998 0 P 0 
L 0.62171004 -2.16661998 0.71726998 -2.16661998 0 P 0 
L 0.62108002 -2.16561998 0.71613996 -2.16561998 0 P 0 
L 0.62043996 -2.16461998 0.71501004 -2.16461998 0 P 0 
L 0.61981004 -2.16361998 0.71388002 -2.16361998 0 P 0 
L 0.61916998 -2.16261998 0.71276004 -2.16261998 0 P 0 
L 0.61853002 -2.16161998 0.71163002 -2.16161998 0 P 0 
L 0.6179 -2.16061998 0.7105 -2.16061998 0 P 0 
L 0.61726004 -2.15961998 0.7094 -2.15961998 0 P 0 
L 0.61665 -2.15861998 0.70845 -2.15861998 0 P 0 
L 0.61611004 -2.15761998 0.7075 -2.15761998 0 P 0 
L 0.75383996 -2.24561998 0.901 -2.24561998 0 P 0 
L 0.74876998 -2.24461998 0.90541998 -2.24461998 0 P 0 
L 0.74431004 -2.24361998 0.90985 -2.24361998 0 P 0 
L 0.7407 -2.24261998 0.91426998 -2.24261998 0 P 0 
L 0.73708002 -2.24161998 0.9187 -2.24161998 0 P 0 
L 0.73346998 -2.24061998 0.92311998 -2.24061998 0 P 0 
L 0.72986004 -2.23961998 0.92753996 -2.23961998 0 P 0 
L 0.72633996 -2.23861998 0.93145 -2.23861998 0 P 0 
L 0.72348996 -2.23761998 0.93473996 -2.23761998 0 P 0 
L 0.72063996 -2.23661998 0.93803996 -2.23661998 0 P 0 
L 0.7178 -2.23561998 0.94133002 -2.23561998 0 P 0 
L 0.71495 -2.23461998 0.94461998 -2.23461998 0 P 0 
L 0.7121 -2.23361998 0.94791998 -2.23361998 0 P 0 
L 0.70968996 -2.23261998 0.95121004 -2.23261998 0 P 0 
L 0.70731004 -2.23161998 0.95451004 -2.23161998 0 P 0 
L 0.70491998 -2.23061998 0.9578 -2.23061998 0 P 0 
L 0.70253996 -2.22961998 0.9611 -2.22961998 0 P 0 
L 0.70015 -2.22861998 0.96431998 -2.22861998 0 P 0 
L 0.0349 -2.3038 0.0349 -1.0038 3 P 0 
L 0.0349 -1.0038 4.5349 -1.0038 3 P 0 
L 4.5349 -1.0038 4.5349 -2.3038 3 P 0 
L 4.5349 -2.3038 0.0349 -2.3038 3 P 0 
L 0.0349 -1.6038 4.5349 -1.6038 3 P 0 
L 0.0349 -1.8038 4.5349 -1.8038 3 P 0 
L 2.4349 -2.1038 4.0349 -2.1038 3 P 0 
L 2.4349 -2.3038 2.4349 -1.8038 3 P 0 
L 3.2349 -2.1038 3.2349 -1.8038 3 P 0 
L 4.0349 -2.3038 4.0349 -1.8038 3 P 0 
L 0.0723999 -1.6844687 0.07906663 -1.69030079 2 P 0 ;0,5=6,7=0.000000
L 0.07906663 -1.69030079 0.08656654 -1.6938 2 P 0 ;0,5=6,7=0.000000
L 0.08656654 -1.6938 0.09323337 -1.6938 2 P 0 ;0,5=6,7=0.000000
L 0.09323337 -1.6938 0.0999001 -1.69030079 2 P 0 ;0,5=6,7=0.000000
L 0.0999001 -1.69030079 0.10490059 -1.6844687 2 P 0 ;0,5=6,7=0.000000
L 0.10490059 -1.6844687 0.1074 -1.67629951 2 P 0 ;0,5=6,7=0.000000
L 0.1074 -1.67629951 0.10573376 -1.66813455 2 P 0 ;0,5=6,7=0.000000
L 0.10573376 -1.66813455 0.10156644 -1.66113396 2 P 0 ;0,5=6,7=0.000000
L 0.10156644 -1.66113396 0.09406654 -1.65646614 2 P 0 ;0,5=6,7=0.000000
L 0.09406654 -1.65646614 0.08406713 -1.65413327 2 P 0 ;0,5=6,7=0.000000
L 0.08406713 -1.65413327 0.07823346 -1.64946762 2 P 0 ;0,5=6,7=0.000000
L 0.07823346 -1.64946762 0.07573248 -1.64130059 2 P 0 ;0,5=6,7=0.000000
L 0.07573248 -1.64130059 0.0774003 -1.63313356 2 P 0 ;0,5=6,7=0.000000
L 0.0774003 -1.63313356 0.08156614 -1.62730148 2 P 0 ;0,5=6,7=0.000000
L 0.08156614 -1.62730148 0.0873997 -1.6238 2 P 0 ;0,5=6,7=0.000000
L 0.0873997 -1.6238 0.09323337 -1.6238 2 P 0 ;0,5=6,7=0.000000
L 0.09323337 -1.6238 0.09906693 -1.62613287 2 P 0 ;0,5=6,7=0.000000
L 0.09906693 -1.62613287 0.10406742 -1.63196713 2 P 0 ;0,5=6,7=0.000000
L 0.1383999 -1.6938 0.1383999 -1.6238 2 P 0 ;0,5=6,7=0.000000
L 0.1734 -1.6238 0.1734 -1.6938 2 P 0 ;0,5=6,7=0.000000
L 0.1734 -1.65880108 0.1383999 -1.65880108 2 P 0 ;0,5=6,7=0.000000
L 0.23856683 -1.6938 0.20523307 -1.6938 2 P 0 ;0,5=6,7=0.000000
L 0.20523307 -1.6938 0.20523307 -1.6238 2 P 0 ;0,5=6,7=0.000000
L 0.20523307 -1.6238 0.23856683 -1.6238 2 P 0 ;0,5=6,7=0.000000
L 0.22523337 -1.65763258 0.20523307 -1.65763258 2 P 0 ;0,5=6,7=0.000000
L 0.30456683 -1.6938 0.27123307 -1.6938 2 P 0 ;0,5=6,7=0.000000
L 0.27123307 -1.6938 0.27123307 -1.6238 2 P 0 ;0,5=6,7=0.000000
L 0.27123307 -1.6238 0.30456683 -1.6238 2 P 0 ;0,5=6,7=0.000000
L 0.29123337 -1.65763258 0.27123307 -1.65763258 2 P 0 ;0,5=6,7=0.000000
L 0.35389921 -1.6238 0.35389921 -1.6938 2 P 0 ;0,5=6,7=0.000000
L 0.33473356 -1.6238 0.37306634 -1.6238 2 P 0 ;0,5=6,7=0.000000
L 0.09489921 -1.7188 0.09489921 -1.7888 2 P 0 ;0,5=7,7=0.000000
L 0.07573356 -1.7188 0.11406634 -1.7188 2 P 0 ;0,5=7,7=0.000000
L 0.1508998 -1.7188 0.17089862 -1.7188 2 P 0 ;0,5=7,7=0.000000
L 0.16089921 -1.7188 0.16089921 -1.7888 2 P 0 ;0,5=7,7=0.000000
L 0.1508998 -1.7888 0.17089862 -1.7888 2 P 0 ;0,5=7,7=0.000000
L 0.22689921 -1.7188 0.22689921 -1.7888 2 P 0 ;0,5=7,7=0.000000
L 0.20773356 -1.7188 0.24606634 -1.7188 2 P 0 ;0,5=7,7=0.000000
L 0.27623307 -1.7188 0.27623307 -1.7888 2 P 0 ;0,5=7,7=0.000000
L 0.27623307 -1.7888 0.30956683 -1.7888 2 P 0 ;0,5=7,7=0.000000
L 0.37556683 -1.7888 0.34223307 -1.7888 2 P 0 ;0,5=7,7=0.000000
L 0.34223307 -1.7888 0.34223307 -1.7188 2 P 0 ;0,5=7,7=0.000000
L 0.34223307 -1.7188 0.37556683 -1.7188 2 P 0 ;0,5=7,7=0.000000
L 0.36223337 -1.75263258 0.34223307 -1.75263258 2 P 0 ;0,5=7,7=0.000000
L 2.5438999 -1.96813563 2.5519 -1.97480089 2 P 0 ;0,5=8,7=0.000000
L 2.5519 -1.97480089 2.5608999 -1.9788 2 P 0 ;0,5=8,7=0.000000
L 2.5608999 -1.9788 2.5689 -1.9788 2 P 0 ;0,5=8,7=0.000000
L 2.5689 -1.9788 2.5769001 -1.97480089 2 P 0 ;0,5=8,7=0.000000
L 2.5769001 -1.97480089 2.58290069 -1.96813563 2 P 0 ;0,5=8,7=0.000000
L 2.58290069 -1.96813563 2.5859 -1.95879941 2 P 0 ;0,5=8,7=0.000000
L 2.5859 -1.95879941 2.58390049 -1.94946811 2 P 0 ;0,5=8,7=0.000000
L 2.58390049 -1.94946811 2.5788997 -1.94146732 2 P 0 ;0,5=8,7=0.000000
L 2.5788997 -1.94146732 2.5698998 -1.93613278 2 P 0 ;0,5=8,7=0.000000
L 2.5698998 -1.93613278 2.55790049 -1.93346663 2 P 0 ;0,5=8,7=0.000000
L 2.55790049 -1.93346663 2.5509002 -1.92813445 2 P 0 ;0,5=8,7=0.000000
L 2.5509002 -1.92813445 2.54789902 -1.91880069 2 P 0 ;0,5=8,7=0.000000
L 2.54789902 -1.91880069 2.54990039 -1.90946683 2 P 0 ;0,5=8,7=0.000000
L 2.54990039 -1.90946683 2.55489931 -1.90280167 2 P 0 ;0,5=8,7=0.000000
L 2.55489931 -1.90280167 2.5618997 -1.8988 2 P 0 ;0,5=8,7=0.000000
L 2.5618997 -1.8988 2.5689 -1.8988 2 P 0 ;0,5=8,7=0.000000
L 2.5689 -1.8988 2.57590039 -1.90146614 2 P 0 ;0,5=8,7=0.000000
L 2.57590039 -1.90146614 2.58190089 -1.90813386 2 P 0 ;0,5=8,7=0.000000
L 2.6648998 -1.90546772 2.65889931 -1.90146614 2 P 0 ;0,5=8,7=0.000000
L 2.65889931 -1.90146614 2.65190079 -1.8988 2 P 0 ;0,5=8,7=0.000000
L 2.65190079 -1.8988 2.64390069 -1.8988 2 P 0 ;0,5=8,7=0.000000
L 2.64390069 -1.8988 2.63489892 -1.90280167 2 P 0 ;0,5=8,7=0.000000
L 2.63489892 -1.90280167 2.62790039 -1.90946683 2 P 0 ;0,5=8,7=0.000000
L 2.62790039 -1.90946683 2.62289961 -1.91746762 2 P 0 ;0,5=8,7=0.000000
L 2.62289961 -1.91746762 2.61889862 -1.93080049 2 P 0 ;0,5=8,7=0.000000
L 2.61889862 -1.93080049 2.61789892 -1.94280039 2 P 0 ;0,5=8,7=0.000000
L 2.61789892 -1.94280039 2.6199003 -1.9548003 2 P 0 ;0,5=8,7=0.000000
L 2.6199003 -1.9548003 2.62289961 -1.96280098 2 P 0 ;0,5=8,7=0.000000
L 2.62289961 -1.96280098 2.6289002 -1.97080177 2 P 0 ;0,5=8,7=0.000000
L 2.6289002 -1.97080177 2.63590049 -1.97613396 2 P 0 ;0,5=8,7=0.000000
L 2.63590049 -1.97613396 2.64289902 -1.9788 2 P 0 ;0,5=8,7=0.000000
L 2.64289902 -1.9788 2.64989941 -1.9788 2 P 0 ;0,5=8,7=0.000000
L 2.64989941 -1.9788 2.6568997 -1.97613396 2 P 0 ;0,5=8,7=0.000000
L 2.6568997 -1.97613396 2.6629003 -1.97213484 2 P 0 ;0,5=8,7=0.000000
L 2.6629003 -1.97213484 2.66790098 -1.96680266 2 P 0 ;0,5=8,7=0.000000
L 2.69589892 -1.9788 2.72089902 -1.8988 2 P 0 ;0,5=8,7=0.000000
L 2.72089902 -1.8988 2.74590098 -1.9788 2 P 0 ;0,5=8,7=0.000000
L 2.73689931 -1.95080118 2.70489882 -1.95080118 2 P 0 ;0,5=8,7=0.000000
L 2.77889961 -1.8988 2.77889961 -1.9788 2 P 0 ;0,5=8,7=0.000000
L 2.77889961 -1.9788 2.8189003 -1.9788 2 P 0 ;0,5=8,7=0.000000
L 2.8969003 -1.9788 2.85689961 -1.9788 2 P 0 ;0,5=8,7=0.000000
L 2.85689961 -1.9788 2.85689961 -1.8988 2 P 0 ;0,5=8,7=0.000000
L 2.85689961 -1.8988 2.8969003 -1.8988 2 P 0 ;0,5=8,7=0.000000
L 2.8809 -1.93746575 2.85689961 -1.93746575 2 P 0 ;0,5=8,7=0.000000
L 3.03289902 -1.9788 3.03289902 -1.8988 2 P 0 ;0,5=8,7=0.000000
L 3.03289902 -1.8988 3.0208998 -1.91479911 2 P 0 ;0,5=8,7=0.000000
L 3.0208998 -1.9788 3.04489833 -1.9788 2 P 0 ;0,5=8,7=0.000000
L 3.11089902 -1.98146604 3.10889951 -1.98013297 2 P 0 ;0,5=8,7=0.000000
L 3.10889951 -1.98013297 3.10889951 -1.97746703 2 P 0 ;0,5=8,7=0.000000
L 3.10889951 -1.97746703 3.11089902 -1.97613396 2 P 0 ;0,5=8,7=0.000000
L 3.11089902 -1.97613396 3.11290039 -1.97746703 2 P 0 ;0,5=8,7=0.000000
L 3.11290039 -1.97746703 3.11290039 -1.98013297 2 P 0 ;0,5=8,7=0.000000
L 3.11290039 -1.98013297 3.11089902 -1.98146604 2 P 0 ;0,5=8,7=0.000000
L 3.11089902 -1.945469 3.10889951 -1.94413346 2 P 0 ;0,5=8,7=0.000000
L 3.10889951 -1.94413346 3.10889951 -1.94146732 2 P 0 ;0,5=8,7=0.000000
L 3.10889951 -1.94146732 3.11089902 -1.94013435 2 P 0 ;0,5=8,7=0.000000
L 3.11089902 -1.94013435 3.11290039 -1.94146732 2 P 0 ;0,5=8,7=0.000000
L 3.11290039 -1.94146732 3.11290039 -1.94413346 2 P 0 ;0,5=8,7=0.000000
L 3.11290039 -1.94413346 3.11089902 -1.945469 2 P 0 ;0,5=8,7=0.000000
L 3.18889902 -1.9788 3.18889902 -1.8988 2 P 0 ;0,5=8,7=0.000000
L 3.18889902 -1.8988 3.1768998 -1.91479911 2 P 0 ;0,5=8,7=0.000000
L 3.1768998 -1.9788 3.20089833 -1.9788 2 P 0 ;0,5=8,7=0.000000
L 2.5138999 -2.23313563 2.5219 -2.23980089 2 P 0 ;0,5=6,7=0.000000
L 2.5219 -2.23980089 2.5308999 -2.2438 2 P 0 ;0,5=6,7=0.000000
L 2.5308999 -2.2438 2.5389 -2.2438 2 P 0 ;0,5=6,7=0.000000
L 2.5389 -2.2438 2.5469001 -2.23980089 2 P 0 ;0,5=6,7=0.000000
L 2.5469001 -2.23980089 2.55290069 -2.23313563 2 P 0 ;0,5=6,7=0.000000
L 2.55290069 -2.23313563 2.5559 -2.22379941 2 P 0 ;0,5=6,7=0.000000
L 2.5559 -2.22379941 2.55390049 -2.21446811 2 P 0 ;0,5=6,7=0.000000
L 2.55390049 -2.21446811 2.5488997 -2.20646732 2 P 0 ;0,5=6,7=0.000000
L 2.5488997 -2.20646732 2.5398998 -2.20113278 2 P 0 ;0,5=6,7=0.000000
L 2.5398998 -2.20113278 2.52790049 -2.19846663 2 P 0 ;0,5=6,7=0.000000
L 2.52790049 -2.19846663 2.5209002 -2.19313445 2 P 0 ;0,5=6,7=0.000000
L 2.5209002 -2.19313445 2.51789902 -2.18380069 2 P 0 ;0,5=6,7=0.000000
L 2.51789902 -2.18380069 2.51990039 -2.17446683 2 P 0 ;0,5=6,7=0.000000
L 2.51990039 -2.17446683 2.52489931 -2.16780167 2 P 0 ;0,5=6,7=0.000000
L 2.52489931 -2.16780167 2.5318997 -2.1638 2 P 0 ;0,5=6,7=0.000000
L 2.5318997 -2.1638 2.5389 -2.1638 2 P 0 ;0,5=6,7=0.000000
L 2.5389 -2.1638 2.54590039 -2.16646614 2 P 0 ;0,5=6,7=0.000000
L 2.54590039 -2.16646614 2.55190089 -2.17313386 2 P 0 ;0,5=6,7=0.000000
L 2.5918999 -2.2438 2.5918999 -2.1638 2 P 0 ;0,5=6,7=0.000000
L 2.6339 -2.1638 2.6339 -2.2438 2 P 0 ;0,5=6,7=0.000000
L 2.6339 -2.20380128 2.5918999 -2.20380128 2 P 0 ;0,5=6,7=0.000000
L 2.7109003 -2.2438 2.67089961 -2.2438 2 P 0 ;0,5=6,7=0.000000
L 2.67089961 -2.2438 2.67089961 -2.1638 2 P 0 ;0,5=6,7=0.000000
L 2.67089961 -2.1638 2.7109003 -2.1638 2 P 0 ;0,5=6,7=0.000000
L 2.6949 -2.20246575 2.67089961 -2.20246575 2 P 0 ;0,5=6,7=0.000000
L 2.7889003 -2.2438 2.74889961 -2.2438 2 P 0 ;0,5=6,7=0.000000
L 2.74889961 -2.2438 2.74889961 -2.1638 2 P 0 ;0,5=6,7=0.000000
L 2.74889961 -2.1638 2.7889003 -2.1638 2 P 0 ;0,5=6,7=0.000000
L 2.7729 -2.20246575 2.74889961 -2.20246575 2 P 0 ;0,5=6,7=0.000000
L 2.84689902 -2.1638 2.84689902 -2.2438 2 P 0 ;0,5=6,7=0.000000
L 2.8239003 -2.1638 2.86989961 -2.1638 2 P 0 ;0,5=6,7=0.000000
L 3.29489961 -1.9238 3.29489961 -2.0038 2 P 0 ;0,5=9,7=0.000000
L 3.29489961 -2.0038 3.3349003 -2.0038 2 P 0 ;0,5=9,7=0.000000
L 3.36789892 -2.0038 3.39289902 -1.9238 2 P 0 ;0,5=9,7=0.000000
L 3.39289902 -1.9238 3.41790098 -2.0038 2 P 0 ;0,5=9,7=0.000000
L 3.40889931 -1.97580118 3.37689882 -1.97580118 2 P 0 ;0,5=9,7=0.000000
L 3.47089902 -2.0038 3.47089902 -1.96780039 2 P 0 ;0,5=9,7=0.000000
L 3.47089902 -1.96780039 3.45089961 -1.9238 2 P 0 ;0,5=9,7=0.000000
L 3.4909003 -1.9238 3.47089902 -1.96780039 2 P 0 ;0,5=9,7=0.000000
L 3.5689003 -2.0038 3.52889961 -2.0038 2 P 0 ;0,5=9,7=0.000000
L 3.52889961 -2.0038 3.52889961 -1.9238 2 P 0 ;0,5=9,7=0.000000
L 3.52889961 -1.9238 3.5689003 -1.9238 2 P 0 ;0,5=9,7=0.000000
L 3.5529 -1.96246575 3.52889961 -1.96246575 2 P 0 ;0,5=9,7=0.000000
L 3.60689961 -2.0038 3.60689961 -1.9238 2 P 0 ;0,5=9,7=0.000000
L 3.60689961 -1.9238 3.6318998 -1.9238 2 P 0 ;0,5=9,7=0.000000
L 3.6318998 -1.9238 3.6398999 -1.92780167 2 P 0 ;0,5=9,7=0.000000
L 3.6398999 -1.92780167 3.64490069 -1.93313386 2 P 0 ;0,5=9,7=0.000000
L 3.64490069 -1.93313386 3.6469003 -1.94380069 2 P 0 ;0,5=9,7=0.000000
L 3.6469003 -1.94380069 3.64490069 -1.95446752 2 P 0 ;0,5=9,7=0.000000
L 3.64490069 -1.95446752 3.6389001 -1.96113278 2 P 0 ;0,5=9,7=0.000000
L 3.6389001 -1.96113278 3.6318998 -1.96513435 2 P 0 ;0,5=9,7=0.000000
L 3.6318998 -1.96513435 3.60689961 -1.96513435 2 P 0 ;0,5=9,7=0.000000
L 3.6318998 -1.96513435 3.6469003 -2.0038 2 P 0 ;0,5=9,7=0.000000
L 3.33989902 -2.2538 3.33189892 -2.25246703 2 P 0 ;0,5=10,7=0.000000
L 3.33189892 -2.25246703 3.32490039 -2.24713484 2 P 0 ;0,5=10,7=0.000000
L 3.32490039 -2.24713484 3.3188999 -2.23913406 2 P 0 ;0,5=10,7=0.000000
L 3.3188999 -2.23913406 3.31489892 -2.2298003 2 P 0 ;0,5=10,7=0.000000
L 3.31489892 -2.2298003 3.31289931 -2.21913346 2 P 0 ;0,5=10,7=0.000000
L 3.31289931 -2.21913346 3.31289931 -2.20846663 2 P 0 ;0,5=10,7=0.000000
L 3.31289931 -2.20846663 3.31489892 -2.1977998 2 P 0 ;0,5=10,7=0.000000
L 3.31489892 -2.1977998 3.3188999 -2.18846604 2 P 0 ;0,5=10,7=0.000000
L 3.3188999 -2.18846604 3.32490039 -2.18046772 2 P 0 ;0,5=10,7=0.000000
L 3.32490039 -2.18046772 3.33189892 -2.17513307 2 P 0 ;0,5=10,7=0.000000
L 3.33189892 -2.17513307 3.33989902 -2.1738 2 P 0 ;0,5=10,7=0.000000
L 3.33989902 -2.1738 3.34789911 -2.17513307 2 P 0 ;0,5=10,7=0.000000
L 3.34789911 -2.17513307 3.35489951 -2.18046772 2 P 0 ;0,5=10,7=0.000000
L 3.35489951 -2.18046772 3.3609 -2.18846604 2 P 0 ;0,5=10,7=0.000000
L 3.3609 -2.18846604 3.36490098 -2.1977998 2 P 0 ;0,5=10,7=0.000000
L 3.36490098 -2.1977998 3.36690059 -2.20846663 2 P 0 ;0,5=10,7=0.000000
L 3.36690059 -2.20846663 3.36690059 -2.21913346 2 P 0 ;0,5=10,7=0.000000
L 3.36690059 -2.21913346 3.36490098 -2.2298003 2 P 0 ;0,5=10,7=0.000000
L 3.36490098 -2.2298003 3.3609 -2.23913406 2 P 0 ;0,5=10,7=0.000000
L 3.3609 -2.23913406 3.35489951 -2.24713484 2 P 0 ;0,5=10,7=0.000000
L 3.35489951 -2.24713484 3.34789911 -2.25246703 2 P 0 ;0,5=10,7=0.000000
L 3.34789911 -2.25246703 3.33989902 -2.2538 2 P 0 ;0,5=10,7=0.000000
L 3.39889941 -2.2538 3.39889941 -2.1738 2 P 0 ;0,5=10,7=0.000000
L 3.39889941 -2.1738 3.43690049 -2.1738 2 P 0 ;0,5=10,7=0.000000
L 3.4228998 -2.21246575 3.39889941 -2.21246575 2 P 0 ;0,5=10,7=0.000000
L 0.16489872 -1.0538 0.16489872 -1.1538 2 P 0 ;0,5=7,7=0.000000
L 0.13423376 -1.0538 0.19556614 -1.0538 2 P 0 ;0,5=7,7=0.000000
L 0.2588997 -1.0538 0.29089774 -1.0538 2 P 0 ;0,5=7,7=0.000000
L 0.27489872 -1.0538 0.27489872 -1.1538 2 P 0 ;0,5=7,7=0.000000
L 0.2588997 -1.1538 0.29089774 -1.1538 2 P 0 ;0,5=7,7=0.000000
L 0.38489872 -1.0538 0.38489872 -1.1538 2 P 0 ;0,5=7,7=0.000000
L 0.35423376 -1.0538 0.41556614 -1.0538 2 P 0 ;0,5=7,7=0.000000
L 0.46823287 -1.0538 0.46823287 -1.1538 2 P 0 ;0,5=7,7=0.000000
L 0.46823287 -1.1538 0.52156703 -1.1538 2 P 0 ;0,5=7,7=0.000000
L 0.63156703 -1.1538 0.57823287 -1.1538 2 P 0 ;0,5=7,7=0.000000
L 0.57823287 -1.1538 0.57823287 -1.0538 2 P 0 ;0,5=7,7=0.000000
L 0.57823287 -1.0538 0.63156703 -1.0538 2 P 0 ;0,5=7,7=0.000000
L 0.61023337 -1.10213219 0.57823287 -1.10213219 2 P 0 ;0,5=7,7=0.000000
L 4.18989892 -1.9538 4.21489902 -1.8738 2 P 0 ;0,5=11,7=0.000000
L 4.21489902 -1.8738 4.23990098 -1.9538 2 P 0 ;0,5=11,7=0.000000
L 4.23089931 -1.92580118 4.19889882 -1.92580118 2 P 0 ;0,5=11,7=0.000000
L 4.27289961 -1.9538 4.27289961 -1.8738 2 P 0 ;0,5=11,7=0.000000
L 4.27289961 -1.8738 4.2978998 -1.8738 2 P 0 ;0,5=11,7=0.000000
L 4.2978998 -1.8738 4.3058999 -1.87780167 2 P 0 ;0,5=11,7=0.000000
L 4.3058999 -1.87780167 4.31090069 -1.88313386 2 P 0 ;0,5=11,7=0.000000
L 4.31090069 -1.88313386 4.3129003 -1.89380069 2 P 0 ;0,5=11,7=0.000000
L 4.3129003 -1.89380069 4.31090069 -1.90446752 2 P 0 ;0,5=11,7=0.000000
L 4.31090069 -1.90446752 4.3049001 -1.91113278 2 P 0 ;0,5=11,7=0.000000
L 4.3049001 -1.91113278 4.2978998 -1.91513435 2 P 0 ;0,5=11,7=0.000000
L 4.2978998 -1.91513435 4.27289961 -1.91513435 2 P 0 ;0,5=11,7=0.000000
L 4.2978998 -1.91513435 4.3129003 -1.9538 2 P 0 ;0,5=11,7=0.000000
L 4.37089902 -1.8738 4.37089902 -1.9538 2 P 0 ;0,5=11,7=0.000000
L 4.3479003 -1.8738 4.39389961 -1.8738 2 P 0 ;0,5=11,7=0.000000
L 2.1244002 -1.74180266 2.11506663 -1.74930098 2 P 0 ;0,3,5=12,7=0.000000
L 2.11506663 -1.74930098 2.10456683 -1.7538 2 P 0 ;0,3,5=12,7=0.000000
L 2.10456683 -1.7538 2.09523327 -1.7538 2 P 0 ;0,3,5=12,7=0.000000
L 2.09523327 -1.7538 2.0858998 -1.74930098 2 P 0 ;0,3,5=12,7=0.000000
L 2.0858998 -1.74930098 2.07889921 -1.74180266 2 P 0 ;0,3,5=12,7=0.000000
L 2.07889921 -1.74180266 2.0753999 -1.73129941 2 P 0 ;0,3,5=12,7=0.000000
L 2.0753999 -1.73129941 2.07773278 -1.72080157 2 P 0 ;0,3,5=12,7=0.000000
L 2.07773278 -1.72080157 2.08356703 -1.71180079 2 P 0 ;0,3,5=12,7=0.000000
L 2.08356703 -1.71180079 2.09406693 -1.70579931 2 P 0 ;0,3,5=12,7=0.000000
L 2.09406693 -1.70579931 2.10806604 -1.7028 2 P 0 ;0,3,5=12,7=0.000000
L 2.10806604 -1.7028 2.11623307 -1.69680128 2 P 0 ;0,3,5=12,7=0.000000
L 2.11623307 -1.69680128 2.11973445 -1.68630069 2 P 0 ;0,3,5=12,7=0.000000
L 2.11973445 -1.68630069 2.11739951 -1.6758002 2 P 0 ;0,3,5=12,7=0.000000
L 2.11739951 -1.6758002 2.11156742 -1.66830187 2 P 0 ;0,3,5=12,7=0.000000
L 2.11156742 -1.66830187 2.10340039 -1.6638 2 P 0 ;0,3,5=12,7=0.000000
L 2.10340039 -1.6638 2.09523327 -1.6638 2 P 0 ;0,3,5=12,7=0.000000
L 2.09523327 -1.6638 2.08706624 -1.66679941 2 P 0 ;0,3,5=12,7=0.000000
L 2.08706624 -1.66679941 2.08006565 -1.67430059 2 P 0 ;0,3,5=12,7=0.000000
L 2.00990108 -1.7538 2.01923455 -1.75230039 2 P 0 ;0,3,5=12,7=0.000000
L 2.01923455 -1.75230039 2.02739951 -1.74630167 2 P 0 ;0,3,5=12,7=0.000000
L 2.02739951 -1.74630167 2.0344002 -1.73730079 2 P 0 ;0,3,5=12,7=0.000000
L 2.0344002 -1.73730079 2.03906791 -1.7268003 2 P 0 ;0,3,5=12,7=0.000000
L 2.03906791 -1.7268003 2.04140079 -1.7148001 2 P 0 ;0,3,5=12,7=0.000000
L 2.04140079 -1.7148001 2.04140079 -1.7028 2 P 0 ;0,3,5=12,7=0.000000
L 2.04140079 -1.7028 2.03906791 -1.6907998 2 P 0 ;0,3,5=12,7=0.000000
L 2.03906791 -1.6907998 2.0344002 -1.68029931 2 P 0 ;0,3,5=12,7=0.000000
L 2.0344002 -1.68029931 2.02739951 -1.67130118 2 P 0 ;0,3,5=12,7=0.000000
L 2.02739951 -1.67130118 2.01923455 -1.6652997 2 P 0 ;0,3,5=12,7=0.000000
L 2.01923455 -1.6652997 2.00990108 -1.6638 2 P 0 ;0,3,5=12,7=0.000000
L 2.00990108 -1.6638 2.00056762 -1.6652997 2 P 0 ;0,3,5=12,7=0.000000
L 2.00056762 -1.6652997 1.99240059 -1.67130118 2 P 0 ;0,3,5=12,7=0.000000
L 1.99240059 -1.67130118 1.9853999 -1.68029931 2 P 0 ;0,3,5=12,7=0.000000
L 1.9853999 -1.68029931 1.98073219 -1.6907998 2 P 0 ;0,3,5=12,7=0.000000
L 1.98073219 -1.6907998 1.97839931 -1.7028 2 P 0 ;0,3,5=12,7=0.000000
L 1.97839931 -1.7028 1.97839931 -1.7148001 2 P 0 ;0,3,5=12,7=0.000000
L 1.97839931 -1.7148001 1.98073219 -1.7268003 2 P 0 ;0,3,5=12,7=0.000000
L 1.98073219 -1.7268003 1.9853999 -1.73730079 2 P 0 ;0,3,5=12,7=0.000000
L 1.9853999 -1.73730079 1.99240059 -1.74630167 2 P 0 ;0,3,5=12,7=0.000000
L 1.99240059 -1.74630167 2.00056762 -1.75230039 2 P 0 ;0,3,5=12,7=0.000000
L 2.00056762 -1.75230039 2.00990108 -1.7538 2 P 0 ;0,3,5=12,7=0.000000
L 1.94323376 -1.6638 1.94323376 -1.7538 2 P 0 ;0,3,5=12,7=0.000000
L 1.94323376 -1.7538 1.89656634 -1.7538 2 P 0 ;0,3,5=12,7=0.000000
L 1.85556654 -1.7538 1.85556654 -1.6638 2 P 0 ;0,3,5=12,7=0.000000
L 1.85556654 -1.6638 1.83223396 -1.6638 2 P 0 ;0,3,5=12,7=0.000000
L 1.83223396 -1.6638 1.82290049 -1.66830187 2 P 0 ;0,3,5=12,7=0.000000
L 1.82290049 -1.66830187 1.8158998 -1.67430059 2 P 0 ;0,3,5=12,7=0.000000
L 1.8158998 -1.67430059 1.81006565 -1.68329862 2 P 0 ;0,3,5=12,7=0.000000
L 1.81006565 -1.68329862 1.8053999 -1.69380187 2 P 0 ;0,3,5=12,7=0.000000
L 1.8053999 -1.69380187 1.80423356 -1.70880138 2 P 0 ;0,3,5=12,7=0.000000
L 1.80423356 -1.70880138 1.8053999 -1.72380098 2 P 0 ;0,3,5=12,7=0.000000
L 1.8053999 -1.72380098 1.81006565 -1.73430148 2 P 0 ;0,3,5=12,7=0.000000
L 1.81006565 -1.73430148 1.8158998 -1.74330226 2 P 0 ;0,3,5=12,7=0.000000
L 1.8158998 -1.74330226 1.82290049 -1.74930098 2 P 0 ;0,3,5=12,7=0.000000
L 1.82290049 -1.74930098 1.83223396 -1.7538 2 P 0 ;0,3,5=12,7=0.000000
L 1.83223396 -1.7538 1.85556654 -1.7538 2 P 0 ;0,3,5=12,7=0.000000
L 1.71656634 -1.7538 1.76323376 -1.7538 2 P 0 ;0,3,5=12,7=0.000000
L 1.76323376 -1.7538 1.76323376 -1.6638 2 P 0 ;0,3,5=12,7=0.000000
L 1.76323376 -1.6638 1.71656634 -1.6638 2 P 0 ;0,3,5=12,7=0.000000
L 1.73523327 -1.70729902 1.76323376 -1.70729902 2 P 0 ;0,3,5=12,7=0.000000
L 1.67323376 -1.7538 1.67323376 -1.6638 2 P 0 ;0,3,5=12,7=0.000000
L 1.67323376 -1.6638 1.64406693 -1.6638 2 P 0 ;0,3,5=12,7=0.000000
L 1.64406693 -1.6638 1.63473346 -1.66830187 2 P 0 ;0,3,5=12,7=0.000000
L 1.63473346 -1.66830187 1.62889921 -1.67430059 2 P 0 ;0,3,5=12,7=0.000000
L 1.62889921 -1.67430059 1.62656634 -1.68630069 2 P 0 ;0,3,5=12,7=0.000000
L 1.62656634 -1.68630069 1.62889921 -1.69830089 2 P 0 ;0,3,5=12,7=0.000000
L 1.62889921 -1.69830089 1.6358998 -1.70579931 2 P 0 ;0,3,5=12,7=0.000000
L 1.6358998 -1.70579931 1.64406693 -1.71030108 2 P 0 ;0,3,5=12,7=0.000000
L 1.64406693 -1.71030108 1.67323376 -1.71030108 2 P 0 ;0,3,5=12,7=0.000000
L 1.64406693 -1.71030108 1.62656634 -1.7538 2 P 0 ;0,3,5=12,7=0.000000
L 1.49323376 -1.7538 1.49323376 -1.6638 2 P 0 ;0,3,5=12,7=0.000000
L 1.49323376 -1.6638 1.46523327 -1.6638 2 P 0 ;0,3,5=12,7=0.000000
L 1.46523327 -1.6638 1.4558998 -1.66830187 2 P 0 ;0,3,5=12,7=0.000000
L 1.4558998 -1.66830187 1.44889921 -1.67879961 2 P 0 ;0,3,5=12,7=0.000000
L 1.44889921 -1.67879961 1.44656634 -1.6907998 2 P 0 ;0,3,5=12,7=0.000000
L 1.44656634 -1.6907998 1.44889921 -1.7028 2 P 0 ;0,3,5=12,7=0.000000
L 1.44889921 -1.7028 1.45473346 -1.71180079 2 P 0 ;0,3,5=12,7=0.000000
L 1.45473346 -1.71180079 1.46523327 -1.71630256 2 P 0 ;0,3,5=12,7=0.000000
L 1.46523327 -1.71630256 1.49323376 -1.71630256 2 P 0 ;0,3,5=12,7=0.000000
L 1.40906791 -1.7538 1.37990108 -1.6638 2 P 0 ;0,3,5=12,7=0.000000
L 1.37990108 -1.6638 1.35073219 -1.7538 2 P 0 ;0,3,5=12,7=0.000000
L 1.36123415 -1.72230128 1.39856811 -1.72230128 2 P 0 ;0,3,5=12,7=0.000000
L 1.3144002 -1.74180266 1.30506663 -1.74930098 2 P 0 ;0,3,5=12,7=0.000000
L 1.30506663 -1.74930098 1.29456683 -1.7538 2 P 0 ;0,3,5=12,7=0.000000
L 1.29456683 -1.7538 1.28523327 -1.7538 2 P 0 ;0,3,5=12,7=0.000000
L 1.28523327 -1.7538 1.2758998 -1.74930098 2 P 0 ;0,3,5=12,7=0.000000
L 1.2758998 -1.74930098 1.26889921 -1.74180266 2 P 0 ;0,3,5=12,7=0.000000
L 1.26889921 -1.74180266 1.2653999 -1.73129941 2 P 0 ;0,3,5=12,7=0.000000
L 1.2653999 -1.73129941 1.26773278 -1.72080157 2 P 0 ;0,3,5=12,7=0.000000
L 1.26773278 -1.72080157 1.27356703 -1.71180079 2 P 0 ;0,3,5=12,7=0.000000
L 1.27356703 -1.71180079 1.28406693 -1.70579931 2 P 0 ;0,3,5=12,7=0.000000
L 1.28406693 -1.70579931 1.29806604 -1.7028 2 P 0 ;0,3,5=12,7=0.000000
L 1.29806604 -1.7028 1.30623307 -1.69680128 2 P 0 ;0,3,5=12,7=0.000000
L 1.30623307 -1.69680128 1.30973445 -1.68630069 2 P 0 ;0,3,5=12,7=0.000000
L 1.30973445 -1.68630069 1.30739951 -1.6758002 2 P 0 ;0,3,5=12,7=0.000000
L 1.30739951 -1.6758002 1.30156742 -1.66830187 2 P 0 ;0,3,5=12,7=0.000000
L 1.30156742 -1.66830187 1.29340039 -1.6638 2 P 0 ;0,3,5=12,7=0.000000
L 1.29340039 -1.6638 1.28523327 -1.6638 2 P 0 ;0,3,5=12,7=0.000000
L 1.28523327 -1.6638 1.27706624 -1.66679941 2 P 0 ;0,3,5=12,7=0.000000
L 1.27706624 -1.66679941 1.27006565 -1.67430059 2 P 0 ;0,3,5=12,7=0.000000
L 1.19990108 -1.6638 1.19990108 -1.7538 2 P 0 ;0,3,5=12,7=0.000000
L 1.22673297 -1.6638 1.17306713 -1.6638 2 P 0 ;0,3,5=12,7=0.000000
L 1.08656634 -1.7538 1.13323376 -1.7538 2 P 0 ;0,3,5=12,7=0.000000
L 1.13323376 -1.7538 1.13323376 -1.6638 2 P 0 ;0,3,5=12,7=0.000000
L 1.13323376 -1.6638 1.08656634 -1.6638 2 P 0 ;0,3,5=12,7=0.000000
L 1.10523327 -1.70729902 1.13323376 -1.70729902 2 P 0 ;0,3,5=12,7=0.000000
L 0.93573317 -1.78379902 0.94739951 -1.76879951 2 P 0 ;0,3,5=12,7=0.000000
L 0.94739951 -1.76879951 0.95323376 -1.7538 2 P 0 ;0,3,5=12,7=0.000000
L 0.95323376 -1.7538 0.95323376 -1.69380187 2 P 0 ;0,3,5=12,7=0.000000
L 0.95323376 -1.69380187 0.94739951 -1.67879961 2 P 0 ;0,3,5=12,7=0.000000
L 0.94739951 -1.67879961 0.93573317 -1.6638 2 P 0 ;0,3,5=12,7=0.000000
L 0.83056762 -1.70579931 0.8258998 -1.7013003 2 P 0 ;0,3,5=12,7=0.000000
L 0.8258998 -1.7013003 0.82240059 -1.69380187 2 P 0 ;0,3,5=12,7=0.000000
L 0.82240059 -1.69380187 0.82006565 -1.68329862 2 P 0 ;0,3,5=12,7=0.000000
L 0.82006565 -1.68329862 0.82240059 -1.67430059 2 P 0 ;0,3,5=12,7=0.000000
L 0.82240059 -1.67430059 0.82706624 -1.66830187 2 P 0 ;0,3,5=12,7=0.000000
L 0.82706624 -1.66830187 0.83523327 -1.6638 2 P 0 ;0,3,5=12,7=0.000000
L 0.83523327 -1.6638 0.86673297 -1.6638 2 P 0 ;0,3,5=12,7=0.000000
L 0.86673297 -1.6638 0.86673297 -1.7538 2 P 0 ;0,3,5=12,7=0.000000
L 0.86673297 -1.7538 0.82823268 -1.7538 2 P 0 ;0,3,5=12,7=0.000000
L 0.82823268 -1.7538 0.82006565 -1.74780138 2 P 0 ;0,3,5=12,7=0.000000
L 0.82006565 -1.74780138 0.8153999 -1.73880049 2 P 0 ;0,3,5=12,7=0.000000
L 0.8153999 -1.73880049 0.81306713 -1.7283 2 P 0 ;0,3,5=12,7=0.000000
L 0.81306713 -1.7283 0.8153999 -1.71780226 2 P 0 ;0,3,5=12,7=0.000000
L 0.8153999 -1.71780226 0.82240059 -1.70880138 2 P 0 ;0,3,5=12,7=0.000000
L 0.82240059 -1.70880138 0.83056762 -1.70579931 2 P 0 ;0,3,5=12,7=0.000000
L 0.83056762 -1.70579931 0.86673297 -1.70579931 2 P 0 ;0,3,5=12,7=0.000000
L 0.74990108 -1.7538 0.75923455 -1.75230039 2 P 0 ;0,3,5=12,7=0.000000
L 0.75923455 -1.75230039 0.76739951 -1.74630167 2 P 0 ;0,3,5=12,7=0.000000
L 0.76739951 -1.74630167 0.7744002 -1.73730079 2 P 0 ;0,3,5=12,7=0.000000
L 0.7744002 -1.73730079 0.77906791 -1.7268003 2 P 0 ;0,3,5=12,7=0.000000
L 0.77906791 -1.7268003 0.78140079 -1.7148001 2 P 0 ;0,3,5=12,7=0.000000
L 0.78140079 -1.7148001 0.78140079 -1.7028 2 P 0 ;0,3,5=12,7=0.000000
L 0.78140079 -1.7028 0.77906791 -1.6907998 2 P 0 ;0,3,5=12,7=0.000000
L 0.77906791 -1.6907998 0.7744002 -1.68029931 2 P 0 ;0,3,5=12,7=0.000000
L 0.7744002 -1.68029931 0.76739951 -1.67130118 2 P 0 ;0,3,5=12,7=0.000000
L 0.76739951 -1.67130118 0.75923455 -1.6652997 2 P 0 ;0,3,5=12,7=0.000000
L 0.75923455 -1.6652997 0.74990108 -1.6638 2 P 0 ;0,3,5=12,7=0.000000
L 0.74990108 -1.6638 0.74056762 -1.6652997 2 P 0 ;0,3,5=12,7=0.000000
L 0.74056762 -1.6652997 0.73240059 -1.67130118 2 P 0 ;0,3,5=12,7=0.000000
L 0.73240059 -1.67130118 0.7253999 -1.68029931 2 P 0 ;0,3,5=12,7=0.000000
L 0.7253999 -1.68029931 0.72073219 -1.6907998 2 P 0 ;0,3,5=12,7=0.000000
L 0.72073219 -1.6907998 0.71839931 -1.7028 2 P 0 ;0,3,5=12,7=0.000000
L 0.71839931 -1.7028 0.71839931 -1.7148001 2 P 0 ;0,3,5=12,7=0.000000
L 0.71839931 -1.7148001 0.72073219 -1.7268003 2 P 0 ;0,3,5=12,7=0.000000
L 0.72073219 -1.7268003 0.7253999 -1.73730079 2 P 0 ;0,3,5=12,7=0.000000
L 0.7253999 -1.73730079 0.73240059 -1.74630167 2 P 0 ;0,3,5=12,7=0.000000
L 0.73240059 -1.74630167 0.74056762 -1.75230039 2 P 0 ;0,3,5=12,7=0.000000
L 0.74056762 -1.75230039 0.74990108 -1.7538 2 P 0 ;0,3,5=12,7=0.000000
L 0.65990108 -1.6638 0.65990108 -1.7538 2 P 0 ;0,3,5=12,7=0.000000
L 0.68673297 -1.6638 0.63306713 -1.6638 2 P 0 ;0,3,5=12,7=0.000000
L 0.56406693 -1.78379902 0.55240059 -1.76879951 2 P 0 ;0,3,5=12,7=0.000000
L 0.55240059 -1.76879951 0.54656634 -1.7538 2 P 0 ;0,3,5=12,7=0.000000
L 0.54656634 -1.7538 0.54656634 -1.69380187 2 P 0 ;0,3,5=12,7=0.000000
L 0.54656634 -1.69380187 0.55240059 -1.67879961 2 P 0 ;0,3,5=12,7=0.000000
L 0.55240059 -1.67879961 0.56406693 -1.6638 2 P 0 ;0,3,5=12,7=0.000000
L 3.72973337 -1.97380098 3.76006654 -1.97380098 2 P 0 ;0,5=13,7=0.000000
L 3.06989892 -2.2538 3.06989892 -2.1638 2 P 0 ;0,5=14,7=0.000000
L 3.06989892 -2.1638 3.0558997 -2.18179892 2 P 0 ;0,5=14,7=0.000000
L 3.0558997 -2.2538 3.08389803 -2.2538 2 P 0 ;0,5=14,7=0.000000
L 3.64489892 -2.2538 3.64489892 -2.1638 2 P 0 ;0,5=14,7=0.000000
L 3.64489892 -2.1638 3.6308997 -2.18179892 2 P 0 ;0,5=14,7=0.000000
L 3.6308997 -2.2538 3.65889803 -2.2538 2 P 0 ;0,5=14,7=0.000000
L 0.59099833 -1.36499882 0.5990003 -1.35750039 2 P 0 ;0,5=15,7=0.000000
L 0.5990003 -1.35750039 0.60499902 -1.34500315 2 P 0 ;0,5=15,7=0.000000
L 0.60499902 -1.34500315 0.60900187 -1.32749764 2 P 0 ;0,5=15,7=0.000000
L 0.60900187 -1.32749764 0.60499902 -1.31250089 2 P 0 ;0,5=15,7=0.000000
L 0.60499902 -1.31250089 0.59700079 -1.30250305 2 P 0 ;0,5=15,7=0.000000
L 0.59700079 -1.30250305 0.5830001 -1.295 2 P 0 ;0,5=15,7=0.000000
L 0.5830001 -1.295 0.52900059 -1.295 2 P 0 ;0,5=15,7=0.000000
L 0.52900059 -1.295 0.52900059 -1.445 2 P 0 ;0,5=15,7=0.000000
L 0.52900059 -1.445 0.59500118 -1.445 2 P 0 ;0,5=15,7=0.000000
L 0.59500118 -1.445 0.60900187 -1.43500217 2 P 0 ;0,5=15,7=0.000000
L 0.60900187 -1.43500217 0.6170001 -1.42000079 2 P 0 ;0,5=15,7=0.000000
L 0.6170001 -1.42000079 0.62099931 -1.4025 2 P 0 ;0,5=15,7=0.000000
L 0.62099931 -1.4025 0.6170001 -1.38500374 2 P 0 ;0,5=15,7=0.000000
L 0.6170001 -1.38500374 0.60499902 -1.37000236 2 P 0 ;0,5=15,7=0.000000
L 0.60499902 -1.37000236 0.59099833 -1.36499882 2 P 0 ;0,5=15,7=0.000000
L 0.59099833 -1.36499882 0.52900059 -1.36499882 2 P 0 ;0,5=15,7=0.000000
L 0.77100138 -1.445 0.77100138 -1.34500315 2 P 0 ;0,5=15,7=0.000000
L 0.77100138 -1.36249941 0.76299951 -1.35250148 2 P 0 ;0,5=15,7=0.000000
L 0.76299951 -1.35250148 0.75099833 -1.34750256 2 P 0 ;0,5=15,7=0.000000
L 0.75099833 -1.34750256 0.73700138 -1.34500315 2 P 0 ;0,5=15,7=0.000000
L 0.73700138 -1.34500315 0.72300069 -1.35000207 2 P 0 ;0,5=15,7=0.000000
L 0.72300069 -1.35000207 0.71099961 -1.3599999 2 P 0 ;0,5=15,7=0.000000
L 0.71099961 -1.3599999 0.70299764 -1.37500128 2 P 0 ;0,5=15,7=0.000000
L 0.70299764 -1.37500128 0.69899852 -1.39500157 2 P 0 ;0,5=15,7=0.000000
L 0.69899852 -1.39500157 0.70299764 -1.41500187 2 P 0 ;0,5=15,7=0.000000
L 0.70299764 -1.41500187 0.71099961 -1.43000325 2 P 0 ;0,5=15,7=0.000000
L 0.71099961 -1.43000325 0.72300069 -1.44000108 2 P 0 ;0,5=15,7=0.000000
L 0.72300069 -1.44000108 0.73700138 -1.445 2 P 0 ;0,5=15,7=0.000000
L 0.73700138 -1.445 0.75099833 -1.44250059 2 P 0 ;0,5=15,7=0.000000
L 0.75099833 -1.44250059 0.76299951 -1.43500217 2 P 0 ;0,5=15,7=0.000000
L 0.76299951 -1.43500217 0.77100138 -1.42500433 2 P 0 ;0,5=15,7=0.000000
L 0.86700039 -1.445 0.86700039 -1.34500315 2 P 0 ;0,5=15,7=0.000000
L 0.86700039 -1.36499882 0.87699833 -1.35500098 2 P 0 ;0,5=15,7=0.000000
L 0.87699833 -1.35500098 0.8869998 -1.34750256 2 P 0 ;0,5=15,7=0.000000
L 0.8869998 -1.34750256 0.90100049 -1.34500315 2 P 0 ;0,5=15,7=0.000000
L 0.90100049 -1.34500315 0.91099833 -1.34750256 2 P 0 ;0,5=15,7=0.000000
L 0.91099833 -1.34750256 0.92299951 -1.35500098 2 P 0 ;0,5=15,7=0.000000
L 1.02700039 -1.445 1.02700039 -1.34500315 2 P 0 ;0,5=15,7=0.000000
L 1.02700039 -1.36499882 1.03699833 -1.35500098 2 P 0 ;0,5=15,7=0.000000
L 1.03699833 -1.35500098 1.0469998 -1.34750256 2 P 0 ;0,5=15,7=0.000000
L 1.0469998 -1.34750256 1.06100049 -1.34500315 2 P 0 ;0,5=15,7=0.000000
L 1.06100049 -1.34500315 1.07099833 -1.34750256 2 P 0 ;0,5=15,7=0.000000
L 1.07099833 -1.34750256 1.08299951 -1.35500098 2 P 0 ;0,5=15,7=0.000000
L 1.18500089 -1.37750069 1.24900187 -1.37750069 2 P 0 ;0,5=15,7=0.000000
L 1.24900187 -1.37750069 1.24299951 -1.3599999 2 P 0 ;0,5=15,7=0.000000
L 1.24299951 -1.3599999 1.23300157 -1.35000207 2 P 0 ;0,5=15,7=0.000000
L 1.23300157 -1.35000207 1.21900089 -1.34500315 2 P 0 ;0,5=15,7=0.000000
L 1.21900089 -1.34500315 1.2050003 -1.34750256 2 P 0 ;0,5=15,7=0.000000
L 1.2050003 -1.34750256 1.19299911 -1.35500098 2 P 0 ;0,5=15,7=0.000000
L 1.19299911 -1.35500098 1.18500089 -1.37250177 2 P 0 ;0,5=15,7=0.000000
L 1.18500089 -1.37250177 1.18099803 -1.38750315 2 P 0 ;0,5=15,7=0.000000
L 1.18099803 -1.38750315 1.18099803 -1.4025 2 P 0 ;0,5=15,7=0.000000
L 1.18099803 -1.4025 1.18500089 -1.41750138 2 P 0 ;0,5=15,7=0.000000
L 1.18500089 -1.41750138 1.19499872 -1.43250276 2 P 0 ;0,5=15,7=0.000000
L 1.19499872 -1.43250276 1.2069998 -1.44250059 2 P 0 ;0,5=15,7=0.000000
L 1.2069998 -1.44250059 1.22100049 -1.445 2 P 0 ;0,5=15,7=0.000000
L 1.22100049 -1.445 1.23500118 -1.44000108 2 P 0 ;0,5=15,7=0.000000
L 1.23500118 -1.44000108 1.24900187 -1.42500433 2 P 0 ;0,5=15,7=0.000000
L 1.37499813 -1.445 1.37499813 -1.295 2 P 0 ;0,5=15,7=0.000000
L 1.50500089 -1.37750069 1.56900187 -1.37750069 2 P 0 ;0,5=15,7=0.000000
L 1.56900187 -1.37750069 1.56299951 -1.3599999 2 P 0 ;0,5=15,7=0.000000
L 1.56299951 -1.3599999 1.55300157 -1.35000207 2 P 0 ;0,5=15,7=0.000000
L 1.55300157 -1.35000207 1.53900089 -1.34500315 2 P 0 ;0,5=15,7=0.000000
L 1.53900089 -1.34500315 1.5250003 -1.34750256 2 P 0 ;0,5=15,7=0.000000
L 1.5250003 -1.34750256 1.51299911 -1.35500098 2 P 0 ;0,5=15,7=0.000000
L 1.51299911 -1.35500098 1.50500089 -1.37250177 2 P 0 ;0,5=15,7=0.000000
L 1.50500089 -1.37250177 1.50099803 -1.38750315 2 P 0 ;0,5=15,7=0.000000
L 1.50099803 -1.38750315 1.50099803 -1.4025 2 P 0 ;0,5=15,7=0.000000
L 1.50099803 -1.4025 1.50500089 -1.41750138 2 P 0 ;0,5=15,7=0.000000
L 1.50500089 -1.41750138 1.51499872 -1.43250276 2 P 0 ;0,5=15,7=0.000000
L 1.51499872 -1.43250276 1.5269998 -1.44250059 2 P 0 ;0,5=15,7=0.000000
L 1.5269998 -1.44250059 1.54100049 -1.445 2 P 0 ;0,5=15,7=0.000000
L 1.54100049 -1.445 1.55500118 -1.44000108 2 P 0 ;0,5=15,7=0.000000
L 1.55500118 -1.44000108 1.56900187 -1.42500433 2 P 0 ;0,5=15,7=0.000000
L 1.6529998 -1.48999951 1.66500089 -1.49499843 2 P 0 ;0,5=15,7=0.000000
L 1.66500089 -1.49499843 1.68100108 -1.48999951 2 P 0 ;0,5=15,7=0.000000
L 1.68100108 -1.48999951 1.69099902 -1.48000167 2 P 0 ;0,5=15,7=0.000000
L 1.69099902 -1.48000167 1.69900089 -1.4674997 2 P 0 ;0,5=15,7=0.000000
L 1.69900089 -1.4674997 1.71099833 -1.42750374 2 P 0 ;0,5=15,7=0.000000
L 1.71099833 -1.42750374 1.7370001 -1.34500315 2 P 0 ;0,5=15,7=0.000000
L 1.67299911 -1.34500315 1.71099833 -1.42750374 2 P 0 ;0,5=15,7=0.000000
L 1.82500089 -1.37750069 1.88900187 -1.37750069 2 P 0 ;0,5=15,7=0.000000
L 1.88900187 -1.37750069 1.88299951 -1.3599999 2 P 0 ;0,5=15,7=0.000000
L 1.88299951 -1.3599999 1.87300157 -1.35000207 2 P 0 ;0,5=15,7=0.000000
L 1.87300157 -1.35000207 1.85900089 -1.34500315 2 P 0 ;0,5=15,7=0.000000
L 1.85900089 -1.34500315 1.8450003 -1.34750256 2 P 0 ;0,5=15,7=0.000000
L 1.8450003 -1.34750256 1.83299911 -1.35500098 2 P 0 ;0,5=15,7=0.000000
L 1.83299911 -1.35500098 1.82500089 -1.37250177 2 P 0 ;0,5=15,7=0.000000
L 1.82500089 -1.37250177 1.82099803 -1.38750315 2 P 0 ;0,5=15,7=0.000000
L 1.82099803 -1.38750315 1.82099803 -1.4025 2 P 0 ;0,5=15,7=0.000000
L 1.82099803 -1.4025 1.82500089 -1.41750138 2 P 0 ;0,5=15,7=0.000000
L 1.82500089 -1.41750138 1.83499872 -1.43250276 2 P 0 ;0,5=15,7=0.000000
L 1.83499872 -1.43250276 1.8469998 -1.44250059 2 P 0 ;0,5=15,7=0.000000
L 1.8469998 -1.44250059 1.86100049 -1.445 2 P 0 ;0,5=15,7=0.000000
L 1.86100049 -1.445 1.87500118 -1.44000108 2 P 0 ;0,5=15,7=0.000000
L 1.87500118 -1.44000108 1.88900187 -1.42500433 2 P 0 ;0,5=15,7=0.000000
L 2.18699921 -1.37000236 2.22700167 -1.37000236 2 P 0 ;0,5=15,7=0.000000
L 2.22700167 -1.37000236 2.22700167 -1.41500187 2 P 0 ;0,5=15,7=0.000000
L 2.22700167 -1.41500187 2.21500059 -1.43000325 2 P 0 ;0,5=15,7=0.000000
L 2.21500059 -1.43000325 2.2009999 -1.44000108 2 P 0 ;0,5=15,7=0.000000
L 2.2009999 -1.44000108 2.18100049 -1.445 2 P 0 ;0,5=15,7=0.000000
L 2.18100049 -1.445 2.16100108 -1.44000108 2 P 0 ;0,5=15,7=0.000000
L 2.16100108 -1.44000108 2.14700039 -1.43000325 2 P 0 ;0,5=15,7=0.000000
L 2.14700039 -1.43000325 2.13499931 -1.41500187 2 P 0 ;0,5=15,7=0.000000
L 2.13499931 -1.41500187 2.12699734 -1.39750108 2 P 0 ;0,5=15,7=0.000000
L 2.12699734 -1.39750108 2.12299823 -1.37750069 2 P 0 ;0,5=15,7=0.000000
L 2.12299823 -1.37750069 2.12299823 -1.3599999 2 P 0 ;0,5=15,7=0.000000
L 2.12299823 -1.3599999 2.12699734 -1.34500315 2 P 0 ;0,5=15,7=0.000000
L 2.12699734 -1.34500315 2.13499931 -1.32749764 2 P 0 ;0,5=15,7=0.000000
L 2.13499931 -1.32749764 2.14700039 -1.31250089 2 P 0 ;0,5=15,7=0.000000
L 2.14700039 -1.31250089 2.15899783 -1.30250305 2 P 0 ;0,5=15,7=0.000000
L 2.15899783 -1.30250305 2.17499813 -1.295 2 P 0 ;0,5=15,7=0.000000
L 2.17499813 -1.295 2.18899882 -1.295 2 P 0 ;0,5=15,7=0.000000
L 2.18899882 -1.295 2.20499902 -1.29999902 2 P 0 ;0,5=15,7=0.000000
L 2.20499902 -1.29999902 2.2170001 -1.31000138 2 P 0 ;0,5=15,7=0.000000
L 2.29699892 -1.31999931 2.309 -1.30500246 2 P 0 ;0,5=15,7=0.000000
L 2.309 -1.30500246 2.32300069 -1.29749951 2 P 0 ;0,5=15,7=0.000000
L 2.32300069 -1.29749951 2.33900089 -1.295 2 P 0 ;0,5=15,7=0.000000
L 2.33900089 -1.295 2.3590003 -1.29999902 2 P 0 ;0,5=15,7=0.000000
L 2.3590003 -1.29999902 2.37300098 -1.31250089 2 P 0 ;0,5=15,7=0.000000
L 2.37300098 -1.31250089 2.3770001 -1.32749764 2 P 0 ;0,5=15,7=0.000000
L 2.3770001 -1.32749764 2.37500059 -1.34250364 2 P 0 ;0,5=15,7=0.000000
L 2.37500059 -1.34250364 2.36699862 -1.35500098 2 P 0 ;0,5=15,7=0.000000
L 2.36699862 -1.35500098 2.3269998 -1.3800002 2 P 0 ;0,5=15,7=0.000000
L 2.3269998 -1.3800002 2.309 -1.39750108 2 P 0 ;0,5=15,7=0.000000
L 2.309 -1.39750108 2.29699892 -1.42250482 2 P 0 ;0,5=15,7=0.000000
L 2.29699892 -1.42250482 2.2929998 -1.445 2 P 0 ;0,5=15,7=0.000000
L 2.2929998 -1.445 2.3770001 -1.445 2 P 0 ;0,5=15,7=0.000000
L 2.6129998 -1.42500433 2.629 -1.43750167 2 P 0 ;0,5=15,7=0.000000
L 2.629 -1.43750167 2.6469998 -1.445 2 P 0 ;0,5=15,7=0.000000
L 2.6469998 -1.445 2.6630001 -1.445 2 P 0 ;0,5=15,7=0.000000
L 2.6630001 -1.445 2.6790003 -1.43750167 2 P 0 ;0,5=15,7=0.000000
L 2.6790003 -1.43750167 2.69100138 -1.42500433 2 P 0 ;0,5=15,7=0.000000
L 2.69100138 -1.42500433 2.6970001 -1.40749892 2 P 0 ;0,5=15,7=0.000000
L 2.6970001 -1.40749892 2.69300098 -1.39000266 2 P 0 ;0,5=15,7=0.000000
L 2.69300098 -1.39000266 2.68299951 -1.37500128 2 P 0 ;0,5=15,7=0.000000
L 2.68299951 -1.37500128 2.66499961 -1.36499882 2 P 0 ;0,5=15,7=0.000000
L 2.66499961 -1.36499882 2.64100108 -1.3599999 2 P 0 ;0,5=15,7=0.000000
L 2.64100108 -1.3599999 2.62700039 -1.35000207 2 P 0 ;0,5=15,7=0.000000
L 2.62700039 -1.35000207 2.62099803 -1.33250118 2 P 0 ;0,5=15,7=0.000000
L 2.62099803 -1.33250118 2.62500089 -1.31500039 2 P 0 ;0,5=15,7=0.000000
L 2.62500089 -1.31500039 2.63499872 -1.30250305 2 P 0 ;0,5=15,7=0.000000
L 2.63499872 -1.30250305 2.64899941 -1.295 2 P 0 ;0,5=15,7=0.000000
L 2.64899941 -1.295 2.6630001 -1.295 2 P 0 ;0,5=15,7=0.000000
L 2.6630001 -1.295 2.67700079 -1.29999902 2 P 0 ;0,5=15,7=0.000000
L 2.67700079 -1.29999902 2.68900187 -1.31250089 2 P 0 ;0,5=15,7=0.000000
L 2.7729998 -1.445 2.8570001 -1.295 2 P 0 ;0,5=15,7=0.000000
L 2.7729998 -1.295 2.8570001 -1.445 2 P 0 ;0,5=15,7=0.000000
L 2.92299823 -1.445 2.92299823 -1.295 2 P 0 ;0,5=15,7=0.000000
L 2.92299823 -1.295 2.97499813 -1.42000079 2 P 0 ;0,5=15,7=0.000000
L 2.97499813 -1.42000079 3.02700167 -1.295 2 P 0 ;0,5=15,7=0.000000
L 3.02700167 -1.295 3.02700167 -1.445 2 P 0 ;0,5=15,7=0.000000
L 3.09699892 -1.31999931 3.109 -1.30500246 2 P 0 ;0,5=15,7=0.000000
L 3.109 -1.30500246 3.12300069 -1.29749951 2 P 0 ;0,5=15,7=0.000000
L 3.12300069 -1.29749951 3.13900089 -1.295 2 P 0 ;0,5=15,7=0.000000
L 3.13900089 -1.295 3.1590003 -1.29999902 2 P 0 ;0,5=15,7=0.000000
L 3.1590003 -1.29999902 3.17300098 -1.31250089 2 P 0 ;0,5=15,7=0.000000
L 3.17300098 -1.31250089 3.1770001 -1.32749764 2 P 0 ;0,5=15,7=0.000000
L 3.1770001 -1.32749764 3.17500059 -1.34250364 2 P 0 ;0,5=15,7=0.000000
L 3.17500059 -1.34250364 3.16699862 -1.35500098 2 P 0 ;0,5=15,7=0.000000
L 3.16699862 -1.35500098 3.1269998 -1.3800002 2 P 0 ;0,5=15,7=0.000000
L 3.1269998 -1.3800002 3.109 -1.39750108 2 P 0 ;0,5=15,7=0.000000
L 3.109 -1.39750108 3.09699892 -1.42250482 2 P 0 ;0,5=15,7=0.000000
L 3.09699892 -1.42250482 3.0929998 -1.445 2 P 0 ;0,5=15,7=0.000000
L 3.0929998 -1.445 3.1770001 -1.445 2 P 0 ;0,5=15,7=0.000000
L 3.269 -1.39500157 3.3209999 -1.39500157 2 P 0 ;0,5=15,7=0.000000
L 3.41499931 -1.445 3.41499931 -1.295 2 P 0 ;0,5=15,7=0.000000
L 3.41499931 -1.295 3.46499961 -1.295 2 P 0 ;0,5=15,7=0.000000
L 3.46499961 -1.295 3.4809999 -1.30250305 2 P 0 ;0,5=15,7=0.000000
L 3.4809999 -1.30250305 3.49100138 -1.31250089 2 P 0 ;0,5=15,7=0.000000
L 3.49100138 -1.31250089 3.49500059 -1.33250118 2 P 0 ;0,5=15,7=0.000000
L 3.49500059 -1.33250118 3.49100138 -1.35250148 2 P 0 ;0,5=15,7=0.000000
L 3.49100138 -1.35250148 3.4790003 -1.36499882 2 P 0 ;0,5=15,7=0.000000
L 3.4790003 -1.36499882 3.46499961 -1.37250177 2 P 0 ;0,5=15,7=0.000000
L 3.46499961 -1.37250177 3.41499931 -1.37250177 2 P 0 ;0,5=15,7=0.000000
L 3.46499961 -1.37250177 3.49500059 -1.445 2 P 0 ;0,5=15,7=0.000000
L 3.61499813 -1.34500315 3.61499813 -1.445 2 P 0 ;0,5=15,7=0.000000
L 3.61499813 -1.30500246 3.61099902 -1.30250305 2 P 0 ;0,5=15,7=0.000000
L 3.61099902 -1.30250305 3.61099902 -1.29749951 2 P 0 ;0,5=15,7=0.000000
L 3.61099902 -1.29749951 3.61499813 -1.295 2 P 0 ;0,5=15,7=0.000000
L 3.61499813 -1.295 3.61900089 -1.29749951 2 P 0 ;0,5=15,7=0.000000
L 3.61900089 -1.29749951 3.61900089 -1.30250305 2 P 0 ;0,5=15,7=0.000000
L 3.61900089 -1.30250305 3.61499813 -1.30500246 2 P 0 ;0,5=15,7=0.000000
L 3.74500089 -1.42750374 3.75499872 -1.43750167 2 P 0 ;0,5=15,7=0.000000
L 3.75499872 -1.43750167 3.76899941 -1.445 2 P 0 ;0,5=15,7=0.000000
L 3.76899941 -1.445 3.78100049 -1.445 2 P 0 ;0,5=15,7=0.000000
L 3.78100049 -1.445 3.79300157 -1.44000108 2 P 0 ;0,5=15,7=0.000000
L 3.79300157 -1.44000108 3.8009999 -1.43250276 2 P 0 ;0,5=15,7=0.000000
L 3.8009999 -1.43250276 3.80499902 -1.42250482 2 P 0 ;0,5=15,7=0.000000
L 3.80499902 -1.42250482 3.80299951 -1.40749892 2 P 0 ;0,5=15,7=0.000000
L 3.80299951 -1.40749892 3.79500118 -1.40000049 2 P 0 ;0,5=15,7=0.000000
L 3.79500118 -1.40000049 3.75899783 -1.38500374 2 P 0 ;0,5=15,7=0.000000
L 3.75899783 -1.38500374 3.75099961 -1.36749833 2 P 0 ;0,5=15,7=0.000000
L 3.75099961 -1.36749833 3.75499872 -1.35500098 2 P 0 ;0,5=15,7=0.000000
L 3.75499872 -1.35500098 3.76300069 -1.34750256 2 P 0 ;0,5=15,7=0.000000
L 3.76300069 -1.34750256 3.77499813 -1.34500315 2 P 0 ;0,5=15,7=0.000000
L 3.77499813 -1.34500315 3.78699921 -1.34750256 2 P 0 ;0,5=15,7=0.000000
L 3.78699921 -1.34750256 3.7990003 -1.35500098 2 P 0 ;0,5=15,7=0.000000
L 3.90500089 -1.37750069 3.96900187 -1.37750069 2 P 0 ;0,5=15,7=0.000000
L 3.96900187 -1.37750069 3.96299951 -1.3599999 2 P 0 ;0,5=15,7=0.000000
L 3.96299951 -1.3599999 3.95300157 -1.35000207 2 P 0 ;0,5=15,7=0.000000
L 3.95300157 -1.35000207 3.93900089 -1.34500315 2 P 0 ;0,5=15,7=0.000000
L 3.93900089 -1.34500315 3.9250003 -1.34750256 2 P 0 ;0,5=15,7=0.000000
L 3.9250003 -1.34750256 3.91299911 -1.35500098 2 P 0 ;0,5=15,7=0.000000
L 3.91299911 -1.35500098 3.90500089 -1.37250177 2 P 0 ;0,5=15,7=0.000000
L 3.90500089 -1.37250177 3.90099803 -1.38750315 2 P 0 ;0,5=15,7=0.000000
L 3.90099803 -1.38750315 3.90099803 -1.4025 2 P 0 ;0,5=15,7=0.000000
L 3.90099803 -1.4025 3.90500089 -1.41750138 2 P 0 ;0,5=15,7=0.000000
L 3.90500089 -1.41750138 3.91499872 -1.43250276 2 P 0 ;0,5=15,7=0.000000
L 3.91499872 -1.43250276 3.9269998 -1.44250059 2 P 0 ;0,5=15,7=0.000000
L 3.9269998 -1.44250059 3.94100049 -1.445 2 P 0 ;0,5=15,7=0.000000
L 3.94100049 -1.445 3.95500118 -1.44000108 2 P 0 ;0,5=15,7=0.000000
L 3.95500118 -1.44000108 3.96900187 -1.42500433 2 P 0 ;0,5=15,7=0.000000
L 4.06700039 -1.445 4.06700039 -1.34500315 2 P 0 ;0,5=15,7=0.000000
L 4.06700039 -1.36499882 4.07699833 -1.35500098 2 P 0 ;0,5=15,7=0.000000
L 4.07699833 -1.35500098 4.0869998 -1.34750256 2 P 0 ;0,5=15,7=0.000000
L 4.0869998 -1.34750256 4.10100049 -1.34500315 2 P 0 ;0,5=15,7=0.000000
L 4.10100049 -1.34500315 4.11099833 -1.34750256 2 P 0 ;0,5=15,7=0.000000
L 4.11099833 -1.34750256 4.12299951 -1.35500098 2 P 0 ;0,5=15,7=0.000000
L 4.16964783 -2.2038 4.21839813 -2.0478 2 P 0 ;0,5=16,7=0.000000
L 4.21839813 -2.0478 4.26715207 -2.2038 2 P 0 ;0,5=16,7=0.000000
L 4.24959862 -2.14920217 4.18719774 -2.14920217 2 P 0 ;0,5=16,7=0.000000
L 4.37939813 -2.2038 4.37939813 -2.0478 2 P 0 ;0,5=16,7=0.000000
L 4.37939813 -2.0478 4.35599961 -2.07899813 2 P 0 ;0,5=16,7=0.000000
L 4.35599961 -2.2038 4.40279675 -2.2038 2 P 0 ;0,5=16,7=0.000000
L 2.0009002 -0.9538 2.0009002 -0.8038 2 P 0 ;0,5=17,7=0.000000
L 2.0009002 -0.8038 2.04089902 -0.8038 2 P 0 ;0,5=17,7=0.000000
L 2.04089902 -0.8038 2.05689921 -0.81130305 2 P 0 ;0,5=17,7=0.000000
L 2.05689921 -0.81130305 2.0689003 -0.82130089 2 P 0 ;0,5=17,7=0.000000
L 2.0689003 -0.82130089 2.07890187 -0.83629764 2 P 0 ;0,5=17,7=0.000000
L 2.07890187 -0.83629764 2.0869001 -0.85380315 2 P 0 ;0,5=17,7=0.000000
L 2.0869001 -0.85380315 2.0888997 -0.87880236 2 P 0 ;0,5=17,7=0.000000
L 2.0888997 -0.87880236 2.0869001 -0.90380157 2 P 0 ;0,5=17,7=0.000000
L 2.0869001 -0.90380157 2.07890187 -0.92130246 2 P 0 ;0,5=17,7=0.000000
L 2.07890187 -0.92130246 2.0689003 -0.93630374 2 P 0 ;0,5=17,7=0.000000
L 2.0689003 -0.93630374 2.05689921 -0.94630167 2 P 0 ;0,5=17,7=0.000000
L 2.05689921 -0.94630167 2.04089902 -0.9538 2 P 0 ;0,5=17,7=0.000000
L 2.04089902 -0.9538 2.0009002 -0.9538 2 P 0 ;0,5=17,7=0.000000
L 2.15489783 -0.9538 2.20489813 -0.8038 2 P 0 ;0,5=17,7=0.000000
L 2.20489813 -0.8038 2.25490207 -0.9538 2 P 0 ;0,5=17,7=0.000000
L 2.23689862 -0.90130207 2.17289764 -0.90130207 2 P 0 ;0,5=17,7=0.000000
L 2.36489813 -0.8038 2.36489813 -0.9538 2 P 0 ;0,5=17,7=0.000000
L 2.31890059 -0.8038 2.41089931 -0.8038 2 P 0 ;0,5=17,7=0.000000
L 2.56490059 -0.9538 2.48489931 -0.9538 2 P 0 ;0,5=17,7=0.000000
L 2.48489931 -0.9538 2.48489931 -0.8038 2 P 0 ;0,5=17,7=0.000000
L 2.48489931 -0.8038 2.56490059 -0.8038 2 P 0 ;0,5=17,7=0.000000
L 2.5329001 -0.87629833 2.48489931 -0.87629833 2 P 0 ;0,5=17,7=0.000000
L 2.84489813 -0.9538 2.82889783 -0.95130059 2 P 0 ;0,5=17,7=0.000000
L 2.82889783 -0.95130059 2.81490089 -0.94130276 2 P 0 ;0,5=17,7=0.000000
L 2.81490089 -0.94130276 2.8028998 -0.92630138 2 P 0 ;0,5=17,7=0.000000
L 2.8028998 -0.92630138 2.79489783 -0.90880049 2 P 0 ;0,5=17,7=0.000000
L 2.79489783 -0.90880049 2.79089862 -0.8888002 2 P 0 ;0,5=17,7=0.000000
L 2.79089862 -0.8888002 2.79089862 -0.8687999 2 P 0 ;0,5=17,7=0.000000
L 2.79089862 -0.8687999 2.79489783 -0.84879961 2 P 0 ;0,5=17,7=0.000000
L 2.79489783 -0.84879961 2.8028998 -0.83129872 2 P 0 ;0,5=17,7=0.000000
L 2.8028998 -0.83129872 2.81490089 -0.81630197 2 P 0 ;0,5=17,7=0.000000
L 2.81490089 -0.81630197 2.82889783 -0.80629951 2 P 0 ;0,5=17,7=0.000000
L 2.82889783 -0.80629951 2.84489813 -0.8038 2 P 0 ;0,5=17,7=0.000000
L 2.84489813 -0.8038 2.86089833 -0.80629951 2 P 0 ;0,5=17,7=0.000000
L 2.86089833 -0.80629951 2.87489902 -0.81630197 2 P 0 ;0,5=17,7=0.000000
L 2.87489902 -0.81630197 2.8869001 -0.83129872 2 P 0 ;0,5=17,7=0.000000
L 2.8869001 -0.83129872 2.89490207 -0.84879961 2 P 0 ;0,5=17,7=0.000000
L 2.89490207 -0.84879961 2.89890128 -0.8687999 2 P 0 ;0,5=17,7=0.000000
L 2.89890128 -0.8687999 2.89890128 -0.8888002 2 P 0 ;0,5=17,7=0.000000
L 2.89890128 -0.8888002 2.89490207 -0.90880049 2 P 0 ;0,5=17,7=0.000000
L 2.89490207 -0.90880049 2.8869001 -0.92630138 2 P 0 ;0,5=17,7=0.000000
L 2.8869001 -0.92630138 2.87489902 -0.94130276 2 P 0 ;0,5=17,7=0.000000
L 2.87489902 -0.94130276 2.86089833 -0.95130059 2 P 0 ;0,5=17,7=0.000000
L 2.86089833 -0.95130059 2.84489813 -0.9538 2 P 0 ;0,5=17,7=0.000000
L 3.0488997 -0.81630197 3.03689862 -0.80879902 2 P 0 ;0,5=17,7=0.000000
L 3.03689862 -0.80879902 3.02290157 -0.8038 2 P 0 ;0,5=17,7=0.000000
L 3.02290157 -0.8038 3.00690138 -0.8038 2 P 0 ;0,5=17,7=0.000000
L 3.00690138 -0.8038 2.98889783 -0.81130305 2 P 0 ;0,5=17,7=0.000000
L 2.98889783 -0.81130305 2.97490089 -0.82380039 2 P 0 ;0,5=17,7=0.000000
L 2.97490089 -0.82380039 2.96489931 -0.83880177 2 P 0 ;0,5=17,7=0.000000
L 2.96489931 -0.83880177 2.95689734 -0.86380098 2 P 0 ;0,5=17,7=0.000000
L 2.95689734 -0.86380098 2.95489783 -0.88630069 2 P 0 ;0,5=17,7=0.000000
L 2.95489783 -0.88630069 2.95890059 -0.90880049 2 P 0 ;0,5=17,7=0.000000
L 2.95890059 -0.90880049 2.96489931 -0.92380187 2 P 0 ;0,5=17,7=0.000000
L 2.96489931 -0.92380187 2.97690039 -0.93880325 2 P 0 ;0,5=17,7=0.000000
L 2.97690039 -0.93880325 2.99090108 -0.94880108 2 P 0 ;0,5=17,7=0.000000
L 2.99090108 -0.94880108 3.00489813 -0.9538 2 P 0 ;0,5=17,7=0.000000
L 3.00489813 -0.9538 3.01889882 -0.9538 2 P 0 ;0,5=17,7=0.000000
L 3.01889882 -0.9538 3.03289951 -0.94880108 2 P 0 ;0,5=17,7=0.000000
L 3.03289951 -0.94880108 3.04490059 -0.94130276 2 P 0 ;0,5=17,7=0.000000
L 3.04490059 -0.94130276 3.05490207 -0.93130482 2 P 0 ;0,5=17,7=0.000000
L 3.16489813 -0.8038 3.16489813 -0.9538 2 P 0 ;0,5=17,7=0.000000
L 3.11890059 -0.8038 3.21089931 -0.8038 2 P 0 ;0,5=17,7=0.000000
L 3.28889852 -0.95879892 3.36090138 -0.8038 2 P 0 ;0,5=17,7=0.000000
L 3.44689892 -0.82879931 3.4589 -0.81380246 2 P 0 ;0,5=17,7=0.000000
L 3.4589 -0.81380246 3.47290069 -0.80629951 2 P 0 ;0,5=17,7=0.000000
L 3.47290069 -0.80629951 3.48890089 -0.8038 2 P 0 ;0,5=17,7=0.000000
L 3.48890089 -0.8038 3.5089003 -0.80879902 2 P 0 ;0,5=17,7=0.000000
L 3.5089003 -0.80879902 3.52290098 -0.82130089 2 P 0 ;0,5=17,7=0.000000
L 3.52290098 -0.82130089 3.5269001 -0.83629764 2 P 0 ;0,5=17,7=0.000000
L 3.5269001 -0.83629764 3.52490059 -0.85130364 2 P 0 ;0,5=17,7=0.000000
L 3.52490059 -0.85130364 3.51689862 -0.86380098 2 P 0 ;0,5=17,7=0.000000
L 3.51689862 -0.86380098 3.4768998 -0.8888002 2 P 0 ;0,5=17,7=0.000000
L 3.4768998 -0.8888002 3.4589 -0.90630108 2 P 0 ;0,5=17,7=0.000000
L 3.4589 -0.90630108 3.44689892 -0.93130482 2 P 0 ;0,5=17,7=0.000000
L 3.44689892 -0.93130482 3.4428998 -0.9538 2 P 0 ;0,5=17,7=0.000000
L 3.4428998 -0.9538 3.5269001 -0.9538 2 P 0 ;0,5=17,7=0.000000
L 3.64089902 -0.9538 3.64489813 -0.92130246 2 P 0 ;0,5=17,7=0.000000
L 3.64489813 -0.92130246 3.65090049 -0.89380374 2 P 0 ;0,5=17,7=0.000000
L 3.65090049 -0.89380374 3.65889882 -0.8687999 2 P 0 ;0,5=17,7=0.000000
L 3.65889882 -0.8687999 3.6689003 -0.84130118 2 P 0 ;0,5=17,7=0.000000
L 3.6689003 -0.84130118 3.68490059 -0.8038 2 P 0 ;0,5=17,7=0.000000
L 3.68490059 -0.8038 3.60489931 -0.8038 2 P 0 ;0,5=17,7=0.000000
L 3.76889852 -0.95879892 3.84090138 -0.8038 2 P 0 ;0,5=17,7=0.000000
L 3.92689892 -0.82879931 3.9389 -0.81380246 2 P 0 ;0,5=17,7=0.000000
L 3.9389 -0.81380246 3.95290069 -0.80629951 2 P 0 ;0,5=17,7=0.000000
L 3.95290069 -0.80629951 3.96890089 -0.8038 2 P 0 ;0,5=17,7=0.000000
L 3.96890089 -0.8038 3.9889003 -0.80879902 2 P 0 ;0,5=17,7=0.000000
L 3.9889003 -0.80879902 4.00290098 -0.82130089 2 P 0 ;0,5=17,7=0.000000
L 4.00290098 -0.82130089 4.0069001 -0.83629764 2 P 0 ;0,5=17,7=0.000000
L 4.0069001 -0.83629764 4.00490059 -0.85130364 2 P 0 ;0,5=17,7=0.000000
L 4.00490059 -0.85130364 3.99689862 -0.86380098 2 P 0 ;0,5=17,7=0.000000
L 3.99689862 -0.86380098 3.9568998 -0.8888002 2 P 0 ;0,5=17,7=0.000000
L 3.9568998 -0.8888002 3.9389 -0.90630108 2 P 0 ;0,5=17,7=0.000000
L 3.9389 -0.90630108 3.92689892 -0.93130482 2 P 0 ;0,5=17,7=0.000000
L 3.92689892 -0.93130482 3.9228998 -0.9538 2 P 0 ;0,5=17,7=0.000000
L 3.9228998 -0.9538 4.0069001 -0.9538 2 P 0 ;0,5=17,7=0.000000
L 4.12489813 -0.8038 4.10889783 -0.80879902 2 P 0 ;0,5=17,7=0.000000
L 4.10889783 -0.80879902 4.09690039 -0.82130089 2 P 0 ;0,5=17,7=0.000000
L 4.09690039 -0.82130089 4.08889852 -0.83629764 2 P 0 ;0,5=17,7=0.000000
L 4.08889852 -0.83629764 4.0828998 -0.85630256 2 P 0 ;0,5=17,7=0.000000
L 4.0828998 -0.85630256 4.0809002 -0.87880236 2 P 0 ;0,5=17,7=0.000000
L 4.0809002 -0.87880236 4.0828998 -0.90130207 2 P 0 ;0,5=17,7=0.000000
L 4.0828998 -0.90130207 4.08889852 -0.92130246 2 P 0 ;0,5=17,7=0.000000
L 4.08889852 -0.92130246 4.09690039 -0.93630374 2 P 0 ;0,5=17,7=0.000000
L 4.09690039 -0.93630374 4.10889783 -0.94880108 2 P 0 ;0,5=17,7=0.000000
L 4.10889783 -0.94880108 4.12489813 -0.9538 2 P 0 ;0,5=17,7=0.000000
L 4.12489813 -0.9538 4.14089833 -0.94880108 2 P 0 ;0,5=17,7=0.000000
L 4.14089833 -0.94880108 4.15289951 -0.93630374 2 P 0 ;0,5=17,7=0.000000
L 4.15289951 -0.93630374 4.16090138 -0.92130246 2 P 0 ;0,5=17,7=0.000000
L 4.16090138 -0.92130246 4.1669001 -0.90130207 2 P 0 ;0,5=17,7=0.000000
L 4.1669001 -0.90130207 4.1688997 -0.87880236 2 P 0 ;0,5=17,7=0.000000
L 4.1688997 -0.87880236 4.1669001 -0.85630256 2 P 0 ;0,5=17,7=0.000000
L 4.1669001 -0.85630256 4.16090138 -0.83629764 2 P 0 ;0,5=17,7=0.000000
L 4.16090138 -0.83629764 4.15289951 -0.82130089 2 P 0 ;0,5=17,7=0.000000
L 4.15289951 -0.82130089 4.14089833 -0.80879902 2 P 0 ;0,5=17,7=0.000000
L 4.14089833 -0.80879902 4.12489813 -0.8038 2 P 0 ;0,5=17,7=0.000000
L 4.28489813 -0.9538 4.28489813 -0.8038 2 P 0 ;0,5=17,7=0.000000
L 4.28489813 -0.8038 4.26089961 -0.83379823 2 P 0 ;0,5=17,7=0.000000
L 4.26089961 -0.9538 4.30889665 -0.9538 2 P 0 ;0,5=17,7=0.000000
L 4.44089902 -0.9538 4.44489813 -0.92130246 2 P 0 ;0,5=17,7=0.000000
L 4.44489813 -0.92130246 4.45090049 -0.89380374 2 P 0 ;0,5=17,7=0.000000
L 4.45090049 -0.89380374 4.45889882 -0.8687999 2 P 0 ;0,5=17,7=0.000000
L 4.45889882 -0.8687999 4.4689003 -0.84130118 2 P 0 ;0,5=17,7=0.000000
L 4.4689003 -0.84130118 4.48490059 -0.8038 2 P 0 ;0,5=17,7=0.000000
L 4.48490059 -0.8038 4.40489931 -0.8038 2 P 0 ;0,5=17,7=0.000000

### steps/drc/layers/smc/features
#
#Feature symbol names
#
$0 r2
$1 r5
$2 r6
$3 r11
$4 r14
$5 r15
$6 r29.2
$7 r34
$8 r48.7
$9 r51.06
$10 r53.37
$11 r65.18
$12 r79.8
$13 r100
$14 r106.52
$15 r112.43
$16 r132.11
$17 r139
$18 r143.92
$19 r151.8
$20 r171.48
$21 r191.17
$22 r319.96
$23 r359.33
$24 r407.7
$25 s25
$26 s33.46
$27 s35
$28 s48.7
$29 s55
$30 s79.8
$31 oval216.85x157.8
$32 rect105x130.98
$33 rect12.6x36.22xr6.3x12
$34 rect12.6x36.22xr6.3x34
$35 rect16.02x48.31
$36 rect166.42x83.74
$37 rect18.78x56.18
$38 rect20.75x40.43
$39 rect20.75x71.93
$40 rect241.22x1619.17
$41 rect28.62x42.4
$42 rect28.62x46.34
$43 rect30.2x77.44
$44 rect33.46x31.5
$45 rect34.92x55
$46 rect36.22x12.6xr6.3x14
$47 rect36.22x12.6xr6.3x23
$48 rect40.43x20.75
$49 rect44.37x113.27
$50 rect77.83x142.8
$51 rect79.8x71.93
$52 rect83.74x162.48
$53 rect83.74x40.43
$54 rect83.74x48.31

#
#Feature attribute names
#
@0 .nomenclature
@1 .smd
@2 .test_point
@3 .geometry
@4 .string
@5 .pad_usage
@6 .string_angle

#
#Feature attribute text strings
#
&0 TPB30V20D10AT28BPM
&1 R0_35X1_3
&2 C1_11P0_7
&3 C1_11P0_7TP
&4 S0_508
&5 R1_05X0_6
&6 ICT-TPT30TPM
&7 R1_27X0_76
&8 R0_9X0_4
&9 R0_9X2
&10 R1_1X0_28
&11 C0_64
&12 V17D8AT30SM11
&13 V20D10AT28SM14
&14 C2_5N
&15 R2X1_1
&16 R1X2_75
&17 S1_11P0_7TP
&18 S1_11P0_7
&19 SP-SC0_2X0_8TI-B
&20 R1_7X0_4
&21 S1_27
&22 R1_7X1_9
&23 S0_762
&24 R1_85X3_5
&25 R4X2
&26 R3_2X2_54
&27 R0_95X0_6
&28 R0_64X1_84
&29 R4_1X2
&30 V20D10AT28PG
&31 C1_17P0_76TPM
&32 C1_9P1_4
&33 S1_9P1_4
&34 SP-8C5_2P0_254
&35 R6X41
&36 SP-9C5_7P0_254
&37 C3_175N-A
&38 E-C40SM100PM5-G
&39 C10N
&40 C3_3N
&41 C4_5N-B
&42 C4N-B
&43 C3_5N
&44 O5X3_5N
&45 C3N
&46 C1_3N
&47 S0TM0_85
&48 R0TM0_85X0_8
&49 C2_35N
&50 C1N
&51 SHEET
&52 TITLE
&53 SCALE 1:1
&54 LAYER
&55 OF
&56 ART
&57 -
&58 1
&59 SOLDER MASK (TOP)
&60 Barreleye G2 SXM2-Riser
&61 A1
&62 DATE OCT/27/2017

#
#Layer features
#
P 7.785 4.45 1 P 0 0;3=0,5=1
P 7.96733002 4.85788002 37 P 0 0;1,3=1,5=0
P 7.835 4.45 1 P 0 0;3=0,5=1
P 7.94371004 4.85788002 37 P 0 0;1,3=1,5=0
P 1.96378996 4.85788002 37 P 0 0;1,3=1,5=0
P 1.8 4.485 1 P 0 0;3=0,5=1
P 1.86 4.485 1 P 0 0;3=0,5=1
P 1.94016998 4.85788002 37 P 0 0;1,3=1,5=0
P 0.27165 1.72835 8 P 0 0;3=2,5=0
P 0.17323002 2.12205 8 P 0 0;3=2,5=0
P 12.73621004 1.76771998 8 P 0 0;3=2,5=0
P 12.81495 2.59448996 8 P 0 0;3=2,5=0
P 12.63778996 2.16141998 8 P 0 0;3=2,5=0
P 0.725 -0.25 8 P 0 0;3=3,5=0
P 0.875 -0.25 8 P 0 0;3=3,5=0
P 1.065 6.26 8 P 0 0;3=3,5=0
P 1.065 6.36 8 P 0 0;3=3,5=0
P 1.29 6.26 8 P 0 0;3=3,5=0
P 1.29 6.36 8 P 0 0;3=3,5=0
P 1.515 6.26 8 P 0 0;3=3,5=0
P 1.515 6.36 8 P 0 0;3=3,5=0
P 0.84 6.26 8 P 0 0;3=3,5=0
P 0.84 6.36 8 P 0 0;3=3,5=0
P 1.74 6.26 8 P 0 0;3=3,5=0
P 1.74 6.36 8 P 0 0;3=3,5=0
P 4.97 5.733 25 P 0 0;1,3=4,5=0
P 4.9574 5.65315 42 P 0 0;1,3=5,5=0
P 4.929 5.744 7 P 0 0;2,3=6,5=1
P 4.535 5.78 45 P 0 0;1,3=7,5=0
P 4.585 5.78 45 P 0 0;1,3=7,5=0
P 5.04441004 5.55965 38 P 0 0;1,3=8,5=0
P 5.125 5.467 25 P 0 0;1,3=4,5=0
P 5.025 5.467 25 P 0 0;1,3=4,5=0
P 5.075 5.467 25 P 0 0;1,3=4,5=0
P 4.665 5.48 7 P 0 0;2,3=6,5=1
P 4.97 5.767 25 P 0 0;1,3=4,5=0
P 5.06 5.733 25 P 0 0;1,3=4,5=0
P 5.07 5.64035 38 P 0 0;1,3=8,5=0
P 5.015 5.755 7 P 0 0;2,3=6,5=1
P 4.92 5.54685 42 P 0 0;1,3=5,5=0
P 4.91 5.442 25 P 0 0;1,3=4,5=0
P 4.86 5.442 25 P 0 0;1,3=4,5=0
P 4.91 5.485 7 P 0 0;2,3=6,5=1
P 4.8826 5.54685 42 P 0 0;1,3=5,5=0
P 4.81 5.442 25 P 0 0;1,3=4,5=0
P 4.76 5.442 25 P 0 0;1,3=4,5=0
P 4.81 5.485 7 P 0 0;2,3=6,5=1
P 4.86 5.733 25 P 0 0;1,3=4,5=0
P 4.76 5.71071004 53 P 0 0;1,3=9,5=0
P 4.8826 5.65315 42 P 0 0;1,3=5,5=0
P 4.725 5.775 7 P 0 0;2,3=6,5=1
P 0.97 4.993 25 P 0 0;1,3=4,5=0
P 0.73 5.027 25 P 0 0;1,3=4,5=0
P 0.73 5.113 25 P 0 0;1,3=4,5=0
P 0.79046998 5.1239 35 P 0 0;1,3=10,5=0
P 0.68 5.113 25 P 0 0;1,3=4,5=0
P 0.73 5.07 7 P 0 0;2,3=6,5=1
P 4.08035 4.66441004 48 P 0 0;1,3=8,5=0
P 4.097 4.59 25 P 0 0;1,3=4,5=0
P 4.14 4.605 7 P 0 0;2,3=6,5=1
P 2.07106004 3.54115 6 P 0 0;1,3=11,5=0
P 2.09606004 3.56615 3 P 0 0;3=12,5=1
P 8.1 3.56615 3 P 0 0;3=12,5=1
P 8.075 3.54115 6 P 0 0;1,3=11,5=0
P 12.55905 3.38188996 8 P 0 0;3=2,5=0
P 12.81495 4.64173996 8 P 0 0;3=2,5=0
P 12.81495 1.88583002 8 P 0 0;3=2,5=0
P 0.35038996 4.60236998 8 P 0 0;3=2,5=0
P 0.35038996 2.55511998 8 P 0 0;3=2,5=0
P 0.35038996 1.84646004 8 P 0 0;3=2,5=0
P 0.09448996 3.34251998 8 P 0 0;3=2,5=0
P 6.385 5.03 4 P 0 0;3=13,5=1
P 6.38348996 4.99705 25 P 0 0;1,3=4,5=0
P 12.68701998 0.97243996 15 P 0 0;3=14
P 0.22245 0.93306998 15 P 0 0;3=14
P 12.68701004 4.91338002 15 P 0 0;3=14
P 3.82558996 4.72035 38 P 0 0;1,3=8,5=0
P 3.94 4.593 25 P 0 0;1,3=4,5=0
P 3.99965 4.69 48 P 0 0;1,3=8,5=0
P 3.94 4.545 1 P 0 0;3=0,5=1
P 4.91 5.375 4 P 0 0;3=13,5=1
P 4.91 5.408 25 P 0 0;1,3=4,5=0
P 4.01676998 5.68 54 P 0 0;1,3=15,5=0
P 9.98 4.577 25 P 0 0;1,3=4,5=0
P 9.97441004 4.64965 38 P 0 0;1,3=8,5=0
P 9.91 4.577 25 P 0 0;1,3=4,5=0
P 9.91 4.633 25 P 0 0;1,3=4,5=0
P 9.865 4.635 7 P 0 0;2,3=6,5=1
P 4.01676998 5.78 54 P 0 0;1,3=15,5=0
P 3.62 4.517 25 P 0 0;1,3=4,5=0
P 3.67 4.517 25 P 0 0;1,3=4,5=0
P 3.64441004 4.58965 38 P 0 0;1,3=8,5=0
P 3.57 4.517 25 P 0 0;1,3=4,5=0
P 3.925 5.78 7 P 0 0;2,3=6,5=1
P 1.04 5.823 25 P 0 0;1,3=4,5=0
P 1.04428996 5.70373996 49 P 0 0;1,3=16,5=0
P 1.08 5.85 1 P 0 0;3=0,5=1
P 3.67 4.67035 38 P 0 0;1,3=8,5=0
P 3.6817 5.74 4 P 0 0;3=13,5=1
P 10.07 2.928 4 P 0 0;3=13,5=1
P 4.105 4.985 1 P 0 0;3=0,5=1
P 4.01676998 5.48 54 P 0 0;1,3=15,5=0
P 4.125 2.725 4 P 0 0;3=13,5=1
P 4.01676998 5.58 54 P 0 0;1,3=15,5=0
P 4.02 4.355 1 P 0 0;3=0,5=1
P 1.12 5.823 25 P 0 0;1,3=4,5=0
P 1.12303002 5.70373996 49 P 0 0;1,3=16,5=0
P 1.16 5.85 1 P 0 0;3=0,5=1
P 10 4.73035 38 P 0 0;1,3=8,5=0
P 3.815 5.815 4 P 0 0;3=13,5=1
P 1.19 6.36 28 P 0 0;3=17,5=0
P 1.19 6.26 28 P 0 0;3=17,5=0
P 1.415 6.36 28 P 0 0;3=17,5=0
P 1.415 6.26 28 P 0 0;3=17,5=0
P 1.64 6.36 28 P 0 0;3=17,5=0
P 1.64 6.26 28 P 0 0;3=17,5=0
P 0.965 6.26 28 P 0 0;3=17,5=0
P 0.965 6.36 28 P 0 0;3=17,5=0
P 0.74 6.26 28 P 0 0;3=17,5=0
P 0.74 6.36 28 P 0 0;3=17,5=0
P 0.97 5.127 25 P 0 0;1,3=4,5=0
P 0.97441004 5.20965 38 P 0 0;1,3=8,5=0
P 0.929 5.037 7 P 0 0;2,3=6,5=1
P 1 5.29035 38 P 0 0;1,3=8,5=0
P 1.044 5.383 25 P 0 0;1,3=4,5=0
P 0.996 5.383 25 P 0 0;1,3=4,5=0
P 1.043 5.343 7 P 0 0;2,3=6,5=1
P 12.63778996 1.37401998 28 P 0 0;3=18,5=0
P 0.17323002 1.33465 28 P 0 0;3=18,5=0
P 6.55228996 4.94855 46 P 0 0;1,3=19,5=0
P 6.501 5.017 1 P 0 0;3=0,5=1
P 6.45818996 4.99705 25 P 0 0;1,3=4,5=0
P 7.425 3.43 1 P 0 0;3=0,5=1
P 7.445 1.705 4 P 0 0;3=13,5=1
P 11.06161004 3.79115 6 P 0 0;1,3=11,5=0
P 11.03661004 3.81615 3 P 0 0;3=12,5=1
P 11.135 2.845 4 P 0 0;3=13,5=1
P 11.03661004 2.16615 3 P 0 0;3=12,5=1
P 11.01161004 2.19115 6 P 0 0;1,3=11,5=0
P 3.89 4.717 25 P 0 0;1,3=4,5=0
P 3.8899 4.79498996 25 P 0 0;1,3=4,5=0
P 3.8899 4.765 1 P 0 0;3=0,5=1
P 4.90768002 2.44115 6 P 0 0;1,3=11,5=0
P 4.93268002 2.41615 3 P 0 0;3=12,5=1
P 4.90768002 2.49115 6 P 0 0;1,3=11,5=0
P 4.93268002 2.46615 3 P 0 0;3=12,5=1
P 7.2926 5.09151004 25 P 0 0;1,3=4,5=0
P 7.3054 4.9602 39 P 0 0;1,3=20,5=0
P 7.3426 5.09151004 25 P 0 0;1,3=4,5=0
P 7.2926 5.04351004 1 P 0 0;3=0,5=1
P 7.2426 5.09151004 25 P 0 0;1,3=4,5=0
P 7.2798 4.9602 39 P 0 0;1,3=20,5=0
P 7.1926 5.09151004 25 P 0 0;1,3=4,5=0
P 7.2426 5.04351004 1 P 0 0;3=0,5=1
P 3.45646004 5.3 1 P 0 0;3=0,5=1
P 3.4591 4.97913996 37 P 0 0;1,3=1,5=0
P 1.28906004 5.04351004 1 P 0 0;3=0,5=1
P 1.30186004 4.9602 39 P 0 0;1,3=20,5=0
P 1.28906004 5.09151004 25 P 0 0;1,3=4,5=0
P 1.33906004 5.09151004 25 P 0 0;1,3=4,5=0
P 1.23906004 5.04351004 1 P 0 0;3=0,5=1
P 1.27626004 4.9602 39 P 0 0;1,3=20,5=0
P 1.23906004 5.09151004 25 P 0 0;1,3=4,5=0
P 1.18906004 5.09151004 25 P 0 0;1,3=4,5=0
P 9.46 5.3 1 P 0 0;3=0,5=1
P 9.46263996 4.97913996 37 P 0 0;1,3=1,5=0
P 4.70768002 2.39115 6 P 0 0;1,3=11,5=0
P 4.68268002 2.36615 3 P 0 0;3=12,5=1
P 0.27165 4.01181004 8 P 0 0;3=2,5=0
P 4.60768002 2.39115 6 P 0 0;1,3=11,5=0
P 4.58268002 2.36615 3 P 0 0;3=12,5=1
P 0.27165 4.16928996 8 P 0 0;3=2,5=0
P 4.65768002 2.44115 6 P 0 0;1,3=11,5=0
P 4.63268002 2.41615 3 P 0 0;3=12,5=1
P 0.27165 4.32676998 8 P 0 0;3=2,5=0
P 4.75768002 2.29115 6 P 0 0;1,3=11,5=0
P 4.73268002 2.26615 3 P 0 0;3=12,5=1
P 0.27165 3.38188996 8 P 0 0;3=2,5=0
P 4.75768002 2.44115 6 P 0 0;1,3=11,5=0
P 4.73268002 2.41615 3 P 0 0;3=12,5=1
P 0.27165 4.48425 8 P 0 0;3=2,5=0
P 4.70768002 2.24115 6 P 0 0;1,3=11,5=0
P 4.68268002 2.21615 3 P 0 0;3=12,5=1
P 0.27165 3.53936998 8 P 0 0;3=2,5=0
P 4.65768002 2.29115 6 P 0 0;1,3=11,5=0
P 4.63268002 2.26615 3 P 0 0;3=12,5=1
P 0.27165 3.85433002 8 P 0 0;3=2,5=0
P 4.60768002 2.09115 6 P 0 0;1,3=11,5=0
P 4.58268002 2.06615 3 P 0 0;3=12,5=1
P 0.35038996 3.02756004 8 P 0 0;3=2,5=0
P 4.60768002 2.14115 6 P 0 0;1,3=11,5=0
P 4.58268002 2.11615 3 P 0 0;3=12,5=1
P 0.27165 2.98818996 8 P 0 0;3=2,5=0
P 4.65768002 1.89115 6 P 0 0;1,3=11,5=0
P 4.63268002 1.86615 3 P 0 0;3=12,5=1
P 0.35038996 2.3189 8 P 0 0;3=2,5=0
P 4.60768002 1.99115 6 P 0 0;1,3=11,5=0
P 4.58268002 1.96615 3 P 0 0;3=12,5=1
P 0.27165 2.43701004 8 P 0 0;3=2,5=0
P 4.70768002 2.09115 6 P 0 0;1,3=11,5=0
P 4.68268002 2.06615 3 P 0 0;3=12,5=1
P 0.35038996 3.18503996 8 P 0 0;3=2,5=0
P 4.60768002 1.94115 6 P 0 0;1,3=11,5=0
P 4.58268002 1.91615 3 P 0 0;3=12,5=1
P 0.35038996 2.47638002 8 P 0 0;3=2,5=0
P 4.65768002 1.94115 6 P 0 0;1,3=11,5=0
P 0.27165 2.27953002 8 P 0 0;3=2,5=0
P 4.63268002 1.91615 3 P 0 0;3=12,5=1
P 5.42048002 1.7396 3 P 0 0;3=12,5=1
P 0.09448996 2.55511998 8 P 0 0;3=2,5=0
P 4.70768002 2.14115 6 P 0 0;1,3=11,5=0
P 4.68268002 2.11615 3 P 0 0;3=12,5=1
P 0.27165 3.14566998 8 P 0 0;3=2,5=0
P 5.42048002 1.7796 3 P 0 0;3=12,5=1
P 0.17323002 2.51575 8 P 0 0;3=2,5=0
P 4.70768002 1.94115 6 P 0 0;1,3=11,5=0
P 4.68268002 1.91615 3 P 0 0;3=12,5=1
P 0.35038996 2.16141998 8 P 0 0;3=2,5=0
P 4.70768002 1.99115 6 P 0 0;1,3=11,5=0
P 4.68268002 1.96615 3 P 0 0;3=12,5=1
P 0.27165 2.12205 8 P 0 0;3=2,5=0
P 5.57531004 2.0878 3 P 0 0;3=12,5=1
P 0.09448996 3.1063 8 P 0 0;3=2,5=0
P 5.57531004 2.1278 3 P 0 0;3=12,5=1
P 0.17323002 3.06693002 8 P 0 0;3=2,5=0
P 5.57531004 2.2232 3 P 0 0;3=12,5=1
P 0.17323002 3.46063002 8 P 0 0;3=2,5=0
P 5.57531004 2.2632 3 P 0 0;3=12,5=1
P 0.09448996 3.42126004 8 P 0 0;3=2,5=0
P 5.42048002 2.4662 3 P 0 0;3=12,5=1
P 0.09448996 4.05118002 8 P 0 0;3=2,5=0
P 5.57531004 2.3986 3 P 0 0;3=12,5=1
P 0.09448996 3.8937 8 P 0 0;3=2,5=0
P 5.57531004 2.673 3 P 0 0;3=12,5=1
P 0.09448996 4.36613996 8 P 0 0;3=2,5=0
P 5.57531004 1.9869 3 P 0 0;3=12,5=1
P 0.17323002 2.75196998 8 P 0 0;3=2,5=0
P 5.57531004 2.4978 3 P 0 0;3=12,5=1
P 0.17323002 4.24803002 8 P 0 0;3=2,5=0
P 5.57531004 1.6718 3 P 0 0;3=12,5=1
P 0.17323002 2.20078996 8 P 0 0;3=2,5=0
P 5.57531004 2.633 3 P 0 0;3=12,5=1
P 0.17323002 4.40551004 8 P 0 0;3=2,5=0
P 5.57531004 1.7118 3 P 0 0;3=12,5=1
P 0.09448996 2.24016004 8 P 0 0;3=2,5=0
P 5.57531004 2.5378 3 P 0 0;3=12,5=1
P 0.09448996 4.20866004 8 P 0 0;3=2,5=0
P 5.42048002 1.6433 3 P 0 0;3=12,5=1
P 0.09448996 2.39763996 8 P 0 0;3=2,5=0
P 5.42048002 2.6054 3 P 0 0;3=12,5=1
P 0.09448996 4.52361998 8 P 0 0;3=2,5=0
P 5.42048002 1.87835 3 P 0 0;3=12,5=1
P 0.09448996 2.94881998 8 P 0 0;3=2,5=0
P 5.57531004 2.3586 3 P 0 0;3=12,5=1
P 0.17323002 3.93306998 8 P 0 0;3=2,5=0
P 5.42048002 1.6033 3 P 0 0;3=12,5=1
P 0.17323002 2.35826998 8 P 0 0;3=2,5=0
P 5.42048002 2.4262 3 P 0 0;3=12,5=1
P 0.17323002 4.09055 8 P 0 0;3=2,5=0
P 5.42048002 1.91835 3 P 0 0;3=12,5=1
P 0.17323002 2.90945 8 P 0 0;3=2,5=0
P 5.42048002 2.0547 3 P 0 0;3=12,5=1
P 0.17323002 3.22441004 8 P 0 0;3=2,5=0
P 5.57531004 1.9469 3 P 0 0;3=12,5=1
P 0.09448996 2.79133996 8 P 0 0;3=2,5=0
P 5.42048002 2.0147 3 P 0 0;3=12,5=1
P 0.09448996 3.26378002 8 P 0 0;3=2,5=0
P 5.57531004 1.8508 3 P 0 0;3=12,5=1
P 0.09448996 2.00393996 8 P 0 0;3=2,5=0
P 5.57531004 1.8108 3 P 0 0;3=12,5=1
P 0.17323002 2.04331004 8 P 0 0;3=2,5=0
P 0.35038996 3.97243996 8 P 0 0;3=2,5=0
P 4.68268002 2.41615 3 P 0 0;3=12,5=1
P 4.70768002 2.44115 6 P 0 0;1,3=11,5=0
P 4.75768002 2.49115 6 P 0 0;1,3=11,5=0
P 4.73268002 2.46615 3 P 0 0;3=12,5=1
P 0.35038996 4.44488002 8 P 0 0;3=2,5=0
P 4.65768002 2.49115 6 P 0 0;1,3=11,5=0
P 4.63268002 2.46615 3 P 0 0;3=12,5=1
P 0.35038996 4.2874 8 P 0 0;3=2,5=0
P 0.35038996 4.12991998 8 P 0 0;3=2,5=0
P 4.58268002 2.41615 3 P 0 0;3=12,5=1
P 4.60768002 2.44115 6 P 0 0;1,3=11,5=0
P 4.70768002 2.29115 6 P 0 0;1,3=11,5=0
P 4.68268002 2.26615 3 P 0 0;3=12,5=1
P 0.35038996 3.5 8 P 0 0;3=2,5=0
P 5.42048002 2.1554 3 P 0 0;3=12,5=1
P 0.17323002 3.77558996 8 P 0 0;3=2,5=0
P 4.75768002 2.34115 6 P 0 0;1,3=11,5=0
P 4.73268002 2.31615 3 P 0 0;3=12,5=1
P 0.35038996 3.34251998 8 P 0 0;3=2,5=0
P 4.65768002 2.34115 6 P 0 0;1,3=11,5=0
P 4.63268002 2.31615 3 P 0 0;3=12,5=1
P 0.35038996 3.81496004 8 P 0 0;3=2,5=0
P 4.60768002 2.29115 6 P 0 0;1,3=11,5=0
P 4.58268002 2.26615 3 P 0 0;3=12,5=1
P 0.35038996 3.65748002 8 P 0 0;3=2,5=0
P 5.42048002 2.5654 3 P 0 0;3=12,5=1
P 0.17323002 4.563 8 P 0 0;3=2,5=0
P 5.42048002 2.1954 3 P 0 0;3=12,5=1
P 0.09448996 3.73621998 8 P 0 0;3=2,5=0
P 0.09448996 3.57873996 8 P 0 0;3=2,5=0
P 5.42048002 2.3308 3 P 0 0;3=12,5=1
P 0.17323002 3.61811004 8 P 0 0;3=2,5=0
P 5.42048002 2.2908 3 P 0 0;3=12,5=1
P 4.75768002 1.94115 6 P 0 0;1,3=11,5=0
P 0.35038996 1.9252 8 P 0 0;3=2,5=0
P 4.73268002 1.91615 3 P 0 0;3=12,5=1
P 4.75768002 1.89115 6 P 0 0;1,3=11,5=0
P 4.73268002 1.86615 3 P 0 0;3=12,5=1
P 0.27165 1.96456998 8 P 0 0;3=2,5=0
P 4.60768002 2.24115 6 P 0 0;1,3=11,5=0
P 4.58268002 2.21615 3 P 0 0;3=12,5=1
P 0.27165 3.69685 8 P 0 0;3=2,5=0
P 4.75768002 2.09115 6 P 0 0;1,3=11,5=0
P 4.73268002 2.06615 3 P 0 0;3=12,5=1
P 0.27165 2.67323002 8 P 0 0;3=2,5=0
P 4.75768002 2.04115 6 P 0 0;1,3=11,5=0
P 4.73268002 2.01615 3 P 0 0;3=12,5=1
P 0.35038996 2.7126 8 P 0 0;3=2,5=0
P 4.65768002 2.04115 6 P 0 0;1,3=11,5=0
P 4.63268002 2.01615 3 P 0 0;3=12,5=1
P 0.35038996 2.87008002 8 P 0 0;3=2,5=0
P 4.65768002 2.09115 6 P 0 0;1,3=11,5=0
P 4.63268002 2.06615 3 P 0 0;3=12,5=1
P 0.27165 2.83071004 8 P 0 0;3=2,5=0
P 6.785 4.725 4 P 0 0;3=13,5=1
P 6.785 4.685 4 P 0 0;3=13,5=1
P 6.74018996 4.765 4 P 0 0;3=13,5=1
P 6.74208996 4.7052 29 P 0 0;1,3=21,5=0
P 6.87618996 4.71823002 51 P 0 0;1,3=22,5=0
P 6.83118996 4.81705 29 P 0 0;1,3=21,5=0
P 6.71318996 4.77205 25 P 0 0;1,3=4,5=0
P 6.69008996 4.88555 47 P 0 0;1,3=19,5=0
P 6.69008996 4.86981004 47 P 0 0;1,3=19,5=0
P 6.69008996 4.85406004 47 P 0 0;1,3=19,5=0
P 6.74 4.805 1 P 0 0;3=0,5=1
P 6.785 4.845 4 P 0 0;3=13,5=1
P 6.785 4.805 4 P 0 0;3=13,5=1
P 6.785 4.765 4 P 0 0;3=13,5=1
P 6.74 4.845 4 P 0 0;3=13,5=1
P 6.63693996 5.00562992 34 P 0 0;1,3=19,5=0
P 6.65818996 5.09705 25 P 0 0;1,3=4,5=0
P 6.65 5.055 1 P 0 0;3=0,5=1
P 6.45818996 5.04705 25 P 0 0;1,3=4,5=0
P 6.45818996 5.09705 25 P 0 0;1,3=4,5=0
P 6.49205 5.09705 1 P 0 0;3=0,5=1
P 6.55228996 4.96428996 46 P 0 0;1,3=19,5=0
P 6.495 4.9328 1 P 0 0;3=0,5=1
P 6.55228996 4.9328 46 P 0 0;1,3=19,5=0
P 6.45818996 4.94705 25 P 0 0;1,3=4,5=0
P 6.55228996 4.98003996 46 P 0 0;1,3=19,5=0
P 6.55118996 5.04705 1 P 0 0;3=0,5=1
P 6.53918996 5.09705 25 P 0 0;1,3=4,5=0
P 6.78 4.94705 1 P 0 0;3=0,5=1
P 6.81218996 4.94705 27 P 0 0;1,3=23,5=0
P 6.69008996 4.9328 47 P 0 0;1,3=19,5=0
P 6.51718996 4.66705 27 P 0 0;1,3=23,5=0
P 6.51618996 4.72305 27 P 0 0;1,3=23,5=0
P 6.52 4.605 7 P 0 0;2,3=6,5=1
P 6.38318996 4.94705 25 P 0 0;1,3=4,5=0
P 6.42418996 4.94705 25 P 0 0;1,3=4,5=0
P 6.755 4.89705 1 P 0 0;3=0,5=1
P 6.81218996 4.88705 27 P 0 0;1,3=23,5=0
P 6.69008996 4.91705 47 P 0 0;1,3=19,5=0
P 6.755 5.13 7 P 0 0;2,3=6,5=1
P 5.49093996 4.5861 25 P 0 0;1,3=4,5=0
P 6.65268996 5.00562992 34 P 0 0;1,3=19,5=0
P 6.71 5.087 25 P 0 0;1,3=4,5=0
P 6.755 5.087 25 P 0 0;1,3=4,5=0
P 6.74 4.987 1 P 0 0;3=0,5=1
P 6.69008996 4.94855 47 P 0 0;1,3=19,5=0
P 6.57518996 4.66705 27 P 0 0;1,3=23,5=0
P 6.57618996 4.73505 25 P 0 0;1,3=4,5=0
P 6.57518996 4.605 7 P 0 0;2,3=6,5=1
P 6.69008996 4.98003996 47 P 0 0;1,3=19,5=0
P 6.71 5.053 25 P 0 0;1,3=4,5=0
P 6.755 5.053 25 P 0 0;1,3=4,5=0
P 6.803 5 25 P 0 0;1,3=4,5=0
P 6.8 5.045 7 P 0 0;2,3=6,5=1
P 6.43043996 4.77205 50 P 0 0;1,3=24,5=0
P 6.34918996 4.94705 25 P 0 0;1,3=4,5=0
P 6.51618996 4.78105 27 P 0 0;1,3=23,5=0
P 6.55228996 4.9013 46 P 0 0;1,3=19,5=0
P 6.55228996 4.88555 46 P 0 0;1,3=19,5=0
P 6.55228996 4.86981004 46 P 0 0;1,3=19,5=0
P 6.55228996 4.85406004 46 P 0 0;1,3=19,5=0
P 12.73621004 2.08268002 8 P 0 0;3=2,5=0
P 12.73621004 2.63386004 8 P 0 0;3=2,5=0
P 12.81495 3.30315 8 P 0 0;3=2,5=0
P 12.73621004 4.60236998 8 P 0 0;3=2,5=0
P 12.55905 1.96456998 8 P 0 0;3=2,5=0
P 12.63778996 1.9252 8 P 0 0;3=2,5=0
P 0.09448996 1.9252 8 P 0 0;3=2,5=0
P 0.17323002 1.88583002 8 P 0 0;3=2,5=0
P 0.27165 2.04331004 8 P 0 0;3=2,5=0
P 0.27165 4.563 8 P 0 0;3=2,5=0
P 0.35038996 3.26378002 8 P 0 0;3=2,5=0
P 0.27165 2.59448996 8 P 0 0;3=2,5=0
P 0.17323002 1.72835 8 P 0 0;3=2,5=0
P 5.00768002 1.94115 6 P 0 0;1,3=11,5=0
P 5.03268002 1.91615 3 P 0 0;3=12,5=1
P 1.025 -0.25 8 P 0 0;3=3,5=0
P 1.175 -0.25 8 P 0 0;3=3,5=0
P 1.325 -0.25 8 P 0 0;3=3,5=0
P 5.00768002 2.09115 6 P 0 0;1,3=11,5=0
P 5.03268002 2.06615 3 P 0 0;3=12,5=1
P 12.63778996 4.12991998 8 P 0 0;3=2,5=0
P 11.53316004 2.372 3 P 0 0;3=12,5=1
P 5.05768002 2.29115 6 P 0 0;1,3=11,5=0
P 5.08268002 2.26615 3 P 0 0;3=12,5=1
P 11.53316004 1.892 3 P 0 0;3=12,5=1
P 12.55905 3.30315 8 P 0 0;3=2,5=0
P 12.81495 2.51575 8 P 0 0;3=2,5=0
P 10.61161004 1.94115 6 P 0 0;1,3=11,5=0
P 10.58661004 1.91615 3 P 0 0;3=12,5=1
P 10.26 1.66445 3 P 0 0;3=12,5=1
P 10.66161004 3.09115 6 P 0 0;1,3=11,5=0
P 10.61161004 3.09115 6 P 0 0;1,3=11,5=0
P 10.61161004 2.99115 6 P 0 0;1,3=11,5=0
P 10.66161004 2.99115 6 P 0 0;1,3=11,5=0
P 10.61161004 2.94115 6 P 0 0;1,3=11,5=0
P 10.66161004 2.94115 6 P 0 0;1,3=11,5=0
P 10.81161004 3.09115 6 P 0 0;1,3=11,5=0
P 10.81161004 2.99115 6 P 0 0;1,3=11,5=0
P 10.86161004 3.09115 6 P 0 0;1,3=11,5=0
P 10.86161004 2.99115 6 P 0 0;1,3=11,5=0
P 10.71161004 3.09115 6 P 0 0;1,3=11,5=0
P 10.76161004 3.09115 6 P 0 0;1,3=11,5=0
P 10.71161004 2.99115 6 P 0 0;1,3=11,5=0
P 10.76161004 2.99115 6 P 0 0;1,3=11,5=0
P 10.81161004 2.94115 6 P 0 0;1,3=11,5=0
P 10.86161004 2.94115 6 P 0 0;1,3=11,5=0
P 10.71161004 2.94115 6 P 0 0;1,3=11,5=0
P 10.76161004 2.94115 6 P 0 0;1,3=11,5=0
P 11.01161004 3.09115 6 P 0 0;1,3=11,5=0
P 11.01161004 2.99115 6 P 0 0;1,3=11,5=0
P 11.06161004 3.09115 6 P 0 0;1,3=11,5=0
P 11.06161004 2.99115 6 P 0 0;1,3=11,5=0
P 10.96161004 3.09115 6 P 0 0;1,3=11,5=0
P 10.91161004 3.09115 6 P 0 0;1,3=11,5=0
P 10.96161004 2.99115 6 P 0 0;1,3=11,5=0
P 10.91161004 2.99115 6 P 0 0;1,3=11,5=0
P 11.01161004 2.94115 6 P 0 0;1,3=11,5=0
P 11.06161004 2.94115 6 P 0 0;1,3=11,5=0
P 10.96161004 2.94115 6 P 0 0;1,3=11,5=0
P 10.91161004 2.94115 6 P 0 0;1,3=11,5=0
P 10.66161004 3.29115 6 P 0 0;1,3=11,5=0
P 10.61161004 3.24115 6 P 0 0;1,3=11,5=0
P 10.61161004 3.29115 6 P 0 0;1,3=11,5=0
P 10.66161004 3.24115 6 P 0 0;1,3=11,5=0
P 10.66161004 3.14115 6 P 0 0;1,3=11,5=0
P 10.61161004 3.14115 6 P 0 0;1,3=11,5=0
P 10.81161004 3.24115 6 P 0 0;1,3=11,5=0
P 10.81161004 3.29115 6 P 0 0;1,3=11,5=0
P 10.86161004 3.29115 6 P 0 0;1,3=11,5=0
P 10.86161004 3.24115 6 P 0 0;1,3=11,5=0
P 10.76161004 3.29115 6 P 0 0;1,3=11,5=0
P 10.76161004 3.24115 6 P 0 0;1,3=11,5=0
P 10.71161004 3.24115 6 P 0 0;1,3=11,5=0
P 10.71161004 3.29115 6 P 0 0;1,3=11,5=0
P 10.81161004 3.14115 6 P 0 0;1,3=11,5=0
P 10.86161004 3.14115 6 P 0 0;1,3=11,5=0
P 10.76161004 3.14115 6 P 0 0;1,3=11,5=0
P 10.71161004 3.14115 6 P 0 0;1,3=11,5=0
P 11.01161004 3.24115 6 P 0 0;1,3=11,5=0
P 11.01161004 3.29115 6 P 0 0;1,3=11,5=0
P 11.06161004 3.24115 6 P 0 0;1,3=11,5=0
P 11.06161004 3.29115 6 P 0 0;1,3=11,5=0
P 10.96161004 3.29115 6 P 0 0;1,3=11,5=0
P 10.96161004 3.24115 6 P 0 0;1,3=11,5=0
P 10.91161004 3.24115 6 P 0 0;1,3=11,5=0
P 10.91161004 3.29115 6 P 0 0;1,3=11,5=0
P 11.01161004 3.14115 6 P 0 0;1,3=11,5=0
P 11.06161004 3.14115 6 P 0 0;1,3=11,5=0
P 10.96161004 3.14115 6 P 0 0;1,3=11,5=0
P 10.91161004 3.14115 6 P 0 0;1,3=11,5=0
P 10.61161004 3.59115 6 P 0 0;1,3=11,5=0
P 10.66161004 3.59115 6 P 0 0;1,3=11,5=0
P 10.61161004 3.54115 6 P 0 0;1,3=11,5=0
P 10.66161004 3.54115 6 P 0 0;1,3=11,5=0
P 10.61161004 3.44115 6 P 0 0;1,3=11,5=0
P 10.66161004 3.39115 6 P 0 0;1,3=11,5=0
P 10.66161004 3.44115 6 P 0 0;1,3=11,5=0
P 10.61161004 3.39115 6 P 0 0;1,3=11,5=0
P 10.81161004 3.59115 6 P 0 0;1,3=11,5=0
P 10.81161004 3.54115 6 P 0 0;1,3=11,5=0
P 10.86161004 3.59115 6 P 0 0;1,3=11,5=0
P 10.86161004 3.54115 6 P 0 0;1,3=11,5=0
P 10.76161004 3.59115 6 P 0 0;1,3=11,5=0
P 10.71161004 3.59115 6 P 0 0;1,3=11,5=0
P 10.76161004 3.54115 6 P 0 0;1,3=11,5=0
P 10.71161004 3.54115 6 P 0 0;1,3=11,5=0
P 10.81161004 3.44115 6 P 0 0;1,3=11,5=0
P 10.81161004 3.39115 6 P 0 0;1,3=11,5=0
P 10.86161004 3.39115 6 P 0 0;1,3=11,5=0
P 10.86161004 3.44115 6 P 0 0;1,3=11,5=0
P 10.76161004 3.39115 6 P 0 0;1,3=11,5=0
P 10.71161004 3.39115 6 P 0 0;1,3=11,5=0
P 10.71161004 3.44115 6 P 0 0;1,3=11,5=0
P 10.76161004 3.44115 6 P 0 0;1,3=11,5=0
P 11.01161004 3.59115 6 P 0 0;1,3=11,5=0
P 11.01161004 3.54115 6 P 0 0;1,3=11,5=0
P 11.06161004 3.59115 6 P 0 0;1,3=11,5=0
P 11.06161004 3.54115 6 P 0 0;1,3=11,5=0
P 10.96161004 3.59115 6 P 0 0;1,3=11,5=0
P 10.91161004 3.59115 6 P 0 0;1,3=11,5=0
P 10.96161004 3.54115 6 P 0 0;1,3=11,5=0
P 10.91161004 3.54115 6 P 0 0;1,3=11,5=0
P 11.01161004 3.44115 6 P 0 0;1,3=11,5=0
P 11.01161004 3.39115 6 P 0 0;1,3=11,5=0
P 11.06161004 3.44115 6 P 0 0;1,3=11,5=0
P 11.06161004 3.39115 6 P 0 0;1,3=11,5=0
P 10.96161004 3.44115 6 P 0 0;1,3=11,5=0
P 10.96161004 3.39115 6 P 0 0;1,3=11,5=0
P 10.91161004 3.44115 6 P 0 0;1,3=11,5=0
P 10.91161004 3.39115 6 P 0 0;1,3=11,5=0
P 10.61161004 3.84115 6 P 0 0;1,3=11,5=0
P 10.66161004 3.84115 6 P 0 0;1,3=11,5=0
P 10.61161004 3.74115 6 P 0 0;1,3=11,5=0
P 10.66161004 3.74115 6 P 0 0;1,3=11,5=0
P 10.61161004 3.69115 6 P 0 0;1,3=11,5=0
P 10.66161004 3.69115 6 P 0 0;1,3=11,5=0
P 10.81161004 3.84115 6 P 0 0;1,3=11,5=0
P 10.81161004 3.74115 6 P 0 0;1,3=11,5=0
P 10.86161004 3.84115 6 P 0 0;1,3=11,5=0
P 10.86161004 3.74115 6 P 0 0;1,3=11,5=0
P 10.76161004 3.84115 6 P 0 0;1,3=11,5=0
P 10.71161004 3.84115 6 P 0 0;1,3=11,5=0
P 10.76161004 3.74115 6 P 0 0;1,3=11,5=0
P 10.71161004 3.74115 6 P 0 0;1,3=11,5=0
P 10.81161004 3.69115 6 P 0 0;1,3=11,5=0
P 10.86161004 3.69115 6 P 0 0;1,3=11,5=0
P 10.76161004 3.69115 6 P 0 0;1,3=11,5=0
P 10.71161004 3.69115 6 P 0 0;1,3=11,5=0
P 11.01161004 3.84115 6 P 0 0;1,3=11,5=0
P 11.01161004 3.74115 6 P 0 0;1,3=11,5=0
P 11.06161004 3.84115 6 P 0 0;1,3=11,5=0
P 11.06161004 3.74115 6 P 0 0;1,3=11,5=0
P 10.96161004 3.84115 6 P 0 0;1,3=11,5=0
P 10.91161004 3.84115 6 P 0 0;1,3=11,5=0
P 10.96161004 3.74115 6 P 0 0;1,3=11,5=0
P 10.91161004 3.74115 6 P 0 0;1,3=11,5=0
P 11.01161004 3.69115 6 P 0 0;1,3=11,5=0
P 11.06161004 3.69115 6 P 0 0;1,3=11,5=0
P 10.96161004 3.69115 6 P 0 0;1,3=11,5=0
P 10.91161004 3.69115 6 P 0 0;1,3=11,5=0
P 11.03998996 4.8431 4 P 0 0;3=13,5=1
P 11.08498996 4.8431 4 P 0 0;3=13,5=1
P 11.13498996 4.8431 4 P 0 0;3=13,5=1
P 11.17998996 4.8431 4 P 0 0;3=13,5=1
P 11.17998996 4.8031 4 P 0 0;3=13,5=1
P 11.17998996 4.7581 4 P 0 0;3=13,5=1
P 11.17998996 4.7131 4 P 0 0;3=13,5=1
P 11.17998996 4.6731 4 P 0 0;3=13,5=1
P 11.03998996 4.6731 4 P 0 0;3=13,5=1
P 11.08498996 4.6731 4 P 0 0;3=13,5=1
P 11.13498996 4.6731 4 P 0 0;3=13,5=1
P 11.03998996 4.7131 4 P 0 0;3=13,5=1
P 11.03998996 4.8031 4 P 0 0;3=13,5=1
P 11.03998996 4.7581 4 P 0 0;3=13,5=1
P 10.81998996 4.6631 4 P 0 0;3=13,5=1
P 10.85998996 4.6631 4 P 0 0;3=13,5=1
P 10.65998996 4.6631 4 P 0 0;3=13,5=1
P 10.69998996 4.6631 4 P 0 0;3=13,5=1
P 10.81998996 4.7031 4 P 0 0;3=13,5=1
P 10.81998996 4.8381 4 P 0 0;3=13,5=1
P 10.81998996 4.7931 4 P 0 0;3=13,5=1
P 10.81998996 4.7481 4 P 0 0;3=13,5=1
P 10.85998996 4.7031 4 P 0 0;3=13,5=1
P 10.85998996 4.8381 4 P 0 0;3=13,5=1
P 10.85998996 4.7931 4 P 0 0;3=13,5=1
P 10.85998996 4.7481 4 P 0 0;3=13,5=1
P 10.65998996 4.7031 4 P 0 0;3=13,5=1
P 10.65998996 4.8381 4 P 0 0;3=13,5=1
P 10.65998996 4.7931 4 P 0 0;3=13,5=1
P 10.65998996 4.7481 4 P 0 0;3=13,5=1
P 10.69998996 4.7031 4 P 0 0;3=13,5=1
P 10.69998996 4.8381 4 P 0 0;3=13,5=1
P 10.69998996 4.7931 4 P 0 0;3=13,5=1
P 10.69998996 4.7481 4 P 0 0;3=13,5=1
P 10.77998996 4.6431 4 P 0 0;3=13,5=1
P 10.73498996 4.6431 4 P 0 0;3=13,5=1
P 10.73998996 4.8381 4 P 0 0;3=13,5=1
P 10.77998996 4.8381 4 P 0 0;3=13,5=1
P 10.30998996 4.6631 4 P 0 0;3=13,5=1
P 10.26998996 4.6631 4 P 0 0;3=13,5=1
P 10.34498996 4.6431 4 P 0 0;3=13,5=1
P 10.38998996 4.6431 4 P 0 0;3=13,5=1
P 10.42998996 4.6631 4 P 0 0;3=13,5=1
P 10.46998996 4.6631 4 P 0 0;3=13,5=1
P 10.30998996 4.7481 4 P 0 0;3=13,5=1
P 10.30998996 4.7931 4 P 0 0;3=13,5=1
P 10.30998996 4.7031 4 P 0 0;3=13,5=1
P 10.26998996 4.7481 4 P 0 0;3=13,5=1
P 10.26998996 4.7931 4 P 0 0;3=13,5=1
P 10.26998996 4.7031 4 P 0 0;3=13,5=1
P 10.26998996 4.8381 4 P 0 0;3=13,5=1
P 10.30998996 4.8381 4 P 0 0;3=13,5=1
P 10.38998996 4.8381 4 P 0 0;3=13,5=1
P 10.34998996 4.8381 4 P 0 0;3=13,5=1
P 10.46998996 4.8381 4 P 0 0;3=13,5=1
P 10.42998996 4.8381 4 P 0 0;3=13,5=1
P 10.42998996 4.7031 4 P 0 0;3=13,5=1
P 10.42998996 4.7931 4 P 0 0;3=13,5=1
P 10.42998996 4.7481 4 P 0 0;3=13,5=1
P 10.46998996 4.7031 4 P 0 0;3=13,5=1
P 10.46998996 4.7931 4 P 0 0;3=13,5=1
P 10.46998996 4.7481 4 P 0 0;3=13,5=1
P 10.36698996 4.74133996 52 P 0 0;1,3=25,5=0
P 10.75698996 4.74133996 52 P 0 0;1,3=25,5=0
P 11.10998996 4.75636998 32 P 0 0;1,3=26,5=0
P 10.58661004 3.16615 3 P 0 0;3=12,5=1
P 10.63661004 3.01615 3 P 0 0;3=12,5=1
P 10.58661004 3.11615 3 P 0 0;3=12,5=1
P 10.58661004 3.01615 3 P 0 0;3=12,5=1
P 10.63661004 3.11615 3 P 0 0;3=12,5=1
P 10.63661004 2.96615 3 P 0 0;3=12,5=1
P 10.58661004 2.96615 3 P 0 0;3=12,5=1
P 10.58661004 3.41615 3 P 0 0;3=12,5=1
P 10.63661004 3.16615 3 P 0 0;3=12,5=1
P 10.63661004 3.26615 3 P 0 0;3=12,5=1
P 10.58661004 3.31615 3 P 0 0;3=12,5=1
P 10.58661004 3.26615 3 P 0 0;3=12,5=1
P 10.63661004 3.31615 3 P 0 0;3=12,5=1
P 10.63661004 3.56615 3 P 0 0;3=12,5=1
P 10.63661004 3.61615 3 P 0 0;3=12,5=1
P 10.58661004 3.56615 3 P 0 0;3=12,5=1
P 10.58661004 3.61615 3 P 0 0;3=12,5=1
P 10.63661004 3.46615 3 P 0 0;3=12,5=1
P 10.63661004 3.41615 3 P 0 0;3=12,5=1
P 10.58661004 3.46615 3 P 0 0;3=12,5=1
P 10.63661004 3.86615 3 P 0 0;3=12,5=1
P 10.63661004 3.76615 3 P 0 0;3=12,5=1
P 10.58661004 3.86615 3 P 0 0;3=12,5=1
P 10.58661004 3.76615 3 P 0 0;3=12,5=1
P 10.63661004 3.71615 3 P 0 0;3=12,5=1
P 10.58661004 3.71615 3 P 0 0;3=12,5=1
P 10.88661004 2.96615 3 P 0 0;3=12,5=1
P 10.83661004 2.96615 3 P 0 0;3=12,5=1
P 10.88661004 3.01615 3 P 0 0;3=12,5=1
P 10.83661004 3.01615 3 P 0 0;3=12,5=1
P 10.88661004 3.11615 3 P 0 0;3=12,5=1
P 10.83661004 3.11615 3 P 0 0;3=12,5=1
P 10.83661004 3.16615 3 P 0 0;3=12,5=1
P 10.78661004 3.16615 3 P 0 0;3=12,5=1
P 10.68661004 3.16615 3 P 0 0;3=12,5=1
P 10.73661004 3.16615 3 P 0 0;3=12,5=1
P 10.78661004 3.01615 3 P 0 0;3=12,5=1
P 10.78661004 3.11615 3 P 0 0;3=12,5=1
P 10.73661004 3.01615 3 P 0 0;3=12,5=1
P 10.73661004 3.11615 3 P 0 0;3=12,5=1
P 10.68661004 3.01615 3 P 0 0;3=12,5=1
P 10.68661004 3.11615 3 P 0 0;3=12,5=1
P 10.78661004 2.96615 3 P 0 0;3=12,5=1
P 10.73661004 2.96615 3 P 0 0;3=12,5=1
P 10.68661004 2.96615 3 P 0 0;3=12,5=1
P 10.88661004 3.16615 3 P 0 0;3=12,5=1
P 10.88661004 3.26615 3 P 0 0;3=12,5=1
P 10.83661004 3.26615 3 P 0 0;3=12,5=1
P 10.83661004 3.31615 3 P 0 0;3=12,5=1
P 10.88661004 3.31615 3 P 0 0;3=12,5=1
P 10.83661004 3.41615 3 P 0 0;3=12,5=1
P 10.78661004 3.41615 3 P 0 0;3=12,5=1
P 10.68661004 3.41615 3 P 0 0;3=12,5=1
P 10.73661004 3.41615 3 P 0 0;3=12,5=1
P 10.78661004 3.31615 3 P 0 0;3=12,5=1
P 10.78661004 3.26615 3 P 0 0;3=12,5=1
P 10.68661004 3.31615 3 P 0 0;3=12,5=1
P 10.68661004 3.26615 3 P 0 0;3=12,5=1
P 10.73661004 3.26615 3 P 0 0;3=12,5=1
P 10.73661004 3.31615 3 P 0 0;3=12,5=1
P 10.88661004 3.41615 3 P 0 0;3=12,5=1
P 10.83661004 3.46615 3 P 0 0;3=12,5=1
P 10.88661004 3.46615 3 P 0 0;3=12,5=1
P 10.83661004 3.56615 3 P 0 0;3=12,5=1
P 10.88661004 3.56615 3 P 0 0;3=12,5=1
P 10.83661004 3.61615 3 P 0 0;3=12,5=1
P 10.88661004 3.61615 3 P 0 0;3=12,5=1
P 10.78661004 3.56615 3 P 0 0;3=12,5=1
P 10.78661004 3.61615 3 P 0 0;3=12,5=1
P 10.68661004 3.61615 3 P 0 0;3=12,5=1
P 10.68661004 3.56615 3 P 0 0;3=12,5=1
P 10.73661004 3.61615 3 P 0 0;3=12,5=1
P 10.73661004 3.56615 3 P 0 0;3=12,5=1
P 10.78661004 3.46615 3 P 0 0;3=12,5=1
P 10.73661004 3.46615 3 P 0 0;3=12,5=1
P 10.68661004 3.46615 3 P 0 0;3=12,5=1
P 10.83661004 3.71615 3 P 0 0;3=12,5=1
P 10.88661004 3.71615 3 P 0 0;3=12,5=1
P 10.83661004 3.76615 3 P 0 0;3=12,5=1
P 10.88661004 3.76615 3 P 0 0;3=12,5=1
P 10.83661004 3.86615 3 P 0 0;3=12,5=1
P 10.88661004 3.86615 3 P 0 0;3=12,5=1
P 10.78661004 3.86615 3 P 0 0;3=12,5=1
P 10.78661004 3.76615 3 P 0 0;3=12,5=1
P 10.68661004 3.86615 3 P 0 0;3=12,5=1
P 10.68661004 3.76615 3 P 0 0;3=12,5=1
P 10.73661004 3.86615 3 P 0 0;3=12,5=1
P 10.73661004 3.76615 3 P 0 0;3=12,5=1
P 10.78661004 3.71615 3 P 0 0;3=12,5=1
P 10.68661004 3.71615 3 P 0 0;3=12,5=1
P 10.73661004 3.71615 3 P 0 0;3=12,5=1
P 11.03661004 2.96615 3 P 0 0;3=12,5=1
P 10.93661004 2.96615 3 P 0 0;3=12,5=1
P 10.98661004 2.96615 3 P 0 0;3=12,5=1
P 11.03661004 3.01615 3 P 0 0;3=12,5=1
P 10.93661004 3.01615 3 P 0 0;3=12,5=1
P 10.98661004 3.01615 3 P 0 0;3=12,5=1
P 11.03661004 3.11615 3 P 0 0;3=12,5=1
P 10.93661004 3.11615 3 P 0 0;3=12,5=1
P 10.98661004 3.11615 3 P 0 0;3=12,5=1
P 11.03661004 3.16615 3 P 0 0;3=12,5=1
P 10.93661004 3.16615 3 P 0 0;3=12,5=1
P 10.98661004 3.16615 3 P 0 0;3=12,5=1
P 11.03661004 3.26615 3 P 0 0;3=12,5=1
P 10.93661004 3.26615 3 P 0 0;3=12,5=1
P 10.98661004 3.26615 3 P 0 0;3=12,5=1
P 10.98661004 3.31615 3 P 0 0;3=12,5=1
P 10.93661004 3.31615 3 P 0 0;3=12,5=1
P 11.03661004 3.31615 3 P 0 0;3=12,5=1
P 10.98661004 3.41615 3 P 0 0;3=12,5=1
P 10.93661004 3.41615 3 P 0 0;3=12,5=1
P 11.03661004 3.41615 3 P 0 0;3=12,5=1
P 10.98661004 3.46615 3 P 0 0;3=12,5=1
P 10.93661004 3.46615 3 P 0 0;3=12,5=1
P 11.03661004 3.46615 3 P 0 0;3=12,5=1
P 10.98661004 3.56615 3 P 0 0;3=12,5=1
P 10.93661004 3.56615 3 P 0 0;3=12,5=1
P 11.03661004 3.56615 3 P 0 0;3=12,5=1
P 10.98661004 3.61615 3 P 0 0;3=12,5=1
P 10.93661004 3.61615 3 P 0 0;3=12,5=1
P 11.03661004 3.61615 3 P 0 0;3=12,5=1
P 10.98661004 3.71615 3 P 0 0;3=12,5=1
P 10.93661004 3.71615 3 P 0 0;3=12,5=1
P 11.03661004 3.71615 3 P 0 0;3=12,5=1
P 10.98661004 3.76615 3 P 0 0;3=12,5=1
P 10.93661004 3.76615 3 P 0 0;3=12,5=1
P 11.03661004 3.76615 3 P 0 0;3=12,5=1
P 10.98661004 3.86615 3 P 0 0;3=12,5=1
P 10.93661004 3.86615 3 P 0 0;3=12,5=1
P 11.03661004 3.86615 3 P 0 0;3=12,5=1
P 5.05768002 2.09115 6 P 0 0;1,3=11,5=0
P 5.08268002 2.06615 3 P 0 0;3=12,5=1
P 10.58661004 2.36615 3 P 0 0;3=12,5=1
P 10.61161004 2.39115 6 P 0 0;1,3=11,5=0
P 9.975 2.4709 3 P 0 0;3=12,5=1
P 12.73621004 4.20866004 8 P 0 0;3=2,5=0
P 11.08661004 2.36615 3 P 0 0;3=12,5=1
P 11.06161004 2.39115 6 P 0 0;1,3=11,5=0
P 5.05768002 2.14115 6 P 0 0;1,3=11,5=0
P 5.08268002 2.11615 3 P 0 0;3=12,5=1
P 11.08661004 2.41615 3 P 0 0;3=12,5=1
P 11.06161004 2.44115 6 P 0 0;1,3=11,5=0
P 12.73621004 2.47638002 8 P 0 0;3=2,5=0
P 10.61161004 1.99115 6 P 0 0;1,3=11,5=0
P 10.58661004 1.96615 3 P 0 0;3=12,5=1
P 10.26 1.70445 3 P 0 0;3=12,5=1
P 10.98661004 2.41615 3 P 0 0;3=12,5=1
P 10.96161004 2.44115 6 P 0 0;1,3=11,5=0
P 8.5 3.76615 3 P 0 0;3=12,5=1
P 8.475 3.74115 6 P 0 0;1,3=11,5=0
P 9.35271004 5.1035 3 P 0 0;3=12,5=1
P 9.34453002 4.97913996 37 P 0 0;1,3=1,5=0
P 4.95768002 2.09115 6 P 0 0;1,3=11,5=0
P 4.98268002 2.06615 3 P 0 0;3=12,5=1
P 8.5 3.81615 3 P 0 0;3=12,5=1
P 8.475 3.79115 6 P 0 0;1,3=11,5=0
P 9.31271004 5.1035 3 P 0 0;3=12,5=1
P 9.3209 4.97913996 37 P 0 0;1,3=1,5=0
P 12.55905 2.59448996 8 P 0 0;3=2,5=0
P 11.53316004 1.572 3 P 0 0;3=12,5=1
P 4.95768002 2.14115 6 P 0 0;1,3=11,5=0
P 4.98268002 2.11615 3 P 0 0;3=12,5=1
P 10.98661004 2.36615 3 P 0 0;3=12,5=1
P 10.96161004 2.39115 6 P 0 0;1,3=11,5=0
P 8.5 3.61615 3 P 0 0;3=12,5=1
P 8.475 3.59115 6 P 0 0;1,3=11,5=0
P 9.56531004 5.14 3 P 0 0;3=12,5=1
P 9.55711998 4.97913996 37 P 0 0;1,3=1,5=0
P 4.90768002 2.04115 6 P 0 0;1,3=11,5=0
P 4.93268002 2.01615 3 P 0 0;3=12,5=1
P 11.53316004 1.412 3 P 0 0;3=12,5=1
P 12.63778996 2.39763996 8 P 0 0;3=2,5=0
P 8.5 3.66615 3 P 0 0;3=12,5=1
P 8.475 3.64115 6 P 0 0;1,3=11,5=0
P 9.52531004 5.14 3 P 0 0;3=12,5=1
P 9.5335 4.97913996 37 P 0 0;1,3=1,5=0
P 12.73621004 2.87008002 8 P 0 0;3=2,5=0
P 10.66161004 2.09115 6 P 0 0;1,3=11,5=0
P 10.63661004 2.06615 3 P 0 0;3=12,5=1
P 10.225 1.96645 3 P 0 0;3=12,5=1
P 11.53316004 1.452 3 P 0 0;3=12,5=1
P 12.55905 2.43701004 8 P 0 0;3=2,5=0
P 8.35 3.66615 3 P 0 0;3=12,5=1
P 8.325 3.64115 6 P 0 0;1,3=11,5=0
P 9.56531004 4.71973002 3 P 0 0;3=12,5=1
P 9.55711998 4.85788002 37 P 0 0;1,3=1,5=0
P 4.90768002 2.09115 6 P 0 0;1,3=11,5=0
P 4.93268002 2.06615 3 P 0 0;3=12,5=1
P 8.35 3.71615 3 P 0 0;3=12,5=1
P 8.325 3.69115 6 P 0 0;1,3=11,5=0
P 9.52531004 4.71973002 3 P 0 0;3=12,5=1
P 9.5335 4.85788002 37 P 0 0;1,3=1,5=0
P 11.83316004 2.212 3 P 0 0;3=12,5=1
P 12.63778996 3.65748002 8 P 0 0;3=2,5=0
P 12.73621004 3.02756004 8 P 0 0;3=2,5=0
P 10.61161004 2.14115 6 P 0 0;1,3=11,5=0
P 10.58661004 2.11615 3 P 0 0;3=12,5=1
P 10.09 2.05655 3 P 0 0;3=12,5=1
P 11.53316004 1.932 3 P 0 0;3=12,5=1
P 12.63778996 3.26378002 8 P 0 0;3=2,5=0
P 8.74578996 5.14 3 P 0 0;3=12,5=1
P 8.75398002 4.97913996 37 P 0 0;1,3=1,5=0
P 8.025 3.59115 6 P 0 0;1,3=11,5=0
P 8.05 3.61615 3 P 0 0;3=12,5=1
P 12.81495 4.01181004 8 P 0 0;3=2,5=0
P 10.71161004 2.44115 6 P 0 0;1,3=11,5=0
P 10.09 2.57845 3 P 0 0;3=12,5=1
P 10.68661004 2.41615 3 P 0 0;3=12,5=1
P 11.73316004 1.492 3 P 0 0;3=12,5=1
P 12.63778996 2.24016004 8 P 0 0;3=2,5=0
P 8.78578996 5.14 3 P 0 0;3=12,5=1
P 8.7776 4.97913996 37 P 0 0;1,3=1,5=0
P 8.025 3.64115 6 P 0 0;1,3=11,5=0
P 8.05 3.66615 3 P 0 0;3=12,5=1
P 12.73621004 2.7126 8 P 0 0;3=2,5=0
P 10.76161004 2.09115 6 P 0 0;1,3=11,5=0
P 10.73661004 2.06615 3 P 0 0;3=12,5=1
P 10.26025 1.86845 3 P 0 0;3=12,5=1
P 11.03661004 2.46615 3 P 0 0;3=12,5=1
P 11.01161004 2.44115 6 P 0 0;1,3=11,5=0
P 8.15 3.61615 3 P 0 0;3=12,5=1
P 8.125 3.59115 6 P 0 0;1,3=11,5=0
P 8.88441004 5.17001998 3 P 0 0;3=12,5=1
P 8.82483996 4.97913996 37 P 0 0;1,3=1,5=0
P 12.55905 4.09055 8 P 0 0;3=2,5=0
P 11.53316004 2.412 3 P 0 0;3=12,5=1
P 11.03661004 2.51615 3 P 0 0;3=12,5=1
P 11.01161004 2.49115 6 P 0 0;1,3=11,5=0
P 8.15 3.66615 3 P 0 0;3=12,5=1
P 8.125 3.64115 6 P 0 0;1,3=11,5=0
P 8.92441004 5.17001998 3 P 0 0;3=12,5=1
P 8.84846004 4.97913996 37 P 0 0;1,3=1,5=0
P 0.97 5.093 25 P 0 0;1,3=4,5=0
P 0.97 5.027 25 P 0 0;1,3=4,5=0
P 1.03 5.027 25 P 0 0;1,3=4,5=0
P 1.057 5.027 1 P 0 0;3=0,5=1
P 12.73621004 3.18503996 8 P 0 0;3=2,5=0
P 10.71161004 2.14115 6 P 0 0;1,3=11,5=0
P 10.68661004 2.11615 3 P 0 0;3=12,5=1
P 10.09 2.17095 3 P 0 0;3=12,5=1
P 11.78316004 1.692 3 P 0 0;3=12,5=1
P 12.55905 2.04331004 8 P 0 0;3=2,5=0
P 12.81495 2.90945 8 P 0 0;3=2,5=0
P 10.66161004 2.04115 6 P 0 0;1,3=11,5=0
P 10.63661004 2.01615 3 P 0 0;3=12,5=1
P 10.225 1.92645 3 P 0 0;3=12,5=1
P 11.78316004 1.652 3 P 0 0;3=12,5=1
P 12.63778996 2.08268002 8 P 0 0;3=2,5=0
P 1.094 5.417 25 P 0 0;1,3=4,5=0
P 1.04428996 5.53641998 49 P 0 0;1,3=16,5=0
P 1.122 5.417 4 P 0 0;3=13,5=1
P 5.855 0.925 4 P 0 0;3=13,5=1
P 3.88 4.545 1 P 0 0;3=0,5=1
P 0.97 5.823 25 P 0 0;1,3=4,5=0
P 0.96555 5.70373996 49 P 0 0;1,3=16,5=0
P 0.5574 5.85528002 41 P 0 0;1,3=27,5=0
P 0.96555 5.78055 1 P 0 0;3=0,5=1
P 4.07 4.625 4 P 0 0;3=13,5=1
P 4.063 4.59 25 P 0 0;1,3=4,5=0
P 10.61161004 2.74115 6 P 0 0;1,3=11,5=0
P 10.58661004 2.71615 3 P 0 0;3=12,5=1
P 9.91 4.543 25 P 0 0;1,3=4,5=0
P 9.91 4.433 1 P 0 0;3=0,5=1
P 4.36323002 5.48 54 P 0 0;1,3=15,5=0
P 4.535 5.48 45 P 0 0;1,3=7,5=0
P 4.36323002 5.68 54 P 0 0;1,3=15,5=0
P 5.075 5.433 25 P 0 0;1,3=4,5=0
P 9.995 2.936 4 P 0 0;3=13,5=1
P 0.46 5.649 7 P 0 0;2,3=6,5=1
P 0.52 5.649 27 P 0 0;1,3=23,5=0
P 0.503 5.7 25 P 0 0;1,3=4,5=0
P 11.83316004 2.252 3 P 0 0;3=12,5=1
P 12.55905 3.61811004 8 P 0 0;3=2,5=0
P 0.537 5.7 25 P 0 0;1,3=4,5=0
P 0.52 5.76471998 41 P 0 0;1,3=27,5=0
P 0.46 5.735 7 P 0 0;2,3=6,5=1
P 1.38906004 5.09151004 25 P 0 0;1,3=4,5=0
P 1.32745 4.9602 39 P 0 0;1,3=20,5=0
P 1.38906004 5.04851004 7 P 0 0;2,3=6,5=1
P 12.81495 3.06693002 8 P 0 0;3=2,5=0
P 10.61161004 2.09115 6 P 0 0;1,3=11,5=0
P 10.58661004 2.06615 3 P 0 0;3=12,5=1
P 10.09 2.01655 3 P 0 0;3=12,5=1
P 8.1 3.81615 3 P 0 0;3=12,5=1
P 8.075 3.79115 6 P 0 0;1,3=11,5=0
P 9.10011004 5.0535 3 P 0 0;3=12,5=1
P 9.10831004 4.97913996 37 P 0 0;1,3=1,5=0
P 8.1 3.86615 3 P 0 0;3=12,5=1
P 8.075 3.84115 6 P 0 0;1,3=11,5=0
P 9.14011004 5.0535 3 P 0 0;3=12,5=1
P 9.13193002 4.97913996 37 P 0 0;1,3=1,5=0
P 3.9599 5.35898996 25 P 0 0;1,3=4,5=0
P 3.9599 5.395 1 P 0 0;3=0,5=1
P 0.89 5.823 25 P 0 0;1,3=4,5=0
P 0.88681004 5.70373996 49 P 0 0;1,3=16,5=0
P 0.88681004 5.78181004 4 P 0 0;3=13,5=1
P 12.73621004 2.3189 8 P 0 0;3=2,5=0
P 10.66161004 1.94115 6 P 0 0;1,3=11,5=0
P 10.63661004 1.91615 3 P 0 0;3=12,5=1
P 10.38371998 1.49328002 3 P 0 0;3=12,5=1
P 8.325 3.79115 6 P 0 0;1,3=11,5=0
P 8.35 3.81615 3 P 0 0;3=12,5=1
P 9.28185 5.22001998 3 P 0 0;3=12,5=1
P 9.27366004 4.97913996 37 P 0 0;1,3=1,5=0
P 0.755 5.417 25 P 0 0;1,3=4,5=0
P 0.72933002 5.53641998 49 P 0 0;1,3=16,5=0
P 0.705 5.417 25 P 0 0;1,3=4,5=0
P 0.72933002 5.463 1 P 0 0;3=0,5=1
P 11.53316004 2.572 3 P 0 0;3=12,5=1
P 12.55905 4.56298996 8 P 0 0;3=2,5=0
P 8.325 3.84115 6 P 0 0;1,3=11,5=0
P 8.35 3.86615 3 P 0 0;3=12,5=1
P 9.24185 5.22001998 3 P 0 0;3=12,5=1
P 9.25003996 4.97913996 37 P 0 0;1,3=1,5=0
P 4.125 2.682 4 P 0 0;3=13,5=1
P 3.62 4.483 25 P 0 0;1,3=4,5=0
P 3.94 4.42 1 P 0 0;3=0,5=1
P 4.36323002 5.58 54 P 0 0;1,3=15,5=0
P 4.36323002 5.78 54 P 0 0;1,3=15,5=0
P 4.585 5.48 45 P 0 0;1,3=7,5=0
P 5.025 5.433 25 P 0 0;1,3=4,5=0
P 5.03 5.4 4 P 0 0;3=13,5=1
P 4.60768002 2.74115 6 P 0 0;1,3=11,5=0
P 4.58268002 2.71615 3 P 0 0;3=12,5=1
P 8.45 3.81615 3 P 0 0;3=12,5=1
P 8.425 3.79115 6 P 0 0;1,3=11,5=0
P 9.21098002 4.78291998 3 P 0 0;3=12,5=1
P 9.20278996 4.85788002 37 P 0 0;1,3=1,5=0
P 8.45 3.86615 3 P 0 0;3=12,5=1
P 8.425 3.84115 6 P 0 0;1,3=11,5=0
P 9.17098002 4.78291998 3 P 0 0;3=12,5=1
P 9.17916998 4.85788002 37 P 0 0;1,3=1,5=0
P 3.75998996 0.2711 25 P 0 0;1,3=4,5=0
P 3.75998996 0.24001004 1 P 0 0;3=0,5=1
P 9.55795 0.29243002 25 P 0 0;1,3=4,5=0
P 9.55795 0.26133996 1 P 0 0;3=0,5=1
P 3.60998996 0.7751 25 P 0 0;1,3=4,5=0
P 3.66998996 0.7751 25 P 0 0;1,3=4,5=0
P 3.71203002 0.77535 4 P 0 0;3=13,5=1
P 3.70998996 0.62931998 43 P 0 0;1,3=28,5=0
P 3.70998996 0.7 4 P 0 0;3=13,5=1
P 9.50795 0.65065 43 P 0 0;1,3=28,5=0
P 9.50795 0.72133002 4 P 0 0;3=13,5=1
P 9.46795 0.82631998 4 P 0 0;3=13,5=1
P 9.40795 0.79643002 25 P 0 0;1,3=4,5=0
P 9.46795 0.79643002 25 P 0 0;1,3=4,5=0
P 4.02893002 2.59336998 4 P 0 0;3=13,5=1
P 11.395 2.725 1 P 0 0;3=0,5=1
P 11.395 2.8 4 P 0 0;3=13,5=1
P 11.58613002 2.905 4 P 0 0;3=13,5=1
P 11.58613002 2.785 4 P 0 0;3=13,5=1
P 1.33906004 4.60351004 1 P 0 0;3=0,5=1
P 1.28906004 4.63151004 25 P 0 0;1,3=4,5=0
P 1.33906004 4.63151004 25 P 0 0;1,3=4,5=0
P 3.67 4.483 25 P 0 0;1,3=4,5=0
P 3.67 4.45 4 P 0 0;3=13,5=1
P 3.72 4.517 25 P 0 0;1,3=4,5=0
P 3.69558996 4.58965 38 P 0 0;1,3=8,5=0
P 3.72 4.545 4 P 0 0;3=13,5=1
P 7.3426 4.63151004 25 P 0 0;1,3=4,5=0
P 7.2926 4.63151004 25 P 0 0;1,3=4,5=0
P 5.37968996 2.8 4 P 0 0;3=13,5=1
P 5.387 2.725 1 P 0 0;3=0,5=1
P 5.5822 2.785 4 P 0 0;3=13,5=1
P 5.5822 2.905 4 P 0 0;3=13,5=1
P 7.2426 4.69351004 4 P 0 0;3=13,5=1
P 7.25421004 4.79681998 39 P 0 0;1,3=20,5=0
P 7.2426 4.66551004 25 P 0 0;1,3=4,5=0
P 7.2926 4.60351004 4 P 0 0;3=13,5=1
P 9.98 4.543 25 P 0 0;1,3=4,5=0
P 9.98 4.51 4 P 0 0;3=13,5=1
P 10.07286004 2.82336998 4 P 0 0;3=13,5=1
P 10.03 4.577 25 P 0 0;1,3=4,5=0
P 10.02558996 4.64965 38 P 0 0;1,3=8,5=0
P 10.03 4.61 4 P 0 0;3=13,5=1
P 1.23906004 4.66551004 25 P 0 0;1,3=4,5=0
P 1.23906004 4.69351004 4 P 0 0;3=13,5=1
P 1.25066998 4.79681998 39 P 0 0;1,3=20,5=0
P 3.89 4.683 25 P 0 0;1,3=4,5=0
P 3.89 4.655 4 P 0 0;3=13,5=1
P 4.0399 4.79498996 25 P 0 0;1,3=4,5=0
P 3.9899 4.79498996 25 P 0 0;1,3=4,5=0
P 3.9899 4.765 4 P 0 0;3=13,5=1
P 4.03666998 4.96076998 39 P 0 0;1,3=20,5=0
P 4.1049 4.82898996 25 P 0 0;1,3=4,5=0
P 4.1049 4.86 4 P 0 0;3=13,5=1
P 4.0599 5.35898996 25 P 0 0;1,3=4,5=0
P 4.0099 5.35898996 25 P 0 0;1,3=4,5=0
P 4.0599 5.395 4 P 0 0;3=13,5=1
P 3.91 5.477 25 P 0 0;1,3=4,5=0
P 3.91 5.51 4 P 0 0;3=13,5=1
P 5.125 5.433 25 P 0 0;1,3=4,5=0
P 5.125 5.4 4 P 0 0;3=13,5=1
P 1.43798996 5.70373996 49 P 0 0;1,3=16,5=0
P 1.35925 5.70373996 49 P 0 0;1,3=16,5=0
P 1.37925 5.78 4 P 0 0;3=13,5=1
P 1.45798996 5.78 4 P 0 0;3=13,5=1
P 1.355 5.823 25 P 0 0;1,3=4,5=0
P 1.455 5.823 25 P 0 0;1,3=4,5=0
P 1.305 5.823 25 P 0 0;1,3=4,5=0
P 1.405 5.823 25 P 0 0;1,3=4,5=0
P 1.42 5.78 4 P 0 0;3=13,5=1
P 1.335 5.78 4 P 0 0;3=13,5=1
P 12.63778996 2.55511998 8 P 0 0;3=2,5=0
P 11.53316004 1.612 3 P 0 0;3=12,5=1
P 8.4 3.76615 3 P 0 0;3=12,5=1
P 8.375 3.74115 6 P 0 0;1,3=11,5=0
P 9.28185 4.642 3 P 0 0;3=12,5=1
P 9.27366004 4.85788002 37 P 0 0;1,3=1,5=0
P 12.73621004 4.36613996 8 P 0 0;3=2,5=0
P 10.66161004 2.44115 6 P 0 0;1,3=11,5=0
P 10.63661004 2.41615 3 P 0 0;3=12,5=1
P 9.975 2.66445 3 P 0 0;3=12,5=1
P 8.4 3.81615 3 P 0 0;3=12,5=1
P 8.375 3.79115 6 P 0 0;1,3=11,5=0
P 9.24185 4.642 3 P 0 0;3=12,5=1
P 9.25003996 4.85788002 37 P 0 0;1,3=1,5=0
P 11.53316004 2.532 3 P 0 0;3=12,5=1
P 12.63778996 4.60236998 8 P 0 0;3=2,5=0
P 8.45 3.66615 3 P 0 0;3=12,5=1
P 8.425 3.64115 6 P 0 0;1,3=11,5=0
P 9.42358002 4.78291998 3 P 0 0;3=12,5=1
P 9.41538996 4.85788002 37 P 0 0;1,3=1,5=0
P 0.96555 5.53641998 49 P 0 0;1,3=16,5=0
P 0.948 5.417 25 P 0 0;1,3=4,5=0
P 0.996 5.417 25 P 0 0;1,3=4,5=0
P 0.95951004 5.4595 1 P 0 0;3=0,5=1
P 8.45 3.71615 3 P 0 0;3=12,5=1
P 8.425 3.69115 6 P 0 0;1,3=11,5=0
P 9.38358002 4.78291998 3 P 0 0;3=12,5=1
P 9.39176998 4.85788002 37 P 0 0;1,3=1,5=0
P 8.4 3.61615 3 P 0 0;3=12,5=1
P 8.375 3.59115 6 P 0 0;1,3=11,5=0
P 9.49445 4.587 3 P 0 0;3=12,5=1
P 9.48626004 4.85788002 37 P 0 0;1,3=1,5=0
P 8.4 3.66615 3 P 0 0;3=12,5=1
P 8.375 3.64115 6 P 0 0;1,3=11,5=0
P 9.45445 4.587 3 P 0 0;3=12,5=1
P 9.46263996 4.85788002 37 P 0 0;1,3=1,5=0
P 9.07353996 4.42 4 P 0 0;3=13,5=1
P 7.1926 5.15351004 1 P 0 0;3=0,5=1
P 7.1926 5.12551004 25 P 0 0;1,3=4,5=0
P 9.10831004 4.85788002 37 P 0 0;1,3=1,5=0
P 8.1 3.66615 3 P 0 0;3=12,5=1
P 8.075 3.64115 6 P 0 0;1,3=11,5=0
P 8.74578996 4.667 3 P 0 0;3=12,5=1
P 8.75398002 4.85788002 37 P 0 0;1,3=1,5=0
P 8.1 3.71615 3 P 0 0;3=12,5=1
P 8.075 3.69115 6 P 0 0;1,3=11,5=0
P 8.78578996 4.667 3 P 0 0;3=12,5=1
P 8.7776 4.85788002 37 P 0 0;1,3=1,5=0
P 8.2 3.66615 3 P 0 0;3=12,5=1
P 8.175 3.64115 6 P 0 0;1,3=11,5=0
P 8.81665 4.78291998 3 P 0 0;3=12,5=1
P 8.82483996 4.85788002 37 P 0 0;1,3=1,5=0
P 8.2 3.71615 3 P 0 0;3=12,5=1
P 8.175 3.69115 6 P 0 0;1,3=11,5=0
P 8.85665 4.78291998 3 P 0 0;3=12,5=1
P 8.84846004 4.85788002 37 P 0 0;1,3=1,5=0
P 8.05 3.76615 3 P 0 0;3=12,5=1
P 8.025 3.74115 6 P 0 0;1,3=11,5=0
P 8.89061998 4.667 3 P 0 0;3=12,5=1
P 8.96656998 4.85788002 37 P 0 0;1,3=1,5=0
P 8.05 3.81615 3 P 0 0;3=12,5=1
P 8.025 3.79115 6 P 0 0;1,3=11,5=0
P 8.93061998 4.667 3 P 0 0;3=12,5=1
P 8.9902 4.85788002 37 P 0 0;1,3=1,5=0
P 9.02925 4.667 3 P 0 0;3=12,5=1
P 9.03743996 4.85788002 37 P 0 0;1,3=1,5=0
P 8.175 3.79115 6 P 0 0;1,3=11,5=0
P 8.2 3.81615 3 P 0 0;3=12,5=1
P 9.06925 4.667 3 P 0 0;3=12,5=1
P 9.06106004 4.85788002 37 P 0 0;1,3=1,5=0
P 8.175 3.84115 6 P 0 0;1,3=11,5=0
P 8.2 3.86615 3 P 0 0;3=12,5=1
P 4.70768002 2.74115 6 P 0 0;1,3=11,5=0
P 4.68268002 2.71615 3 P 0 0;3=12,5=1
P 0.91 5.233 25 P 0 0;1,3=4,5=0
P 1.02558996 5.29035 38 P 0 0;1,3=8,5=0
P 0.91 5.147 25 P 0 0;1,3=4,5=0
P 0.91 5.19 7 P 0 0;2,3=6,5=1
P 4.95768002 2.74115 6 P 0 0;1,3=11,5=0
P 4.98268002 2.71615 3 P 0 0;3=12,5=1
P 2.12106004 2.49115 6 P 0 0;1,3=11,5=0
P 2.14606004 2.51615 3 P 0 0;3=12,5=1
P 8.425 3.39115 6 P 0 0;1,3=11,5=0
P 8.45 3.41615 3 P 0 0;3=12,5=1
P 8.17993002 4.97913996 37 P 0 0;1,3=1,5=0
P 8.18811004 5.0535 3 P 0 0;3=12,5=1
P 5.05768002 3.79115 6 P 0 0;1,3=11,5=0
P 5.03268002 3.81615 3 P 0 0;3=12,5=1
P 4.07408002 4.01978996 1 P 0 0;3=0,5=1
P 8.425 3.44115 6 P 0 0;1,3=11,5=0
P 8.45 3.46615 3 P 0 0;3=12,5=1
P 8.1563 4.97913996 37 P 0 0;1,3=1,5=0
P 8.14811004 5.0535 3 P 0 0;3=12,5=1
P 5.00768002 2.19115 6 P 0 0;1,3=11,5=0
P 5.03268002 2.16615 3 P 0 0;3=12,5=1
P 3.91 5.443 25 P 0 0;1,3=4,5=0
P 3.9099 5.35898996 25 P 0 0;1,3=4,5=0
P 3.9099 5.395 1 P 0 0;3=0,5=1
P 8.45 3.26615 3 P 0 0;3=12,5=1
P 8.425 3.24115 6 P 0 0;1,3=11,5=0
P 8.39251998 4.97913996 37 P 0 0;1,3=1,5=0
P 8.40071004 5.115 3 P 0 0;3=12,5=1
P 0.84953002 5.2361 35 P 0 0;1,3=10,5=0
P 0.91 5.267 25 P 0 0;1,3=4,5=0
P 0.91 5.31 7 P 0 0;2,3=6,5=1
P 8.45 3.31615 3 P 0 0;3=12,5=1
P 8.425 3.29115 6 P 0 0;1,3=11,5=0
P 8.3689 4.97913996 37 P 0 0;1,3=1,5=0
P 8.36071004 5.115 3 P 0 0;3=12,5=1
P 8.325 3.24115 6 P 0 0;1,3=11,5=0
P 8.35 3.26615 3 P 0 0;3=12,5=1
P 8.39251998 4.85788002 37 P 0 0;1,3=1,5=0
P 8.40071004 4.742 3 P 0 0;3=12,5=1
P 8.325 3.29115 6 P 0 0;1,3=11,5=0
P 8.35 3.31615 3 P 0 0;3=12,5=1
P 8.3689 4.85788002 37 P 0 0;1,3=1,5=0
P 8.36071004 4.742 3 P 0 0;3=12,5=1
P 8.275 3.54115 6 P 0 0;1,3=11,5=0
P 8.3 3.56615 3 P 0 0;3=12,5=1
P 8.05 3.31615 3 P 0 0;3=12,5=1
P 8.025 3.29115 6 P 0 0;1,3=11,5=0
P 7.58118996 5.169 3 P 0 0;3=12,5=1
P 7.58938002 4.97913996 37 P 0 0;1,3=1,5=0
P 8.25 3.56615 3 P 0 0;3=12,5=1
P 8.225 3.54115 6 P 0 0;1,3=11,5=0
P 8.05 3.36615 3 P 0 0;3=12,5=1
P 8.025 3.34115 6 P 0 0;1,3=11,5=0
P 7.62118996 5.169 3 P 0 0;3=12,5=1
P 7.613 4.97913996 37 P 0 0;1,3=1,5=0
P 2.22106004 2.84115 6 P 0 0;1,3=11,5=0
P 2.24606004 2.86615 3 P 0 0;3=12,5=1
P 8.05 2.61615 3 P 0 0;3=12,5=1
P 8.05 2.66615 3 P 0 0;3=12,5=1
P 8.1 2.46615 3 P 0 0;3=12,5=1
P 8.1 2.41615 3 P 0 0;3=12,5=1
P 8.2 2.46615 3 P 0 0;3=12,5=1
P 8.2 2.41615 3 P 0 0;3=12,5=1
P 8.15 2.41615 3 P 0 0;3=12,5=1
P 8.15 2.36615 3 P 0 0;3=12,5=1
P 8.05 2.41615 3 P 0 0;3=12,5=1
P 8.05 2.36615 3 P 0 0;3=12,5=1
P 8.2 2.31615 3 P 0 0;3=12,5=1
P 8.2 2.26615 3 P 0 0;3=12,5=1
P 8.15 2.26615 3 P 0 0;3=12,5=1
P 8.15 2.21615 3 P 0 0;3=12,5=1
P 8.1 2.31615 3 P 0 0;3=12,5=1
P 8.1 2.26615 3 P 0 0;3=12,5=1
P 8.05 2.26615 3 P 0 0;3=12,5=1
P 8.05 2.21615 3 P 0 0;3=12,5=1
P 8.1 2.11615 3 P 0 0;3=12,5=1
P 8.1 2.06615 3 P 0 0;3=12,5=1
P 8.2 2.11615 3 P 0 0;3=12,5=1
P 8.2 2.06615 3 P 0 0;3=12,5=1
P 8.15 2.06615 3 P 0 0;3=12,5=1
P 8.15 2.01615 3 P 0 0;3=12,5=1
P 8.05 2.06615 3 P 0 0;3=12,5=1
P 8.05 2.01615 3 P 0 0;3=12,5=1
P 8.2 1.96615 3 P 0 0;3=12,5=1
P 8.2 1.91615 3 P 0 0;3=12,5=1
P 8.15 1.91615 3 P 0 0;3=12,5=1
P 8.15 1.86615 3 P 0 0;3=12,5=1
P 8.1 1.96615 3 P 0 0;3=12,5=1
P 8.1 1.91615 3 P 0 0;3=12,5=1
P 8.05 1.91615 3 P 0 0;3=12,5=1
P 8.05 1.86615 3 P 0 0;3=12,5=1
P 8.1 3.16615 3 P 0 0;3=12,5=1
P 8.1 3.11615 3 P 0 0;3=12,5=1
P 8.2 3.16615 3 P 0 0;3=12,5=1
P 8.2 3.11615 3 P 0 0;3=12,5=1
P 8.15 3.11615 3 P 0 0;3=12,5=1
P 8.15 3.06615 3 P 0 0;3=12,5=1
P 8.05 3.11615 3 P 0 0;3=12,5=1
P 8.05 3.06615 3 P 0 0;3=12,5=1
P 8.2 3.01615 3 P 0 0;3=12,5=1
P 8.2 2.96615 3 P 0 0;3=12,5=1
P 8.15 2.96615 3 P 0 0;3=12,5=1
P 8.15 2.91615 3 P 0 0;3=12,5=1
P 8.1 3.01615 3 P 0 0;3=12,5=1
P 8.1 2.96615 3 P 0 0;3=12,5=1
P 8.05 2.96615 3 P 0 0;3=12,5=1
P 8.05 2.91615 3 P 0 0;3=12,5=1
P 8 2.81615 3 P 0 0;3=12,5=1
P 8 2.76615 3 P 0 0;3=12,5=1
P 8.15 2.81615 3 P 0 0;3=12,5=1
P 8.15 2.76615 3 P 0 0;3=12,5=1
P 8.2 2.76615 3 P 0 0;3=12,5=1
P 8.2 2.71615 3 P 0 0;3=12,5=1
P 8.1 2.76615 3 P 0 0;3=12,5=1
P 8.1 2.71615 3 P 0 0;3=12,5=1
P 8.15 2.66615 3 P 0 0;3=12,5=1
P 8.15 2.61615 3 P 0 0;3=12,5=1
P 8.2 2.61615 3 P 0 0;3=12,5=1
P 8.2 2.56615 3 P 0 0;3=12,5=1
P 8.1 2.61615 3 P 0 0;3=12,5=1
P 8.1 2.56615 3 P 0 0;3=12,5=1
P 8.35 2.56615 3 P 0 0;3=12,5=1
P 8.35 2.61615 3 P 0 0;3=12,5=1
P 8.35 2.46615 3 P 0 0;3=12,5=1
P 8.35 2.41615 3 P 0 0;3=12,5=1
P 8.45 2.46615 3 P 0 0;3=12,5=1
P 8.45 2.41615 3 P 0 0;3=12,5=1
P 8.5 2.41615 3 P 0 0;3=12,5=1
P 8.5 2.36615 3 P 0 0;3=12,5=1
P 8.4 2.41615 3 P 0 0;3=12,5=1
P 8.4 2.36615 3 P 0 0;3=12,5=1
P 8.45 2.31615 3 P 0 0;3=12,5=1
P 8.45 2.26615 3 P 0 0;3=12,5=1
P 8.5 2.26615 3 P 0 0;3=12,5=1
P 8.5 2.21615 3 P 0 0;3=12,5=1
P 8.4 2.26615 3 P 0 0;3=12,5=1
P 8.4 2.21615 3 P 0 0;3=12,5=1
P 8.35 2.31615 3 P 0 0;3=12,5=1
P 8.35 2.26615 3 P 0 0;3=12,5=1
P 8.35 2.11615 3 P 0 0;3=12,5=1
P 8.35 2.06615 3 P 0 0;3=12,5=1
P 8.45 2.11615 3 P 0 0;3=12,5=1
P 8.45 2.06615 3 P 0 0;3=12,5=1
P 8.5 2.06615 3 P 0 0;3=12,5=1
P 8.5 2.01615 3 P 0 0;3=12,5=1
P 8.4 2.06615 3 P 0 0;3=12,5=1
P 8.4 2.01615 3 P 0 0;3=12,5=1
P 8.45 1.96615 3 P 0 0;3=12,5=1
P 8.45 1.91615 3 P 0 0;3=12,5=1
P 8.5 1.91615 3 P 0 0;3=12,5=1
P 8.5 1.86615 3 P 0 0;3=12,5=1
P 8.4 1.91615 3 P 0 0;3=12,5=1
P 8.4 1.86615 3 P 0 0;3=12,5=1
P 8.35 1.96615 3 P 0 0;3=12,5=1
P 8.35 1.91615 3 P 0 0;3=12,5=1
P 8.35 3.16615 3 P 0 0;3=12,5=1
P 8.35 3.11615 3 P 0 0;3=12,5=1
P 8.45 3.16615 3 P 0 0;3=12,5=1
P 8.45 3.11615 3 P 0 0;3=12,5=1
P 8.5 3.11615 3 P 0 0;3=12,5=1
P 8.5 3.06615 3 P 0 0;3=12,5=1
P 8.4 3.11615 3 P 0 0;3=12,5=1
P 8.4 3.06615 3 P 0 0;3=12,5=1
P 8.45 3.01615 3 P 0 0;3=12,5=1
P 8.45 2.96615 3 P 0 0;3=12,5=1
P 8.5 2.96615 3 P 0 0;3=12,5=1
P 8.5 2.91615 3 P 0 0;3=12,5=1
P 8.4 2.96615 3 P 0 0;3=12,5=1
P 8.4 2.91615 3 P 0 0;3=12,5=1
P 8.35 3.01615 3 P 0 0;3=12,5=1
P 8.35 2.96615 3 P 0 0;3=12,5=1
P 8.4 2.81615 3 P 0 0;3=12,5=1
P 8.4 2.76615 3 P 0 0;3=12,5=1
P 8.5 2.81615 3 P 0 0;3=12,5=1
P 8.5 2.76615 3 P 0 0;3=12,5=1
P 8.45 2.76615 3 P 0 0;3=12,5=1
P 8.45 2.71615 3 P 0 0;3=12,5=1
P 8.35 2.76615 3 P 0 0;3=12,5=1
P 8.35 2.71615 3 P 0 0;3=12,5=1
P 8.5 2.66615 3 P 0 0;3=12,5=1
P 8.5 2.61615 3 P 0 0;3=12,5=1
P 8.45 2.61615 3 P 0 0;3=12,5=1
P 8.45 2.56615 3 P 0 0;3=12,5=1
P 8.4 2.66615 3 P 0 0;3=12,5=1
P 8.4 2.61615 3 P 0 0;3=12,5=1
P 2.04606004 2.61615 3 P 0 0;3=12,5=1
P 2.04606004 2.66615 3 P 0 0;3=12,5=1
P 2.09606004 2.46615 3 P 0 0;3=12,5=1
P 2.09606004 2.41615 3 P 0 0;3=12,5=1
P 2.19606004 2.46615 3 P 0 0;3=12,5=1
P 2.19606004 2.41615 3 P 0 0;3=12,5=1
P 2.14606004 2.41615 3 P 0 0;3=12,5=1
P 2.14606004 2.36615 3 P 0 0;3=12,5=1
P 2.04606004 2.41615 3 P 0 0;3=12,5=1
P 2.04606004 2.36615 3 P 0 0;3=12,5=1
P 2.19606004 2.31615 3 P 0 0;3=12,5=1
P 2.19606004 2.26615 3 P 0 0;3=12,5=1
P 2.14606004 2.26615 3 P 0 0;3=12,5=1
P 2.14606004 2.21615 3 P 0 0;3=12,5=1
P 2.09606004 2.31615 3 P 0 0;3=12,5=1
P 2.09606004 2.26615 3 P 0 0;3=12,5=1
P 2.04606004 2.26615 3 P 0 0;3=12,5=1
P 2.04606004 2.21615 3 P 0 0;3=12,5=1
P 2.09606004 2.11615 3 P 0 0;3=12,5=1
P 2.09606004 2.06615 3 P 0 0;3=12,5=1
P 2.19606004 2.11615 3 P 0 0;3=12,5=1
P 2.19606004 2.06615 3 P 0 0;3=12,5=1
P 2.14606004 2.06615 3 P 0 0;3=12,5=1
P 2.14606004 2.01615 3 P 0 0;3=12,5=1
P 2.04606004 2.06615 3 P 0 0;3=12,5=1
P 2.04606004 2.01615 3 P 0 0;3=12,5=1
P 2.19606004 1.96615 3 P 0 0;3=12,5=1
P 2.19606004 1.91615 3 P 0 0;3=12,5=1
P 2.14606004 1.91615 3 P 0 0;3=12,5=1
P 2.14606004 1.86615 3 P 0 0;3=12,5=1
P 2.09606004 1.96615 3 P 0 0;3=12,5=1
P 2.09606004 1.91615 3 P 0 0;3=12,5=1
P 2.04606004 1.91615 3 P 0 0;3=12,5=1
P 2.04606004 1.86615 3 P 0 0;3=12,5=1
P 2.09606004 3.16615 3 P 0 0;3=12,5=1
P 2.09606004 3.11615 3 P 0 0;3=12,5=1
P 2.19606004 3.16615 3 P 0 0;3=12,5=1
P 2.19606004 3.11615 3 P 0 0;3=12,5=1
P 2.14606004 3.11615 3 P 0 0;3=12,5=1
P 2.14606004 3.06615 3 P 0 0;3=12,5=1
P 2.04606004 3.11615 3 P 0 0;3=12,5=1
P 2.04606004 3.06615 3 P 0 0;3=12,5=1
P 2.19606004 3.01615 3 P 0 0;3=12,5=1
P 2.19606004 2.96615 3 P 0 0;3=12,5=1
P 2.14606004 2.96615 3 P 0 0;3=12,5=1
P 2.14606004 2.91615 3 P 0 0;3=12,5=1
P 2.09606004 3.01615 3 P 0 0;3=12,5=1
P 2.09606004 2.96615 3 P 0 0;3=12,5=1
P 2.04606004 2.96615 3 P 0 0;3=12,5=1
P 2.04606004 2.91615 3 P 0 0;3=12,5=1
P 1.99606004 2.81615 3 P 0 0;3=12,5=1
P 1.99606004 2.76615 3 P 0 0;3=12,5=1
P 2.14606004 2.81615 3 P 0 0;3=12,5=1
P 2.14606004 2.76615 3 P 0 0;3=12,5=1
P 2.19606004 2.76615 3 P 0 0;3=12,5=1
P 2.19606004 2.71615 3 P 0 0;3=12,5=1
P 2.09606004 2.76615 3 P 0 0;3=12,5=1
P 2.09606004 2.71615 3 P 0 0;3=12,5=1
P 2.14606004 2.66615 3 P 0 0;3=12,5=1
P 2.14606004 2.61615 3 P 0 0;3=12,5=1
P 2.19606004 2.61615 3 P 0 0;3=12,5=1
P 2.19606004 2.56615 3 P 0 0;3=12,5=1
P 2.09606004 2.61615 3 P 0 0;3=12,5=1
P 2.09606004 2.56615 3 P 0 0;3=12,5=1
P 2.34606004 2.56615 3 P 0 0;3=12,5=1
P 2.34606004 2.61615 3 P 0 0;3=12,5=1
P 2.34606004 2.46615 3 P 0 0;3=12,5=1
P 2.34606004 2.41615 3 P 0 0;3=12,5=1
P 2.44606004 2.46615 3 P 0 0;3=12,5=1
P 2.44606004 2.41615 3 P 0 0;3=12,5=1
P 2.49606004 2.41615 3 P 0 0;3=12,5=1
P 2.49606004 2.36615 3 P 0 0;3=12,5=1
P 2.39606004 2.41615 3 P 0 0;3=12,5=1
P 2.39606004 2.36615 3 P 0 0;3=12,5=1
P 2.44606004 2.31615 3 P 0 0;3=12,5=1
P 2.44606004 2.26615 3 P 0 0;3=12,5=1
P 2.49606004 2.26615 3 P 0 0;3=12,5=1
P 2.49606004 2.21615 3 P 0 0;3=12,5=1
P 2.39606004 2.26615 3 P 0 0;3=12,5=1
P 2.39606004 2.21615 3 P 0 0;3=12,5=1
P 2.34606004 2.31615 3 P 0 0;3=12,5=1
P 2.34606004 2.26615 3 P 0 0;3=12,5=1
P 2.34606004 2.11615 3 P 0 0;3=12,5=1
P 2.34606004 2.06615 3 P 0 0;3=12,5=1
P 2.44606004 2.11615 3 P 0 0;3=12,5=1
P 2.44606004 2.06615 3 P 0 0;3=12,5=1
P 2.49606004 2.06615 3 P 0 0;3=12,5=1
P 2.49606004 2.01615 3 P 0 0;3=12,5=1
P 2.39606004 2.06615 3 P 0 0;3=12,5=1
P 2.39606004 2.01615 3 P 0 0;3=12,5=1
P 2.44606004 1.96615 3 P 0 0;3=12,5=1
P 2.44606004 1.91615 3 P 0 0;3=12,5=1
P 2.49606004 1.91615 3 P 0 0;3=12,5=1
P 2.49606004 1.86615 3 P 0 0;3=12,5=1
P 2.39606004 1.91615 3 P 0 0;3=12,5=1
P 2.39606004 1.86615 3 P 0 0;3=12,5=1
P 2.34606004 1.96615 3 P 0 0;3=12,5=1
P 2.34606004 1.91615 3 P 0 0;3=12,5=1
P 2.34606004 3.16615 3 P 0 0;3=12,5=1
P 2.34606004 3.11615 3 P 0 0;3=12,5=1
P 2.44606004 3.16615 3 P 0 0;3=12,5=1
P 2.44606004 3.11615 3 P 0 0;3=12,5=1
P 2.49606004 3.11615 3 P 0 0;3=12,5=1
P 2.49606004 3.06615 3 P 0 0;3=12,5=1
P 2.39606004 3.11615 3 P 0 0;3=12,5=1
P 2.39606004 3.06615 3 P 0 0;3=12,5=1
P 2.44606004 3.01615 3 P 0 0;3=12,5=1
P 2.44606004 2.96615 3 P 0 0;3=12,5=1
P 2.49606004 2.96615 3 P 0 0;3=12,5=1
P 2.49606004 2.91615 3 P 0 0;3=12,5=1
P 2.39606004 2.96615 3 P 0 0;3=12,5=1
P 2.39606004 2.91615 3 P 0 0;3=12,5=1
P 2.34606004 3.01615 3 P 0 0;3=12,5=1
P 2.34606004 2.96615 3 P 0 0;3=12,5=1
P 2.39606004 2.81615 3 P 0 0;3=12,5=1
P 2.39606004 2.76615 3 P 0 0;3=12,5=1
P 2.49606004 2.81615 3 P 0 0;3=12,5=1
P 2.49606004 2.76615 3 P 0 0;3=12,5=1
P 2.44606004 2.76615 3 P 0 0;3=12,5=1
P 2.44606004 2.71615 3 P 0 0;3=12,5=1
P 2.34606004 2.76615 3 P 0 0;3=12,5=1
P 2.34606004 2.71615 3 P 0 0;3=12,5=1
P 2.49606004 2.66615 3 P 0 0;3=12,5=1
P 2.49606004 2.61615 3 P 0 0;3=12,5=1
P 2.44606004 2.61615 3 P 0 0;3=12,5=1
P 2.44606004 2.56615 3 P 0 0;3=12,5=1
P 2.39606004 2.66615 3 P 0 0;3=12,5=1
P 2.39606004 2.61615 3 P 0 0;3=12,5=1
P 8.94061998 4.70573996 4 P 0 0;3=13,5=1
P 9.01925 4.70573996 4 P 0 0;3=13,5=1
P 9.07925 4.70573996 4 P 0 0;3=13,5=1
P 8.73578996 4.70573996 4 P 0 0;3=13,5=1
P 8.79578996 4.70573996 4 P 0 0;3=13,5=1
P 8.86665 4.74418002 4 P 0 0;3=13,5=1
P 8.80665 4.74418002 4 P 0 0;3=13,5=1
P 9.43358002 4.74418002 4 P 0 0;3=13,5=1
P 9.51531004 4.68098996 4 P 0 0;3=13,5=1
P 9.57531004 4.68098996 4 P 0 0;3=13,5=1
P 9.44445 4.62573996 4 P 0 0;3=13,5=1
P 9.50445 4.62573996 4 P 0 0;3=13,5=1
P 9.23185 4.68073996 4 P 0 0;3=13,5=1
P 9.29185 4.68073996 4 P 0 0;3=13,5=1
P 9.16098002 4.74418002 4 P 0 0;3=13,5=1
P 9.37358002 4.74418002 4 P 0 0;3=13,5=1
P 9.22098002 4.74418002 4 P 0 0;3=13,5=1
P 9.51531004 5.17873996 4 P 0 0;3=13,5=1
P 9.57531004 5.17873996 4 P 0 0;3=13,5=1
P 9.43358002 5.18128002 4 P 0 0;3=13,5=1
P 9.23185 5.18128002 4 P 0 0;3=13,5=1
P 9.29185 5.18128002 4 P 0 0;3=13,5=1
P 9.37358002 5.18128002 4 P 0 0;3=13,5=1
P 9.36271004 5.14223996 4 P 0 0;3=13,5=1
P 9.30271004 5.14223996 4 P 0 0;3=13,5=1
P 9.15011004 5.09223996 4 P 0 0;3=13,5=1
P 9.09011004 5.09223996 4 P 0 0;3=13,5=1
P 9.07925 5.20373996 4 P 0 0;3=13,5=1
P 9.01925 5.20373996 4 P 0 0;3=13,5=1
P 8.93441004 5.20876004 4 P 0 0;3=13,5=1
P 8.73578996 5.17873996 4 P 0 0;3=13,5=1
P 8.79578996 5.17873996 4 P 0 0;3=13,5=1
P 8.87441004 5.20876004 4 P 0 0;3=13,5=1
P 7.64205 4.74418002 4 P 0 0;3=13,5=1
P 7.70205 4.74418002 4 P 0 0;3=13,5=1
P 7.63118996 4.66826004 4 P 0 0;3=13,5=1
P 7.57118996 4.66826004 4 P 0 0;3=13,5=1
P 7.91465 4.61826004 4 P 0 0;3=13,5=1
P 7.78378996 4.74418002 4 P 0 0;3=13,5=1
P 7.84378996 4.74418002 4 P 0 0;3=13,5=1
P 7.85465 4.61826004 4 P 0 0;3=13,5=1
P 8.06725 4.74418002 4 P 0 0;3=13,5=1
P 8.12725 4.74418002 4 P 0 0;3=13,5=1
P 8.02206998 4.62815 4 P 0 0;3=13,5=1
P 8.08206998 4.62815 4 P 0 0;3=13,5=1
P 8.41071004 4.70326004 4 P 0 0;3=13,5=1
P 8.35071004 4.70326004 4 P 0 0;3=13,5=1
P 8.20898002 4.74418002 4 P 0 0;3=13,5=1
P 8.26898002 4.74418002 4 P 0 0;3=13,5=1
P 8.21208996 4.62826004 4 P 0 0;3=13,5=1
P 8.27208996 4.62826004 4 P 0 0;3=13,5=1
P 8.19811004 5.09223996 4 P 0 0;3=13,5=1
P 8.12725 5.13026004 4 P 0 0;3=13,5=1
P 8.06725 5.13026004 4 P 0 0;3=13,5=1
P 7.91465 5.13026004 4 P 0 0;3=13,5=1
P 7.92551004 5.09223996 4 P 0 0;3=13,5=1
P 7.98551004 5.09223996 4 P 0 0;3=13,5=1
P 7.85465 5.13026004 4 P 0 0;3=13,5=1
P 7.64203996 5.09223996 4 P 0 0;3=13,5=1
P 7.70203996 5.09223996 4 P 0 0;3=13,5=1
P 7.57118996 5.13026004 4 P 0 0;3=13,5=1
P 7.63118996 5.13026004 4 P 0 0;3=13,5=1
P 2.73225 4.70573996 4 P 0 0;3=13,5=1
P 2.79225 4.70573996 4 P 0 0;3=13,5=1
P 3.22831004 5.18128002 4 P 0 0;3=13,5=1
P 3.28831004 5.18128002 4 P 0 0;3=13,5=1
P 3.01571004 5.20373996 4 P 0 0;3=13,5=1
P 3.07571004 5.20373996 4 P 0 0;3=13,5=1
P 2.73225 5.17873996 4 P 0 0;3=13,5=1
P 2.79225 5.17873996 4 P 0 0;3=13,5=1
P 1.56765 4.66826004 4 P 0 0;3=13,5=1
P 1.62765 4.66826004 4 P 0 0;3=13,5=1
P 1.56765 5.13026004 4 P 0 0;3=13,5=1
P 1.62765 5.13026004 4 P 0 0;3=13,5=1
P 1.91111004 5.13026004 4 P 0 0;3=13,5=1
P 1.85111004 5.13026004 4 P 0 0;3=13,5=1
P 8.475 3.69115 6 P 0 0;1,3=11,5=0
P 8.475 3.84115 6 P 0 0;1,3=11,5=0
P 8.425 3.54115 6 P 0 0;1,3=11,5=0
P 8.475 3.54115 6 P 0 0;1,3=11,5=0
P 8.475 3.24115 6 P 0 0;1,3=11,5=0
P 8.425 3.34115 6 P 0 0;1,3=11,5=0
P 8.475 3.39115 6 P 0 0;1,3=11,5=0
P 8.225 3.69115 6 P 0 0;1,3=11,5=0
P 8.275 3.74115 6 P 0 0;1,3=11,5=0
P 8.225 3.74115 6 P 0 0;1,3=11,5=0
P 8.175 3.74115 6 P 0 0;1,3=11,5=0
P 8.225 3.79115 6 P 0 0;1,3=11,5=0
P 8.225 3.84115 6 P 0 0;1,3=11,5=0
P 8.225 3.44115 6 P 0 0;1,3=11,5=0
P 8.275 3.49115 6 P 0 0;1,3=11,5=0
P 8.225 3.49115 6 P 0 0;1,3=11,5=0
P 8.175 3.49115 6 P 0 0;1,3=11,5=0
P 8.175 3.54115 6 P 0 0;1,3=11,5=0
P 8.175 3.59115 6 P 0 0;1,3=11,5=0
P 8.225 3.59115 6 P 0 0;1,3=11,5=0
P 8.225 3.64115 6 P 0 0;1,3=11,5=0
P 8.275 3.59115 6 P 0 0;1,3=11,5=0
P 8.375 3.54115 6 P 0 0;1,3=11,5=0
P 8.225 3.24115 6 P 0 0;1,3=11,5=0
P 8.225 3.29115 6 P 0 0;1,3=11,5=0
P 8.175 3.34115 6 P 0 0;1,3=11,5=0
P 8.225 3.34115 6 P 0 0;1,3=11,5=0
P 8.275 3.34115 6 P 0 0;1,3=11,5=0
P 8.225 3.39115 6 P 0 0;1,3=11,5=0
P 8.075 3.49115 6 P 0 0;1,3=11,5=0
P 8.025 3.54115 6 P 0 0;1,3=11,5=0
P 8.125 3.54115 6 P 0 0;1,3=11,5=0
P 8.075 3.34115 6 P 0 0;1,3=11,5=0
P 8.025 3.39115 6 P 0 0;1,3=11,5=0
P 10.96161004 3.79115 6 P 0 0;1,3=11,5=0
P 11.01161004 3.79115 6 P 0 0;1,3=11,5=0
P 11.06161004 3.64115 6 P 0 0;1,3=11,5=0
P 10.96161004 3.64115 6 P 0 0;1,3=11,5=0
P 11.01161004 3.64115 6 P 0 0;1,3=11,5=0
P 11.06161004 3.49115 6 P 0 0;1,3=11,5=0
P 10.96161004 3.49115 6 P 0 0;1,3=11,5=0
P 11.01161004 3.49115 6 P 0 0;1,3=11,5=0
P 11.06161004 3.34115 6 P 0 0;1,3=11,5=0
P 10.96161004 3.34115 6 P 0 0;1,3=11,5=0
P 11.01161004 3.34115 6 P 0 0;1,3=11,5=0
P 11.01161004 3.19115 6 P 0 0;1,3=11,5=0
P 10.96161004 3.19115 6 P 0 0;1,3=11,5=0
P 11.06161004 3.19115 6 P 0 0;1,3=11,5=0
P 11.01161004 3.04115 6 P 0 0;1,3=11,5=0
P 10.96161004 3.04115 6 P 0 0;1,3=11,5=0
P 11.06161004 3.04115 6 P 0 0;1,3=11,5=0
P 11.01161004 2.89115 6 P 0 0;1,3=11,5=0
P 10.96161004 2.89115 6 P 0 0;1,3=11,5=0
P 11.06161004 2.89115 6 P 0 0;1,3=11,5=0
P 10.71161004 3.79115 6 P 0 0;1,3=11,5=0
P 10.76161004 3.79115 6 P 0 0;1,3=11,5=0
P 10.81161004 3.79115 6 P 0 0;1,3=11,5=0
P 10.91161004 3.64115 6 P 0 0;1,3=11,5=0
P 10.91161004 3.79115 6 P 0 0;1,3=11,5=0
P 10.86161004 3.79115 6 P 0 0;1,3=11,5=0
P 10.71161004 3.49115 6 P 0 0;1,3=11,5=0
P 10.76161004 3.49115 6 P 0 0;1,3=11,5=0
P 10.81161004 3.49115 6 P 0 0;1,3=11,5=0
P 10.71161004 3.64115 6 P 0 0;1,3=11,5=0
P 10.76161004 3.64115 6 P 0 0;1,3=11,5=0
P 10.81161004 3.64115 6 P 0 0;1,3=11,5=0
P 10.86161004 3.64115 6 P 0 0;1,3=11,5=0
P 10.91161004 3.49115 6 P 0 0;1,3=11,5=0
P 10.86161004 3.49115 6 P 0 0;1,3=11,5=0
P 10.71161004 3.19115 6 P 0 0;1,3=11,5=0
P 10.71161004 3.34115 6 P 0 0;1,3=11,5=0
P 10.76161004 3.19115 6 P 0 0;1,3=11,5=0
P 10.81161004 3.19115 6 P 0 0;1,3=11,5=0
P 10.76161004 3.34115 6 P 0 0;1,3=11,5=0
P 10.81161004 3.34115 6 P 0 0;1,3=11,5=0
P 10.91161004 3.34115 6 P 0 0;1,3=11,5=0
P 10.86161004 3.34115 6 P 0 0;1,3=11,5=0
P 10.86161004 3.19115 6 P 0 0;1,3=11,5=0
P 10.91161004 3.19115 6 P 0 0;1,3=11,5=0
P 10.71161004 3.04115 6 P 0 0;1,3=11,5=0
P 10.76161004 3.04115 6 P 0 0;1,3=11,5=0
P 10.81161004 3.04115 6 P 0 0;1,3=11,5=0
P 10.86161004 3.04115 6 P 0 0;1,3=11,5=0
P 10.91161004 3.04115 6 P 0 0;1,3=11,5=0
P 10.91161004 2.89115 6 P 0 0;1,3=11,5=0
P 10.71161004 2.89115 6 P 0 0;1,3=11,5=0
P 10.76161004 2.89115 6 P 0 0;1,3=11,5=0
P 10.81161004 2.89115 6 P 0 0;1,3=11,5=0
P 10.86161004 2.89115 6 P 0 0;1,3=11,5=0
P 10.61161004 3.79115 6 P 0 0;1,3=11,5=0
P 10.66161004 3.64115 6 P 0 0;1,3=11,5=0
P 10.66161004 3.79115 6 P 0 0;1,3=11,5=0
P 10.61161004 3.49115 6 P 0 0;1,3=11,5=0
P 10.66161004 3.49115 6 P 0 0;1,3=11,5=0
P 10.61161004 3.64115 6 P 0 0;1,3=11,5=0
P 10.61161004 3.19115 6 P 0 0;1,3=11,5=0
P 10.66161004 3.19115 6 P 0 0;1,3=11,5=0
P 10.61161004 3.34115 6 P 0 0;1,3=11,5=0
P 10.66161004 3.34115 6 P 0 0;1,3=11,5=0
P 10.61161004 3.04115 6 P 0 0;1,3=11,5=0
P 10.66161004 3.04115 6 P 0 0;1,3=11,5=0
P 10.61161004 2.89115 6 P 0 0;1,3=11,5=0
P 10.66161004 2.89115 6 P 0 0;1,3=11,5=0
P 4.65768002 2.19115 6 P 0 0;1,3=11,5=0
P 4.80768002 2.79115 6 P 0 0;1,3=11,5=0
P 4.75768002 2.79115 6 P 0 0;1,3=11,5=0
P 4.65768002 2.79115 6 P 0 0;1,3=11,5=0
P 4.65768002 2.74115 6 P 0 0;1,3=11,5=0
P 4.75768002 2.74115 6 P 0 0;1,3=11,5=0
P 4.60768002 2.69115 6 P 0 0;1,3=11,5=0
P 4.70768002 2.69115 6 P 0 0;1,3=11,5=0
P 4.80768002 2.69115 6 P 0 0;1,3=11,5=0
P 4.80768002 2.64115 6 P 0 0;1,3=11,5=0
P 4.80768002 2.59115 6 P 0 0;1,3=11,5=0
P 4.75768002 2.59115 6 P 0 0;1,3=11,5=0
P 4.65768002 2.59115 6 P 0 0;1,3=11,5=0
P 4.60768002 2.54115 6 P 0 0;1,3=11,5=0
P 4.65768002 2.54115 6 P 0 0;1,3=11,5=0
P 4.70768002 2.54115 6 P 0 0;1,3=11,5=0
P 4.75768002 2.54115 6 P 0 0;1,3=11,5=0
P 4.80768002 2.54115 6 P 0 0;1,3=11,5=0
P 5.05768002 2.89115 6 P 0 0;1,3=11,5=0
P 4.95768002 2.89115 6 P 0 0;1,3=11,5=0
P 5.00768002 2.89115 6 P 0 0;1,3=11,5=0
P 4.90768002 2.89115 6 P 0 0;1,3=11,5=0
P 4.85768002 2.89115 6 P 0 0;1,3=11,5=0
P 5.05768002 3.04115 6 P 0 0;1,3=11,5=0
P 4.95768002 3.04115 6 P 0 0;1,3=11,5=0
P 5.00768002 3.04115 6 P 0 0;1,3=11,5=0
P 4.90768002 3.04115 6 P 0 0;1,3=11,5=0
P 4.85768002 3.04115 6 P 0 0;1,3=11,5=0
P 5.05768002 3.19115 6 P 0 0;1,3=11,5=0
P 4.95768002 3.19115 6 P 0 0;1,3=11,5=0
P 5.00768002 3.19115 6 P 0 0;1,3=11,5=0
P 4.90768002 3.19115 6 P 0 0;1,3=11,5=0
P 4.85768002 3.19115 6 P 0 0;1,3=11,5=0
P 5.00768002 3.34115 6 P 0 0;1,3=11,5=0
P 4.95768002 3.34115 6 P 0 0;1,3=11,5=0
P 5.05768002 3.34115 6 P 0 0;1,3=11,5=0
P 4.85768002 3.34115 6 P 0 0;1,3=11,5=0
P 4.90768002 3.34115 6 P 0 0;1,3=11,5=0
P 5.00768002 3.79115 6 P 0 0;1,3=11,5=0
P 4.95768002 3.79115 6 P 0 0;1,3=11,5=0
P 4.85768002 3.79115 6 P 0 0;1,3=11,5=0
P 4.90768002 3.79115 6 P 0 0;1,3=11,5=0
P 5.00768002 3.49115 6 P 0 0;1,3=11,5=0
P 4.95768002 3.49115 6 P 0 0;1,3=11,5=0
P 5.05768002 3.49115 6 P 0 0;1,3=11,5=0
P 4.85768002 3.49115 6 P 0 0;1,3=11,5=0
P 4.90768002 3.49115 6 P 0 0;1,3=11,5=0
P 5.00768002 3.64115 6 P 0 0;1,3=11,5=0
P 4.95768002 3.64115 6 P 0 0;1,3=11,5=0
P 5.05768002 3.64115 6 P 0 0;1,3=11,5=0
P 4.85768002 3.64115 6 P 0 0;1,3=11,5=0
P 4.90768002 3.64115 6 P 0 0;1,3=11,5=0
P 5.05768002 2.79115 6 P 0 0;1,3=11,5=0
P 5.08268002 2.76615 3 P 0 0;3=12,5=1
P 5.00768002 2.79115 6 P 0 0;1,3=11,5=0
P 5.03268002 2.76615 3 P 0 0;3=12,5=1
P 5.00768002 2.74115 6 P 0 0;1,3=11,5=0
P 5.03268002 2.71615 3 P 0 0;3=12,5=1
P 4.90768002 2.79115 6 P 0 0;1,3=11,5=0
P 4.93268002 2.76615 3 P 0 0;3=12,5=1
P 4.95768002 2.79115 6 P 0 0;1,3=11,5=0
P 4.98268002 2.76615 3 P 0 0;3=12,5=1
P 4.90768002 2.74115 6 P 0 0;1,3=11,5=0
P 4.93268002 2.71615 3 P 0 0;3=12,5=1
P 5.05768002 2.69115 6 P 0 0;1,3=11,5=0
P 5.08268002 2.66615 3 P 0 0;3=12,5=1
P 4.95768002 2.69115 6 P 0 0;1,3=11,5=0
P 4.98268002 2.66615 3 P 0 0;3=12,5=1
P 5.00768002 2.59115 6 P 0 0;1,3=11,5=0
P 5.03268002 2.56615 3 P 0 0;3=12,5=1
P 4.90768002 2.59115 6 P 0 0;1,3=11,5=0
P 4.93268002 2.56615 3 P 0 0;3=12,5=1
P 4.95768002 2.49115 6 P 0 0;1,3=11,5=0
P 4.98268002 2.46615 3 P 0 0;3=12,5=1
P 5.00768002 2.54115 6 P 0 0;1,3=11,5=0
P 4.95768002 2.54115 6 P 0 0;1,3=11,5=0
P 4.98268002 2.51615 3 P 0 0;3=12,5=1
P 4.90768002 2.54115 6 P 0 0;1,3=11,5=0
P 4.93268002 2.51615 3 P 0 0;3=12,5=1
P 5.05768002 2.54115 6 P 0 0;1,3=11,5=0
P 5.08268002 2.51615 3 P 0 0;3=12,5=1
P 5.05768002 2.49115 6 P 0 0;1,3=11,5=0
P 5.08268002 2.46615 3 P 0 0;3=12,5=1
P 5.00768002 2.24115 6 P 0 0;1,3=11,5=0
P 5.03268002 2.21615 3 P 0 0;3=12,5=1
P 4.90768002 2.24115 6 P 0 0;1,3=11,5=0
P 4.93268002 2.21615 3 P 0 0;3=12,5=1
P 4.95768002 2.34115 6 P 0 0;1,3=11,5=0
P 4.98268002 2.31615 3 P 0 0;3=12,5=1
P 4.90768002 2.39115 6 P 0 0;1,3=11,5=0
P 4.93268002 2.36615 3 P 0 0;3=12,5=1
P 5.05768002 2.34115 6 P 0 0;1,3=11,5=0
P 5.08268002 2.31615 3 P 0 0;3=12,5=1
P 5.05768002 2.19115 6 P 0 0;1,3=11,5=0
P 5.08268002 2.16615 3 P 0 0;3=12,5=1
P 4.90768002 2.19115 6 P 0 0;1,3=11,5=0
P 4.93268002 2.16615 3 P 0 0;3=12,5=1
P 4.95768002 2.19115 6 P 0 0;1,3=11,5=0
P 4.98268002 2.16615 3 P 0 0;3=12,5=1
P 4.90768002 1.99115 6 P 0 0;1,3=11,5=0
P 4.93268002 1.96615 3 P 0 0;3=12,5=1
P 5.00768002 1.99115 6 P 0 0;1,3=11,5=0
P 5.03268002 1.96615 3 P 0 0;3=12,5=1
P 5.00768002 2.14115 6 P 0 0;1,3=11,5=0
P 5.03268002 2.11615 3 P 0 0;3=12,5=1
P 4.90768002 2.14115 6 P 0 0;1,3=11,5=0
P 4.93268002 2.11615 3 P 0 0;3=12,5=1
P 4.95768002 2.04115 6 P 0 0;1,3=11,5=0
P 4.98268002 2.01615 3 P 0 0;3=12,5=1
P 5.05768002 2.04115 6 P 0 0;1,3=11,5=0
P 5.08268002 2.01615 3 P 0 0;3=12,5=1
P 4.95768002 1.89115 6 P 0 0;1,3=11,5=0
P 4.98268002 1.86615 3 P 0 0;3=12,5=1
P 5.05768002 1.89115 6 P 0 0;1,3=11,5=0
P 5.08268002 1.86615 3 P 0 0;3=12,5=1
P 4.80768002 3.79115 6 P 0 0;1,3=11,5=0
P 4.78268002 3.81615 3 P 0 0;3=12,5=1
P 4.80768002 3.64115 6 P 0 0;1,3=11,5=0
P 4.78268002 3.66615 3 P 0 0;3=12,5=1
P 4.75768002 3.79115 6 P 0 0;1,3=11,5=0
P 4.73268002 3.81615 3 P 0 0;3=12,5=1
P 4.75768002 3.64115 6 P 0 0;1,3=11,5=0
P 4.73268002 3.66615 3 P 0 0;3=12,5=1
P 4.70768002 3.79115 6 P 0 0;1,3=11,5=0
P 4.68268002 3.81615 3 P 0 0;3=12,5=1
P 4.70768002 3.64115 6 P 0 0;1,3=11,5=0
P 4.68268002 3.66615 3 P 0 0;3=12,5=1
P 4.80768002 3.49115 6 P 0 0;1,3=11,5=0
P 4.78268002 3.51615 3 P 0 0;3=12,5=1
P 4.75768002 3.49115 6 P 0 0;1,3=11,5=0
P 4.73268002 3.51615 3 P 0 0;3=12,5=1
P 4.70768002 3.49115 6 P 0 0;1,3=11,5=0
P 4.68268002 3.51615 3 P 0 0;3=12,5=1
P 4.80768002 3.34115 6 P 0 0;1,3=11,5=0
P 4.78268002 3.36615 3 P 0 0;3=12,5=1
P 4.75768002 3.34115 6 P 0 0;1,3=11,5=0
P 4.73268002 3.36615 3 P 0 0;3=12,5=1
P 4.80768002 3.19115 6 P 0 0;1,3=11,5=0
P 4.78268002 3.21615 3 P 0 0;3=12,5=1
P 4.75768002 3.19115 6 P 0 0;1,3=11,5=0
P 4.73268002 3.21615 3 P 0 0;3=12,5=1
P 4.70768002 3.34115 6 P 0 0;1,3=11,5=0
P 4.68268002 3.36615 3 P 0 0;3=12,5=1
P 4.70768002 3.19115 6 P 0 0;1,3=11,5=0
P 4.68268002 3.21615 3 P 0 0;3=12,5=1
P 4.80768002 3.04115 6 P 0 0;1,3=11,5=0
P 4.78268002 3.06615 3 P 0 0;3=12,5=1
P 4.75768002 3.04115 6 P 0 0;1,3=11,5=0
P 4.73268002 3.06615 3 P 0 0;3=12,5=1
P 4.70768002 3.04115 6 P 0 0;1,3=11,5=0
P 4.68268002 3.06615 3 P 0 0;3=12,5=1
P 4.80768002 2.89115 6 P 0 0;1,3=11,5=0
P 4.78268002 2.91615 3 P 0 0;3=12,5=1
P 4.75768002 2.89115 6 P 0 0;1,3=11,5=0
P 4.73268002 2.91615 3 P 0 0;3=12,5=1
P 4.70768002 2.89115 6 P 0 0;1,3=11,5=0
P 4.68268002 2.91615 3 P 0 0;3=12,5=1
P 4.85768002 2.79115 6 P 0 0;1,3=11,5=0
P 4.88268002 2.76615 3 P 0 0;3=12,5=1
P 4.85768002 2.69115 6 P 0 0;1,3=11,5=0
P 4.88268002 2.66615 3 P 0 0;3=12,5=1
P 4.80768002 2.49115 6 P 0 0;1,3=11,5=0
P 4.78268002 2.46615 3 P 0 0;3=12,5=1
P 4.85768002 2.59115 6 P 0 0;1,3=11,5=0
P 4.88268002 2.56615 3 P 0 0;3=12,5=1
P 4.85768002 2.64115 6 P 0 0;1,3=11,5=0
P 4.88268002 2.61615 3 P 0 0;3=12,5=1
P 4.70768002 2.49115 6 P 0 0;1,3=11,5=0
P 4.68268002 2.46615 3 P 0 0;3=12,5=1
P 4.85768002 2.49115 6 P 0 0;1,3=11,5=0
P 4.88268002 2.46615 3 P 0 0;3=12,5=1
P 4.85768002 2.54115 6 P 0 0;1,3=11,5=0
P 4.88268002 2.51615 3 P 0 0;3=12,5=1
P 4.80768002 2.44115 6 P 0 0;1,3=11,5=0
P 4.78268002 2.41615 3 P 0 0;3=12,5=1
P 4.85768002 2.44115 6 P 0 0;1,3=11,5=0
P 4.88268002 2.41615 3 P 0 0;3=12,5=1
P 4.80768002 2.39115 6 P 0 0;1,3=11,5=0
P 4.78268002 2.36615 3 P 0 0;3=12,5=1
P 4.80768002 2.34115 6 P 0 0;1,3=11,5=0
P 4.78268002 2.31615 3 P 0 0;3=12,5=1
P 4.80768002 2.29115 6 P 0 0;1,3=11,5=0
P 4.78268002 2.26615 3 P 0 0;3=12,5=1
P 4.80768002 2.24115 6 P 0 0;1,3=11,5=0
P 4.78268002 2.21615 3 P 0 0;3=12,5=1
P 4.75768002 2.39115 6 P 0 0;1,3=11,5=0
P 4.73268002 2.36615 3 P 0 0;3=12,5=1
P 4.70768002 2.34115 6 P 0 0;1,3=11,5=0
P 4.68268002 2.31615 3 P 0 0;3=12,5=1
P 4.75768002 2.24115 6 P 0 0;1,3=11,5=0
P 4.73268002 2.21615 3 P 0 0;3=12,5=1
P 4.85768002 2.24115 6 P 0 0;1,3=11,5=0
P 4.88268002 2.21615 3 P 0 0;3=12,5=1
P 4.85768002 2.29115 6 P 0 0;1,3=11,5=0
P 4.88268002 2.26615 3 P 0 0;3=12,5=1
P 4.85768002 2.34115 6 P 0 0;1,3=11,5=0
P 4.88268002 2.31615 3 P 0 0;3=12,5=1
P 4.85768002 2.39115 6 P 0 0;1,3=11,5=0
P 4.88268002 2.36615 3 P 0 0;3=12,5=1
P 4.75768002 2.19115 6 P 0 0;1,3=11,5=0
P 4.73268002 2.16615 3 P 0 0;3=12,5=1
P 4.70768002 2.19115 6 P 0 0;1,3=11,5=0
P 4.68268002 2.16615 3 P 0 0;3=12,5=1
P 4.80768002 1.99115 6 P 0 0;1,3=11,5=0
P 4.78268002 1.96615 3 P 0 0;3=12,5=1
P 4.80768002 2.09115 6 P 0 0;1,3=11,5=0
P 4.78268002 2.06615 3 P 0 0;3=12,5=1
P 4.80768002 2.04115 6 P 0 0;1,3=11,5=0
P 4.78268002 2.01615 3 P 0 0;3=12,5=1
P 4.85768002 1.99115 6 P 0 0;1,3=11,5=0
P 4.88268002 1.96615 3 P 0 0;3=12,5=1
P 4.85768002 2.09115 6 P 0 0;1,3=11,5=0
P 4.88268002 2.06615 3 P 0 0;3=12,5=1
P 4.85768002 2.04115 6 P 0 0;1,3=11,5=0
P 4.88268002 2.01615 3 P 0 0;3=12,5=1
P 4.80768002 2.14115 6 P 0 0;1,3=11,5=0
P 4.78268002 2.11615 3 P 0 0;3=12,5=1
P 4.85768002 2.14115 6 P 0 0;1,3=11,5=0
P 4.88268002 2.11615 3 P 0 0;3=12,5=1
P 4.75768002 2.14115 6 P 0 0;1,3=11,5=0
P 4.73268002 2.11615 3 P 0 0;3=12,5=1
P 4.70768002 2.04115 6 P 0 0;1,3=11,5=0
P 4.68268002 2.01615 3 P 0 0;3=12,5=1
P 4.75768002 1.99115 6 P 0 0;1,3=11,5=0
P 4.73268002 1.96615 3 P 0 0;3=12,5=1
P 4.80768002 1.89115 6 P 0 0;1,3=11,5=0
P 4.78268002 1.86615 3 P 0 0;3=12,5=1
P 4.80768002 1.94115 6 P 0 0;1,3=11,5=0
P 4.85768002 1.89115 6 P 0 0;1,3=11,5=0
P 4.88268002 1.86615 3 P 0 0;3=12,5=1
P 4.85768002 1.94115 6 P 0 0;1,3=11,5=0
P 4.70768002 1.89115 6 P 0 0;1,3=11,5=0
P 4.68268002 1.86615 3 P 0 0;3=12,5=1
P 4.65768002 3.79115 6 P 0 0;1,3=11,5=0
P 4.63268002 3.81615 3 P 0 0;3=12,5=1
P 4.65768002 3.64115 6 P 0 0;1,3=11,5=0
P 4.63268002 3.66615 3 P 0 0;3=12,5=1
P 4.60768002 3.79115 6 P 0 0;1,3=11,5=0
P 4.58268002 3.81615 3 P 0 0;3=12,5=1
P 4.60768002 3.64115 6 P 0 0;1,3=11,5=0
P 4.58268002 3.66615 3 P 0 0;3=12,5=1
P 4.65768002 3.49115 6 P 0 0;1,3=11,5=0
P 4.63268002 3.51615 3 P 0 0;3=12,5=1
P 4.60768002 3.49115 6 P 0 0;1,3=11,5=0
P 4.58268002 3.51615 3 P 0 0;3=12,5=1
P 4.65768002 3.34115 6 P 0 0;1,3=11,5=0
P 4.63268002 3.36615 3 P 0 0;3=12,5=1
P 4.60768002 3.34115 6 P 0 0;1,3=11,5=0
P 4.58268002 3.36615 3 P 0 0;3=12,5=1
P 4.65768002 3.19115 6 P 0 0;1,3=11,5=0
P 4.63268002 3.21615 3 P 0 0;3=12,5=1
P 4.60768002 3.19115 6 P 0 0;1,3=11,5=0
P 4.58268002 3.21615 3 P 0 0;3=12,5=1
P 4.65768002 3.04115 6 P 0 0;1,3=11,5=0
P 4.63268002 3.06615 3 P 0 0;3=12,5=1
P 4.60768002 3.04115 6 P 0 0;1,3=11,5=0
P 4.58268002 3.06615 3 P 0 0;3=12,5=1
P 4.65768002 2.89115 6 P 0 0;1,3=11,5=0
P 4.63268002 2.91615 3 P 0 0;3=12,5=1
P 4.60768002 2.89115 6 P 0 0;1,3=11,5=0
P 4.58268002 2.91615 3 P 0 0;3=12,5=1
P 4.60768002 2.49115 6 P 0 0;1,3=11,5=0
P 4.58268002 2.46615 3 P 0 0;3=12,5=1
P 4.60768002 2.19115 6 P 0 0;1,3=11,5=0
P 4.65768002 2.24115 6 P 0 0;1,3=11,5=0
P 4.63268002 2.21615 3 P 0 0;3=12,5=1
P 4.60768002 2.34115 6 P 0 0;1,3=11,5=0
P 4.58268002 2.31615 3 P 0 0;3=12,5=1
P 4.65768002 2.39115 6 P 0 0;1,3=11,5=0
P 4.63268002 2.36615 3 P 0 0;3=12,5=1
P 4.60768002 2.04115 6 P 0 0;1,3=11,5=0
P 4.58268002 2.01615 3 P 0 0;3=12,5=1
P 4.65768002 2.14115 6 P 0 0;1,3=11,5=0
P 4.63268002 2.11615 3 P 0 0;3=12,5=1
P 4.65768002 1.99115 6 P 0 0;1,3=11,5=0
P 4.63268002 1.96615 3 P 0 0;3=12,5=1
P 4.60768002 1.89115 6 P 0 0;1,3=11,5=0
P 4.58268002 1.86615 3 P 0 0;3=12,5=1
P 2.12106004 2.29115 6 P 0 0;1,3=11,5=0
P 2.07106004 2.34115 6 P 0 0;1,3=11,5=0
P 2.07106004 2.19115 6 P 0 0;1,3=11,5=0
P 2.12106004 2.14115 6 P 0 0;1,3=11,5=0
P 2.17106004 2.19115 6 P 0 0;1,3=11,5=0
P 2.22106004 2.24115 6 P 0 0;1,3=11,5=0
P 2.27106004 2.24115 6 P 0 0;1,3=11,5=0
P 2.22106004 2.19115 6 P 0 0;1,3=11,5=0
P 2.22106004 2.09115 6 P 0 0;1,3=11,5=0
P 2.22106004 2.14115 6 P 0 0;1,3=11,5=0
P 2.27106004 2.14115 6 P 0 0;1,3=11,5=0
P 2.27106004 2.09115 6 P 0 0;1,3=11,5=0
P 2.27106004 2.19115 6 P 0 0;1,3=11,5=0
P 2.32106004 2.19115 6 P 0 0;1,3=11,5=0
P 2.37106004 2.14115 6 P 0 0;1,3=11,5=0
P 2.42106004 2.19115 6 P 0 0;1,3=11,5=0
P 2.47106004 2.14115 6 P 0 0;1,3=11,5=0
P 2.42106004 1.89115 6 P 0 0;1,3=11,5=0
P 2.47106004 1.99115 6 P 0 0;1,3=11,5=0
P 2.42106004 2.04115 6 P 0 0;1,3=11,5=0
P 2.37106004 1.99115 6 P 0 0;1,3=11,5=0
P 2.32106004 2.04115 6 P 0 0;1,3=11,5=0
P 2.27106004 2.04115 6 P 0 0;1,3=11,5=0
P 2.22106004 2.04115 6 P 0 0;1,3=11,5=0
P 2.17106004 2.04115 6 P 0 0;1,3=11,5=0
P 2.27106004 1.99115 6 P 0 0;1,3=11,5=0
P 2.22106004 1.99115 6 P 0 0;1,3=11,5=0
P 2.27106004 1.94115 6 P 0 0;1,3=11,5=0
P 2.22106004 1.94115 6 P 0 0;1,3=11,5=0
P 2.32106004 1.89115 6 P 0 0;1,3=11,5=0
P 2.27106004 1.89115 6 P 0 0;1,3=11,5=0
P 2.22106004 1.89115 6 P 0 0;1,3=11,5=0
P 2.17106004 1.89115 6 P 0 0;1,3=11,5=0
P 2.07106004 1.89115 6 P 0 0;1,3=11,5=0
P 2.12106004 1.99115 6 P 0 0;1,3=11,5=0
P 2.07106004 2.04115 6 P 0 0;1,3=11,5=0
P 2.02106004 1.99115 6 P 0 0;1,3=11,5=0
P 2.02106004 2.14115 6 P 0 0;1,3=11,5=0
P 2.02106004 2.29115 6 P 0 0;1,3=11,5=0
P 2.22106004 2.29115 6 P 0 0;1,3=11,5=0
P 2.27106004 2.29115 6 P 0 0;1,3=11,5=0
P 2.32106004 2.34115 6 P 0 0;1,3=11,5=0
P 2.37106004 2.29115 6 P 0 0;1,3=11,5=0
P 2.47106004 2.29115 6 P 0 0;1,3=11,5=0
P 2.42106004 2.34115 6 P 0 0;1,3=11,5=0
P 2.47106004 2.44115 6 P 0 0;1,3=11,5=0
P 2.47106004 2.49115 6 P 0 0;1,3=11,5=0
P 2.47106004 2.54115 6 P 0 0;1,3=11,5=0
P 2.42106004 2.49115 6 P 0 0;1,3=11,5=0
P 2.37106004 2.54115 6 P 0 0;1,3=11,5=0
P 2.37106004 2.49115 6 P 0 0;1,3=11,5=0
P 2.37106004 2.44115 6 P 0 0;1,3=11,5=0
P 2.27106004 2.34115 6 P 0 0;1,3=11,5=0
P 2.17106004 2.34115 6 P 0 0;1,3=11,5=0
P 2.22106004 2.34115 6 P 0 0;1,3=11,5=0
P 2.22106004 2.39115 6 P 0 0;1,3=11,5=0
P 2.27106004 2.39115 6 P 0 0;1,3=11,5=0
P 2.27106004 2.44115 6 P 0 0;1,3=11,5=0
P 2.22106004 2.44115 6 P 0 0;1,3=11,5=0
P 2.12106004 2.44115 6 P 0 0;1,3=11,5=0
P 2.17106004 2.49115 6 P 0 0;1,3=11,5=0
P 2.22106004 2.49115 6 P 0 0;1,3=11,5=0
P 2.27106004 2.49115 6 P 0 0;1,3=11,5=0
P 2.32106004 2.49115 6 P 0 0;1,3=11,5=0
P 2.27106004 2.54115 6 P 0 0;1,3=11,5=0
P 2.27106004 2.59115 6 P 0 0;1,3=11,5=0
P 2.22106004 2.54115 6 P 0 0;1,3=11,5=0
P 2.22106004 2.59115 6 P 0 0;1,3=11,5=0
P 2.12106004 2.54115 6 P 0 0;1,3=11,5=0
P 2.07106004 2.49115 6 P 0 0;1,3=11,5=0
P 2.02106004 2.44115 6 P 0 0;1,3=11,5=0
P 2.02106004 2.49115 6 P 0 0;1,3=11,5=0
P 2.02106004 2.54115 6 P 0 0;1,3=11,5=0
P 2.02106004 2.69115 6 P 0 0;1,3=11,5=0
P 2.07106004 2.64115 6 P 0 0;1,3=11,5=0
P 2.12106004 2.69115 6 P 0 0;1,3=11,5=0
P 2.17106004 2.64115 6 P 0 0;1,3=11,5=0
P 2.22106004 2.64115 6 P 0 0;1,3=11,5=0
P 2.22106004 2.69115 6 P 0 0;1,3=11,5=0
P 2.27106004 2.64115 6 P 0 0;1,3=11,5=0
P 2.27106004 2.69115 6 P 0 0;1,3=11,5=0
P 2.32106004 2.64115 6 P 0 0;1,3=11,5=0
P 2.37106004 2.69115 6 P 0 0;1,3=11,5=0
P 2.42106004 2.64115 6 P 0 0;1,3=11,5=0
P 2.47106004 2.69115 6 P 0 0;1,3=11,5=0
P 2.47106004 2.84115 6 P 0 0;1,3=11,5=0
P 2.42106004 2.79115 6 P 0 0;1,3=11,5=0
P 2.32106004 2.79115 6 P 0 0;1,3=11,5=0
P 2.37106004 2.84115 6 P 0 0;1,3=11,5=0
P 2.42106004 2.84115 6 P 0 0;1,3=11,5=0
P 2.42106004 2.89115 6 P 0 0;1,3=11,5=0
P 2.47106004 2.99115 6 P 0 0;1,3=11,5=0
P 2.42106004 3.04115 6 P 0 0;1,3=11,5=0
P 2.32106004 3.04115 6 P 0 0;1,3=11,5=0
P 2.37106004 2.99115 6 P 0 0;1,3=11,5=0
P 2.27106004 2.89115 6 P 0 0;1,3=11,5=0
P 2.22106004 2.89115 6 P 0 0;1,3=11,5=0
P 2.17106004 2.89115 6 P 0 0;1,3=11,5=0
P 2.02106004 2.84115 6 P 0 0;1,3=11,5=0
P 2.12106004 2.84115 6 P 0 0;1,3=11,5=0
P 2.07106004 2.89115 6 P 0 0;1,3=11,5=0
P 2.02106004 2.99115 6 P 0 0;1,3=11,5=0
P 2.07106004 3.04115 6 P 0 0;1,3=11,5=0
P 2.12106004 2.99115 6 P 0 0;1,3=11,5=0
P 2.17106004 3.04115 6 P 0 0;1,3=11,5=0
P 2.07106004 2.84115 6 P 0 0;1,3=11,5=0
P 2.07106004 2.79115 6 P 0 0;1,3=11,5=0
P 2.17106004 2.79115 6 P 0 0;1,3=11,5=0
P 2.22106004 2.79115 6 P 0 0;1,3=11,5=0
P 2.22106004 2.74115 6 P 0 0;1,3=11,5=0
P 2.27106004 2.79115 6 P 0 0;1,3=11,5=0
P 2.27106004 2.74115 6 P 0 0;1,3=11,5=0
P 2.32106004 2.89115 6 P 0 0;1,3=11,5=0
P 2.32106004 2.84115 6 P 0 0;1,3=11,5=0
P 2.22106004 2.99115 6 P 0 0;1,3=11,5=0
P 2.22106004 2.94115 6 P 0 0;1,3=11,5=0
P 2.22106004 3.09115 6 P 0 0;1,3=11,5=0
P 2.22106004 3.04115 6 P 0 0;1,3=11,5=0
P 2.27106004 2.99115 6 P 0 0;1,3=11,5=0
P 2.27106004 2.94115 6 P 0 0;1,3=11,5=0
P 2.27106004 3.09115 6 P 0 0;1,3=11,5=0
P 2.27106004 3.04115 6 P 0 0;1,3=11,5=0
P 2.04606004 3.41615 3 P 0 0;3=12,5=1
P 2.02106004 3.39115 6 P 0 0;1,3=11,5=0
P 2.09606004 3.51615 3 P 0 0;3=12,5=1
P 2.07106004 3.49115 6 P 0 0;1,3=11,5=0
P 2.12106004 3.14115 6 P 0 0;1,3=11,5=0
P 2.02106004 3.14115 6 P 0 0;1,3=11,5=0
P 3.37003996 5.18128002 4 P 0 0;3=13,5=1
P 3.43003996 5.18128002 4 P 0 0;3=13,5=1
P 3.29916998 5.14223996 4 P 0 0;3=13,5=1
P 3.35916998 5.14223996 4 P 0 0;3=13,5=1
P 2.93708002 4.70573996 4 P 0 0;3=13,5=1
P 3.07571004 4.70573996 4 P 0 0;3=13,5=1
P 3.01571004 4.70573996 4 P 0 0;3=13,5=1
P 2.87708002 4.70573996 4 P 0 0;3=13,5=1
P 2.93086998 5.20876004 4 P 0 0;3=13,5=1
P 2.87086998 5.20876004 4 P 0 0;3=13,5=1
P 2.80311004 4.74418002 4 P 0 0;3=13,5=1
P 2.86311004 4.74418002 4 P 0 0;3=13,5=1
P 3.08656998 5.09223996 4 P 0 0;3=13,5=1
P 3.14656998 5.09223996 4 P 0 0;3=13,5=1
P 2.26855 4.62826004 4 P 0 0;3=13,5=1
P 2.20855 4.62826004 4 P 0 0;3=13,5=1
P 2.26543996 4.74418002 4 P 0 0;3=13,5=1
P 2.20543996 4.74418002 4 P 0 0;3=13,5=1
P 2.34716998 4.70326004 4 P 0 0;3=13,5=1
P 2.07853002 4.62815 4 P 0 0;3=13,5=1
P 2.01853002 4.62815 4 P 0 0;3=13,5=1
P 2.12371004 4.74418002 4 P 0 0;3=13,5=1
P 2.06371004 4.74418002 4 P 0 0;3=13,5=1
P 2.19456998 5.09223996 4 P 0 0;3=13,5=1
P 2.13456998 5.09223996 4 P 0 0;3=13,5=1
P 2.12371004 5.13026004 4 P 0 0;3=13,5=1
P 2.06371004 5.13026004 4 P 0 0;3=13,5=1
P 1.6985 5.09223996 4 P 0 0;3=13,5=1
P 1.6385 5.09223996 4 P 0 0;3=13,5=1
P 1.85111004 4.61826004 4 P 0 0;3=13,5=1
P 1.63851004 4.74418002 4 P 0 0;3=13,5=1
P 1.69851004 4.74418002 4 P 0 0;3=13,5=1
P 1.98196998 5.09223996 4 P 0 0;3=13,5=1
P 1.92196998 5.09223996 4 P 0 0;3=13,5=1
P 1.84025 4.74418002 4 P 0 0;3=13,5=1
P 1.78025 4.74418002 4 P 0 0;3=13,5=1
P 11.01161004 2.74115 6 P 0 0;1,3=11,5=0
P 11.03661004 2.71615 3 P 0 0;3=12,5=1
P 10.91161004 2.74115 6 P 0 0;1,3=11,5=0
P 10.93661004 2.71615 3 P 0 0;3=12,5=1
P 11.01161004 2.79115 6 P 0 0;1,3=11,5=0
P 11.03661004 2.76615 3 P 0 0;3=12,5=1
P 10.96161004 2.79115 6 P 0 0;1,3=11,5=0
P 10.98661004 2.76615 3 P 0 0;3=12,5=1
P 10.91161004 2.79115 6 P 0 0;1,3=11,5=0
P 10.93661004 2.76615 3 P 0 0;3=12,5=1
P 11.06161004 2.79115 6 P 0 0;1,3=11,5=0
P 11.08661004 2.76615 3 P 0 0;3=12,5=1
P 11.01161004 2.54115 6 P 0 0;1,3=11,5=0
P 11.01161004 2.59115 6 P 0 0;1,3=11,5=0
P 11.03661004 2.56615 3 P 0 0;3=12,5=1
P 10.91161004 2.59115 6 P 0 0;1,3=11,5=0
P 10.93661004 2.56615 3 P 0 0;3=12,5=1
P 10.96161004 2.69115 6 P 0 0;1,3=11,5=0
P 10.98661004 2.66615 3 P 0 0;3=12,5=1
P 10.96161004 2.54115 6 P 0 0;1,3=11,5=0
P 10.98661004 2.51615 3 P 0 0;3=12,5=1
P 10.91161004 2.54115 6 P 0 0;1,3=11,5=0
P 10.93661004 2.51615 3 P 0 0;3=12,5=1
P 11.06161004 2.69115 6 P 0 0;1,3=11,5=0
P 11.08661004 2.66615 3 P 0 0;3=12,5=1
P 11.06161004 2.54115 6 P 0 0;1,3=11,5=0
P 11.08661004 2.51615 3 P 0 0;3=12,5=1
P 11.06161004 2.49115 6 P 0 0;1,3=11,5=0
P 11.08661004 2.46615 3 P 0 0;3=12,5=1
P 10.96161004 2.49115 6 P 0 0;1,3=11,5=0
P 10.98661004 2.46615 3 P 0 0;3=12,5=1
P 11.06161004 2.34115 6 P 0 0;1,3=11,5=0
P 11.08661004 2.31615 3 P 0 0;3=12,5=1
P 10.91161004 2.39115 6 P 0 0;1,3=11,5=0
P 10.93661004 2.36615 3 P 0 0;3=12,5=1
P 10.96161004 2.34115 6 P 0 0;1,3=11,5=0
P 10.98661004 2.31615 3 P 0 0;3=12,5=1
P 10.91161004 2.24115 6 P 0 0;1,3=11,5=0
P 10.93661004 2.21615 3 P 0 0;3=12,5=1
P 11.01161004 2.24115 6 P 0 0;1,3=11,5=0
P 11.03661004 2.21615 3 P 0 0;3=12,5=1
P 11.01161004 2.14115 6 P 0 0;1,3=11,5=0
P 11.03661004 2.11615 3 P 0 0;3=12,5=1
P 10.91161004 2.14115 6 P 0 0;1,3=11,5=0
P 10.93661004 2.11615 3 P 0 0;3=12,5=1
P 10.96161004 2.04115 6 P 0 0;1,3=11,5=0
P 10.98661004 2.01615 3 P 0 0;3=12,5=1
P 10.91161004 1.99115 6 P 0 0;1,3=11,5=0
P 10.93661004 1.96615 3 P 0 0;3=12,5=1
P 11.01161004 1.99115 6 P 0 0;1,3=11,5=0
P 11.03661004 1.96615 3 P 0 0;3=12,5=1
P 11.06161004 2.04115 6 P 0 0;1,3=11,5=0
P 11.08661004 2.01615 3 P 0 0;3=12,5=1
P 10.96161004 2.19115 6 P 0 0;1,3=11,5=0
P 10.98661004 2.16615 3 P 0 0;3=12,5=1
P 10.91161004 2.19115 6 P 0 0;1,3=11,5=0
P 10.93661004 2.16615 3 P 0 0;3=12,5=1
P 11.06161004 2.19115 6 P 0 0;1,3=11,5=0
P 11.08661004 2.16615 3 P 0 0;3=12,5=1
P 10.96161004 1.89115 6 P 0 0;1,3=11,5=0
P 10.98661004 1.86615 3 P 0 0;3=12,5=1
P 11.06161004 1.89115 6 P 0 0;1,3=11,5=0
P 11.08661004 1.86615 3 P 0 0;3=12,5=1
P 10.76161004 2.74115 6 P 0 0;1,3=11,5=0
P 10.73661004 2.71615 3 P 0 0;3=12,5=1
P 10.76161004 2.79115 6 P 0 0;1,3=11,5=0
P 10.73661004 2.76615 3 P 0 0;3=12,5=1
P 10.86161004 2.79115 6 P 0 0;1,3=11,5=0
P 10.88661004 2.76615 3 P 0 0;3=12,5=1
P 10.81161004 2.79115 6 P 0 0;1,3=11,5=0
P 10.78661004 2.76615 3 P 0 0;3=12,5=1
P 10.76161004 2.59115 6 P 0 0;1,3=11,5=0
P 10.73661004 2.56615 3 P 0 0;3=12,5=1
P 10.71161004 2.69115 6 P 0 0;1,3=11,5=0
P 10.68661004 2.66615 3 P 0 0;3=12,5=1
P 10.76161004 2.54115 6 P 0 0;1,3=11,5=0
P 10.73661004 2.51615 3 P 0 0;3=12,5=1
P 10.71161004 2.54115 6 P 0 0;1,3=11,5=0
P 10.68661004 2.51615 3 P 0 0;3=12,5=1
P 10.86161004 2.64115 6 P 0 0;1,3=11,5=0
P 10.88661004 2.61615 3 P 0 0;3=12,5=1
P 10.86161004 2.69115 6 P 0 0;1,3=11,5=0
P 10.86161004 2.59115 6 P 0 0;1,3=11,5=0
P 10.88661004 2.56615 3 P 0 0;3=12,5=1
P 10.86161004 2.54115 6 P 0 0;1,3=11,5=0
P 10.88661004 2.51615 3 P 0 0;3=12,5=1
P 10.81161004 2.59115 6 P 0 0;1,3=11,5=0
P 10.78661004 2.56615 3 P 0 0;3=12,5=1
P 10.81161004 2.64115 6 P 0 0;1,3=11,5=0
P 10.78661004 2.61615 3 P 0 0;3=12,5=1
P 10.81161004 2.69115 6 P 0 0;1,3=11,5=0
P 10.78661004 2.66615 3 P 0 0;3=12,5=1
P 10.81161004 2.54115 6 P 0 0;1,3=11,5=0
P 10.78661004 2.51615 3 P 0 0;3=12,5=1
P 10.81161004 2.49115 6 P 0 0;1,3=11,5=0
P 10.78661004 2.46615 3 P 0 0;3=12,5=1
P 10.71161004 2.49115 6 P 0 0;1,3=11,5=0
P 10.68661004 2.46615 3 P 0 0;3=12,5=1
P 10.86161004 2.49115 6 P 0 0;1,3=11,5=0
P 10.88661004 2.46615 3 P 0 0;3=12,5=1
P 10.81161004 2.24115 6 P 0 0;1,3=11,5=0
P 10.78661004 2.21615 3 P 0 0;3=12,5=1
P 10.81161004 2.29115 6 P 0 0;1,3=11,5=0
P 10.78661004 2.26615 3 P 0 0;3=12,5=1
P 10.81161004 2.34115 6 P 0 0;1,3=11,5=0
P 10.78661004 2.31615 3 P 0 0;3=12,5=1
P 10.81161004 2.39115 6 P 0 0;1,3=11,5=0
P 10.78661004 2.36615 3 P 0 0;3=12,5=1
P 10.71161004 2.34115 6 P 0 0;1,3=11,5=0
P 10.68661004 2.31615 3 P 0 0;3=12,5=1
P 10.76161004 2.39115 6 P 0 0;1,3=11,5=0
P 10.73661004 2.36615 3 P 0 0;3=12,5=1
P 10.76161004 2.24115 6 P 0 0;1,3=11,5=0
P 10.73661004 2.21615 3 P 0 0;3=12,5=1
P 10.81161004 2.44115 6 P 0 0;1,3=11,5=0
P 10.78661004 2.41615 3 P 0 0;3=12,5=1
P 10.86161004 2.44115 6 P 0 0;1,3=11,5=0
P 10.86161004 2.39115 6 P 0 0;1,3=11,5=0
P 10.88661004 2.36615 3 P 0 0;3=12,5=1
P 10.86161004 2.34115 6 P 0 0;1,3=11,5=0
P 10.88661004 2.31615 3 P 0 0;3=12,5=1
P 10.86161004 2.29115 6 P 0 0;1,3=11,5=0
P 10.88661004 2.26615 3 P 0 0;3=12,5=1
P 10.86161004 2.24115 6 P 0 0;1,3=11,5=0
P 10.88661004 2.21615 3 P 0 0;3=12,5=1
P 10.76161004 1.99115 6 P 0 0;1,3=11,5=0
P 10.73661004 1.96615 3 P 0 0;3=12,5=1
P 10.71161004 2.04115 6 P 0 0;1,3=11,5=0
P 10.68661004 2.01615 3 P 0 0;3=12,5=1
P 10.76161004 2.14115 6 P 0 0;1,3=11,5=0
P 10.73661004 2.11615 3 P 0 0;3=12,5=1
P 10.81161004 2.14115 6 P 0 0;1,3=11,5=0
P 10.78661004 2.11615 3 P 0 0;3=12,5=1
P 10.81161004 2.04115 6 P 0 0;1,3=11,5=0
P 10.78661004 2.01615 3 P 0 0;3=12,5=1
P 10.81161004 1.99115 6 P 0 0;1,3=11,5=0
P 10.78661004 1.96615 3 P 0 0;3=12,5=1
P 10.81161004 2.09115 6 P 0 0;1,3=11,5=0
P 10.78661004 2.06615 3 P 0 0;3=12,5=1
P 10.71161004 2.19115 6 P 0 0;1,3=11,5=0
P 10.68661004 2.16615 3 P 0 0;3=12,5=1
P 10.76161004 2.19115 6 P 0 0;1,3=11,5=0
P 10.73661004 2.16615 3 P 0 0;3=12,5=1
P 10.86161004 2.04115 6 P 0 0;1,3=11,5=0
P 10.88661004 2.01615 3 P 0 0;3=12,5=1
P 10.86161004 2.09115 6 P 0 0;1,3=11,5=0
P 10.88661004 2.06615 3 P 0 0;3=12,5=1
P 10.86161004 2.14115 6 P 0 0;1,3=11,5=0
P 10.88661004 2.11615 3 P 0 0;3=12,5=1
P 10.86161004 1.99115 6 P 0 0;1,3=11,5=0
P 10.88661004 1.96615 3 P 0 0;3=12,5=1
P 10.81161004 1.94115 6 P 0 0;1,3=11,5=0
P 10.78661004 1.91615 3 P 0 0;3=12,5=1
P 10.71161004 1.89115 6 P 0 0;1,3=11,5=0
P 10.68661004 1.86615 3 P 0 0;3=12,5=1
P 10.81161004 1.89115 6 P 0 0;1,3=11,5=0
P 10.78661004 1.86615 3 P 0 0;3=12,5=1
P 10.86161004 1.89115 6 P 0 0;1,3=11,5=0
P 10.88661004 1.86615 3 P 0 0;3=12,5=1
P 10.86161004 1.94115 6 P 0 0;1,3=11,5=0
P 10.66161004 2.74115 6 P 0 0;1,3=11,5=0
P 10.63661004 2.71615 3 P 0 0;3=12,5=1
P 10.66161004 2.79115 6 P 0 0;1,3=11,5=0
P 10.63661004 2.76615 3 P 0 0;3=12,5=1
P 10.66161004 2.59115 6 P 0 0;1,3=11,5=0
P 10.63661004 2.56615 3 P 0 0;3=12,5=1
P 10.61161004 2.69115 6 P 0 0;1,3=11,5=0
P 10.58661004 2.66615 3 P 0 0;3=12,5=1
P 10.66161004 2.54115 6 P 0 0;1,3=11,5=0
P 10.63661004 2.51615 3 P 0 0;3=12,5=1
P 10.61161004 2.54115 6 P 0 0;1,3=11,5=0
P 10.58661004 2.51615 3 P 0 0;3=12,5=1
P 10.61161004 2.49115 6 P 0 0;1,3=11,5=0
P 10.58661004 2.46615 3 P 0 0;3=12,5=1
P 10.66161004 2.39115 6 P 0 0;1,3=11,5=0
P 10.63661004 2.36615 3 P 0 0;3=12,5=1
P 10.61161004 2.34115 6 P 0 0;1,3=11,5=0
P 10.58661004 2.31615 3 P 0 0;3=12,5=1
P 10.61161004 2.04115 6 P 0 0;1,3=11,5=0
P 10.58661004 2.01615 3 P 0 0;3=12,5=1
P 10.66161004 1.99115 6 P 0 0;1,3=11,5=0
P 10.63661004 1.96615 3 P 0 0;3=12,5=1
P 10.66161004 2.14115 6 P 0 0;1,3=11,5=0
P 10.63661004 2.11615 3 P 0 0;3=12,5=1
P 10.66161004 2.19115 6 P 0 0;1,3=11,5=0
P 10.61161004 1.89115 6 P 0 0;1,3=11,5=0
P 10.58661004 1.86615 3 P 0 0;3=12,5=1
P 1.92346004 5.377 4 P 0 0;3=13,5=1
P 2.14346004 5.377 4 P 0 0;3=13,5=1
P 7.927 5.377 4 P 0 0;3=13,5=1
P 8.147 5.377 4 P 0 0;3=13,5=1
P 3.43003996 4.74418002 4 P 0 0;3=13,5=1
P 3.51176998 4.68098996 4 P 0 0;3=13,5=1
P 3.57176998 4.68098996 4 P 0 0;3=13,5=1
P 3.21743996 4.74418002 4 P 0 0;3=13,5=1
P 3.37003996 4.74418002 4 P 0 0;3=13,5=1
P 3.41 5.332 4 P 0 0;3=13,5=1
P 5.38048002 1.5957 4 P 0 0;3=13,5=1
P 5.38048002 1.7891 4 P 0 0;3=13,5=1
P 5.38048002 1.732 4 P 0 0;3=13,5=1
P 5.38048002 1.6528 4 P 0 0;3=13,5=1
P 5.53531004 1.8603 4 P 0 0;3=13,5=1
P 5.53531004 1.8032 4 P 0 0;3=13,5=1
P 5.53531004 2.2727 4 P 0 0;3=13,5=1
P 5.53531004 2.1373 4 P 0 0;3=13,5=1
P 5.53531004 1.9964 4 P 0 0;3=13,5=1
P 5.38048002 2.3403 4 P 0 0;3=13,5=1
P 5.38048002 2.2832 4 P 0 0;3=13,5=1
P 5.38048002 2.2049 4 P 0 0;3=13,5=1
P 5.38048002 2.1478 4 P 0 0;3=13,5=1
P 5.38048002 2.0642 4 P 0 0;3=13,5=1
P 5.38048002 2.0071 4 P 0 0;3=13,5=1
P 5.38048002 1.9288 4 P 0 0;3=13,5=1
P 5.38048002 1.8717 4 P 0 0;3=13,5=1
P 5.53531004 2.351 4 P 0 0;3=13,5=1
P 5.38048002 2.4757 4 P 0 0;3=13,5=1
P 5.38048002 2.4186 4 P 0 0;3=13,5=1
P 5.53531004 2.4902 4 P 0 0;3=13,5=1
P 5.53531004 2.6825 4 P 0 0;3=13,5=1
P 5.53531004 2.6254 4 P 0 0;3=13,5=1
P 5.38048002 2.5578 4 P 0 0;3=13,5=1
P 5.38048002 2.6149 4 P 0 0;3=13,5=1
P 6.42418996 4.99705 25 P 0 0;1,3=4,5=0
P 6.42418996 5.04705 25 P 0 0;1,3=4,5=0
P 10.43 1.3341 4 P 0 0;3=13,5=1
P 10.43 1.277 4 P 0 0;3=13,5=1
P 10.4159 1.43 4 P 0 0;3=13,5=1
P 10.473 1.43 4 P 0 0;3=13,5=1
P 10.37313996 1.55336004 4 P 0 0;3=13,5=1
P 10.41451004 1.51198002 4 P 0 0;3=13,5=1
P 10.295 1.713 4 P 0 0;3=13,5=1
P 10.295 1.6559 4 P 0 0;3=13,5=1
P 10.26 1.9179 4 P 0 0;3=13,5=1
P 10.29525 1.877 4 P 0 0;3=13,5=1
P 10.29525 1.8199 4 P 0 0;3=13,5=1
P 10.26 1.975 4 P 0 0;3=13,5=1
P 10.125 2.0651 4 P 0 0;3=13,5=1
P 10.125 2.1224 4 P 0 0;3=13,5=1
P 10.125 2.1795 4 P 0 0;3=13,5=1
P 10.01 2.2481 4 P 0 0;3=13,5=1
P 10.01 2.191 4 P 0 0;3=13,5=1
P 10.01 2.38435 4 P 0 0;3=13,5=1
P 10.01 2.32725 4 P 0 0;3=13,5=1
P 10.125 2.3168 4 P 0 0;3=13,5=1
P 10.125 2.2597 4 P 0 0;3=13,5=1
P 10.125 2.4519 4 P 0 0;3=13,5=1
P 10.125 2.3948 4 P 0 0;3=13,5=1
P 10.01 2.51945 4 P 0 0;3=13,5=1
P 10.01 2.46235 4 P 0 0;3=13,5=1
P 10.125 2.587 4 P 0 0;3=13,5=1
P 10.125 2.5299 4 P 0 0;3=13,5=1
P 10.01 2.673 4 P 0 0;3=13,5=1
P 10.01 2.6159 4 P 0 0;3=13,5=1
P 11.74316004 1.7035 4 P 0 0;3=13,5=1
P 11.74316004 1.6405 4 P 0 0;3=13,5=1
P 11.69316004 1.4805 4 P 0 0;3=13,5=1
P 11.69316004 1.5435 4 P 0 0;3=13,5=1
P 11.49316004 1.5605 4 P 0 0;3=13,5=1
P 11.49316004 1.6235 4 P 0 0;3=13,5=1
P 11.49316004 1.4635 4 P 0 0;3=13,5=1
P 11.49366004 1.401 4 P 0 0;3=13,5=1
P 11.69316004 2.6005 4 P 0 0;3=13,5=1
P 11.69316004 2.5035 4 P 0 0;3=13,5=1
P 11.69316004 2.4405 4 P 0 0;3=13,5=1
P 11.69316004 2.3435 4 P 0 0;3=13,5=1
P 11.69316004 2.2805 4 P 0 0;3=13,5=1
P 11.69316004 2.1835 4 P 0 0;3=13,5=1
P 11.69316004 1.9605 4 P 0 0;3=13,5=1
P 11.69316004 2.0235 4 P 0 0;3=13,5=1
P 11.69316004 2.1205 4 P 0 0;3=13,5=1
P 11.69316004 1.8005 4 P 0 0;3=13,5=1
P 11.69316004 1.8635 4 P 0 0;3=13,5=1
P 11.49316004 2.5205 4 P 0 0;3=13,5=1
P 11.49316004 2.5835 4 P 0 0;3=13,5=1
P 11.49316004 2.4235 4 P 0 0;3=13,5=1
P 11.49316004 2.3605 4 P 0 0;3=13,5=1
P 11.79316004 2.2635 4 P 0 0;3=13,5=1
P 11.79316004 2.2005 4 P 0 0;3=13,5=1
P 11.49316004 1.9435 4 P 0 0;3=13,5=1
P 11.49316004 2.1035 4 P 0 0;3=13,5=1
P 11.49316004 2.0405 4 P 0 0;3=13,5=1
P 11.49316004 1.8805 4 P 0 0;3=13,5=1
P 11.49366004 1.721 4 P 0 0;3=13,5=1
P 11.49316004 1.7835 4 P 0 0;3=13,5=1
P 10.125 2.7451 4 P 0 0;3=13,5=1
P 10.125 2.688 4 P 0 0;3=13,5=1
P 12.34 2.19 4 P 0 0;3=13,5=1
P 9.415 5.332 4 P 0 0;3=13,5=1
P 9.265 5.332 4 P 0 0;3=13,5=1
P 9.07 5.332 4 P 0 0;3=13,5=1
P 4.76 5.54928996 53 P 0 0;1,3=9,5=0
P 4.7 5.54928996 4 P 0 0;3=13,5=1
P 4.81 5.408 25 P 0 0;1,3=4,5=0
P 4.81 5.375 4 P 0 0;3=13,5=1
P 4.96 5.408 25 P 0 0;1,3=4,5=0
P 4.96 5.375 4 P 0 0;3=13,5=1
P 5.16 5.617 25 P 0 0;1,3=4,5=0
P 5.16 5.645 4 P 0 0;3=13,5=1
P 5.04441004 5.64035 38 P 0 0;1,3=8,5=0
P 5.04441004 5.605 4 P 0 0;3=13,5=1
P 4.92 5.65315 42 P 0 0;1,3=5,5=0
P 4.92 5.7 4 P 0 0;3=13,5=1
P 9.91 4.667 25 P 0 0;1,3=4,5=0
P 9.91 4.7 4 P 0 0;3=13,5=1
P 3.57 4.483 25 P 0 0;1,3=4,5=0
P 3.57 4.45 4 P 0 0;3=13,5=1
P 11.87126004 4.88 36 P 0 0;1,3=29,5=0
P 10.465 5.195 4 P 0 0;3=13,5=1
P 10.515 5.32 4 P 0 0;3=13,5=1
P 10.465 5.275 4 P 0 0;3=13,5=1
P 12.025 4.915 4 P 0 0;3=13,5=1
P 12.12 4.965 4 P 0 0;3=13,5=1
P 12.185 4.915 4 P 0 0;3=13,5=1
P 3.72 4.483 25 P 0 0;1,3=4,5=0
P 3.72 4.45 4 P 0 0;3=13,5=1
P 3.64441004 4.67035 38 P 0 0;1,3=8,5=0
P 3.66 4.63 4 P 0 0;3=13,5=1
P 3.77 4.827 25 P 0 0;1,3=4,5=0
P 3.77 4.86 4 P 0 0;3=13,5=1
P 9.97441004 4.73035 38 P 0 0;1,3=8,5=0
P 9.96 4.69 4 P 0 0;3=13,5=1
P 10.03 4.543 25 P 0 0;1,3=4,5=0
P 10.03 4.51 4 P 0 0;3=13,5=1
P 3.835 4.6 4 P 0 0;3=13,5=1
P 3.99965 4.66441004 48 P 0 0;1,3=8,5=0
P 3.9865 4.635 4 P 0 0;3=13,5=1
P 4.14 4.683 25 P 0 0;1,3=4,5=0
P 4.14 4.655 4 P 0 0;3=13,5=1
P 4.1049 4.79498996 25 P 0 0;1,3=4,5=0
P 4.1049 4.7649 4 P 0 0;3=13,5=1
P 1.28051004 5.53641998 49 P 0 0;1,3=16,5=0
P 1.28051004 5.70373996 49 P 0 0;1,3=16,5=0
P 1.28051004 5.78 4 P 0 0;3=13,5=1
P 3.88313002 5.18321004 39 P 0 0;1,3=20,5=0
P 3.87 5.125 4 P 0 0;3=13,5=1
P 0.4826 5.85528002 41 P 0 0;1,3=27,5=0
P 0.4826 5.8976 4 P 0 0;3=13,5=1
P 0.84953002 5.1239 35 P 0 0;1,3=10,5=0
P 0.84953002 5.17 4 P 0 0;3=13,5=1
P 0.97441004 5.29035 38 P 0 0;1,3=8,5=0
P 0.955 5.325 4 P 0 0;3=13,5=1
P 1.03 5.093 25 P 0 0;1,3=4,5=0
P 0.73 5.147 25 P 0 0;1,3=4,5=0
P 0.73 5.267 25 P 0 0;1,3=4,5=0
P 0.705 5.383 25 P 0 0;1,3=4,5=0
P 1.455 5.857 25 P 0 0;1,3=4,5=0
P 1.405 5.857 25 P 0 0;1,3=4,5=0
P 1.355 5.857 25 P 0 0;1,3=4,5=0
P 1.305 5.857 25 P 0 0;1,3=4,5=0
P 1.46 5.383 25 P 0 0;1,3=4,5=0
P 1.41 5.383 25 P 0 0;1,3=4,5=0
P 1.36 5.383 25 P 0 0;1,3=4,5=0
P 1.31 5.383 25 P 0 0;1,3=4,5=0
P 1.31 5.355 4 P 0 0;3=13,5=1
P 1.51673002 5.53641998 49 P 0 0;1,3=16,5=0
P 1.20176998 5.53641998 49 P 0 0;1,3=16,5=0
P 1.12303002 5.53641998 49 P 0 0;1,3=16,5=0
P 1.51673002 5.70373996 49 P 0 0;1,3=16,5=0
P 1.20176998 5.70373996 49 P 0 0;1,3=16,5=0
P 1.20176998 5.78 4 P 0 0;3=13,5=1
P 6.31295 4.99705 4 P 0 0;3=13,5=1
P 6.87 5 4 P 0 0;3=13,5=1
P 9.64796004 0.79643002 4 P 0 0;3=13,5=1
P 9.40795 0.26133002 4 P 0 0;3=13,5=1
P 9.45795 0.42821004 43 P 0 0;1,3=28,5=0
P 3.60998996 0.24 4 P 0 0;3=13,5=1
P 3.65998996 0.40688002 43 P 0 0;1,3=28,5=0
P 3.65998996 0.345 4 P 0 0;3=13,5=1
P 3.86 0.7751 1 P 0 0;3=0,5=1
P 6.57318996 5.09705 25 P 0 0;1,3=4,5=0
P 6.87018996 4.94705 27 P 0 0;1,3=23,5=0
P 6.905 4.94705 4 P 0 0;3=13,5=1
P 6.87018996 4.88705 27 P 0 0;1,3=23,5=0
P 6.905 4.88705 4 P 0 0;3=13,5=1
P 6.91118996 4.81705 29 P 0 0;1,3=21,5=0
P 6.955 4.8 4 P 0 0;3=13,5=1
P 6.955 4.84 4 P 0 0;3=13,5=1
P 6.955 4.72 4 P 0 0;3=13,5=1
P 6.955 4.76 4 P 0 0;3=13,5=1
P 6.59708996 5.0502 4 P 0 0;3=13,5=1
P 6.67918996 4.77205 25 P 0 0;1,3=4,5=0
P 6.57618996 4.76905 25 P 0 0;1,3=4,5=0
P 6.65268996 4.82846998 33 P 0 0;1,3=19,5=0
P 6.63693996 4.82846998 33 P 0 0;1,3=19,5=0
P 6.62118996 4.82846998 33 P 0 0;1,3=19,5=0
P 6.60543996 4.82846998 33 P 0 0;1,3=19,5=0
P 6.58968996 4.82846998 33 P 0 0;1,3=19,5=0
P 6.66208996 4.6252 29 P 0 0;1,3=21,5=0
P 6.66208996 4.7052 29 P 0 0;1,3=21,5=0
P 6.65218996 4.77 4 P 0 0;3=13,5=1
P 6.69008996 4.96428996 47 P 0 0;1,3=19,5=0
P 6.62118996 4.95641998 1 P 0 0;3=30,5=1
P 6.6015 4.93673996 1 P 0 0;3=30,5=1
P 6.64088002 4.93673996 1 P 0 0;3=30,5=1
P 6.62118996 4.91705 1 P 0 0;3=30,5=1
P 6.62118996 4.87768002 1 P 0 0;3=30,5=1
P 6.6015 4.89736004 1 P 0 0;3=30,5=1
P 6.64088002 4.89736004 1 P 0 0;3=30,5=1
P 6.62 4.69 4 P 0 0;3=13,5=1
P 6.62 4.725 4 P 0 0;3=13,5=1
P 6.385 5.07 4 P 0 0;3=13,5=1
P 5.53593996 4.5861 25 P 0 0;1,3=4,5=0
P 5.53593996 4.55505 4 P 0 0;3=13,5=1
P 5.99708996 4.5552 29 P 0 0;1,3=21,5=0
P 5.91708996 4.5552 29 P 0 0;1,3=21,5=0
P 6.07708996 4.5552 29 P 0 0;1,3=21,5=0
P 5.75708996 4.5552 29 P 0 0;1,3=21,5=0
P 5.83708996 4.5552 29 P 0 0;1,3=21,5=0
P 5.67708996 4.5552 29 P 0 0;1,3=21,5=0
P 5.59778996 4.5552 29 P 0 0;1,3=21,5=0
P 6.05708996 4.5102 4 P 0 0;3=13,5=1
P 6.01708996 4.5102 4 P 0 0;3=13,5=1
P 5.97708996 4.5102 4 P 0 0;3=13,5=1
P 5.93708996 4.5102 4 P 0 0;3=13,5=1
P 5.89708996 4.5102 4 P 0 0;3=13,5=1
P 6.09708996 4.5102 4 P 0 0;3=13,5=1
P 5.61708996 4.5102 4 P 0 0;3=13,5=1
P 5.65708996 4.5102 4 P 0 0;3=13,5=1
P 5.85708996 4.5102 4 P 0 0;3=13,5=1
P 5.81708996 4.5102 4 P 0 0;3=13,5=1
P 5.77708996 4.5102 4 P 0 0;3=13,5=1
P 5.73708996 4.5102 4 P 0 0;3=13,5=1
P 5.69708996 4.5102 4 P 0 0;3=13,5=1
P 5.57708996 4.5102 4 P 0 0;3=13,5=1
P 0.036 0.10868002 4 P 0 0;3=13,5=1
P 0.036 0.15868002 4 P 0 0;3=13,5=1
P 0.036 0.20868002 4 P 0 0;3=13,5=1
P 0.22873996 0.036 4 P 0 0;3=13,5=1
P 0.17873996 0.036 4 P 0 0;3=13,5=1
P 0.12873996 0.036 4 P 0 0;3=13,5=1
P 0.07873996 0.036 4 P 0 0;3=13,5=1
P 0.47873996 0.036 4 P 0 0;3=13,5=1
P 0.42873996 0.036 4 P 0 0;3=13,5=1
P 0.37873996 0.036 4 P 0 0;3=13,5=1
P 0.32873996 0.036 4 P 0 0;3=13,5=1
P 0.27873996 0.036 4 P 0 0;3=13,5=1
P 0.77873996 0.036 4 P 0 0;3=13,5=1
P 0.72873996 0.036 4 P 0 0;3=13,5=1
P 0.67873996 0.036 4 P 0 0;3=13,5=1
P 0.62873996 0.036 4 P 0 0;3=13,5=1
P 0.57873996 0.036 4 P 0 0;3=13,5=1
P 0.52873996 0.036 4 P 0 0;3=13,5=1
P 1.02873996 0.036 4 P 0 0;3=13,5=1
P 0.97873996 0.036 4 P 0 0;3=13,5=1
P 0.92873996 0.036 4 P 0 0;3=13,5=1
P 0.87873996 0.036 4 P 0 0;3=13,5=1
P 0.82873996 0.036 4 P 0 0;3=13,5=1
P 1.27873996 0.036 4 P 0 0;3=13,5=1
P 1.22873996 0.036 4 P 0 0;3=13,5=1
P 1.17873996 0.036 4 P 0 0;3=13,5=1
P 1.12873996 0.036 4 P 0 0;3=13,5=1
P 1.07873996 0.036 4 P 0 0;3=13,5=1
P 1.52873996 0.036 4 P 0 0;3=13,5=1
P 1.47873996 0.036 4 P 0 0;3=13,5=1
P 1.42873996 0.036 4 P 0 0;3=13,5=1
P 1.37873996 0.036 4 P 0 0;3=13,5=1
P 1.32873996 0.036 4 P 0 0;3=13,5=1
P 1.82873996 0.036 4 P 0 0;3=13,5=1
P 1.77873996 0.036 4 P 0 0;3=13,5=1
P 1.72873996 0.036 4 P 0 0;3=13,5=1
P 1.67873996 0.036 4 P 0 0;3=13,5=1
P 1.62873996 0.036 4 P 0 0;3=13,5=1
P 1.57873996 0.036 4 P 0 0;3=13,5=1
P 2.07873996 0.036 4 P 0 0;3=13,5=1
P 2.02873996 0.036 4 P 0 0;3=13,5=1
P 1.97873996 0.036 4 P 0 0;3=13,5=1
P 1.92873996 0.036 4 P 0 0;3=13,5=1
P 1.87873996 0.036 4 P 0 0;3=13,5=1
P 2.32873996 0.036 4 P 0 0;3=13,5=1
P 2.27873996 0.036 4 P 0 0;3=13,5=1
P 2.22873996 0.036 4 P 0 0;3=13,5=1
P 2.17873996 0.036 4 P 0 0;3=13,5=1
P 2.12873996 0.036 4 P 0 0;3=13,5=1
P 2.62873996 0.036 4 P 0 0;3=13,5=1
P 2.57873996 0.036 4 P 0 0;3=13,5=1
P 2.52873996 0.036 4 P 0 0;3=13,5=1
P 2.47873996 0.036 4 P 0 0;3=13,5=1
P 2.42873996 0.036 4 P 0 0;3=13,5=1
P 2.37873996 0.036 4 P 0 0;3=13,5=1
P 2.87873996 0.036 4 P 0 0;3=13,5=1
P 2.82873996 0.036 4 P 0 0;3=13,5=1
P 2.77873996 0.036 4 P 0 0;3=13,5=1
P 2.72873996 0.036 4 P 0 0;3=13,5=1
P 2.67873996 0.036 4 P 0 0;3=13,5=1
P 3.12873996 0.036 4 P 0 0;3=13,5=1
P 3.07873996 0.036 4 P 0 0;3=13,5=1
P 3.02873996 0.036 4 P 0 0;3=13,5=1
P 2.97873996 0.036 4 P 0 0;3=13,5=1
P 2.92873996 0.036 4 P 0 0;3=13,5=1
P 3.37873996 0.036 4 P 0 0;3=13,5=1
P 3.32873996 0.036 4 P 0 0;3=13,5=1
P 3.27873996 0.036 4 P 0 0;3=13,5=1
P 3.22873996 0.036 4 P 0 0;3=13,5=1
P 3.17873996 0.036 4 P 0 0;3=13,5=1
P 3.67873996 0.036 4 P 0 0;3=13,5=1
P 3.62873996 0.036 4 P 0 0;3=13,5=1
P 3.57873996 0.036 4 P 0 0;3=13,5=1
P 3.52873996 0.036 4 P 0 0;3=13,5=1
P 3.47873996 0.036 4 P 0 0;3=13,5=1
P 3.42873996 0.036 4 P 0 0;3=13,5=1
P 3.92873996 0.036 4 P 0 0;3=13,5=1
P 3.87873996 0.036 4 P 0 0;3=13,5=1
P 3.82873996 0.036 4 P 0 0;3=13,5=1
P 3.77873996 0.036 4 P 0 0;3=13,5=1
P 3.72873996 0.036 4 P 0 0;3=13,5=1
P 4.17873996 0.036 4 P 0 0;3=13,5=1
P 4.12873996 0.036 4 P 0 0;3=13,5=1
P 4.07873996 0.036 4 P 0 0;3=13,5=1
P 4.02873996 0.036 4 P 0 0;3=13,5=1
P 3.97873996 0.036 4 P 0 0;3=13,5=1
P 4.42873996 0.036 4 P 0 0;3=13,5=1
P 4.37873996 0.036 4 P 0 0;3=13,5=1
P 4.32873996 0.036 4 P 0 0;3=13,5=1
P 4.27873996 0.036 4 P 0 0;3=13,5=1
P 4.22873996 0.036 4 P 0 0;3=13,5=1
P 4.72873996 0.036 4 P 0 0;3=13,5=1
P 4.67873996 0.036 4 P 0 0;3=13,5=1
P 4.62873996 0.036 4 P 0 0;3=13,5=1
P 4.57873996 0.036 4 P 0 0;3=13,5=1
P 4.52873996 0.036 4 P 0 0;3=13,5=1
P 4.47873996 0.036 4 P 0 0;3=13,5=1
P 4.81833996 0.21825 4 P 0 0;3=13,5=1
P 4.81833996 0.16825 4 P 0 0;3=13,5=1
P 4.81833996 0.11825 4 P 0 0;3=13,5=1
P 4.81703996 0.06826004 4 P 0 0;3=13,5=1
P 4.77873996 0.03611998 4 P 0 0;3=13,5=1
P 6.80731004 0.036 4 P 0 0;3=13,5=1
P 6.75731004 0.036 4 P 0 0;3=13,5=1
P 6.70731004 0.036 4 P 0 0;3=13,5=1
P 6.65731004 0.03676004 4 P 0 0;3=13,5=1
P 6.62298996 0.07311998 4 P 0 0;3=13,5=1
P 6.62261998 0.12311998 4 P 0 0;3=13,5=1
P 6.62261998 0.17311998 4 P 0 0;3=13,5=1
P 6.62261998 0.22311998 4 P 0 0;3=13,5=1
P 7.00731004 0.036 4 P 0 0;3=13,5=1
P 6.95731004 0.036 4 P 0 0;3=13,5=1
P 6.90731004 0.036 4 P 0 0;3=13,5=1
P 6.85731004 0.036 4 P 0 0;3=13,5=1
P 0.036 0.25868002 4 P 0 0;3=13,5=1
P 0.036 0.30868002 4 P 0 0;3=13,5=1
P 0.036 0.35868002 4 P 0 0;3=13,5=1
P 0.036 0.40868002 4 P 0 0;3=13,5=1
P 0.036 0.45868002 4 P 0 0;3=13,5=1
P 4.96803996 0.46906998 4 P 0 0;3=13,5=1
P 4.91805 0.46808002 4 P 0 0;3=13,5=1
P 4.87108996 0.45088996 4 P 0 0;3=13,5=1
P 4.83591004 0.41536004 4 P 0 0;3=13,5=1
P 4.81918996 0.36823996 4 P 0 0;3=13,5=1
P 4.81833996 0.31825 4 P 0 0;3=13,5=1
P 4.81833996 0.26825 4 P 0 0;3=13,5=1
P 5.21803996 0.46906998 4 P 0 0;3=13,5=1
P 5.16803996 0.46906998 4 P 0 0;3=13,5=1
P 5.11803996 0.46906998 4 P 0 0;3=13,5=1
P 5.06803996 0.46906998 4 P 0 0;3=13,5=1
P 5.01803996 0.46906998 4 P 0 0;3=13,5=1
P 5.51803996 0.46906998 4 P 0 0;3=13,5=1
P 5.46803996 0.46906998 4 P 0 0;3=13,5=1
P 5.41803996 0.46906998 4 P 0 0;3=13,5=1
P 5.36803996 0.46906998 4 P 0 0;3=13,5=1
P 5.31803996 0.46906998 4 P 0 0;3=13,5=1
P 5.26803996 0.46906998 4 P 0 0;3=13,5=1
P 5.76803996 0.46906998 4 P 0 0;3=13,5=1
P 5.71803996 0.46906998 4 P 0 0;3=13,5=1
P 5.66803996 0.46906998 4 P 0 0;3=13,5=1
P 5.61803996 0.46906998 4 P 0 0;3=13,5=1
P 5.56803996 0.46906998 4 P 0 0;3=13,5=1
P 6.01803996 0.46906998 4 P 0 0;3=13,5=1
P 5.96803996 0.46906998 4 P 0 0;3=13,5=1
P 5.91803996 0.46906998 4 P 0 0;3=13,5=1
P 5.86803996 0.46906998 4 P 0 0;3=13,5=1
P 5.81803996 0.46906998 4 P 0 0;3=13,5=1
P 6.31803996 0.46906998 4 P 0 0;3=13,5=1
P 6.26803996 0.46906998 4 P 0 0;3=13,5=1
P 6.21803996 0.46906998 4 P 0 0;3=13,5=1
P 6.16803996 0.46906998 4 P 0 0;3=13,5=1
P 6.11803996 0.46906998 4 P 0 0;3=13,5=1
P 6.06803996 0.46906998 4 P 0 0;3=13,5=1
P 6.56568002 0.45345 4 P 0 0;3=13,5=1
P 6.51803002 0.46861998 4 P 0 0;3=13,5=1
P 6.46803996 0.46906998 4 P 0 0;3=13,5=1
P 6.41803996 0.46906998 4 P 0 0;3=13,5=1
P 6.36803996 0.46906998 4 P 0 0;3=13,5=1
P 6.62261998 0.27311998 4 P 0 0;3=13,5=1
P 6.62261998 0.32311998 4 P 0 0;3=13,5=1
P 6.62106998 0.3731 4 P 0 0;3=13,5=1
P 6.60233996 0.41946004 4 P 0 0;3=13,5=1
P 0.036 0.50868002 4 P 0 0;3=13,5=1
P 0.036 0.55868002 4 P 0 0;3=13,5=1
P 11.845 2.85 4 P 0 0;3=13,5=1
P 8.98115 2.7861 4 P 0 0;3=13,5=1
P 8.98115 2.8989 4 P 0 0;3=13,5=1
P 11.58613002 2.855 4 P 0 0;3=13,5=1
P 11.50361998 2.8 4 P 0 0;3=13,5=1
P 11.50361998 2.73 4 P 0 0;3=13,5=1
P 5.5722 3 4 P 0 0;3=13,5=1
P 5.75778996 3.02558996 4 P 0 0;3=13,5=1
P 5.9192 2.943 4 P 0 0;3=13,5=1
P 4.07386004 2.55 4 P 0 0;3=13,5=1
P 3.86826998 2.64558996 4 P 0 0;3=13,5=1
P 9.995 2.87558996 4 P 0 0;3=13,5=1
P 10.11778996 2.78 4 P 0 0;3=13,5=1
P 1.32745 4.79681998 39 P 0 0;1,3=20,5=0
P 1.18906004 5.01551004 25 P 0 0;1,3=4,5=0
P 1.23906004 4.63151004 25 P 0 0;1,3=4,5=0
P 7.2426 4.63151004 25 P 0 0;1,3=4,5=0
P 7.2426 4.60351004 4 P 0 0;3=13,5=1
P 7.33098996 4.79681998 39 P 0 0;1,3=20,5=0
P 7.3401 4.85601004 4 P 0 0;3=13,5=1
P 7.1926 5.01551004 25 P 0 0;1,3=4,5=0
P 7.1926 5.04351004 4 P 0 0;3=13,5=1
P 0.66 2.045 1 P 0 0;3=0,5=1
P 1.792 2.4781 4 P 0 0;3=13,5=1
P 2.97721004 2.8989 4 P 0 0;3=13,5=1
P 2.97721004 2.7861 4 P 0 0;3=13,5=1
P 2.9422 2.925 4 P 0 0;3=13,5=1
P 8.94278996 2.925 4 P 0 0;3=13,5=1
P 5.5822 2.855 4 P 0 0;3=13,5=1
P 5.84968996 2.85 4 P 0 0;3=13,5=1
P 0.65348996 1.85608996 4 P 0 0;3=13,5=1
P 0.65348996 1.91628996 4 P 0 0;3=13,5=1
P 10.61161004 2.19115 6 P 0 0;1,3=11,5=0
P 11.01161004 2.39115 6 P 0 0;1,3=11,5=0
P 10.66161004 2.24115 6 P 0 0;1,3=11,5=0
P 5.00768002 2.39115 6 P 0 0;1,3=11,5=0
P 0.09448996 4.60236998 8 P 0 0;3=2,5=0
P 0.35038996 4.20866004 8 P 0 0;3=2,5=0
P 0.09448996 4.2874 8 P 0 0;3=2,5=0
P 0.09448996 4.12991998 8 P 0 0;3=2,5=0
P 0.17323002 4.16928996 8 P 0 0;3=2,5=0
P 0.27165 4.09055 8 P 0 0;3=2,5=0
P 0.27165 3.93306998 8 P 0 0;3=2,5=0
P 0.35038996 4.05118002 8 P 0 0;3=2,5=0
P 0.35038996 3.8937 8 P 0 0;3=2,5=0
P 0.09448996 3.97243996 8 P 0 0;3=2,5=0
P 0.09448996 3.81496004 8 P 0 0;3=2,5=0
P 0.17323002 4.01181004 8 P 0 0;3=2,5=0
P 0.17323002 3.85433002 8 P 0 0;3=2,5=0
P 0.27165 3.77558996 8 P 0 0;3=2,5=0
P 0.27165 3.61811004 8 P 0 0;3=2,5=0
P 0.35038996 3.73621998 8 P 0 0;3=2,5=0
P 0.35038996 3.57873996 8 P 0 0;3=2,5=0
P 0.09448996 3.65748002 8 P 0 0;3=2,5=0
P 0.09448996 3.5 8 P 0 0;3=2,5=0
P 0.17323002 3.69685 8 P 0 0;3=2,5=0
P 0.17323002 3.53936998 8 P 0 0;3=2,5=0
P 0.27165 3.46063002 8 P 0 0;3=2,5=0
P 0.35038996 3.42126004 8 P 0 0;3=2,5=0
P 0.27165 3.30315 8 P 0 0;3=2,5=0
P 0.27165 3.22441004 8 P 0 0;3=2,5=0
P 0.17323002 3.38188996 8 P 0 0;3=2,5=0
P 0.17323002 3.30315 8 P 0 0;3=2,5=0
P 0.35038996 3.1063 8 P 0 0;3=2,5=0
P 0.35038996 2.94881998 8 P 0 0;3=2,5=0
P 0.27165 3.06693002 8 P 0 0;3=2,5=0
P 0.27165 2.90945 8 P 0 0;3=2,5=0
P 0.17323002 3.14566998 8 P 0 0;3=2,5=0
P 0.17323002 2.98818996 8 P 0 0;3=2,5=0
P 0.09448996 3.18503996 8 P 0 0;3=2,5=0
P 0.09448996 3.02756004 8 P 0 0;3=2,5=0
P 0.35038996 2.79133996 8 P 0 0;3=2,5=0
P 0.27165 2.75196998 8 P 0 0;3=2,5=0
P 0.35038996 2.63386004 8 P 0 0;3=2,5=0
P 0.17323002 2.83071004 8 P 0 0;3=2,5=0
P 0.09448996 2.87008002 8 P 0 0;3=2,5=0
P 0.09448996 2.7126 8 P 0 0;3=2,5=0
P 0.35038996 2.39763996 8 P 0 0;3=2,5=0
P 0.27165 2.51575 8 P 0 0;3=2,5=0
P 0.27165 2.35826998 8 P 0 0;3=2,5=0
P 0.17323002 2.59448996 8 P 0 0;3=2,5=0
P 0.17323002 2.43701004 8 P 0 0;3=2,5=0
P 0.09448996 2.47638002 8 P 0 0;3=2,5=0
P 0.09448996 2.3189 8 P 0 0;3=2,5=0
P 0.35038996 2.24016004 8 P 0 0;3=2,5=0
P 0.35038996 2.08268002 8 P 0 0;3=2,5=0
P 0.35038996 2.00393996 8 P 0 0;3=2,5=0
P 0.27165 2.20078996 8 P 0 0;3=2,5=0
P 0.17323002 2.27953002 8 P 0 0;3=2,5=0
P 0.09448996 2.16141998 8 P 0 0;3=2,5=0
P 0.09448996 2.08268002 8 P 0 0;3=2,5=0
P 0.17323002 1.96456998 8 P 0 0;3=2,5=0
P 0.09448996 1.84646004 8 P 0 0;3=2,5=0
P 0.09448996 4.44488002 8 P 0 0;3=2,5=0
P 12.63778996 2.00393996 8 P 0 0;3=2,5=0
P 12.55905 2.12205 8 P 0 0;3=2,5=0
P 12.55905 1.88583002 8 P 0 0;3=2,5=0
P 12.81495 2.12205 8 P 0 0;3=2,5=0
P 12.81495 2.04331004 8 P 0 0;3=2,5=0
P 12.73621004 2.39763996 8 P 0 0;3=2,5=0
P 12.73621004 2.24016004 8 P 0 0;3=2,5=0
P 12.63778996 2.3189 8 P 0 0;3=2,5=0
P 12.55905 2.35826998 8 P 0 0;3=2,5=0
P 12.55905 2.20078996 8 P 0 0;3=2,5=0
P 12.81495 2.43701004 8 P 0 0;3=2,5=0
P 12.81495 2.27953002 8 P 0 0;3=2,5=0
P 12.73621004 2.55511998 8 P 0 0;3=2,5=0
P 12.63778996 2.63386004 8 P 0 0;3=2,5=0
P 12.63778996 2.47638002 8 P 0 0;3=2,5=0
P 12.55905 2.51575 8 P 0 0;3=2,5=0
P 12.81495 2.67323002 8 P 0 0;3=2,5=0
P 12.73621004 2.94881998 8 P 0 0;3=2,5=0
P 12.73621004 2.79133996 8 P 0 0;3=2,5=0
P 12.63778996 3.02756004 8 P 0 0;3=2,5=0
P 12.63778996 2.87008002 8 P 0 0;3=2,5=0
P 12.55905 2.90945 8 P 0 0;3=2,5=0
P 12.55905 2.75196998 8 P 0 0;3=2,5=0
P 12.81495 2.98818996 8 P 0 0;3=2,5=0
P 12.81495 2.83071004 8 P 0 0;3=2,5=0
P 12.73621004 3.26378002 8 P 0 0;3=2,5=0
P 12.73621004 3.1063 8 P 0 0;3=2,5=0
P 12.63778996 3.18503996 8 P 0 0;3=2,5=0
P 12.55905 3.22441004 8 P 0 0;3=2,5=0
P 12.55905 3.06693002 8 P 0 0;3=2,5=0
P 12.81495 3.14566998 8 P 0 0;3=2,5=0
P 12.55905 3.53936998 8 P 0 0;3=2,5=0
P 12.63778996 3.57873996 8 P 0 0;3=2,5=0
P 12.63778996 3.42126004 8 P 0 0;3=2,5=0
P 12.73621004 3.5 8 P 0 0;3=2,5=0
P 12.73621004 3.34251998 8 P 0 0;3=2,5=0
P 12.63778996 3.34251998 8 P 0 0;3=2,5=0
P 12.81495 3.61811004 8 P 0 0;3=2,5=0
P 12.81495 3.46063002 8 P 0 0;3=2,5=0
P 12.55905 3.85433002 8 P 0 0;3=2,5=0
P 12.55905 3.69685 8 P 0 0;3=2,5=0
P 12.63778996 3.8937 8 P 0 0;3=2,5=0
P 12.63778996 3.73621998 8 P 0 0;3=2,5=0
P 12.73621004 3.81496004 8 P 0 0;3=2,5=0
P 12.73621004 3.65748002 8 P 0 0;3=2,5=0
P 12.81495 3.93306998 8 P 0 0;3=2,5=0
P 12.81495 3.77558996 8 P 0 0;3=2,5=0
P 12.55905 4.16928996 8 P 0 0;3=2,5=0
P 12.55905 4.01181004 8 P 0 0;3=2,5=0
P 12.63778996 4.20866004 8 P 0 0;3=2,5=0
P 12.63778996 4.05118002 8 P 0 0;3=2,5=0
P 12.73621004 4.12991998 8 P 0 0;3=2,5=0
P 12.73621004 3.97243996 8 P 0 0;3=2,5=0
P 12.81495 4.09055 8 P 0 0;3=2,5=0
P 12.55905 4.48425 8 P 0 0;3=2,5=0
P 12.55905 4.32676998 8 P 0 0;3=2,5=0
P 12.63778996 4.52361998 8 P 0 0;3=2,5=0
P 12.63778996 4.36613996 8 P 0 0;3=2,5=0
P 12.73621004 4.44488002 8 P 0 0;3=2,5=0
P 12.73621004 4.2874 8 P 0 0;3=2,5=0
P 12.81495 4.40551004 8 P 0 0;3=2,5=0
P 12.81495 4.24803002 8 P 0 0;3=2,5=0
P 12.55905 4.64173996 8 P 0 0;3=2,5=0
P 12.81495 4.56298996 8 P 0 0;3=2,5=0
P 0.27165 4.40551004 8 P 0 0;3=2,5=0
P 0.35038996 4.52361998 8 P 0 0;3=2,5=0
P 0.17323002 4.48425 8 P 0 0;3=2,5=0
P 0.27165 4.24803002 8 P 0 0;3=2,5=0
P 0.35038996 4.36613996 8 P 0 0;3=2,5=0
P 0.17323002 4.32676998 8 P 0 0;3=2,5=0
P 5.49221004 2.73 4 P 0 0;3=13,5=1
P 5.44886004 2.9414 4 P 0 0;3=13,5=1
P 5.44886004 3.0214 4 P 0 0;3=13,5=1
P 5.44886004 3.0564 4 P 0 0;3=13,5=1
P 5.44886004 3.1014 4 P 0 0;3=13,5=1
P 5.44886004 3.1364 4 P 0 0;3=13,5=1
P 5.44886004 3.2164 4 P 0 0;3=13,5=1
P 5.44886004 3.1814 4 P 0 0;3=13,5=1
P 5.44886004 2.9764 4 P 0 0;3=13,5=1
P 5.44886004 3.2614 4 P 0 0;3=13,5=1
P 5.44886004 3.2964 4 P 0 0;3=13,5=1
P 10.33998996 4.9231 4 P 0 0;3=13,5=1
P 10.38498996 4.9231 1 P 0 0;3=0,5=1
P 10.77498996 4.9231 4 P 0 0;3=13,5=1
P 10.72998996 4.9231 4 P 0 0;3=13,5=1
P 10.30498996 4.9431 4 P 0 0;3=13,5=1
P 10.26498996 4.9431 4 P 0 0;3=13,5=1
P 10.30498996 5.0281 4 P 0 0;3=13,5=1
P 10.30498996 5.0731 4 P 0 0;3=13,5=1
P 10.30498996 4.9831 4 P 0 0;3=13,5=1
P 10.26498996 5.0281 4 P 0 0;3=13,5=1
P 10.26498996 5.0731 4 P 0 0;3=13,5=1
P 10.26498996 4.9831 4 P 0 0;3=13,5=1
P 10.26498996 5.1181 4 P 0 0;3=13,5=1
P 10.30498996 5.1181 4 P 0 0;3=13,5=1
P 10.34498996 5.1181 4 P 0 0;3=13,5=1
P 10.42498996 4.9431 4 P 0 0;3=13,5=1
P 10.46498996 4.9431 4 P 0 0;3=13,5=1
P 10.38498996 5.1181 4 P 0 0;3=13,5=1
P 10.46498996 5.1181 4 P 0 0;3=13,5=1
P 10.42498996 5.1181 4 P 0 0;3=13,5=1
P 10.42498996 4.9831 4 P 0 0;3=13,5=1
P 10.42498996 5.0731 4 P 0 0;3=13,5=1
P 10.42498996 5.0281 4 P 0 0;3=13,5=1
P 10.46498996 4.9831 4 P 0 0;3=13,5=1
P 10.46498996 5.0731 4 P 0 0;3=13,5=1
P 10.46498996 5.0281 4 P 0 0;3=13,5=1
P 10.85498996 4.9431 4 P 0 0;3=13,5=1
P 10.81498996 4.9431 4 P 0 0;3=13,5=1
P 10.65498996 4.9431 4 P 0 0;3=13,5=1
P 10.69498996 4.9431 4 P 0 0;3=13,5=1
P 10.85498996 5.0281 4 P 0 0;3=13,5=1
P 10.85498996 5.0731 4 P 0 0;3=13,5=1
P 10.85498996 4.9831 4 P 0 0;3=13,5=1
P 10.81498996 5.0281 4 P 0 0;3=13,5=1
P 10.81498996 5.0731 4 P 0 0;3=13,5=1
P 10.81498996 4.9831 4 P 0 0;3=13,5=1
P 10.81498996 5.1181 4 P 0 0;3=13,5=1
P 10.85498996 5.1181 4 P 0 0;3=13,5=1
P 10.73498996 5.1181 4 P 0 0;3=13,5=1
P 10.69498996 5.1181 4 P 0 0;3=13,5=1
P 10.65498996 5.1181 4 P 0 0;3=13,5=1
P 10.77498996 5.1181 4 P 0 0;3=13,5=1
P 10.65498996 4.9831 4 P 0 0;3=13,5=1
P 10.65498996 5.0731 4 P 0 0;3=13,5=1
P 10.65498996 5.0281 4 P 0 0;3=13,5=1
P 10.69498996 4.9831 4 P 0 0;3=13,5=1
P 10.69498996 5.0731 4 P 0 0;3=13,5=1
P 10.69498996 5.0281 4 P 0 0;3=13,5=1
P 1.23906004 4.60351004 4 P 0 0;3=13,5=1
P 1.18906004 5.04351004 4 P 0 0;3=13,5=1
P 1.33656004 4.85601004 4 P 0 0;3=13,5=1
P 10.16606998 2.81 4 P 0 0;3=13,5=1
P 4.15221004 2.9281 4 P 0 0;3=13,5=1
P 11.45278996 2.9414 4 P 0 0;3=13,5=1
P 11.45278996 3.0214 4 P 0 0;3=13,5=1
P 11.45278996 3.0564 4 P 0 0;3=13,5=1
P 11.45278996 3.1014 4 P 0 0;3=13,5=1
P 11.45278996 3.1364 4 P 0 0;3=13,5=1
P 11.45278996 3.2164 4 P 0 0;3=13,5=1
P 11.45278996 3.1814 4 P 0 0;3=13,5=1
P 11.45278996 2.9764 4 P 0 0;3=13,5=1
P 11.45278996 3.2614 4 P 0 0;3=13,5=1
P 11.45278996 3.2964 4 P 0 0;3=13,5=1
P 0.09448996 1.45276004 8 P 0 0;3=2,5=0
P 0.27165 1.57086998 8 P 0 0;3=2,5=0
P 0.35038996 1.45276004 8 P 0 0;3=2,5=0
P 12.81495 1.49213002 8 P 0 0;3=2,5=0
P 12.73621004 1.61023996 8 P 0 0;3=2,5=0
P 12.55905 1.49213002 8 P 0 0;3=2,5=0
P 0.27165 1.88583002 8 P 0 0;3=2,5=0
P 12.73621004 1.9252 8 P 0 0;3=2,5=0
P 10.36698996 5.02086004 52 P 0 0;1,3=25,5=0
P 10.75698996 5.02086004 52 P 0 0;1,3=25,5=0
P 7.35731004 0.036 4 P 0 0;3=13,5=1
P 7.60731004 0.036 4 P 0 0;3=13,5=1
P 7.55731004 0.036 4 P 0 0;3=13,5=1
P 7.50731004 0.036 4 P 0 0;3=13,5=1
P 7.45731004 0.036 4 P 0 0;3=13,5=1
P 7.40731004 0.036 4 P 0 0;3=13,5=1
P 7.85731004 0.036 4 P 0 0;3=13,5=1
P 7.80731004 0.036 4 P 0 0;3=13,5=1
P 7.75731004 0.036 4 P 0 0;3=13,5=1
P 7.70731004 0.036 4 P 0 0;3=13,5=1
P 7.65731004 0.036 4 P 0 0;3=13,5=1
P 8.15731004 0.036 4 P 0 0;3=13,5=1
P 8.10731004 0.036 4 P 0 0;3=13,5=1
P 8.05731004 0.036 4 P 0 0;3=13,5=1
P 8.00731004 0.036 4 P 0 0;3=13,5=1
P 7.95731004 0.036 4 P 0 0;3=13,5=1
P 7.90731004 0.036 4 P 0 0;3=13,5=1
P 8.40731004 0.036 4 P 0 0;3=13,5=1
P 8.35731004 0.036 4 P 0 0;3=13,5=1
P 8.30731004 0.036 4 P 0 0;3=13,5=1
P 8.25731004 0.036 4 P 0 0;3=13,5=1
P 8.20731004 0.036 4 P 0 0;3=13,5=1
P 8.65731004 0.036 4 P 0 0;3=13,5=1
P 8.60731004 0.036 4 P 0 0;3=13,5=1
P 8.55731004 0.036 4 P 0 0;3=13,5=1
P 8.50731004 0.036 4 P 0 0;3=13,5=1
P 8.45731004 0.036 4 P 0 0;3=13,5=1
P 8.90731004 0.036 4 P 0 0;3=13,5=1
P 8.85731004 0.036 4 P 0 0;3=13,5=1
P 8.80731004 0.036 4 P 0 0;3=13,5=1
P 8.75731004 0.036 4 P 0 0;3=13,5=1
P 8.70731004 0.036 4 P 0 0;3=13,5=1
P 9.20731004 0.036 4 P 0 0;3=13,5=1
P 9.15731004 0.036 4 P 0 0;3=13,5=1
P 9.10731004 0.036 4 P 0 0;3=13,5=1
P 9.05731004 0.036 4 P 0 0;3=13,5=1
P 9.00731004 0.036 4 P 0 0;3=13,5=1
P 8.95731004 0.036 4 P 0 0;3=13,5=1
P 9.45731004 0.036 4 P 0 0;3=13,5=1
P 9.40731004 0.036 4 P 0 0;3=13,5=1
P 9.35731004 0.036 4 P 0 0;3=13,5=1
P 9.30731004 0.036 4 P 0 0;3=13,5=1
P 9.25731004 0.036 4 P 0 0;3=13,5=1
P 9.70731004 0.036 4 P 0 0;3=13,5=1
P 9.65731004 0.036 4 P 0 0;3=13,5=1
P 9.60731004 0.036 4 P 0 0;3=13,5=1
P 9.55731004 0.036 4 P 0 0;3=13,5=1
P 9.50731004 0.036 4 P 0 0;3=13,5=1
P 10.00731004 0.036 4 P 0 0;3=13,5=1
P 9.95731004 0.036 4 P 0 0;3=13,5=1
P 9.90731004 0.036 4 P 0 0;3=13,5=1
P 9.85731004 0.036 4 P 0 0;3=13,5=1
P 9.80731004 0.036 4 P 0 0;3=13,5=1
P 9.75731004 0.036 4 P 0 0;3=13,5=1
P 10.25731004 0.036 4 P 0 0;3=13,5=1
P 10.20731004 0.036 4 P 0 0;3=13,5=1
P 10.15731004 0.036 4 P 0 0;3=13,5=1
P 10.10731004 0.036 4 P 0 0;3=13,5=1
P 10.05731004 0.036 4 P 0 0;3=13,5=1
P 10.50731004 0.036 4 P 0 0;3=13,5=1
P 10.45731004 0.036 4 P 0 0;3=13,5=1
P 10.40731004 0.036 4 P 0 0;3=13,5=1
P 10.35731004 0.036 4 P 0 0;3=13,5=1
P 10.30731004 0.036 4 P 0 0;3=13,5=1
P 10.75731004 0.036 4 P 0 0;3=13,5=1
P 10.70731004 0.036 4 P 0 0;3=13,5=1
P 10.65731004 0.036 4 P 0 0;3=13,5=1
P 10.60731004 0.036 4 P 0 0;3=13,5=1
P 10.55731004 0.036 4 P 0 0;3=13,5=1
P 11.05731004 0.036 4 P 0 0;3=13,5=1
P 11.00731004 0.036 4 P 0 0;3=13,5=1
P 10.95731004 0.036 4 P 0 0;3=13,5=1
P 10.90731004 0.036 4 P 0 0;3=13,5=1
P 10.85731004 0.036 4 P 0 0;3=13,5=1
P 10.80731004 0.036 4 P 0 0;3=13,5=1
P 11.30731004 0.036 4 P 0 0;3=13,5=1
P 11.25731004 0.036 4 P 0 0;3=13,5=1
P 11.20731004 0.036 4 P 0 0;3=13,5=1
P 11.15731004 0.036 4 P 0 0;3=13,5=1
P 11.10731004 0.036 4 P 0 0;3=13,5=1
P 11.55731004 0.036 4 P 0 0;3=13,5=1
P 11.50731004 0.036 4 P 0 0;3=13,5=1
P 11.45731004 0.036 4 P 0 0;3=13,5=1
P 11.40731004 0.036 4 P 0 0;3=13,5=1
P 11.35731004 0.036 4 P 0 0;3=13,5=1
P 11.80731004 0.036 4 P 0 0;3=13,5=1
P 11.75731004 0.036 4 P 0 0;3=13,5=1
P 11.70731004 0.036 4 P 0 0;3=13,5=1
P 11.65731004 0.036 4 P 0 0;3=13,5=1
P 11.60731004 0.036 4 P 0 0;3=13,5=1
P 12.10731004 0.036 4 P 0 0;3=13,5=1
P 12.05731004 0.036 4 P 0 0;3=13,5=1
P 12.00731004 0.036 4 P 0 0;3=13,5=1
P 11.95731004 0.036 4 P 0 0;3=13,5=1
P 11.90731004 0.036 4 P 0 0;3=13,5=1
P 11.85731004 0.036 4 P 0 0;3=13,5=1
P 12.35731004 0.036 4 P 0 0;3=13,5=1
P 12.30731004 0.036 4 P 0 0;3=13,5=1
P 12.25731004 0.036 4 P 0 0;3=13,5=1
P 12.20731004 0.036 4 P 0 0;3=13,5=1
P 12.15731004 0.036 4 P 0 0;3=13,5=1
P 12.60731004 0.036 4 P 0 0;3=13,5=1
P 12.55731004 0.036 4 P 0 0;3=13,5=1
P 12.50731004 0.036 4 P 0 0;3=13,5=1
P 12.45731004 0.036 4 P 0 0;3=13,5=1
P 12.40731004 0.036 4 P 0 0;3=13,5=1
P 12.8892 0.22596004 4 P 0 0;3=13,5=1
P 12.8892 0.17596004 4 P 0 0;3=13,5=1
P 12.8892 0.12596004 4 P 0 0;3=13,5=1
P 12.88911004 0.07596004 4 P 0 0;3=13,5=1
P 12.85728996 0.03738996 4 P 0 0;3=13,5=1
P 12.80731004 0.036 4 P 0 0;3=13,5=1
P 12.75731004 0.036 4 P 0 0;3=13,5=1
P 12.70731004 0.036 4 P 0 0;3=13,5=1
P 12.65731004 0.036 4 P 0 0;3=13,5=1
P 12.8892 0.47596004 4 P 0 0;3=13,5=1
P 12.8892 0.42596004 4 P 0 0;3=13,5=1
P 12.8892 0.37596004 4 P 0 0;3=13,5=1
P 12.8892 0.32596004 4 P 0 0;3=13,5=1
P 12.8892 0.27596004 4 P 0 0;3=13,5=1
P 12.8892 0.62596004 4 P 0 0;3=13,5=1
P 12.8892 0.57596004 4 P 0 0;3=13,5=1
P 12.8892 0.52596004 4 P 0 0;3=13,5=1
P 0.036 1.00868002 4 P 0 0;3=13,5=1
P 0.036 1.05868002 4 P 0 0;3=13,5=1
P 0.036 1.10868002 4 P 0 0;3=13,5=1
P 0.036 1.15868002 4 P 0 0;3=13,5=1
P 0.036 1.20868002 4 P 0 0;3=13,5=1
P 0.036 1.25868002 4 P 0 0;3=13,5=1
P 0.036 1.30868002 4 P 0 0;3=13,5=1
P 0.036 1.35868002 4 P 0 0;3=13,5=1
P 0.036 1.40868002 4 P 0 0;3=13,5=1
P 0.036 1.45868002 4 P 0 0;3=13,5=1
P 0.036 1.50868002 4 P 0 0;3=13,5=1
P 0.036 1.55868002 4 P 0 0;3=13,5=1
P 0.036 1.60868002 4 P 0 0;3=13,5=1
P 0.036 1.65868002 4 P 0 0;3=13,5=1
P 0.036 1.70868002 4 P 0 0;3=13,5=1
P 0.036 1.75868002 4 P 0 0;3=13,5=1
P 0.036 1.80868002 4 P 0 0;3=13,5=1
P 0.036 1.85868002 4 P 0 0;3=13,5=1
P 0.036 1.90868002 4 P 0 0;3=13,5=1
P 0.036 1.95868002 4 P 0 0;3=13,5=1
P 0.036 2.00868002 4 P 0 0;3=13,5=1
P 0.036 2.05868002 4 P 0 0;3=13,5=1
P 0.036 2.10868002 4 P 0 0;3=13,5=1
P 0.036 2.15868002 4 P 0 0;3=13,5=1
P 0.036 2.20868002 4 P 0 0;3=13,5=1
P 0.036 2.25868002 4 P 0 0;3=13,5=1
P 0.036 2.30868002 4 P 0 0;3=13,5=1
P 0.036 2.35868002 4 P 0 0;3=13,5=1
P 0.036 2.40868002 4 P 0 0;3=13,5=1
P 0.036 2.45868002 4 P 0 0;3=13,5=1
P 0.036 2.50868002 4 P 0 0;3=13,5=1
P 0.036 2.55868002 4 P 0 0;3=13,5=1
P 0.036 2.60868002 4 P 0 0;3=13,5=1
P 0.036 2.65868002 4 P 0 0;3=13,5=1
P 0.036 2.70868002 4 P 0 0;3=13,5=1
P 0.036 2.75868002 4 P 0 0;3=13,5=1
P 0.036 2.80868002 4 P 0 0;3=13,5=1
P 0.036 2.85868002 4 P 0 0;3=13,5=1
P 0.036 2.90868002 4 P 0 0;3=13,5=1
P 0.036 2.95868002 4 P 0 0;3=13,5=1
P 0.036 3.00868002 4 P 0 0;3=13,5=1
P 0.036 3.05868002 4 P 0 0;3=13,5=1
P 0.036 3.10868002 4 P 0 0;3=13,5=1
P 0.036 3.15868002 4 P 0 0;3=13,5=1
P 0.036 3.20868002 4 P 0 0;3=13,5=1
P 0.036 3.25868002 4 P 0 0;3=13,5=1
P 0.036 3.30868002 4 P 0 0;3=13,5=1
P 0.036 3.35868002 4 P 0 0;3=13,5=1
P 0.036 3.40868002 4 P 0 0;3=13,5=1
P 0.036 3.45868002 4 P 0 0;3=13,5=1
P 0.036 3.50868002 4 P 0 0;3=13,5=1
P 0.036 3.55868002 4 P 0 0;3=13,5=1
P 0.036 3.60868002 4 P 0 0;3=13,5=1
P 0.036 3.65868002 4 P 0 0;3=13,5=1
P 0.036 3.70868002 4 P 0 0;3=13,5=1
P 0.036 3.75868002 4 P 0 0;3=13,5=1
P 0.036 3.80868002 4 P 0 0;3=13,5=1
P 0.036 3.85868002 4 P 0 0;3=13,5=1
P 0.036 3.90868002 4 P 0 0;3=13,5=1
P 0.036 3.95868002 4 P 0 0;3=13,5=1
P 0.036 4.00868002 4 P 0 0;3=13,5=1
P 0.036 4.05868002 4 P 0 0;3=13,5=1
P 0.036 4.10868002 4 P 0 0;3=13,5=1
P 0.036 4.15868002 4 P 0 0;3=13,5=1
P 0.036 4.20868002 4 P 0 0;3=13,5=1
P 0.036 4.25868002 4 P 0 0;3=13,5=1
P 0.036 4.30868002 4 P 0 0;3=13,5=1
P 0.036 4.35868002 4 P 0 0;3=13,5=1
P 0.036 4.40868002 4 P 0 0;3=13,5=1
P 0.036 4.45868002 4 P 0 0;3=13,5=1
P 0.036 4.50868002 4 P 0 0;3=13,5=1
P 0.036 4.55868002 4 P 0 0;3=13,5=1
P 0.036 4.60868002 4 P 0 0;3=13,5=1
P 0.036 4.65868002 4 P 0 0;3=13,5=1
P 0.036 4.70868002 4 P 0 0;3=13,5=1
P 0.036 4.75868002 4 P 0 0;3=13,5=1
P 12.8892 1.02596004 4 P 0 0;3=13,5=1
P 12.8892 1.27596004 4 P 0 0;3=13,5=1
P 12.8892 1.22596004 4 P 0 0;3=13,5=1
P 12.8892 1.17596004 4 P 0 0;3=13,5=1
P 12.8892 1.12596004 4 P 0 0;3=13,5=1
P 12.8892 1.07596004 4 P 0 0;3=13,5=1
P 12.8892 1.52596004 4 P 0 0;3=13,5=1
P 12.8892 1.47596004 4 P 0 0;3=13,5=1
P 12.8892 1.42596004 4 P 0 0;3=13,5=1
P 12.8892 1.37596004 4 P 0 0;3=13,5=1
P 12.8892 1.32596004 4 P 0 0;3=13,5=1
P 12.8892 1.77596004 4 P 0 0;3=13,5=1
P 12.8892 1.72596004 4 P 0 0;3=13,5=1
P 12.8892 1.67596004 4 P 0 0;3=13,5=1
P 12.8892 1.62596004 4 P 0 0;3=13,5=1
P 12.8892 1.57596004 4 P 0 0;3=13,5=1
P 12.8892 2.07596004 4 P 0 0;3=13,5=1
P 12.8892 2.02596004 4 P 0 0;3=13,5=1
P 12.8892 1.97596004 4 P 0 0;3=13,5=1
P 12.8892 1.92596004 4 P 0 0;3=13,5=1
P 12.8892 1.87596004 4 P 0 0;3=13,5=1
P 12.8892 1.82596004 4 P 0 0;3=13,5=1
P 12.8892 2.32596004 4 P 0 0;3=13,5=1
P 12.8892 2.27596004 4 P 0 0;3=13,5=1
P 12.8892 2.22596004 4 P 0 0;3=13,5=1
P 12.8892 2.17596004 4 P 0 0;3=13,5=1
P 12.8892 2.57596004 4 P 0 0;3=13,5=1
P 12.8892 2.52596004 4 P 0 0;3=13,5=1
P 12.8892 2.47596004 4 P 0 0;3=13,5=1
P 12.8892 2.42596004 4 P 0 0;3=13,5=1
P 12.8892 2.37596004 4 P 0 0;3=13,5=1
P 12.8892 2.82596004 4 P 0 0;3=13,5=1
P 12.8892 2.77596004 4 P 0 0;3=13,5=1
P 12.8892 2.72596004 4 P 0 0;3=13,5=1
P 12.8892 2.67596004 4 P 0 0;3=13,5=1
P 12.8892 2.62596004 4 P 0 0;3=13,5=1
P 12.8892 3.12596004 4 P 0 0;3=13,5=1
P 12.8892 3.07596004 4 P 0 0;3=13,5=1
P 12.8892 3.02596004 4 P 0 0;3=13,5=1
P 12.8892 2.97596004 4 P 0 0;3=13,5=1
P 12.8892 2.92596004 4 P 0 0;3=13,5=1
P 12.8892 2.87596004 4 P 0 0;3=13,5=1
P 12.8892 3.37596004 4 P 0 0;3=13,5=1
P 12.8892 3.32596004 4 P 0 0;3=13,5=1
P 12.8892 3.27596004 4 P 0 0;3=13,5=1
P 12.8892 3.22596004 4 P 0 0;3=13,5=1
P 12.8892 3.17596004 4 P 0 0;3=13,5=1
P 12.8892 3.62596004 4 P 0 0;3=13,5=1
P 12.8892 3.57596004 4 P 0 0;3=13,5=1
P 12.8892 3.52596004 4 P 0 0;3=13,5=1
P 12.8892 3.47596004 4 P 0 0;3=13,5=1
P 12.8892 3.42596004 4 P 0 0;3=13,5=1
P 12.8892 3.92596004 4 P 0 0;3=13,5=1
P 12.8892 3.87596004 4 P 0 0;3=13,5=1
P 12.8892 3.82596004 4 P 0 0;3=13,5=1
P 12.8892 3.77596004 4 P 0 0;3=13,5=1
P 12.8892 3.72596004 4 P 0 0;3=13,5=1
P 12.8892 3.67596004 4 P 0 0;3=13,5=1
P 12.8892 4.17596004 4 P 0 0;3=13,5=1
P 12.8892 4.12596004 4 P 0 0;3=13,5=1
P 12.8892 4.07596004 4 P 0 0;3=13,5=1
P 12.8892 4.02596004 4 P 0 0;3=13,5=1
P 12.8892 3.97596004 4 P 0 0;3=13,5=1
P 12.8892 4.42596004 4 P 0 0;3=13,5=1
P 12.8892 4.37596004 4 P 0 0;3=13,5=1
P 12.8892 4.32596004 4 P 0 0;3=13,5=1
P 12.8892 4.27596004 4 P 0 0;3=13,5=1
P 12.8892 4.22596004 4 P 0 0;3=13,5=1
P 12.8892 4.67596004 4 P 0 0;3=13,5=1
P 12.8892 4.62596004 4 P 0 0;3=13,5=1
P 12.8892 4.57596004 4 P 0 0;3=13,5=1
P 12.8892 4.52596004 4 P 0 0;3=13,5=1
P 12.8892 4.47596004 4 P 0 0;3=13,5=1
P 12.8892 4.82596004 4 P 0 0;3=13,5=1
P 12.8892 4.77596004 4 P 0 0;3=13,5=1
P 12.8892 4.72596004 4 P 0 0;3=13,5=1
P 0.036 5.25868002 4 P 0 0;3=13,5=1
P 0.036 5.30868002 4 P 0 0;3=13,5=1
P 0.036 5.35868002 4 P 0 0;3=13,5=1
P 0.036 5.40868002 4 P 0 0;3=13,5=1
P 0.036 5.45868002 4 P 0 0;3=13,5=1
P 0.036 5.50868002 4 P 0 0;3=13,5=1
P 0.036 5.55868002 4 P 0 0;3=13,5=1
P 0.036 5.60868002 4 P 0 0;3=13,5=1
P 0.036 5.65868002 4 P 0 0;3=13,5=1
P 0.036 5.70868002 4 P 0 0;3=13,5=1
P 0.036 5.75868002 4 P 0 0;3=13,5=1
P 0.036 5.80868002 4 P 0 0;3=13,5=1
P 0.036 5.85868002 4 P 0 0;3=13,5=1
P 0.036 5.90868002 4 P 0 0;3=13,5=1
P 0.03826998 5.95863002 4 P 0 0;3=13,5=1
P 0.07901004 5.98761998 4 P 0 0;3=13,5=1
P 0.12901004 5.98761998 4 P 0 0;3=13,5=1
P 0.17901004 5.98761998 4 P 0 0;3=13,5=1
P 0.22901004 5.98761998 4 P 0 0;3=13,5=1
P 0.27901004 5.98761998 4 P 0 0;3=13,5=1
P 0.32901004 5.98761998 4 P 0 0;3=13,5=1
P 0.37901004 5.98761998 4 P 0 0;3=13,5=1
P 0.42901004 5.98761998 4 P 0 0;3=13,5=1
P 0.47901004 5.98761998 4 P 0 0;3=13,5=1
P 0.52901004 5.98761998 4 P 0 0;3=13,5=1
P 0.57901004 5.98761998 4 P 0 0;3=13,5=1
P 0.62901004 5.98761998 4 P 0 0;3=13,5=1
P 0.67901004 5.98761998 4 P 0 0;3=13,5=1
P 0.72901004 5.98761998 4 P 0 0;3=13,5=1
P 0.77901004 5.98761998 4 P 0 0;3=13,5=1
P 0.82901004 5.98761998 4 P 0 0;3=13,5=1
P 0.87901004 5.98761998 4 P 0 0;3=13,5=1
P 0.92901004 5.98761998 4 P 0 0;3=13,5=1
P 0.97901004 5.98761998 4 P 0 0;3=13,5=1
P 1.02901004 5.98761998 4 P 0 0;3=13,5=1
P 1.07901004 5.98761998 4 P 0 0;3=13,5=1
P 1.12901004 5.98761998 4 P 0 0;3=13,5=1
P 1.17901004 5.98761998 4 P 0 0;3=13,5=1
P 1.22901004 5.98761998 4 P 0 0;3=13,5=1
P 1.27901004 5.98761998 4 P 0 0;3=13,5=1
P 1.32901004 5.98761998 4 P 0 0;3=13,5=1
P 1.37901004 5.98761998 4 P 0 0;3=13,5=1
P 1.42901004 5.98761998 4 P 0 0;3=13,5=1
P 1.47901004 5.98761998 4 P 0 0;3=13,5=1
P 1.52901004 5.98761998 4 P 0 0;3=13,5=1
P 1.57901004 5.98761998 4 P 0 0;3=13,5=1
P 1.62901004 5.98761998 4 P 0 0;3=13,5=1
P 1.67901004 5.98761998 4 P 0 0;3=13,5=1
P 1.72901004 5.98761998 4 P 0 0;3=13,5=1
P 1.77901004 5.98761998 4 P 0 0;3=13,5=1
P 1.82901004 5.98761998 4 P 0 0;3=13,5=1
P 1.87901004 5.98761998 4 P 0 0;3=13,5=1
P 1.92901004 5.98761998 4 P 0 0;3=13,5=1
P 1.97901004 5.98761998 4 P 0 0;3=13,5=1
P 2.02901004 5.98761998 4 P 0 0;3=13,5=1
P 2.07901004 5.98761998 4 P 0 0;3=13,5=1
P 2.12901004 5.98761998 4 P 0 0;3=13,5=1
P 2.17901004 5.98761998 4 P 0 0;3=13,5=1
P 2.22901004 5.98761998 4 P 0 0;3=13,5=1
P 2.27901004 5.98761998 4 P 0 0;3=13,5=1
P 2.32901004 5.98761998 4 P 0 0;3=13,5=1
P 2.37901004 5.98761998 4 P 0 0;3=13,5=1
P 2.42901004 5.98761998 4 P 0 0;3=13,5=1
P 2.47901004 5.98761998 4 P 0 0;3=13,5=1
P 2.52901004 5.98761998 4 P 0 0;3=13,5=1
P 2.57901004 5.98761998 4 P 0 0;3=13,5=1
P 2.62901004 5.98761998 4 P 0 0;3=13,5=1
P 2.67901004 5.98761998 4 P 0 0;3=13,5=1
P 2.72901004 5.98761998 4 P 0 0;3=13,5=1
P 2.77901004 5.98761998 4 P 0 0;3=13,5=1
P 2.82901004 5.98761998 4 P 0 0;3=13,5=1
P 2.87901004 5.98761998 4 P 0 0;3=13,5=1
P 2.92901004 5.98761998 4 P 0 0;3=13,5=1
P 2.97901004 5.98761998 4 P 0 0;3=13,5=1
P 3.02901004 5.98761998 4 P 0 0;3=13,5=1
P 3.07901004 5.98761998 4 P 0 0;3=13,5=1
P 3.12901004 5.98761998 4 P 0 0;3=13,5=1
P 3.17901004 5.98761998 4 P 0 0;3=13,5=1
P 3.22901004 5.98761998 4 P 0 0;3=13,5=1
P 3.27901004 5.98761998 4 P 0 0;3=13,5=1
P 3.32901004 5.98761998 4 P 0 0;3=13,5=1
P 3.37901004 5.98761998 4 P 0 0;3=13,5=1
P 3.42901004 5.98761998 4 P 0 0;3=13,5=1
P 3.47901004 5.98761998 4 P 0 0;3=13,5=1
P 3.52901004 5.98761998 4 P 0 0;3=13,5=1
P 3.57901004 5.98761998 4 P 0 0;3=13,5=1
P 3.62901004 5.98761998 4 P 0 0;3=13,5=1
P 3.67901004 5.98761998 4 P 0 0;3=13,5=1
P 3.72901004 5.98761998 4 P 0 0;3=13,5=1
P 3.77901004 5.98761998 4 P 0 0;3=13,5=1
P 3.82901004 5.98761998 4 P 0 0;3=13,5=1
P 3.87901004 5.98761998 4 P 0 0;3=13,5=1
P 3.92901004 5.98761998 4 P 0 0;3=13,5=1
P 3.97901004 5.98761998 4 P 0 0;3=13,5=1
P 4.02901004 5.98761998 4 P 0 0;3=13,5=1
P 4.07901004 5.98761998 4 P 0 0;3=13,5=1
P 4.12901004 5.98761998 4 P 0 0;3=13,5=1
P 4.17901004 5.98761998 4 P 0 0;3=13,5=1
P 4.22901004 5.98761998 4 P 0 0;3=13,5=1
P 4.27901004 5.98761998 4 P 0 0;3=13,5=1
P 4.32901004 5.98761998 4 P 0 0;3=13,5=1
P 4.37901004 5.98761998 4 P 0 0;3=13,5=1
P 4.42901004 5.98761998 4 P 0 0;3=13,5=1
P 4.47901004 5.98761998 4 P 0 0;3=13,5=1
P 4.52901004 5.98761998 4 P 0 0;3=13,5=1
P 4.57901004 5.98761998 4 P 0 0;3=13,5=1
P 4.62901004 5.98761998 4 P 0 0;3=13,5=1
P 4.67901004 5.98761998 4 P 0 0;3=13,5=1
P 4.72901004 5.98761998 4 P 0 0;3=13,5=1
P 4.77901004 5.98761998 4 P 0 0;3=13,5=1
P 4.82901004 5.98761998 4 P 0 0;3=13,5=1
P 4.87901004 5.98761998 4 P 0 0;3=13,5=1
P 4.92901004 5.98761998 4 P 0 0;3=13,5=1
P 4.97901004 5.98761998 4 P 0 0;3=13,5=1
P 5.02901004 5.98761998 4 P 0 0;3=13,5=1
P 5.07901004 5.98761998 4 P 0 0;3=13,5=1
P 5.12901004 5.98761998 4 P 0 0;3=13,5=1
P 5.17901004 5.98761998 4 P 0 0;3=13,5=1
P 5.22901004 5.98761998 4 P 0 0;3=13,5=1
P 5.27901004 5.98761998 4 P 0 0;3=13,5=1
P 5.32901004 5.98761998 4 P 0 0;3=13,5=1
P 5.37901004 5.98761998 4 P 0 0;3=13,5=1
P 5.42901004 5.98761998 4 P 0 0;3=13,5=1
P 5.47901004 5.98761998 4 P 0 0;3=13,5=1
P 5.52901004 5.98761998 4 P 0 0;3=13,5=1
P 5.57901004 5.98761998 4 P 0 0;3=13,5=1
P 5.62901004 5.98761998 4 P 0 0;3=13,5=1
P 5.67901004 5.98761998 4 P 0 0;3=13,5=1
P 5.72901004 5.98761998 4 P 0 0;3=13,5=1
P 5.77901004 5.98761998 4 P 0 0;3=13,5=1
P 5.82901004 5.98761998 4 P 0 0;3=13,5=1
P 5.87901004 5.98761998 4 P 0 0;3=13,5=1
P 5.92901004 5.98761998 4 P 0 0;3=13,5=1
P 5.97901004 5.98761998 4 P 0 0;3=13,5=1
P 6.02901004 5.98761998 4 P 0 0;3=13,5=1
P 6.07901004 5.98761998 4 P 0 0;3=13,5=1
P 6.12901004 5.98761998 4 P 0 0;3=13,5=1
P 6.17901004 5.98761998 4 P 0 0;3=13,5=1
P 6.22901004 5.98761998 4 P 0 0;3=13,5=1
P 6.27901004 5.98761998 4 P 0 0;3=13,5=1
P 6.32901004 5.98761998 4 P 0 0;3=13,5=1
P 6.37901004 5.98761998 4 P 0 0;3=13,5=1
P 6.42901004 5.98761998 4 P 0 0;3=13,5=1
P 6.47901004 5.98761998 4 P 0 0;3=13,5=1
P 6.52901004 5.98761998 4 P 0 0;3=13,5=1
P 6.57901004 5.98761998 4 P 0 0;3=13,5=1
P 6.62901004 5.98761998 4 P 0 0;3=13,5=1
P 6.67901004 5.98761998 4 P 0 0;3=13,5=1
P 6.72901004 5.98761998 4 P 0 0;3=13,5=1
P 6.77901004 5.98761998 4 P 0 0;3=13,5=1
P 6.82901004 5.98761998 4 P 0 0;3=13,5=1
P 6.87901004 5.98761998 4 P 0 0;3=13,5=1
P 6.92901004 5.98761998 4 P 0 0;3=13,5=1
P 6.97901004 5.98761998 4 P 0 0;3=13,5=1
P 12.8892 5.47596004 4 P 0 0;3=13,5=1
P 12.8892 5.42596004 4 P 0 0;3=13,5=1
P 12.8892 5.37596004 4 P 0 0;3=13,5=1
P 12.8892 5.32596004 4 P 0 0;3=13,5=1
P 12.8892 5.27596004 4 P 0 0;3=13,5=1
P 12.8892 5.72596004 4 P 0 0;3=13,5=1
P 12.8892 5.67596004 4 P 0 0;3=13,5=1
P 12.8892 5.62596004 4 P 0 0;3=13,5=1
P 12.8892 5.57596004 4 P 0 0;3=13,5=1
P 12.8892 5.52596004 4 P 0 0;3=13,5=1
P 7.37901004 5.98761998 4 P 0 0;3=13,5=1
P 7.42901004 5.98761998 4 P 0 0;3=13,5=1
P 7.47901004 5.98761998 4 P 0 0;3=13,5=1
P 7.52901004 5.98761998 4 P 0 0;3=13,5=1
P 7.57901004 5.98761998 4 P 0 0;3=13,5=1
P 7.62901004 5.98761998 4 P 0 0;3=13,5=1
P 7.67901004 5.98761998 4 P 0 0;3=13,5=1
P 7.72901004 5.98761998 4 P 0 0;3=13,5=1
P 7.77901004 5.98761998 4 P 0 0;3=13,5=1
P 7.82901004 5.98761998 4 P 0 0;3=13,5=1
P 7.87901004 5.98761998 4 P 0 0;3=13,5=1
P 7.92901004 5.98761998 4 P 0 0;3=13,5=1
P 7.97901004 5.98761998 4 P 0 0;3=13,5=1
P 8.02901004 5.98761998 4 P 0 0;3=13,5=1
P 8.07901004 5.98761998 4 P 0 0;3=13,5=1
P 8.12901004 5.98761998 4 P 0 0;3=13,5=1
P 8.17901004 5.98761998 4 P 0 0;3=13,5=1
P 8.22901004 5.98761998 4 P 0 0;3=13,5=1
P 8.27901004 5.98761998 4 P 0 0;3=13,5=1
P 8.32901004 5.98761998 4 P 0 0;3=13,5=1
P 8.37901004 5.98761998 4 P 0 0;3=13,5=1
P 8.42901004 5.98761998 4 P 0 0;3=13,5=1
P 8.47901004 5.98761998 4 P 0 0;3=13,5=1
P 8.52901004 5.98761998 4 P 0 0;3=13,5=1
P 8.57901004 5.98761998 4 P 0 0;3=13,5=1
P 8.62901004 5.98761998 4 P 0 0;3=13,5=1
P 8.67901004 5.98761998 4 P 0 0;3=13,5=1
P 8.72901004 5.98761998 4 P 0 0;3=13,5=1
P 8.77901004 5.98761998 4 P 0 0;3=13,5=1
P 8.82901004 5.98761998 4 P 0 0;3=13,5=1
P 8.87901004 5.98761998 4 P 0 0;3=13,5=1
P 8.92901004 5.98761998 4 P 0 0;3=13,5=1
P 8.97901004 5.98761998 4 P 0 0;3=13,5=1
P 9.02901004 5.98761998 4 P 0 0;3=13,5=1
P 9.07901004 5.98761998 4 P 0 0;3=13,5=1
P 9.12901004 5.98761998 4 P 0 0;3=13,5=1
P 9.17901004 5.98761998 4 P 0 0;3=13,5=1
P 9.22901004 5.98761998 4 P 0 0;3=13,5=1
P 9.27901004 5.98761998 4 P 0 0;3=13,5=1
P 9.32901004 5.98761998 4 P 0 0;3=13,5=1
P 9.37901004 5.98761998 4 P 0 0;3=13,5=1
P 9.42901004 5.98761998 4 P 0 0;3=13,5=1
P 9.47901004 5.98761998 4 P 0 0;3=13,5=1
P 9.52901004 5.98761998 4 P 0 0;3=13,5=1
P 9.57901004 5.98761998 4 P 0 0;3=13,5=1
P 9.62901004 5.98761998 4 P 0 0;3=13,5=1
P 9.67901004 5.98761998 4 P 0 0;3=13,5=1
P 9.72901004 5.98761998 4 P 0 0;3=13,5=1
P 9.77901004 5.98761998 4 P 0 0;3=13,5=1
P 9.82901004 5.98761998 4 P 0 0;3=13,5=1
P 9.87901004 5.98761998 4 P 0 0;3=13,5=1
P 9.92901004 5.98761998 4 P 0 0;3=13,5=1
P 9.97901004 5.98761998 4 P 0 0;3=13,5=1
P 10.02901004 5.98761998 4 P 0 0;3=13,5=1
P 10.07901004 5.98761998 4 P 0 0;3=13,5=1
P 10.12901004 5.98761998 4 P 0 0;3=13,5=1
P 10.17901004 5.98761998 4 P 0 0;3=13,5=1
P 10.22901004 5.98761998 4 P 0 0;3=13,5=1
P 10.27901004 5.98761998 4 P 0 0;3=13,5=1
P 10.32901004 5.98761998 4 P 0 0;3=13,5=1
P 10.37901004 5.98761998 4 P 0 0;3=13,5=1
P 10.42901004 5.98761998 4 P 0 0;3=13,5=1
P 10.47901004 5.98761998 4 P 0 0;3=13,5=1
P 10.52901004 5.98761998 4 P 0 0;3=13,5=1
P 10.57901004 5.98761998 4 P 0 0;3=13,5=1
P 10.62901004 5.98761998 4 P 0 0;3=13,5=1
P 10.67901004 5.98761998 4 P 0 0;3=13,5=1
P 10.72901004 5.98761998 4 P 0 0;3=13,5=1
P 10.77901004 5.98761998 4 P 0 0;3=13,5=1
P 10.82901004 5.98761998 4 P 0 0;3=13,5=1
P 10.87901004 5.98761998 4 P 0 0;3=13,5=1
P 10.92901004 5.98761998 4 P 0 0;3=13,5=1
P 10.97901004 5.98761998 4 P 0 0;3=13,5=1
P 11.02901004 5.98761998 4 P 0 0;3=13,5=1
P 11.07901004 5.98761998 4 P 0 0;3=13,5=1
P 11.12901004 5.98761998 4 P 0 0;3=13,5=1
P 11.17901004 5.98761998 4 P 0 0;3=13,5=1
P 11.22901004 5.98761998 4 P 0 0;3=13,5=1
P 11.27901004 5.98761998 4 P 0 0;3=13,5=1
P 11.32901004 5.98761998 4 P 0 0;3=13,5=1
P 11.37901004 5.98761998 4 P 0 0;3=13,5=1
P 11.42901004 5.98761998 4 P 0 0;3=13,5=1
P 11.47901004 5.98761998 4 P 0 0;3=13,5=1
P 11.52901004 5.98761998 4 P 0 0;3=13,5=1
P 11.57901004 5.98761998 4 P 0 0;3=13,5=1
P 11.62901004 5.98761998 4 P 0 0;3=13,5=1
P 11.67901004 5.98761998 4 P 0 0;3=13,5=1
P 11.72901004 5.98761998 4 P 0 0;3=13,5=1
P 11.77901004 5.98761998 4 P 0 0;3=13,5=1
P 11.82901004 5.98761998 4 P 0 0;3=13,5=1
P 11.87901004 5.98761998 4 P 0 0;3=13,5=1
P 11.92901004 5.98761998 4 P 0 0;3=13,5=1
P 11.97901004 5.98761998 4 P 0 0;3=13,5=1
P 12.02901004 5.98761998 4 P 0 0;3=13,5=1
P 12.07901004 5.98761998 4 P 0 0;3=13,5=1
P 12.12901004 5.98761998 4 P 0 0;3=13,5=1
P 12.17901004 5.98761998 4 P 0 0;3=13,5=1
P 12.22901004 5.98761998 4 P 0 0;3=13,5=1
P 12.27901004 5.98761998 4 P 0 0;3=13,5=1
P 12.32901004 5.98761998 4 P 0 0;3=13,5=1
P 12.37901004 5.98761998 4 P 0 0;3=13,5=1
P 12.42901004 5.98761998 4 P 0 0;3=13,5=1
P 12.47901004 5.98761998 4 P 0 0;3=13,5=1
P 12.52901004 5.98761998 4 P 0 0;3=13,5=1
P 12.57901004 5.98761998 4 P 0 0;3=13,5=1
P 12.62901004 5.98761998 4 P 0 0;3=13,5=1
P 12.67901004 5.98761998 4 P 0 0;3=13,5=1
P 12.72901004 5.98761998 4 P 0 0;3=13,5=1
P 12.77901004 5.98761998 4 P 0 0;3=13,5=1
P 12.82901004 5.98761998 4 P 0 0;3=13,5=1
P 12.87726004 5.97451004 4 P 0 0;3=13,5=1
P 12.8892 5.92596004 4 P 0 0;3=13,5=1
P 12.8892 5.87596004 4 P 0 0;3=13,5=1
P 12.8892 5.82596004 4 P 0 0;3=13,5=1
P 12.8892 5.77596004 4 P 0 0;3=13,5=1
P 4.33605 4.9231 4 P 0 0;3=13,5=1
P 4.38105 4.9231 4 P 0 0;3=13,5=1
P 4.30105 4.9431 4 P 0 0;3=13,5=1
P 4.42105 4.9431 4 P 0 0;3=13,5=1
P 4.46105 4.9431 4 P 0 0;3=13,5=1
P 4.26105 4.9431 4 P 0 0;3=13,5=1
P 4.72605 4.9231 4 P 0 0;3=13,5=1
P 4.65105 4.9431 4 P 0 0;3=13,5=1
P 4.69105 4.9431 4 P 0 0;3=13,5=1
P 4.85105 4.9431 4 P 0 0;3=13,5=1
P 4.81105 4.9431 4 P 0 0;3=13,5=1
P 4.77105 4.9231 4 P 0 0;3=13,5=1
P 4.30105 5.0281 4 P 0 0;3=13,5=1
P 4.30105 5.0731 4 P 0 0;3=13,5=1
P 4.30105 4.9831 4 P 0 0;3=13,5=1
P 4.34105 5.1181 4 P 0 0;3=13,5=1
P 4.38105 5.1181 4 P 0 0;3=13,5=1
P 4.46105 5.1181 4 P 0 0;3=13,5=1
P 4.42105 5.1181 4 P 0 0;3=13,5=1
P 4.42105 4.9831 4 P 0 0;3=13,5=1
P 4.42105 5.0731 4 P 0 0;3=13,5=1
P 4.42105 5.0281 4 P 0 0;3=13,5=1
P 4.46105 4.9831 4 P 0 0;3=13,5=1
P 4.46105 5.0731 4 P 0 0;3=13,5=1
P 4.46105 5.0281 4 P 0 0;3=13,5=1
P 4.26105 5.0281 4 P 0 0;3=13,5=1
P 4.26105 5.0731 4 P 0 0;3=13,5=1
P 4.26105 4.9831 4 P 0 0;3=13,5=1
P 4.73105 5.1181 4 P 0 0;3=13,5=1
P 4.69105 5.1181 4 P 0 0;3=13,5=1
P 4.65105 5.1181 4 P 0 0;3=13,5=1
P 4.65105 4.9831 4 P 0 0;3=13,5=1
P 4.65105 5.0731 4 P 0 0;3=13,5=1
P 4.65105 5.0281 4 P 0 0;3=13,5=1
P 4.69105 4.9831 4 P 0 0;3=13,5=1
P 4.69105 5.0731 4 P 0 0;3=13,5=1
P 4.69105 5.0281 4 P 0 0;3=13,5=1
P 4.85105 5.0281 4 P 0 0;3=13,5=1
P 4.85105 5.0731 4 P 0 0;3=13,5=1
P 4.85105 4.9831 4 P 0 0;3=13,5=1
P 4.81105 5.0281 4 P 0 0;3=13,5=1
P 4.81105 5.0731 4 P 0 0;3=13,5=1
P 4.81105 4.9831 4 P 0 0;3=13,5=1
P 4.81105 5.1181 4 P 0 0;3=13,5=1
P 4.85105 5.1181 4 P 0 0;3=13,5=1
P 4.77105 5.1181 4 P 0 0;3=13,5=1
P 4.30105 5.1181 4 P 0 0;3=13,5=1
P 4.26105 5.1181 4 P 0 0;3=13,5=1
P 4.36305 5.02086004 52 P 0 0;1,3=25,5=0
P 4.75305 5.02086004 52 P 0 0;1,3=25,5=0
P 6.62418996 5.09705 25 P 0 0;1,3=4,5=0
P 6.58968996 5.00562992 34 P 0 0;1,3=19,5=0
P 6.60543996 5.00562992 34 P 0 0;1,3=19,5=0
P 9.45795 0.36633002 4 P 0 0;3=13,5=1
P 6.62 4.645 4 P 0 0;3=13,5=1
P 6.62 4.61 4 P 0 0;3=13,5=1
P 6.605 4.77 4 P 0 0;3=13,5=1
P 6.315 4.9 4 P 0 0;3=13,5=1
P 6.315 4.865 4 P 0 0;3=13,5=1
P 6.315 4.82 4 P 0 0;3=13,5=1
P 6.315 4.785 4 P 0 0;3=13,5=1
P 6.315 4.705 4 P 0 0;3=13,5=1
P 6.315 4.74 4 P 0 0;3=13,5=1
P 6.315 4.66 4 P 0 0;3=13,5=1
P 6.315 4.625 4 P 0 0;3=13,5=1
P 6.837 5 25 P 0 0;1,3=4,5=0
P 1.51673002 5.78 4 P 0 0;3=13,5=1
P 1.12303002 5.46016004 4 P 0 0;3=13,5=1
P 1.20176998 5.46016004 4 P 0 0;3=13,5=1
P 1.51673002 5.46016004 4 P 0 0;3=13,5=1
P 1.36 5.355 4 P 0 0;3=13,5=1
P 1.41 5.355 4 P 0 0;3=13,5=1
P 1.46 5.355 4 P 0 0;3=13,5=1
P 1.305 5.885 4 P 0 0;3=13,5=1
P 1.355 5.885 4 P 0 0;3=13,5=1
P 1.405 5.885 4 P 0 0;3=13,5=1
P 1.455 5.885 4 P 0 0;3=13,5=1
P 0.705 5.355 4 P 0 0;3=13,5=1
P 0.7 5.267 1 P 0 0;3=0,5=1
P 0.73 5.175 4 P 0 0;3=13,5=1
P 1.03 5.065 4 P 0 0;3=13,5=1
P 1.28051004 5.46016004 4 P 0 0;3=13,5=1
P 12.215 4.915 4 P 0 0;3=13,5=1
P 12.055 4.915 4 P 0 0;3=13,5=1
P 10.465 5.245 4 P 0 0;3=13,5=1
P 10.465 5.165 4 P 0 0;3=13,5=1
P 11.7719 4.80998996 4 P 0 0;3=13,5=1
P 11.7719 4.85498996 4 P 0 0;3=13,5=1
P 11.7719 4.90498996 4 P 0 0;3=13,5=1
P 11.7719 4.94998996 4 P 0 0;3=13,5=1
P 11.9719 4.94998996 4 P 0 0;3=13,5=1
P 11.9719 4.80998996 4 P 0 0;3=13,5=1
P 11.9719 4.85498996 4 P 0 0;3=13,5=1
P 11.9719 4.90498996 4 P 0 0;3=13,5=1
P 11.9219 4.94998996 4 P 0 0;3=13,5=1
P 11.9219 4.80998996 4 P 0 0;3=13,5=1
P 11.8719 4.94998996 4 P 0 0;3=13,5=1
P 11.8719 4.80998996 4 P 0 0;3=13,5=1
P 11.8219 4.80998996 4 P 0 0;3=13,5=1
P 11.8219 4.94998996 4 P 0 0;3=13,5=1
P 3.81998996 0.7751 25 P 0 0;1,3=4,5=0
P 3.60998996 0.2711 25 P 0 0;1,3=4,5=0
P 9.61795 0.79643002 25 P 0 0;1,3=4,5=0
P 9.40795 0.29243002 25 P 0 0;1,3=4,5=0
P 3.82558996 4.63965 38 P 0 0;1,3=8,5=0
P 11.69316004 2.6635 4 P 0 0;3=13,5=1
P 10.125 2.008 4 P 0 0;3=13,5=1
P 5.53531004 1.6642 4 P 0 0;3=13,5=1
P 5.53531004 1.7213 4 P 0 0;3=13,5=1
P 5.53531004 2.0802 4 P 0 0;3=13,5=1
P 5.53531004 1.9393 4 P 0 0;3=13,5=1
P 5.53531004 2.2156 4 P 0 0;3=13,5=1
P 5.53531004 2.4081 4 P 0 0;3=13,5=1
P 5.53531004 2.5473 4 P 0 0;3=13,5=1
P 2.86855 4.92 4 P 0 0;3=13,5=1
P 2.79768002 4.92 4 P 0 0;3=13,5=1
P 3.08113996 4.92 4 P 0 0;3=13,5=1
P 3.36461004 4.926 4 P 0 0;3=13,5=1
P 3.22288002 4.92 4 P 0 0;3=13,5=1
P 3.50633996 4.92 4 P 0 0;3=13,5=1
P 3.43546998 4.928 4 P 0 0;3=13,5=1
P 3.15398002 4.81401998 4 P 0 0;3=13,5=1
P 3.22288002 4.81401998 4 P 0 0;3=13,5=1
P 3.36461004 4.81401998 4 P 0 0;3=13,5=1
P 3.43546998 4.81401998 4 P 0 0;3=13,5=1
P 3.50633996 4.81401998 4 P 0 0;3=13,5=1
P 3.22288002 5.023 4 P 0 0;3=13,5=1
P 3.50633996 5.023 4 P 0 0;3=13,5=1
P 3.43546998 5.023 4 P 0 0;3=13,5=1
P 3.14 4.92 4 P 0 0;3=13,5=1
P 3.275 4.92 4 P 0 0;3=13,5=1
P 3.26 5.332 4 P 0 0;3=13,5=1
P 3.06791998 5.332 4 P 0 0;3=13,5=1
P 3.51176998 5.17873996 4 P 0 0;3=13,5=1
P 3.57176998 5.17873996 4 P 0 0;3=13,5=1
P 3.15743996 4.74418002 4 P 0 0;3=13,5=1
P 1.63308002 4.92 4 P 0 0;3=13,5=1
P 1.84568002 4.92 4 P 0 0;3=13,5=1
P 1.77481004 4.92 4 P 0 0;3=13,5=1
P 1.70395 4.92 4 P 0 0;3=13,5=1
P 2.12913996 4.92 4 P 0 0;3=13,5=1
P 2.05828002 4.92 4 P 0 0;3=13,5=1
P 1.98741004 4.92 4 P 0 0;3=13,5=1
P 1.91653996 4.92 4 P 0 0;3=13,5=1
P 2.34173996 4.92 4 P 0 0;3=13,5=1
P 2.27086998 4.92 4 P 0 0;3=13,5=1
P 2.20001004 4.926 4 P 0 0;3=13,5=1
P 2.34173996 4.81 4 P 0 0;3=13,5=1
P 2.27086998 4.81 4 P 0 0;3=13,5=1
P 2.20001004 4.81 4 P 0 0;3=13,5=1
P 1.63173002 4.81526998 4 P 0 0;3=13,5=1
P 1.7 4.812 4 P 0 0;3=13,5=1
P 1.84568002 4.81 4 P 0 0;3=13,5=1
P 1.776 4.812 4 P 0 0;3=13,5=1
P 2.12913996 4.81 4 P 0 0;3=13,5=1
P 1.99 4.81 4 P 0 0;3=13,5=1
P 1.92 4.81 4 P 0 0;3=13,5=1
P 2.40716998 5.15373996 4 P 0 0;3=13,5=1
P 2.34716998 5.15373996 4 P 0 0;3=13,5=1
P 10.58661004 2.16615 3 P 0 0;3=12,5=1
P 10.63661004 2.16615 3 P 0 0;3=12,5=1
P 10.63661004 2.21615 3 P 0 0;3=12,5=1
P 10.88661004 1.91615 3 P 0 0;3=12,5=1
P 10.88661004 2.41615 3 P 0 0;3=12,5=1
P 10.88661004 2.66615 3 P 0 0;3=12,5=1
P 11.03661004 2.41615 3 P 0 0;3=12,5=1
P 11.03661004 2.36615 3 P 0 0;3=12,5=1
P 1.91111004 4.61826004 4 P 0 0;3=13,5=1
P 2.40716998 4.70326004 4 P 0 0;3=13,5=1
P 2.945 4.92 4 P 0 0;3=13,5=1
P 3.01028002 4.92 4 P 0 0;3=13,5=1
P 7.78 2.4781 1 P 0 0;3=0,5=1
P 2.24606004 3.86615 3 P 0 0;3=12,5=1
P 2.22106004 3.84115 6 P 0 0;1,3=11,5=0
P 2.49606004 3.86615 3 P 0 0;3=12,5=1
P 2.47106004 3.84115 6 P 0 0;1,3=11,5=0
P 2.24606004 3.81615 3 P 0 0;3=12,5=1
P 2.22106004 3.79115 6 P 0 0;1,3=11,5=0
P 2.19606004 3.76615 3 P 0 0;3=12,5=1
P 2.17106004 3.74115 6 P 0 0;1,3=11,5=0
P 2.24606004 3.76615 3 P 0 0;3=12,5=1
P 2.22106004 3.74115 6 P 0 0;1,3=11,5=0
P 2.29606004 3.76615 3 P 0 0;3=12,5=1
P 2.27106004 3.74115 6 P 0 0;1,3=11,5=0
P 2.49606004 3.71615 3 P 0 0;3=12,5=1
P 2.47106004 3.69115 6 P 0 0;1,3=11,5=0
P 2.49606004 3.56615 3 P 0 0;3=12,5=1
P 2.47106004 3.54115 6 P 0 0;1,3=11,5=0
P 2.44606004 3.56615 3 P 0 0;3=12,5=1
P 2.42106004 3.54115 6 P 0 0;1,3=11,5=0
P 2.39606004 3.56615 3 P 0 0;3=12,5=1
P 2.37106004 3.54115 6 P 0 0;1,3=11,5=0
P 2.29606004 3.61615 3 P 0 0;3=12,5=1
P 2.27106004 3.59115 6 P 0 0;1,3=11,5=0
P 2.24606004 3.71615 3 P 0 0;3=12,5=1
P 2.22106004 3.69115 6 P 0 0;1,3=11,5=0
P 2.24606004 3.66615 3 P 0 0;3=12,5=1
P 2.22106004 3.64115 6 P 0 0;1,3=11,5=0
P 2.24606004 3.61615 3 P 0 0;3=12,5=1
P 2.22106004 3.59115 6 P 0 0;1,3=11,5=0
P 2.19606004 3.61615 3 P 0 0;3=12,5=1
P 2.17106004 3.59115 6 P 0 0;1,3=11,5=0
P 2.19606004 3.56615 3 P 0 0;3=12,5=1
P 2.17106004 3.54115 6 P 0 0;1,3=11,5=0
P 2.14606004 3.56615 3 P 0 0;3=12,5=1
P 2.12106004 3.54115 6 P 0 0;1,3=11,5=0
P 2.04606004 3.56615 3 P 0 0;3=12,5=1
P 2.02106004 3.54115 6 P 0 0;1,3=11,5=0
P 1.99606004 3.56615 3 P 0 0;3=12,5=1
P 2.04606004 3.51615 3 P 0 0;3=12,5=1
P 2.04606004 3.46615 3 P 0 0;3=12,5=1
P 2.19606004 3.51615 3 P 0 0;3=12,5=1
P 2.17106004 3.49115 6 P 0 0;1,3=11,5=0
P 2.24606004 3.51615 3 P 0 0;3=12,5=1
P 2.22106004 3.49115 6 P 0 0;1,3=11,5=0
P 2.29606004 3.51615 3 P 0 0;3=12,5=1
P 2.27106004 3.49115 6 P 0 0;1,3=11,5=0
P 2.49606004 3.41615 3 P 0 0;3=12,5=1
P 2.47106004 3.39115 6 P 0 0;1,3=11,5=0
P 2.44606004 3.36615 3 P 0 0;3=12,5=1
P 2.42106004 3.34115 6 P 0 0;1,3=11,5=0
P 2.24606004 3.46615 3 P 0 0;3=12,5=1
P 2.22106004 3.44115 6 P 0 0;1,3=11,5=0
P 2.24606004 3.41615 3 P 0 0;3=12,5=1
P 2.22106004 3.39115 6 P 0 0;1,3=11,5=0
P 2.29606004 3.36615 3 P 0 0;3=12,5=1
P 2.27106004 3.34115 6 P 0 0;1,3=11,5=0
P 2.24606004 3.36615 3 P 0 0;3=12,5=1
P 2.22106004 3.34115 6 P 0 0;1,3=11,5=0
P 2.19606004 3.36615 3 P 0 0;3=12,5=1
P 2.17106004 3.34115 6 P 0 0;1,3=11,5=0
P 1.99606004 3.41615 3 P 0 0;3=12,5=1
P 2.09606004 3.36615 3 P 0 0;3=12,5=1
P 2.07106004 3.34115 6 P 0 0;1,3=11,5=0
P 2.24606004 3.31615 3 P 0 0;3=12,5=1
P 2.22106004 3.29115 6 P 0 0;1,3=11,5=0
P 2.24606004 3.26615 3 P 0 0;3=12,5=1
P 2.22106004 3.24115 6 P 0 0;1,3=11,5=0
P 2.29606004 3.21615 3 P 0 0;3=12,5=1
P 2.27106004 3.19115 6 P 0 0;1,3=11,5=0
P 2.24606004 3.21615 3 P 0 0;3=12,5=1
P 2.22106004 3.19115 6 P 0 0;1,3=11,5=0
P 2.19606004 3.21615 3 P 0 0;3=12,5=1
P 2.17106004 3.19115 6 P 0 0;1,3=11,5=0
P 2.09606004 3.21615 3 P 0 0;3=12,5=1
P 2.07106004 3.19115 6 P 0 0;1,3=11,5=0
P 2.14606004 3.16615 3 P 0 0;3=12,5=1
P 2.04606004 3.16615 3 P 0 0;3=12,5=1
P 2.24606004 3.16615 3 P 0 0;3=12,5=1
P 2.22106004 3.14115 6 P 0 0;1,3=11,5=0
P 2.29606004 3.16615 3 P 0 0;3=12,5=1
P 2.27106004 3.14115 6 P 0 0;1,3=11,5=0
P 2.34606004 3.21615 3 P 0 0;3=12,5=1
P 2.32106004 3.19115 6 P 0 0;1,3=11,5=0
P 2.44606004 3.21615 3 P 0 0;3=12,5=1
P 2.42106004 3.19115 6 P 0 0;1,3=11,5=0
P 2.49606004 3.21615 3 P 0 0;3=12,5=1
P 2.47106004 3.19115 6 P 0 0;1,3=11,5=0
P 2.49606004 3.26615 3 P 0 0;3=12,5=1
P 2.47106004 3.24115 6 P 0 0;1,3=11,5=0
P 2.49606004 3.16615 3 P 0 0;3=12,5=1
P 2.47106004 3.14115 6 P 0 0;1,3=11,5=0
P 2.39606004 3.16615 3 P 0 0;3=12,5=1
P 2.37106004 3.14115 6 P 0 0;1,3=11,5=0
P 2.29606004 3.06615 3 P 0 0;3=12,5=1
P 2.29606004 3.11615 3 P 0 0;3=12,5=1
P 2.29606004 2.96615 3 P 0 0;3=12,5=1
P 2.29606004 3.01615 3 P 0 0;3=12,5=1
P 2.24606004 3.06615 3 P 0 0;3=12,5=1
P 2.24606004 3.11615 3 P 0 0;3=12,5=1
P 2.24606004 2.96615 3 P 0 0;3=12,5=1
P 2.24606004 3.01615 3 P 0 0;3=12,5=1
P 2.34606004 2.86615 3 P 0 0;3=12,5=1
P 2.34606004 2.91615 3 P 0 0;3=12,5=1
P 2.29606004 2.76615 3 P 0 0;3=12,5=1
P 2.29606004 2.81615 3 P 0 0;3=12,5=1
P 2.24606004 2.76615 3 P 0 0;3=12,5=1
P 2.24606004 2.81615 3 P 0 0;3=12,5=1
P 2.19606004 2.81615 3 P 0 0;3=12,5=1
P 2.09606004 2.81615 3 P 0 0;3=12,5=1
P 2.09606004 2.86615 3 P 0 0;3=12,5=1
P 2.19606004 3.06615 3 P 0 0;3=12,5=1
P 2.14606004 3.01615 3 P 0 0;3=12,5=1
P 2.09606004 3.06615 3 P 0 0;3=12,5=1
P 2.04606004 3.01615 3 P 0 0;3=12,5=1
P 2.09606004 2.91615 3 P 0 0;3=12,5=1
P 2.14606004 2.86615 3 P 0 0;3=12,5=1
P 2.04606004 2.86615 3 P 0 0;3=12,5=1
P 2.19606004 2.91615 3 P 0 0;3=12,5=1
P 2.24606004 2.91615 3 P 0 0;3=12,5=1
P 2.29606004 2.91615 3 P 0 0;3=12,5=1
P 2.39606004 3.01615 3 P 0 0;3=12,5=1
P 2.34606004 3.06615 3 P 0 0;3=12,5=1
P 2.44606004 3.06615 3 P 0 0;3=12,5=1
P 2.49606004 3.01615 3 P 0 0;3=12,5=1
P 2.44606004 2.91615 3 P 0 0;3=12,5=1
P 2.44606004 2.86615 3 P 0 0;3=12,5=1
P 2.39606004 2.86615 3 P 0 0;3=12,5=1
P 2.34606004 2.81615 3 P 0 0;3=12,5=1
P 2.44606004 2.81615 3 P 0 0;3=12,5=1
P 2.49606004 2.86615 3 P 0 0;3=12,5=1
P 2.49606004 2.71615 3 P 0 0;3=12,5=1
P 2.44606004 2.66615 3 P 0 0;3=12,5=1
P 2.39606004 2.71615 3 P 0 0;3=12,5=1
P 2.34606004 2.66615 3 P 0 0;3=12,5=1
P 2.29606004 2.71615 3 P 0 0;3=12,5=1
P 2.29606004 2.66615 3 P 0 0;3=12,5=1
P 2.24606004 2.71615 3 P 0 0;3=12,5=1
P 2.24606004 2.66615 3 P 0 0;3=12,5=1
P 2.19606004 2.66615 3 P 0 0;3=12,5=1
P 2.14606004 2.71615 3 P 0 0;3=12,5=1
P 2.09606004 2.66615 3 P 0 0;3=12,5=1
P 2.04606004 2.71615 3 P 0 0;3=12,5=1
P 2.04606004 2.56615 3 P 0 0;3=12,5=1
P 2.04606004 2.51615 3 P 0 0;3=12,5=1
P 2.04606004 2.46615 3 P 0 0;3=12,5=1
P 2.09606004 2.51615 3 P 0 0;3=12,5=1
P 2.14606004 2.56615 3 P 0 0;3=12,5=1
P 2.24606004 2.61615 3 P 0 0;3=12,5=1
P 2.24606004 2.56615 3 P 0 0;3=12,5=1
P 2.29606004 2.61615 3 P 0 0;3=12,5=1
P 2.29606004 2.56615 3 P 0 0;3=12,5=1
P 2.34606004 2.51615 3 P 0 0;3=12,5=1
P 2.29606004 2.51615 3 P 0 0;3=12,5=1
P 2.24606004 2.51615 3 P 0 0;3=12,5=1
P 2.19606004 2.51615 3 P 0 0;3=12,5=1
P 2.14606004 2.46615 3 P 0 0;3=12,5=1
P 2.24606004 2.46615 3 P 0 0;3=12,5=1
P 2.29606004 2.46615 3 P 0 0;3=12,5=1
P 2.29606004 2.41615 3 P 0 0;3=12,5=1
P 2.24606004 2.41615 3 P 0 0;3=12,5=1
P 2.24606004 2.36615 3 P 0 0;3=12,5=1
P 2.19606004 2.36615 3 P 0 0;3=12,5=1
P 2.29606004 2.36615 3 P 0 0;3=12,5=1
P 2.39606004 2.46615 3 P 0 0;3=12,5=1
P 2.39606004 2.51615 3 P 0 0;3=12,5=1
P 2.39606004 2.56615 3 P 0 0;3=12,5=1
P 2.44606004 2.51615 3 P 0 0;3=12,5=1
P 2.49606004 2.56615 3 P 0 0;3=12,5=1
P 2.49606004 2.51615 3 P 0 0;3=12,5=1
P 2.49606004 2.46615 3 P 0 0;3=12,5=1
P 2.44606004 2.36615 3 P 0 0;3=12,5=1
P 2.49606004 2.31615 3 P 0 0;3=12,5=1
P 2.39606004 2.31615 3 P 0 0;3=12,5=1
P 2.34606004 2.36615 3 P 0 0;3=12,5=1
P 2.29606004 2.31615 3 P 0 0;3=12,5=1
P 2.24606004 2.31615 3 P 0 0;3=12,5=1
P 2.04606004 2.31615 3 P 0 0;3=12,5=1
P 2.04606004 2.16615 3 P 0 0;3=12,5=1
P 2.04606004 2.11615 3 P 0 0;3=12,5=1
P 2.04606004 1.96615 3 P 0 0;3=12,5=1
P 2.09606004 2.01615 3 P 0 0;3=12,5=1
P 2.14606004 1.96615 3 P 0 0;3=12,5=1
P 2.09606004 1.86615 3 P 0 0;3=12,5=1
P 2.19606004 1.86615 3 P 0 0;3=12,5=1
P 2.24606004 1.86615 3 P 0 0;3=12,5=1
P 2.29606004 1.86615 3 P 0 0;3=12,5=1
P 2.34606004 1.86615 3 P 0 0;3=12,5=1
P 2.24606004 1.91615 3 P 0 0;3=12,5=1
P 2.29606004 1.91615 3 P 0 0;3=12,5=1
P 2.24606004 1.96615 3 P 0 0;3=12,5=1
P 2.29606004 1.96615 3 P 0 0;3=12,5=1
P 2.19606004 2.01615 3 P 0 0;3=12,5=1
P 2.24606004 2.01615 3 P 0 0;3=12,5=1
P 2.29606004 2.01615 3 P 0 0;3=12,5=1
P 2.34606004 2.01615 3 P 0 0;3=12,5=1
P 2.39606004 1.96615 3 P 0 0;3=12,5=1
P 2.44606004 2.01615 3 P 0 0;3=12,5=1
P 2.49606004 1.96615 3 P 0 0;3=12,5=1
P 2.44606004 1.86615 3 P 0 0;3=12,5=1
P 2.49606004 2.11615 3 P 0 0;3=12,5=1
P 2.44606004 2.16615 3 P 0 0;3=12,5=1
P 2.49606004 2.16615 3 P 0 0;3=12,5=1
P 2.44606004 2.21615 3 P 0 0;3=12,5=1
P 2.39606004 2.16615 3 P 0 0;3=12,5=1
P 2.39606004 2.11615 3 P 0 0;3=12,5=1
P 2.34606004 2.16615 3 P 0 0;3=12,5=1
P 2.34606004 2.21615 3 P 0 0;3=12,5=1
P 2.29606004 2.21615 3 P 0 0;3=12,5=1
P 2.29606004 2.16615 3 P 0 0;3=12,5=1
P 2.29606004 2.06615 3 P 0 0;3=12,5=1
P 2.29606004 2.11615 3 P 0 0;3=12,5=1
P 2.24606004 2.11615 3 P 0 0;3=12,5=1
P 2.24606004 2.16615 3 P 0 0;3=12,5=1
P 2.24606004 2.06615 3 P 0 0;3=12,5=1
P 2.24606004 2.21615 3 P 0 0;3=12,5=1
P 2.29606004 2.26615 3 P 0 0;3=12,5=1
P 2.24606004 2.26615 3 P 0 0;3=12,5=1
P 2.19606004 2.21615 3 P 0 0;3=12,5=1
P 2.19606004 2.16615 3 P 0 0;3=12,5=1
P 2.14606004 2.11615 3 P 0 0;3=12,5=1
P 2.14606004 2.16615 3 P 0 0;3=12,5=1
P 2.09606004 2.21615 3 P 0 0;3=12,5=1
P 2.09606004 2.16615 3 P 0 0;3=12,5=1
P 2.09606004 2.36615 3 P 0 0;3=12,5=1
P 2.14606004 2.31615 3 P 0 0;3=12,5=1
P 1.99606004 2.71615 3 P 0 0;3=12,5=1
P 1.99606004 2.86615 3 P 0 0;3=12,5=1
P 2.04606004 2.81615 3 P 0 0;3=12,5=1
P 2.04606004 2.76615 3 P 0 0;3=12,5=1
P 3.29373996 5.023 4 P 0 0;3=13,5=1
P 2.14606004 3.26615 3 P 0 0;3=12,5=1
P 2.12106004 3.24115 6 P 0 0;1,3=11,5=0
P 2.04606004 3.26615 3 P 0 0;3=12,5=1
P 2.02106004 3.24115 6 P 0 0;1,3=11,5=0
P 2.04606004 3.21615 3 P 0 0;3=12,5=1
P 2.02106004 3.19115 6 P 0 0;1,3=11,5=0
P 2.14606004 3.21615 3 P 0 0;3=12,5=1
P 2.12106004 3.19115 6 P 0 0;1,3=11,5=0
P 2.39606004 3.21615 3 P 0 0;3=12,5=1
P 2.37106004 3.19115 6 P 0 0;1,3=11,5=0
P 2.39606004 3.26615 3 P 0 0;3=12,5=1
P 2.37106004 3.24115 6 P 0 0;1,3=11,5=0
P 2.29606004 3.26615 3 P 0 0;3=12,5=1
P 2.27106004 3.24115 6 P 0 0;1,3=11,5=0
P 2.29606004 3.31615 3 P 0 0;3=12,5=1
P 2.27106004 3.29115 6 P 0 0;1,3=11,5=0
P 2.34606004 3.36615 3 P 0 0;3=12,5=1
P 2.32106004 3.34115 6 P 0 0;1,3=11,5=0
P 2.14606004 3.41615 3 P 0 0;3=12,5=1
P 2.12106004 3.39115 6 P 0 0;1,3=11,5=0
P 2.09606004 3.61615 3 P 0 0;3=12,5=1
P 2.07106004 3.59115 6 P 0 0;1,3=11,5=0
P 2.29606004 3.46615 3 P 0 0;3=12,5=1
P 2.27106004 3.44115 6 P 0 0;1,3=11,5=0
P 2.29606004 3.41615 3 P 0 0;3=12,5=1
P 2.27106004 3.39115 6 P 0 0;1,3=11,5=0
P 2.39606004 3.41615 3 P 0 0;3=12,5=1
P 2.37106004 3.39115 6 P 0 0;1,3=11,5=0
P 2.34606004 3.51615 3 P 0 0;3=12,5=1
P 2.32106004 3.49115 6 P 0 0;1,3=11,5=0
P 2.34606004 3.61615 3 P 0 0;3=12,5=1
P 2.32106004 3.59115 6 P 0 0;1,3=11,5=0
P 2.34606004 3.56615 3 P 0 0;3=12,5=1
P 2.32106004 3.54115 6 P 0 0;1,3=11,5=0
P 2.44606004 3.51615 3 P 0 0;3=12,5=1
P 2.42106004 3.49115 6 P 0 0;1,3=11,5=0
P 2.44606004 3.61615 3 P 0 0;3=12,5=1
P 2.42106004 3.59115 6 P 0 0;1,3=11,5=0
P 2.14606004 3.71615 3 P 0 0;3=12,5=1
P 2.12106004 3.69115 6 P 0 0;1,3=11,5=0
P 2.04606004 3.71615 3 P 0 0;3=12,5=1
P 2.02106004 3.69115 6 P 0 0;1,3=11,5=0
P 2.09606004 3.76615 3 P 0 0;3=12,5=1
P 2.07106004 3.74115 6 P 0 0;1,3=11,5=0
P 2.14606004 3.86615 3 P 0 0;3=12,5=1
P 2.12106004 3.84115 6 P 0 0;1,3=11,5=0
P 2.04606004 3.86615 3 P 0 0;3=12,5=1
P 2.02106004 3.84115 6 P 0 0;1,3=11,5=0
P 2.29606004 3.71615 3 P 0 0;3=12,5=1
P 2.27106004 3.69115 6 P 0 0;1,3=11,5=0
P 2.29606004 3.66615 3 P 0 0;3=12,5=1
P 2.27106004 3.64115 6 P 0 0;1,3=11,5=0
P 2.39606004 3.71615 3 P 0 0;3=12,5=1
P 2.37106004 3.69115 6 P 0 0;1,3=11,5=0
P 2.34606004 3.76615 3 P 0 0;3=12,5=1
P 2.32106004 3.74115 6 P 0 0;1,3=11,5=0
P 2.29606004 3.81615 3 P 0 0;3=12,5=1
P 2.27106004 3.79115 6 P 0 0;1,3=11,5=0
P 2.39606004 3.86615 3 P 0 0;3=12,5=1
P 2.37106004 3.84115 6 P 0 0;1,3=11,5=0
P 2.29606004 3.86615 3 P 0 0;3=12,5=1
P 2.27106004 3.84115 6 P 0 0;1,3=11,5=0
P 2.44606004 3.76615 3 P 0 0;3=12,5=1
P 2.42106004 3.74115 6 P 0 0;1,3=11,5=0
P 2.17106004 2.84115 6 P 0 0;1,3=11,5=0
P 2.19606004 2.86615 3 P 0 0;3=12,5=1
P 3.36461004 5.023 4 P 0 0;3=13,5=1
P 3.29373996 4.81401998 4 P 0 0;3=13,5=1
P 3.01028002 4.81401998 4 P 0 0;3=13,5=1
P 2.94141004 4.81401998 4 P 0 0;3=13,5=1
P 2.86555 4.81401998 4 P 0 0;3=13,5=1
P 2.79768002 4.81401998 4 P 0 0;3=13,5=1
P 3.15201004 5.023 4 P 0 0;3=13,5=1
P 3.08113996 5.023 4 P 0 0;3=13,5=1
P 3.01028002 5.023 4 P 0 0;3=13,5=1
P 2.93941004 5.023 4 P 0 0;3=13,5=1
P 2.86855 5.023 4 P 0 0;3=13,5=1
P 2.79768002 5.023 4 P 0 0;3=13,5=1
P 1.70395 5.023 4 P 0 0;3=13,5=1
P 1.63308002 5.023 4 P 0 0;3=13,5=1
P 1.77481004 5.023 4 P 0 0;3=13,5=1
P 1.91653996 5.023 4 P 0 0;3=13,5=1
P 1.84568002 5.023 4 P 0 0;3=13,5=1
P 1.98741004 5.023 4 P 0 0;3=13,5=1
P 2.05828002 5.023 4 P 0 0;3=13,5=1
P 2.12913996 5.023 4 P 0 0;3=13,5=1
P 2.20001004 5.023 4 P 0 0;3=13,5=1
P 2.27086998 5.023 4 P 0 0;3=13,5=1
P 2.34173996 5.023 4 P 0 0;3=13,5=1
P 1.56221004 5.023 4 P 0 0;3=13,5=1
P 1.56221004 4.81401998 4 P 0 0;3=13,5=1
P 2.06086998 4.81 4 P 0 0;3=13,5=1
P 2.41261004 5.023 4 P 0 0;3=13,5=1
P 2.41261004 4.81401998 4 P 0 0;3=13,5=1
P 2.72681004 5.023 4 P 0 0;3=13,5=1
P 2.72681004 4.81401998 4 P 0 0;3=13,5=1
P 3.57721004 4.81401998 4 P 0 0;3=13,5=1
P 3.57721004 5.023 4 P 0 0;3=13,5=1
P 4.88268002 1.91615 3 P 0 0;3=12,5=1
P 4.78268002 1.91615 3 P 0 0;3=12,5=1
P 5.03268002 2.36615 3 P 0 0;3=12,5=1
P 5.03268002 2.41615 3 P 0 0;3=12,5=1
P 4.88268002 3.66615 3 P 0 0;3=12,5=1
P 4.83268002 3.66615 3 P 0 0;3=12,5=1
P 5.03268002 3.66615 3 P 0 0;3=12,5=1
P 4.93268002 3.66615 3 P 0 0;3=12,5=1
P 4.98268002 3.66615 3 P 0 0;3=12,5=1
P 4.88268002 3.51615 3 P 0 0;3=12,5=1
P 4.83268002 3.51615 3 P 0 0;3=12,5=1
P 5.03268002 3.51615 3 P 0 0;3=12,5=1
P 4.93268002 3.51615 3 P 0 0;3=12,5=1
P 4.98268002 3.51615 3 P 0 0;3=12,5=1
P 4.88268002 3.81615 3 P 0 0;3=12,5=1
P 4.83268002 3.81615 3 P 0 0;3=12,5=1
P 4.93268002 3.81615 3 P 0 0;3=12,5=1
P 4.98268002 3.81615 3 P 0 0;3=12,5=1
P 4.88268002 3.36615 3 P 0 0;3=12,5=1
P 4.83268002 3.36615 3 P 0 0;3=12,5=1
P 5.03268002 3.36615 3 P 0 0;3=12,5=1
P 4.93268002 3.36615 3 P 0 0;3=12,5=1
P 4.98268002 3.36615 3 P 0 0;3=12,5=1
P 4.83268002 3.21615 3 P 0 0;3=12,5=1
P 4.88268002 3.21615 3 P 0 0;3=12,5=1
P 4.98268002 3.21615 3 P 0 0;3=12,5=1
P 4.93268002 3.21615 3 P 0 0;3=12,5=1
P 5.03268002 3.21615 3 P 0 0;3=12,5=1
P 4.83268002 3.06615 3 P 0 0;3=12,5=1
P 4.88268002 3.06615 3 P 0 0;3=12,5=1
P 4.98268002 3.06615 3 P 0 0;3=12,5=1
P 4.93268002 3.06615 3 P 0 0;3=12,5=1
P 5.03268002 3.06615 3 P 0 0;3=12,5=1
P 4.83268002 2.91615 3 P 0 0;3=12,5=1
P 4.88268002 2.91615 3 P 0 0;3=12,5=1
P 4.98268002 2.91615 3 P 0 0;3=12,5=1
P 4.93268002 2.91615 3 P 0 0;3=12,5=1
P 5.03268002 2.91615 3 P 0 0;3=12,5=1
P 4.78268002 2.51615 3 P 0 0;3=12,5=1
P 4.73268002 2.51615 3 P 0 0;3=12,5=1
P 4.68268002 2.51615 3 P 0 0;3=12,5=1
P 4.63268002 2.51615 3 P 0 0;3=12,5=1
P 4.58268002 2.51615 3 P 0 0;3=12,5=1
P 4.63268002 2.56615 3 P 0 0;3=12,5=1
P 4.73268002 2.56615 3 P 0 0;3=12,5=1
P 4.78268002 2.56615 3 P 0 0;3=12,5=1
P 4.78268002 2.61615 3 P 0 0;3=12,5=1
P 4.78268002 2.66615 3 P 0 0;3=12,5=1
P 4.68268002 2.66615 3 P 0 0;3=12,5=1
P 4.58268002 2.66615 3 P 0 0;3=12,5=1
P 4.73268002 2.71615 3 P 0 0;3=12,5=1
P 4.63268002 2.71615 3 P 0 0;3=12,5=1
P 4.63268002 2.76615 3 P 0 0;3=12,5=1
P 4.73268002 2.76615 3 P 0 0;3=12,5=1
P 4.78268002 2.76615 3 P 0 0;3=12,5=1
P 4.63268002 2.16615 3 P 0 0;3=12,5=1
P 4.78268002 2.16615 3 P 0 0;3=12,5=1
P 10.63661004 2.91615 3 P 0 0;3=12,5=1
P 10.58661004 2.91615 3 P 0 0;3=12,5=1
P 10.63661004 3.06615 3 P 0 0;3=12,5=1
P 10.58661004 3.06615 3 P 0 0;3=12,5=1
P 10.63661004 3.36615 3 P 0 0;3=12,5=1
P 10.58661004 3.36615 3 P 0 0;3=12,5=1
P 10.63661004 3.21615 3 P 0 0;3=12,5=1
P 10.58661004 3.21615 3 P 0 0;3=12,5=1
P 10.58661004 3.66615 3 P 0 0;3=12,5=1
P 10.63661004 3.51615 3 P 0 0;3=12,5=1
P 10.58661004 3.51615 3 P 0 0;3=12,5=1
P 10.63661004 3.81615 3 P 0 0;3=12,5=1
P 10.63661004 3.66615 3 P 0 0;3=12,5=1
P 10.58661004 3.81615 3 P 0 0;3=12,5=1
P 10.83661004 2.91615 3 P 0 0;3=12,5=1
P 10.78661004 2.91615 3 P 0 0;3=12,5=1
P 10.73661004 2.91615 3 P 0 0;3=12,5=1
P 10.68661004 2.91615 3 P 0 0;3=12,5=1
P 10.88661004 2.91615 3 P 0 0;3=12,5=1
P 10.88661004 3.06615 3 P 0 0;3=12,5=1
P 10.83661004 3.06615 3 P 0 0;3=12,5=1
P 10.78661004 3.06615 3 P 0 0;3=12,5=1
P 10.73661004 3.06615 3 P 0 0;3=12,5=1
P 10.68661004 3.06615 3 P 0 0;3=12,5=1
P 10.88661004 3.21615 3 P 0 0;3=12,5=1
P 10.83661004 3.21615 3 P 0 0;3=12,5=1
P 10.83661004 3.36615 3 P 0 0;3=12,5=1
P 10.88661004 3.36615 3 P 0 0;3=12,5=1
P 10.78661004 3.36615 3 P 0 0;3=12,5=1
P 10.73661004 3.36615 3 P 0 0;3=12,5=1
P 10.78661004 3.21615 3 P 0 0;3=12,5=1
P 10.73661004 3.21615 3 P 0 0;3=12,5=1
P 10.68661004 3.36615 3 P 0 0;3=12,5=1
P 10.68661004 3.21615 3 P 0 0;3=12,5=1
P 10.83661004 3.51615 3 P 0 0;3=12,5=1
P 10.88661004 3.51615 3 P 0 0;3=12,5=1
P 10.83661004 3.66615 3 P 0 0;3=12,5=1
P 10.78661004 3.66615 3 P 0 0;3=12,5=1
P 10.73661004 3.66615 3 P 0 0;3=12,5=1
P 10.68661004 3.66615 3 P 0 0;3=12,5=1
P 10.78661004 3.51615 3 P 0 0;3=12,5=1
P 10.73661004 3.51615 3 P 0 0;3=12,5=1
P 10.68661004 3.51615 3 P 0 0;3=12,5=1
P 10.83661004 3.81615 3 P 0 0;3=12,5=1
P 10.88661004 3.81615 3 P 0 0;3=12,5=1
P 10.88661004 3.66615 3 P 0 0;3=12,5=1
P 10.78661004 3.81615 3 P 0 0;3=12,5=1
P 10.73661004 3.81615 3 P 0 0;3=12,5=1
P 10.68661004 3.81615 3 P 0 0;3=12,5=1
P 11.03661004 2.91615 3 P 0 0;3=12,5=1
P 10.93661004 2.91615 3 P 0 0;3=12,5=1
P 10.98661004 2.91615 3 P 0 0;3=12,5=1
P 11.03661004 3.06615 3 P 0 0;3=12,5=1
P 10.93661004 3.06615 3 P 0 0;3=12,5=1
P 10.98661004 3.06615 3 P 0 0;3=12,5=1
P 11.03661004 3.21615 3 P 0 0;3=12,5=1
P 10.93661004 3.21615 3 P 0 0;3=12,5=1
P 10.98661004 3.21615 3 P 0 0;3=12,5=1
P 10.98661004 3.36615 3 P 0 0;3=12,5=1
P 10.93661004 3.36615 3 P 0 0;3=12,5=1
P 11.03661004 3.36615 3 P 0 0;3=12,5=1
P 10.98661004 3.51615 3 P 0 0;3=12,5=1
P 10.93661004 3.51615 3 P 0 0;3=12,5=1
P 11.03661004 3.51615 3 P 0 0;3=12,5=1
P 10.98661004 3.66615 3 P 0 0;3=12,5=1
P 10.93661004 3.66615 3 P 0 0;3=12,5=1
P 11.03661004 3.66615 3 P 0 0;3=12,5=1
P 10.98661004 3.81615 3 P 0 0;3=12,5=1
P 10.93661004 3.81615 3 P 0 0;3=12,5=1
P 3.07691004 4.81401998 4 P 0 0;3=13,5=1
P 8.1 1.86615 3 P 0 0;3=12,5=1
P 8.15 2.16615 3 P 0 0;3=12,5=1
P 8.15 2.11615 3 P 0 0;3=12,5=1
P 8.15 1.96615 3 P 0 0;3=12,5=1
P 8.1 2.01615 3 P 0 0;3=12,5=1
P 8.05 1.96615 3 P 0 0;3=12,5=1
P 8.05 2.11615 3 P 0 0;3=12,5=1
P 8.05 2.16615 3 P 0 0;3=12,5=1
P 8.15 2.31615 3 P 0 0;3=12,5=1
P 8.1 2.36615 3 P 0 0;3=12,5=1
P 8.1 2.16615 3 P 0 0;3=12,5=1
P 8.1 2.21615 3 P 0 0;3=12,5=1
P 8.05 2.31615 3 P 0 0;3=12,5=1
P 8.15 2.46615 3 P 0 0;3=12,5=1
P 8.15 2.56615 3 P 0 0;3=12,5=1
P 8.1 2.51615 3 P 0 0;3=12,5=1
P 8.05 2.46615 3 P 0 0;3=12,5=1
P 8.05 2.51615 3 P 0 0;3=12,5=1
P 8.05 2.56615 3 P 0 0;3=12,5=1
P 8.1 2.66615 3 P 0 0;3=12,5=1
P 8.05 2.76615 3 P 0 0;3=12,5=1
P 8.05 2.81615 3 P 0 0;3=12,5=1
P 8 2.86615 3 P 0 0;3=12,5=1
P 8 2.71615 3 P 0 0;3=12,5=1
P 8.05 2.71615 3 P 0 0;3=12,5=1
P 8.15 2.71615 3 P 0 0;3=12,5=1
P 8.05 2.86615 3 P 0 0;3=12,5=1
P 8.15 2.86615 3 P 0 0;3=12,5=1
P 8.1 2.91615 3 P 0 0;3=12,5=1
P 8.1 2.86615 3 P 0 0;3=12,5=1
P 8.1 2.81615 3 P 0 0;3=12,5=1
P 8.05 3.01615 3 P 0 0;3=12,5=1
P 8.1 3.06615 3 P 0 0;3=12,5=1
P 8.15 3.01615 3 P 0 0;3=12,5=1
P 8.15 3.16615 3 P 0 0;3=12,5=1
P 8.05 3.16615 3 P 0 0;3=12,5=1
P 8 3.41615 3 P 0 0;3=12,5=1
P 8.05 3.41615 3 P 0 0;3=12,5=1
P 8.1 3.36615 3 P 0 0;3=12,5=1
P 8.1 3.21615 3 P 0 0;3=12,5=1
P 8.15 3.56615 3 P 0 0;3=12,5=1
P 8.05 3.56615 3 P 0 0;3=12,5=1
P 8 3.56615 3 P 0 0;3=12,5=1
P 8.05 3.51615 3 P 0 0;3=12,5=1
P 8.05 3.46615 3 P 0 0;3=12,5=1
P 8.1 3.51615 3 P 0 0;3=12,5=1
P 8.35 1.86615 3 P 0 0;3=12,5=1
P 8.3 1.86615 3 P 0 0;3=12,5=1
P 8.25 1.86615 3 P 0 0;3=12,5=1
P 8.2 1.86615 3 P 0 0;3=12,5=1
P 8.25 2.06615 3 P 0 0;3=12,5=1
P 8.25 2.16615 3 P 0 0;3=12,5=1
P 8.25 2.11615 3 P 0 0;3=12,5=1
P 8.3 2.11615 3 P 0 0;3=12,5=1
P 8.3 2.06615 3 P 0 0;3=12,5=1
P 8.4 2.11615 3 P 0 0;3=12,5=1
P 8.4 2.16615 3 P 0 0;3=12,5=1
P 8.4 1.96615 3 P 0 0;3=12,5=1
P 8.35 2.01615 3 P 0 0;3=12,5=1
P 8.3 2.01615 3 P 0 0;3=12,5=1
P 8.25 2.01615 3 P 0 0;3=12,5=1
P 8.2 2.01615 3 P 0 0;3=12,5=1
P 8.3 1.96615 3 P 0 0;3=12,5=1
P 8.25 1.96615 3 P 0 0;3=12,5=1
P 8.3 1.91615 3 P 0 0;3=12,5=1
P 8.25 1.91615 3 P 0 0;3=12,5=1
P 8.2 2.16615 3 P 0 0;3=12,5=1
P 8.2 2.21615 3 P 0 0;3=12,5=1
P 8.25 2.26615 3 P 0 0;3=12,5=1
P 8.3 2.26615 3 P 0 0;3=12,5=1
P 8.25 2.21615 3 P 0 0;3=12,5=1
P 8.3 2.16615 3 P 0 0;3=12,5=1
P 8.3 2.21615 3 P 0 0;3=12,5=1
P 8.35 2.21615 3 P 0 0;3=12,5=1
P 8.35 2.16615 3 P 0 0;3=12,5=1
P 8.25 2.31615 3 P 0 0;3=12,5=1
P 8.3 2.31615 3 P 0 0;3=12,5=1
P 8.35 2.36615 3 P 0 0;3=12,5=1
P 8.4 2.31615 3 P 0 0;3=12,5=1
P 8.3 2.36615 3 P 0 0;3=12,5=1
P 8.2 2.36615 3 P 0 0;3=12,5=1
P 8.25 2.36615 3 P 0 0;3=12,5=1
P 8.25 2.41615 3 P 0 0;3=12,5=1
P 8.3 2.41615 3 P 0 0;3=12,5=1
P 8.4 2.56615 3 P 0 0;3=12,5=1
P 8.4 2.51615 3 P 0 0;3=12,5=1
P 8.4 2.46615 3 P 0 0;3=12,5=1
P 8.3 2.46615 3 P 0 0;3=12,5=1
P 8.25 2.46615 3 P 0 0;3=12,5=1
P 8.2 2.51615 3 P 0 0;3=12,5=1
P 8.25 2.51615 3 P 0 0;3=12,5=1
P 8.3 2.51615 3 P 0 0;3=12,5=1
P 8.35 2.51615 3 P 0 0;3=12,5=1
P 8.3 2.56615 3 P 0 0;3=12,5=1
P 8.3 2.61615 3 P 0 0;3=12,5=1
P 8.25 2.56615 3 P 0 0;3=12,5=1
P 8.25 2.61615 3 P 0 0;3=12,5=1
P 8.2 2.66615 3 P 0 0;3=12,5=1
P 8.25 2.66615 3 P 0 0;3=12,5=1
P 8.3 2.66615 3 P 0 0;3=12,5=1
P 8.35 2.66615 3 P 0 0;3=12,5=1
P 8.25 2.71615 3 P 0 0;3=12,5=1
P 8.3 2.71615 3 P 0 0;3=12,5=1
P 8.4 2.71615 3 P 0 0;3=12,5=1
P 8.35 2.81615 3 P 0 0;3=12,5=1
P 8.4 2.86615 3 P 0 0;3=12,5=1
P 8.3 2.91615 3 P 0 0;3=12,5=1
P 8.25 2.91615 3 P 0 0;3=12,5=1
P 8.2 2.91615 3 P 0 0;3=12,5=1
P 8.2 2.81615 3 P 0 0;3=12,5=1
P 8.25 2.81615 3 P 0 0;3=12,5=1
P 8.25 2.76615 3 P 0 0;3=12,5=1
P 8.3 2.81615 3 P 0 0;3=12,5=1
P 8.3 2.76615 3 P 0 0;3=12,5=1
P 8.35 2.91615 3 P 0 0;3=12,5=1
P 8.35 2.86615 3 P 0 0;3=12,5=1
P 8.35 3.06615 3 P 0 0;3=12,5=1
P 8.4 3.01615 3 P 0 0;3=12,5=1
P 8.2 3.06615 3 P 0 0;3=12,5=1
P 8.25 3.01615 3 P 0 0;3=12,5=1
P 8.25 2.96615 3 P 0 0;3=12,5=1
P 8.25 3.11615 3 P 0 0;3=12,5=1
P 8.25 3.06615 3 P 0 0;3=12,5=1
P 8.3 3.01615 3 P 0 0;3=12,5=1
P 8.3 2.96615 3 P 0 0;3=12,5=1
P 8.3 3.11615 3 P 0 0;3=12,5=1
P 8.3 3.06615 3 P 0 0;3=12,5=1
P 8.25 3.16615 3 P 0 0;3=12,5=1
P 8.3 3.16615 3 P 0 0;3=12,5=1
P 8.4 3.16615 3 P 0 0;3=12,5=1
P 8.25 3.41615 3 P 0 0;3=12,5=1
P 8.3 3.36615 3 P 0 0;3=12,5=1
P 8.25 3.36615 3 P 0 0;3=12,5=1
P 8.2 3.36615 3 P 0 0;3=12,5=1
P 8.25 3.31615 3 P 0 0;3=12,5=1
P 8.25 3.26615 3 P 0 0;3=12,5=1
P 8.3 3.21615 3 P 0 0;3=12,5=1
P 8.25 3.21615 3 P 0 0;3=12,5=1
P 8.2 3.21615 3 P 0 0;3=12,5=1
P 8.35 3.21615 3 P 0 0;3=12,5=1
P 8.4 3.56615 3 P 0 0;3=12,5=1
P 8.3 3.61615 3 P 0 0;3=12,5=1
P 8.25 3.66615 3 P 0 0;3=12,5=1
P 8.25 3.61615 3 P 0 0;3=12,5=1
P 8.2 3.61615 3 P 0 0;3=12,5=1
P 8.2 3.56615 3 P 0 0;3=12,5=1
P 8.2 3.51615 3 P 0 0;3=12,5=1
P 8.25 3.51615 3 P 0 0;3=12,5=1
P 8.3 3.51615 3 P 0 0;3=12,5=1
P 8.25 3.46615 3 P 0 0;3=12,5=1
P 8.25 3.86615 3 P 0 0;3=12,5=1
P 8.25 3.81615 3 P 0 0;3=12,5=1
P 8.2 3.76615 3 P 0 0;3=12,5=1
P 8.25 3.76615 3 P 0 0;3=12,5=1
P 8.3 3.76615 3 P 0 0;3=12,5=1
P 8.25 3.71615 3 P 0 0;3=12,5=1
P 8.45 1.86615 3 P 0 0;3=12,5=1
P 8.5 2.16615 3 P 0 0;3=12,5=1
P 8.5 2.11615 3 P 0 0;3=12,5=1
P 8.5 1.96615 3 P 0 0;3=12,5=1
P 8.45 2.01615 3 P 0 0;3=12,5=1
P 8.45 2.21615 3 P 0 0;3=12,5=1
P 8.45 2.16615 3 P 0 0;3=12,5=1
P 8.5 2.31615 3 P 0 0;3=12,5=1
P 8.45 2.36615 3 P 0 0;3=12,5=1
P 8.5 2.46615 3 P 0 0;3=12,5=1
P 8.5 2.51615 3 P 0 0;3=12,5=1
P 8.5 2.56615 3 P 0 0;3=12,5=1
P 8.45 2.51615 3 P 0 0;3=12,5=1
P 8.45 2.66615 3 P 0 0;3=12,5=1
P 8.5 2.71615 3 P 0 0;3=12,5=1
P 8.5 2.86615 3 P 0 0;3=12,5=1
P 8.45 2.81615 3 P 0 0;3=12,5=1
P 8.45 2.86615 3 P 0 0;3=12,5=1
P 8.45 2.91615 3 P 0 0;3=12,5=1
P 8.5 3.01615 3 P 0 0;3=12,5=1
P 8.45 3.06615 3 P 0 0;3=12,5=1
P 8.5 3.16615 3 P 0 0;3=12,5=1
P 8.5 3.41615 3 P 0 0;3=12,5=1
P 8.45 3.36615 3 P 0 0;3=12,5=1
P 8.45 3.21615 3 P 0 0;3=12,5=1
P 8.5 3.21615 3 P 0 0;3=12,5=1
P 8.5 3.26615 3 P 0 0;3=12,5=1
P 8.5 3.56615 3 P 0 0;3=12,5=1
P 8.45 3.56615 3 P 0 0;3=12,5=1
P 8.5 3.86615 3 P 0 0;3=12,5=1
P 8.5 3.71615 3 P 0 0;3=12,5=1
P 8.2 2.86615 3 P 0 0;3=12,5=1
P 8.025 3.24115 6 P 0 0;1,3=11,5=0
P 8.05 3.26615 3 P 0 0;3=12,5=1
P 8.05 3.21615 3 P 0 0;3=12,5=1
P 8.275 3.24115 6 P 0 0;1,3=11,5=0
P 8.3 3.26615 3 P 0 0;3=12,5=1
P 8.275 3.29115 6 P 0 0;1,3=11,5=0
P 8.3 3.31615 3 P 0 0;3=12,5=1
P 8.325 3.34115 6 P 0 0;1,3=11,5=0
P 8.35 3.36615 3 P 0 0;3=12,5=1
P 8.125 3.24115 6 P 0 0;1,3=11,5=0
P 8.15 3.26615 3 P 0 0;3=12,5=1
P 8.15 3.21615 3 P 0 0;3=12,5=1
P 8.4 3.21615 3 P 0 0;3=12,5=1
P 8.375 3.24115 6 P 0 0;1,3=11,5=0
P 8.4 3.26615 3 P 0 0;3=12,5=1
P 8.075 3.59115 6 P 0 0;1,3=11,5=0
P 8.1 3.61615 3 P 0 0;3=12,5=1
P 8.275 3.44115 6 P 0 0;1,3=11,5=0
P 8.3 3.46615 3 P 0 0;3=12,5=1
P 8.275 3.39115 6 P 0 0;1,3=11,5=0
P 8.3 3.41615 3 P 0 0;3=12,5=1
P 8.325 3.49115 6 P 0 0;1,3=11,5=0
P 8.35 3.51615 3 P 0 0;3=12,5=1
P 8.325 3.59115 6 P 0 0;1,3=11,5=0
P 8.35 3.61615 3 P 0 0;3=12,5=1
P 8.325 3.54115 6 P 0 0;1,3=11,5=0
P 8.35 3.56615 3 P 0 0;3=12,5=1
P 8.125 3.39115 6 P 0 0;1,3=11,5=0
P 8.15 3.41615 3 P 0 0;3=12,5=1
P 8.425 3.49115 6 P 0 0;1,3=11,5=0
P 8.45 3.51615 3 P 0 0;3=12,5=1
P 8.425 3.59115 6 P 0 0;1,3=11,5=0
P 8.45 3.61615 3 P 0 0;3=12,5=1
P 8.375 3.39115 6 P 0 0;1,3=11,5=0
P 8.4 3.41615 3 P 0 0;3=12,5=1
P 8.025 3.69115 6 P 0 0;1,3=11,5=0
P 8.05 3.71615 3 P 0 0;3=12,5=1
P 8.075 3.74115 6 P 0 0;1,3=11,5=0
P 8.1 3.76615 3 P 0 0;3=12,5=1
P 8.025 3.84115 6 P 0 0;1,3=11,5=0
P 8.05 3.86615 3 P 0 0;3=12,5=1
P 8.275 3.69115 6 P 0 0;1,3=11,5=0
P 8.3 3.71615 3 P 0 0;3=12,5=1
P 8.275 3.64115 6 P 0 0;1,3=11,5=0
P 8.3 3.66615 3 P 0 0;3=12,5=1
P 8.325 3.74115 6 P 0 0;1,3=11,5=0
P 8.35 3.76615 3 P 0 0;3=12,5=1
P 8.275 3.79115 6 P 0 0;1,3=11,5=0
P 8.3 3.81615 3 P 0 0;3=12,5=1
P 8.275 3.84115 6 P 0 0;1,3=11,5=0
P 8.3 3.86615 3 P 0 0;3=12,5=1
P 8.125 3.69115 6 P 0 0;1,3=11,5=0
P 8.15 3.71615 3 P 0 0;3=12,5=1
P 8.125 3.84115 6 P 0 0;1,3=11,5=0
P 8.15 3.86615 3 P 0 0;3=12,5=1
P 8.425 3.74115 6 P 0 0;1,3=11,5=0
P 8.45 3.76615 3 P 0 0;3=12,5=1
P 8.375 3.69115 6 P 0 0;1,3=11,5=0
P 8.4 3.71615 3 P 0 0;3=12,5=1
P 8.375 3.84115 6 P 0 0;1,3=11,5=0
P 8.4 3.86615 3 P 0 0;3=12,5=1
P 3.28831004 4.68073996 4 P 0 0;3=13,5=1
P 3.22831004 4.68073996 4 P 0 0;3=13,5=1
P 3.50091004 4.62573996 4 P 0 0;3=13,5=1
P 3.44091004 4.62573996 4 P 0 0;3=13,5=1
P 7.56575 5.023 4 P 0 0;3=13,5=1
P 7.63661998 5.023 4 P 0 0;3=13,5=1
P 7.84921998 5.023 4 P 0 0;3=13,5=1
P 7.77835 5.023 4 P 0 0;3=13,5=1
P 7.70748996 5.023 4 P 0 0;3=13,5=1
P 7.92008002 5.023 4 P 0 0;3=13,5=1
P 8.06181998 5.023 4 P 0 0;3=13,5=1
P 8.13268002 5.023 4 P 0 0;3=13,5=1
P 7.99095 5.023 4 P 0 0;3=13,5=1
P 8.34528002 5.023 4 P 0 0;3=13,5=1
P 8.27441004 5.023 4 P 0 0;3=13,5=1
P 8.20355 5.023 4 P 0 0;3=13,5=1
P 8.41615 5.023 4 P 0 0;3=13,5=1
P 7.63661998 4.92 4 P 0 0;3=13,5=1
P 7.84921998 4.9207 4 P 0 0;3=13,5=1
P 7.70748996 4.9207 4 P 0 0;3=13,5=1
P 7.77835 4.9207 4 P 0 0;3=13,5=1
P 7.99095 4.9207 4 P 0 0;3=13,5=1
P 7.92008002 4.9207 4 P 0 0;3=13,5=1
P 8.06181998 4.9207 4 P 0 0;3=13,5=1
P 8.13268002 4.9207 4 P 0 0;3=13,5=1
P 8.27441004 4.9207 4 P 0 0;3=13,5=1
P 8.20355 4.9267 4 P 0 0;3=13,5=1
P 8.34528002 4.9207 4 P 0 0;3=13,5=1
P 7.63526998 4.81526998 4 P 0 0;3=13,5=1
P 7.84921998 4.81 4 P 0 0;3=13,5=1
P 7.77953996 4.812 4 P 0 0;3=13,5=1
P 7.70353996 4.812 4 P 0 0;3=13,5=1
P 8.13268002 4.81 4 P 0 0;3=13,5=1
P 8.06441004 4.81 4 P 0 0;3=13,5=1
P 7.99353996 4.81 4 P 0 0;3=13,5=1
P 7.92353996 4.81 4 P 0 0;3=13,5=1
P 8.27441004 4.81 4 P 0 0;3=13,5=1
P 8.34528002 4.81 4 P 0 0;3=13,5=1
P 8.20355 4.81 4 P 0 0;3=13,5=1
P 8.41615 4.81401998 4 P 0 0;3=13,5=1
P 8.86908996 4.81401998 4 P 0 0;3=13,5=1
P 8.73035 4.81401998 4 P 0 0;3=13,5=1
P 8.80121998 4.81401998 4 P 0 0;3=13,5=1
P 8.94495 4.81401998 4 P 0 0;3=13,5=1
P 9.08045 4.81401998 4 P 0 0;3=13,5=1
P 9.01381998 4.81401998 4 P 0 0;3=13,5=1
P 9.36815 4.81401998 4 P 0 0;3=13,5=1
P 9.29728002 4.81401998 4 P 0 0;3=13,5=1
P 9.22641998 4.81401998 4 P 0 0;3=13,5=1
P 9.15751998 4.81401998 4 P 0 0;3=13,5=1
P 9.43901004 4.81401998 4 P 0 0;3=13,5=1
P 9.50988002 4.81401998 4 P 0 0;3=13,5=1
P 9.58075 4.81401998 4 P 0 0;3=13,5=1
P 8.80121998 5.023 4 P 0 0;3=13,5=1
P 8.73035 5.023 4 P 0 0;3=13,5=1
P 8.87208996 5.023 4 P 0 0;3=13,5=1
P 9.08468002 5.023 4 P 0 0;3=13,5=1
P 9.01381998 5.023 4 P 0 0;3=13,5=1
P 8.94295 5.023 4 P 0 0;3=13,5=1
P 8.87208996 4.92 4 P 0 0;3=13,5=1
P 8.80121998 4.92 4 P 0 0;3=13,5=1
P 9.01381998 4.92 4 P 0 0;3=13,5=1
P 9.08468002 4.92 4 P 0 0;3=13,5=1
P 9.22641998 4.92 4 P 0 0;3=13,5=1
P 9.36815 4.926 4 P 0 0;3=13,5=1
P 9.50988002 4.92 4 P 0 0;3=13,5=1
P 9.43901004 4.928 4 P 0 0;3=13,5=1
P 9.36815 5.023 4 P 0 0;3=13,5=1
P 9.29728002 5.023 4 P 0 0;3=13,5=1
P 9.22641998 5.023 4 P 0 0;3=13,5=1
P 9.15555 5.023 4 P 0 0;3=13,5=1
P 9.50988002 5.023 4 P 0 0;3=13,5=1
P 9.43901004 5.023 4 P 0 0;3=13,5=1
P 9.58075 5.023 4 P 0 0;3=13,5=1
P 8.94853996 4.92 4 P 0 0;3=13,5=1
P 9.27853996 4.92 4 P 0 0;3=13,5=1
P 9.14353996 4.92 4 P 0 0;3=13,5=1
P 8.13811004 5.09223996 4 P 0 0;3=13,5=1
P 8.35071004 5.15373996 4 P 0 0;3=13,5=1
P 8.41071004 5.15373996 4 P 0 0;3=13,5=1
P 7.56575 4.81401998 4 P 0 0;3=13,5=1
P 8.88061998 4.70573996 4 P 0 0;3=13,5=1
P 2.37106004 2.59115 6 P 0 0;1,3=11,5=0
P 2.37106004 2.64115 6 P 0 0;1,3=11,5=0
P 2.42106004 2.54115 6 P 0 0;1,3=11,5=0
P 2.42106004 2.59115 6 P 0 0;1,3=11,5=0
P 2.47106004 2.59115 6 P 0 0;1,3=11,5=0
P 2.47106004 2.64115 6 P 0 0;1,3=11,5=0
P 2.32106004 2.69115 6 P 0 0;1,3=11,5=0
P 2.32106004 2.74115 6 P 0 0;1,3=11,5=0
P 2.42106004 2.69115 6 P 0 0;1,3=11,5=0
P 2.42106004 2.74115 6 P 0 0;1,3=11,5=0
P 2.47106004 2.74115 6 P 0 0;1,3=11,5=0
P 2.47106004 2.79115 6 P 0 0;1,3=11,5=0
P 2.37106004 2.74115 6 P 0 0;1,3=11,5=0
P 2.37106004 2.79115 6 P 0 0;1,3=11,5=0
P 2.32106004 2.94115 6 P 0 0;1,3=11,5=0
P 2.32106004 2.99115 6 P 0 0;1,3=11,5=0
P 2.37106004 2.89115 6 P 0 0;1,3=11,5=0
P 2.37106004 2.94115 6 P 0 0;1,3=11,5=0
P 2.47106004 2.89115 6 P 0 0;1,3=11,5=0
P 2.47106004 2.94115 6 P 0 0;1,3=11,5=0
P 2.42106004 2.94115 6 P 0 0;1,3=11,5=0
P 2.42106004 2.99115 6 P 0 0;1,3=11,5=0
P 2.37106004 3.04115 6 P 0 0;1,3=11,5=0
P 2.37106004 3.09115 6 P 0 0;1,3=11,5=0
P 2.47106004 3.04115 6 P 0 0;1,3=11,5=0
P 2.47106004 3.09115 6 P 0 0;1,3=11,5=0
P 2.42106004 3.09115 6 P 0 0;1,3=11,5=0
P 2.42106004 3.14115 6 P 0 0;1,3=11,5=0
P 2.32106004 3.09115 6 P 0 0;1,3=11,5=0
P 2.32106004 3.14115 6 P 0 0;1,3=11,5=0
P 2.32106004 1.94115 6 P 0 0;1,3=11,5=0
P 2.32106004 1.99115 6 P 0 0;1,3=11,5=0
P 2.37106004 1.89115 6 P 0 0;1,3=11,5=0
P 2.37106004 1.94115 6 P 0 0;1,3=11,5=0
P 2.47106004 1.89115 6 P 0 0;1,3=11,5=0
P 2.47106004 1.94115 6 P 0 0;1,3=11,5=0
P 2.42106004 1.94115 6 P 0 0;1,3=11,5=0
P 2.42106004 1.99115 6 P 0 0;1,3=11,5=0
P 2.37106004 2.04115 6 P 0 0;1,3=11,5=0
P 2.37106004 2.09115 6 P 0 0;1,3=11,5=0
P 2.47106004 2.04115 6 P 0 0;1,3=11,5=0
P 2.47106004 2.09115 6 P 0 0;1,3=11,5=0
P 2.42106004 2.09115 6 P 0 0;1,3=11,5=0
P 2.42106004 2.14115 6 P 0 0;1,3=11,5=0
P 2.32106004 2.09115 6 P 0 0;1,3=11,5=0
P 2.32106004 2.14115 6 P 0 0;1,3=11,5=0
P 2.32106004 2.24115 6 P 0 0;1,3=11,5=0
P 2.32106004 2.29115 6 P 0 0;1,3=11,5=0
P 2.37106004 2.19115 6 P 0 0;1,3=11,5=0
P 2.37106004 2.24115 6 P 0 0;1,3=11,5=0
P 2.47106004 2.19115 6 P 0 0;1,3=11,5=0
P 2.47106004 2.24115 6 P 0 0;1,3=11,5=0
P 2.42106004 2.24115 6 P 0 0;1,3=11,5=0
P 2.42106004 2.29115 6 P 0 0;1,3=11,5=0
P 2.37106004 2.34115 6 P 0 0;1,3=11,5=0
P 2.37106004 2.39115 6 P 0 0;1,3=11,5=0
P 2.47106004 2.34115 6 P 0 0;1,3=11,5=0
P 2.47106004 2.39115 6 P 0 0;1,3=11,5=0
P 2.42106004 2.39115 6 P 0 0;1,3=11,5=0
P 2.42106004 2.44115 6 P 0 0;1,3=11,5=0
P 2.32106004 2.39115 6 P 0 0;1,3=11,5=0
P 2.32106004 2.44115 6 P 0 0;1,3=11,5=0
P 2.32106004 2.59115 6 P 0 0;1,3=11,5=0
P 2.32106004 2.54115 6 P 0 0;1,3=11,5=0
P 2.07106004 2.54115 6 P 0 0;1,3=11,5=0
P 2.07106004 2.59115 6 P 0 0;1,3=11,5=0
P 2.17106004 2.54115 6 P 0 0;1,3=11,5=0
P 2.17106004 2.59115 6 P 0 0;1,3=11,5=0
P 2.12106004 2.59115 6 P 0 0;1,3=11,5=0
P 2.12106004 2.64115 6 P 0 0;1,3=11,5=0
P 2.07106004 2.69115 6 P 0 0;1,3=11,5=0
P 2.07106004 2.74115 6 P 0 0;1,3=11,5=0
P 2.17106004 2.69115 6 P 0 0;1,3=11,5=0
P 2.17106004 2.74115 6 P 0 0;1,3=11,5=0
P 2.12106004 2.74115 6 P 0 0;1,3=11,5=0
P 2.12106004 2.79115 6 P 0 0;1,3=11,5=0
P 2.02106004 2.74115 6 P 0 0;1,3=11,5=0
P 2.02106004 2.79115 6 P 0 0;1,3=11,5=0
P 2.02106004 2.89115 6 P 0 0;1,3=11,5=0
P 2.02106004 2.94115 6 P 0 0;1,3=11,5=0
P 2.07106004 2.94115 6 P 0 0;1,3=11,5=0
P 2.07106004 2.99115 6 P 0 0;1,3=11,5=0
P 2.12106004 2.89115 6 P 0 0;1,3=11,5=0
P 2.12106004 2.94115 6 P 0 0;1,3=11,5=0
P 2.17106004 2.94115 6 P 0 0;1,3=11,5=0
P 2.17106004 2.99115 6 P 0 0;1,3=11,5=0
P 2.02106004 3.04115 6 P 0 0;1,3=11,5=0
P 2.02106004 3.09115 6 P 0 0;1,3=11,5=0
P 2.12106004 3.04115 6 P 0 0;1,3=11,5=0
P 2.12106004 3.09115 6 P 0 0;1,3=11,5=0
P 2.17106004 3.09115 6 P 0 0;1,3=11,5=0
P 2.17106004 3.14115 6 P 0 0;1,3=11,5=0
P 2.07106004 3.09115 6 P 0 0;1,3=11,5=0
P 2.07106004 3.14115 6 P 0 0;1,3=11,5=0
P 2.02106004 1.89115 6 P 0 0;1,3=11,5=0
P 2.02106004 1.94115 6 P 0 0;1,3=11,5=0
P 2.07106004 1.94115 6 P 0 0;1,3=11,5=0
P 2.07106004 1.99115 6 P 0 0;1,3=11,5=0
P 2.12106004 1.89115 6 P 0 0;1,3=11,5=0
P 2.12106004 1.94115 6 P 0 0;1,3=11,5=0
P 2.17106004 1.94115 6 P 0 0;1,3=11,5=0
P 2.17106004 1.99115 6 P 0 0;1,3=11,5=0
P 2.02106004 2.04115 6 P 0 0;1,3=11,5=0
P 2.02106004 2.09115 6 P 0 0;1,3=11,5=0
P 2.12106004 2.04115 6 P 0 0;1,3=11,5=0
P 2.12106004 2.09115 6 P 0 0;1,3=11,5=0
P 2.17106004 2.09115 6 P 0 0;1,3=11,5=0
P 2.17106004 2.14115 6 P 0 0;1,3=11,5=0
P 2.07106004 2.09115 6 P 0 0;1,3=11,5=0
P 2.07106004 2.14115 6 P 0 0;1,3=11,5=0
P 2.02106004 2.19115 6 P 0 0;1,3=11,5=0
P 2.02106004 2.24115 6 P 0 0;1,3=11,5=0
P 2.07106004 2.24115 6 P 0 0;1,3=11,5=0
P 2.07106004 2.29115 6 P 0 0;1,3=11,5=0
P 2.12106004 2.19115 6 P 0 0;1,3=11,5=0
P 2.12106004 2.24115 6 P 0 0;1,3=11,5=0
P 2.17106004 2.24115 6 P 0 0;1,3=11,5=0
P 2.17106004 2.29115 6 P 0 0;1,3=11,5=0
P 2.02106004 2.34115 6 P 0 0;1,3=11,5=0
P 2.02106004 2.39115 6 P 0 0;1,3=11,5=0
P 2.12106004 2.34115 6 P 0 0;1,3=11,5=0
P 2.12106004 2.39115 6 P 0 0;1,3=11,5=0
P 2.17106004 2.39115 6 P 0 0;1,3=11,5=0
P 2.17106004 2.44115 6 P 0 0;1,3=11,5=0
P 2.07106004 2.39115 6 P 0 0;1,3=11,5=0
P 2.07106004 2.44115 6 P 0 0;1,3=11,5=0
P 2.02106004 2.64115 6 P 0 0;1,3=11,5=0
P 2.02106004 2.59115 6 P 0 0;1,3=11,5=0
P 8.125 1.89115 6 P 0 0;1,3=11,5=0
P 8.025 1.89115 6 P 0 0;1,3=11,5=0
P 8.075 1.89115 6 P 0 0;1,3=11,5=0
P 8.125 1.94115 6 P 0 0;1,3=11,5=0
P 8.025 1.94115 6 P 0 0;1,3=11,5=0
P 8.075 1.99115 6 P 0 0;1,3=11,5=0
P 8.075 1.94115 6 P 0 0;1,3=11,5=0
P 8.125 2.09115 6 P 0 0;1,3=11,5=0
P 8.125 2.04115 6 P 0 0;1,3=11,5=0
P 8.025 2.09115 6 P 0 0;1,3=11,5=0
P 8.025 2.04115 6 P 0 0;1,3=11,5=0
P 8.075 2.14115 6 P 0 0;1,3=11,5=0
P 8.075 2.09115 6 P 0 0;1,3=11,5=0
P 8.125 2.14115 6 P 0 0;1,3=11,5=0
P 8.125 1.99115 6 P 0 0;1,3=11,5=0
P 8.075 2.04115 6 P 0 0;1,3=11,5=0
P 8.025 1.99115 6 P 0 0;1,3=11,5=0
P 8.025 2.14115 6 P 0 0;1,3=11,5=0
P 8.025 2.19115 6 P 0 0;1,3=11,5=0
P 8.025 2.24115 6 P 0 0;1,3=11,5=0
P 8.125 2.19115 6 P 0 0;1,3=11,5=0
P 8.125 2.24115 6 P 0 0;1,3=11,5=0
P 8.075 2.24115 6 P 0 0;1,3=11,5=0
P 8.075 2.29115 6 P 0 0;1,3=11,5=0
P 8.125 2.34115 6 P 0 0;1,3=11,5=0
P 8.125 2.39115 6 P 0 0;1,3=11,5=0
P 8.025 2.34115 6 P 0 0;1,3=11,5=0
P 8.025 2.39115 6 P 0 0;1,3=11,5=0
P 8.075 2.39115 6 P 0 0;1,3=11,5=0
P 8.125 2.29115 6 P 0 0;1,3=11,5=0
P 8.075 2.34115 6 P 0 0;1,3=11,5=0
P 8.075 2.19115 6 P 0 0;1,3=11,5=0
P 8.025 2.29115 6 P 0 0;1,3=11,5=0
P 8.075 2.44115 6 P 0 0;1,3=11,5=0
P 8.125 2.59115 6 P 0 0;1,3=11,5=0
P 8.125 2.64115 6 P 0 0;1,3=11,5=0
P 8.075 2.54115 6 P 0 0;1,3=11,5=0
P 8.075 2.59115 6 P 0 0;1,3=11,5=0
P 8.025 2.59115 6 P 0 0;1,3=11,5=0
P 8.025 2.64115 6 P 0 0;1,3=11,5=0
P 8.125 2.44115 6 P 0 0;1,3=11,5=0
P 8.125 2.54115 6 P 0 0;1,3=11,5=0
P 8.075 2.49115 6 P 0 0;1,3=11,5=0
P 8.025 2.44115 6 P 0 0;1,3=11,5=0
P 8.025 2.49115 6 P 0 0;1,3=11,5=0
P 8.025 2.54115 6 P 0 0;1,3=11,5=0
P 8.075 2.64115 6 P 0 0;1,3=11,5=0
P 8.025 2.74115 6 P 0 0;1,3=11,5=0
P 8.025 2.79115 6 P 0 0;1,3=11,5=0
P 8.075 2.69115 6 P 0 0;1,3=11,5=0
P 8.075 2.74115 6 P 0 0;1,3=11,5=0
P 8.125 2.74115 6 P 0 0;1,3=11,5=0
P 8.125 2.79115 6 P 0 0;1,3=11,5=0
P 8.025 2.89115 6 P 0 0;1,3=11,5=0
P 8.125 2.89115 6 P 0 0;1,3=11,5=0
P 8.075 2.79115 6 P 0 0;1,3=11,5=0
P 8.075 2.84115 6 P 0 0;1,3=11,5=0
P 8.025 2.84115 6 P 0 0;1,3=11,5=0
P 8.025 2.69115 6 P 0 0;1,3=11,5=0
P 8.125 2.69115 6 P 0 0;1,3=11,5=0
P 8.125 2.84115 6 P 0 0;1,3=11,5=0
P 8.075 2.89115 6 P 0 0;1,3=11,5=0
P 8.025 2.94115 6 P 0 0;1,3=11,5=0
P 8.075 2.99115 6 P 0 0;1,3=11,5=0
P 8.075 2.94115 6 P 0 0;1,3=11,5=0
P 8.125 2.94115 6 P 0 0;1,3=11,5=0
P 8.025 3.04115 6 P 0 0;1,3=11,5=0
P 8.125 3.04115 6 P 0 0;1,3=11,5=0
P 8.125 3.09115 6 P 0 0;1,3=11,5=0
P 8.025 3.09115 6 P 0 0;1,3=11,5=0
P 8.075 3.09115 6 P 0 0;1,3=11,5=0
P 8.075 3.14115 6 P 0 0;1,3=11,5=0
P 8.025 2.99115 6 P 0 0;1,3=11,5=0
P 8.075 3.04115 6 P 0 0;1,3=11,5=0
P 8.125 2.99115 6 P 0 0;1,3=11,5=0
P 8.125 3.14115 6 P 0 0;1,3=11,5=0
P 8.025 3.14115 6 P 0 0;1,3=11,5=0
P 8.125 3.19115 6 P 0 0;1,3=11,5=0
P 8.025 3.19115 6 P 0 0;1,3=11,5=0
P 8.075 3.19115 6 P 0 0;1,3=11,5=0
P 8.375 1.89115 6 P 0 0;1,3=11,5=0
P 8.325 1.89115 6 P 0 0;1,3=11,5=0
P 8.275 1.89115 6 P 0 0;1,3=11,5=0
P 8.225 1.89115 6 P 0 0;1,3=11,5=0
P 8.175 1.89115 6 P 0 0;1,3=11,5=0
P 8.325 2.14115 6 P 0 0;1,3=11,5=0
P 8.325 2.09115 6 P 0 0;1,3=11,5=0
P 8.375 2.09115 6 P 0 0;1,3=11,5=0
P 8.375 2.04115 6 P 0 0;1,3=11,5=0
P 8.375 1.94115 6 P 0 0;1,3=11,5=0
P 8.325 1.99115 6 P 0 0;1,3=11,5=0
P 8.325 1.94115 6 P 0 0;1,3=11,5=0
P 8.175 1.99115 6 P 0 0;1,3=11,5=0
P 8.175 1.94115 6 P 0 0;1,3=11,5=0
P 8.175 2.14115 6 P 0 0;1,3=11,5=0
P 8.175 2.09115 6 P 0 0;1,3=11,5=0
P 8.225 2.09115 6 P 0 0;1,3=11,5=0
P 8.225 2.14115 6 P 0 0;1,3=11,5=0
P 8.275 2.14115 6 P 0 0;1,3=11,5=0
P 8.275 2.09115 6 P 0 0;1,3=11,5=0
P 8.375 2.14115 6 P 0 0;1,3=11,5=0
P 8.375 1.99115 6 P 0 0;1,3=11,5=0
P 8.325 2.04115 6 P 0 0;1,3=11,5=0
P 8.275 2.04115 6 P 0 0;1,3=11,5=0
P 8.225 2.04115 6 P 0 0;1,3=11,5=0
P 8.175 2.04115 6 P 0 0;1,3=11,5=0
P 8.275 1.99115 6 P 0 0;1,3=11,5=0
P 8.225 1.99115 6 P 0 0;1,3=11,5=0
P 8.275 1.94115 6 P 0 0;1,3=11,5=0
P 8.225 1.94115 6 P 0 0;1,3=11,5=0
P 8.325 2.39115 6 P 0 0;1,3=11,5=0
P 8.375 2.34115 6 P 0 0;1,3=11,5=0
P 8.375 2.39115 6 P 0 0;1,3=11,5=0
P 8.375 2.19115 6 P 0 0;1,3=11,5=0
P 8.375 2.24115 6 P 0 0;1,3=11,5=0
P 8.325 2.24115 6 P 0 0;1,3=11,5=0
P 8.325 2.29115 6 P 0 0;1,3=11,5=0
P 8.175 2.24115 6 P 0 0;1,3=11,5=0
P 8.175 2.29115 6 P 0 0;1,3=11,5=0
P 8.175 2.39115 6 P 0 0;1,3=11,5=0
P 8.175 2.19115 6 P 0 0;1,3=11,5=0
P 8.225 2.24115 6 P 0 0;1,3=11,5=0
P 8.275 2.24115 6 P 0 0;1,3=11,5=0
P 8.225 2.19115 6 P 0 0;1,3=11,5=0
P 8.275 2.19115 6 P 0 0;1,3=11,5=0
P 8.325 2.19115 6 P 0 0;1,3=11,5=0
P 8.225 2.29115 6 P 0 0;1,3=11,5=0
P 8.275 2.29115 6 P 0 0;1,3=11,5=0
P 8.325 2.34115 6 P 0 0;1,3=11,5=0
P 8.375 2.29115 6 P 0 0;1,3=11,5=0
P 8.275 2.34115 6 P 0 0;1,3=11,5=0
P 8.175 2.34115 6 P 0 0;1,3=11,5=0
P 8.225 2.34115 6 P 0 0;1,3=11,5=0
P 8.225 2.39115 6 P 0 0;1,3=11,5=0
P 8.275 2.39115 6 P 0 0;1,3=11,5=0
P 8.325 2.44115 6 P 0 0;1,3=11,5=0
P 8.175 2.44115 6 P 0 0;1,3=11,5=0
P 8.175 2.54115 6 P 0 0;1,3=11,5=0
P 8.175 2.59115 6 P 0 0;1,3=11,5=0
P 8.375 2.59115 6 P 0 0;1,3=11,5=0
P 8.375 2.64115 6 P 0 0;1,3=11,5=0
P 8.325 2.54115 6 P 0 0;1,3=11,5=0
P 8.325 2.59115 6 P 0 0;1,3=11,5=0
P 8.375 2.54115 6 P 0 0;1,3=11,5=0
P 8.375 2.49115 6 P 0 0;1,3=11,5=0
P 8.375 2.44115 6 P 0 0;1,3=11,5=0
P 8.275 2.44115 6 P 0 0;1,3=11,5=0
P 8.225 2.44115 6 P 0 0;1,3=11,5=0
P 8.175 2.49115 6 P 0 0;1,3=11,5=0
P 8.225 2.49115 6 P 0 0;1,3=11,5=0
P 8.275 2.49115 6 P 0 0;1,3=11,5=0
P 8.325 2.49115 6 P 0 0;1,3=11,5=0
P 8.275 2.54115 6 P 0 0;1,3=11,5=0
P 8.275 2.59115 6 P 0 0;1,3=11,5=0
P 8.225 2.54115 6 P 0 0;1,3=11,5=0
P 8.225 2.59115 6 P 0 0;1,3=11,5=0
P 8.175 2.64115 6 P 0 0;1,3=11,5=0
P 8.225 2.64115 6 P 0 0;1,3=11,5=0
P 8.275 2.64115 6 P 0 0;1,3=11,5=0
P 8.325 2.64115 6 P 0 0;1,3=11,5=0
P 8.175 2.69115 6 P 0 0;1,3=11,5=0
P 8.175 2.74115 6 P 0 0;1,3=11,5=0
P 8.325 2.69115 6 P 0 0;1,3=11,5=0
P 8.325 2.74115 6 P 0 0;1,3=11,5=0
P 8.375 2.74115 6 P 0 0;1,3=11,5=0
P 8.375 2.79115 6 P 0 0;1,3=11,5=0
P 8.375 2.89115 6 P 0 0;1,3=11,5=0
P 8.175 2.84115 6 P 0 0;1,3=11,5=0
P 8.225 2.69115 6 P 0 0;1,3=11,5=0
P 8.275 2.69115 6 P 0 0;1,3=11,5=0
P 8.375 2.69115 6 P 0 0;1,3=11,5=0
P 8.325 2.79115 6 P 0 0;1,3=11,5=0
P 8.375 2.84115 6 P 0 0;1,3=11,5=0
P 8.275 2.89115 6 P 0 0;1,3=11,5=0
P 8.225 2.89115 6 P 0 0;1,3=11,5=0
P 8.175 2.89115 6 P 0 0;1,3=11,5=0
P 8.175 2.79115 6 P 0 0;1,3=11,5=0
P 8.225 2.79115 6 P 0 0;1,3=11,5=0
P 8.225 2.74115 6 P 0 0;1,3=11,5=0
P 8.275 2.79115 6 P 0 0;1,3=11,5=0
P 8.275 2.74115 6 P 0 0;1,3=11,5=0
P 8.325 2.89115 6 P 0 0;1,3=11,5=0
P 8.325 2.84115 6 P 0 0;1,3=11,5=0
P 8.375 2.94115 6 P 0 0;1,3=11,5=0
P 8.325 2.94115 6 P 0 0;1,3=11,5=0
P 8.325 2.99115 6 P 0 0;1,3=11,5=0
P 8.175 2.94115 6 P 0 0;1,3=11,5=0
P 8.175 2.99115 6 P 0 0;1,3=11,5=0
P 8.375 3.09115 6 P 0 0;1,3=11,5=0
P 8.375 3.04115 6 P 0 0;1,3=11,5=0
P 8.325 3.09115 6 P 0 0;1,3=11,5=0
P 8.325 3.14115 6 P 0 0;1,3=11,5=0
P 8.175 3.09115 6 P 0 0;1,3=11,5=0
P 8.175 3.14115 6 P 0 0;1,3=11,5=0
P 8.325 3.04115 6 P 0 0;1,3=11,5=0
P 8.375 2.99115 6 P 0 0;1,3=11,5=0
P 8.175 3.04115 6 P 0 0;1,3=11,5=0
P 8.225 2.99115 6 P 0 0;1,3=11,5=0
P 8.225 2.94115 6 P 0 0;1,3=11,5=0
P 8.225 3.09115 6 P 0 0;1,3=11,5=0
P 8.225 3.04115 6 P 0 0;1,3=11,5=0
P 8.275 2.99115 6 P 0 0;1,3=11,5=0
P 8.275 2.94115 6 P 0 0;1,3=11,5=0
P 8.275 3.09115 6 P 0 0;1,3=11,5=0
P 8.275 3.04115 6 P 0 0;1,3=11,5=0
P 8.225 3.14115 6 P 0 0;1,3=11,5=0
P 8.275 3.14115 6 P 0 0;1,3=11,5=0
P 8.375 3.14115 6 P 0 0;1,3=11,5=0
P 8.375 3.19115 6 P 0 0;1,3=11,5=0
P 8.275 3.19115 6 P 0 0;1,3=11,5=0
P 8.225 3.19115 6 P 0 0;1,3=11,5=0
P 8.175 3.19115 6 P 0 0;1,3=11,5=0
P 8.325 3.19115 6 P 0 0;1,3=11,5=0
P 8.475 1.89115 6 P 0 0;1,3=11,5=0
P 8.425 1.89115 6 P 0 0;1,3=11,5=0
P 8.475 2.09115 6 P 0 0;1,3=11,5=0
P 8.475 2.04115 6 P 0 0;1,3=11,5=0
P 8.425 2.14115 6 P 0 0;1,3=11,5=0
P 8.425 2.09115 6 P 0 0;1,3=11,5=0
P 8.475 1.94115 6 P 0 0;1,3=11,5=0
P 8.425 1.99115 6 P 0 0;1,3=11,5=0
P 8.425 1.94115 6 P 0 0;1,3=11,5=0
P 8.475 2.14115 6 P 0 0;1,3=11,5=0
P 8.475 1.99115 6 P 0 0;1,3=11,5=0
P 8.425 2.04115 6 P 0 0;1,3=11,5=0
P 8.425 2.39115 6 P 0 0;1,3=11,5=0
P 8.475 2.34115 6 P 0 0;1,3=11,5=0
P 8.475 2.39115 6 P 0 0;1,3=11,5=0
P 8.475 2.19115 6 P 0 0;1,3=11,5=0
P 8.475 2.24115 6 P 0 0;1,3=11,5=0
P 8.425 2.24115 6 P 0 0;1,3=11,5=0
P 8.425 2.29115 6 P 0 0;1,3=11,5=0
P 8.425 2.19115 6 P 0 0;1,3=11,5=0
P 8.475 2.29115 6 P 0 0;1,3=11,5=0
P 8.425 2.34115 6 P 0 0;1,3=11,5=0
P 8.425 2.44115 6 P 0 0;1,3=11,5=0
P 8.475 2.59115 6 P 0 0;1,3=11,5=0
P 8.475 2.64115 6 P 0 0;1,3=11,5=0
P 8.425 2.54115 6 P 0 0;1,3=11,5=0
P 8.425 2.59115 6 P 0 0;1,3=11,5=0
P 8.475 2.44115 6 P 0 0;1,3=11,5=0
P 8.475 2.49115 6 P 0 0;1,3=11,5=0
P 8.475 2.54115 6 P 0 0;1,3=11,5=0
P 8.425 2.49115 6 P 0 0;1,3=11,5=0
P 8.425 2.64115 6 P 0 0;1,3=11,5=0
P 8.425 2.69115 6 P 0 0;1,3=11,5=0
P 8.425 2.74115 6 P 0 0;1,3=11,5=0
P 8.475 2.74115 6 P 0 0;1,3=11,5=0
P 8.475 2.79115 6 P 0 0;1,3=11,5=0
P 8.475 2.89115 6 P 0 0;1,3=11,5=0
P 8.475 2.69115 6 P 0 0;1,3=11,5=0
P 8.475 2.84115 6 P 0 0;1,3=11,5=0
P 8.425 2.79115 6 P 0 0;1,3=11,5=0
P 8.425 2.84115 6 P 0 0;1,3=11,5=0
P 8.425 2.89115 6 P 0 0;1,3=11,5=0
P 8.475 2.94115 6 P 0 0;1,3=11,5=0
P 8.425 2.94115 6 P 0 0;1,3=11,5=0
P 8.425 2.99115 6 P 0 0;1,3=11,5=0
P 8.475 3.04115 6 P 0 0;1,3=11,5=0
P 8.475 3.09115 6 P 0 0;1,3=11,5=0
P 8.425 3.09115 6 P 0 0;1,3=11,5=0
P 8.425 3.14115 6 P 0 0;1,3=11,5=0
P 8.475 2.99115 6 P 0 0;1,3=11,5=0
P 8.425 3.04115 6 P 0 0;1,3=11,5=0
P 8.475 3.14115 6 P 0 0;1,3=11,5=0
P 8.425 3.19115 6 P 0 0;1,3=11,5=0
P 8.475 3.19115 6 P 0 0;1,3=11,5=0
P 1.79843002 4.97913996 37 P 0 0;1,3=1,5=0
P 1.75118996 4.85788002 37 P 0 0;1,3=1,5=0
P 1.72756998 4.85788002 37 P 0 0;1,3=1,5=0
P 1.75118996 4.97913996 37 P 0 0;1,3=1,5=0
P 1.82206004 4.97913996 37 P 0 0;1,3=1,5=0
P 1.72756998 4.97913996 37 P 0 0;1,3=1,5=0
P 2.22363002 4.97913996 37 P 0 0;1,3=1,5=0
P 2.17638996 4.85788002 37 P 0 0;1,3=1,5=0
P 2.15276004 4.85788002 37 P 0 0;1,3=1,5=0
P 2.31811998 4.97913996 37 P 0 0;1,3=1,5=0
P 2.2945 4.97913996 37 P 0 0;1,3=1,5=0
P 2.24725 4.97913996 37 P 0 0;1,3=1,5=0
P 2.41261004 4.97913996 37 P 0 0;1,3=1,5=0
P 2.34173996 4.97913996 37 P 0 0;1,3=1,5=0
P 2.27086998 4.97913996 37 P 0 0;1,3=1,5=0
P 2.20001004 4.97913996 37 P 0 0;1,3=1,5=0
P 2.12913996 4.97913996 37 P 0 0;1,3=1,5=0
P 2.05828002 4.97913996 37 P 0 0;1,3=1,5=0
P 1.98741004 4.97913996 37 P 0 0;1,3=1,5=0
P 1.91653996 4.97913996 37 P 0 0;1,3=1,5=0
P 1.84568002 4.97913996 37 P 0 0;1,3=1,5=0
P 1.77481004 4.97913996 37 P 0 0;1,3=1,5=0
P 1.70395 4.97913996 37 P 0 0;1,3=1,5=0
P 1.63308002 4.97913996 37 P 0 0;1,3=1,5=0
P 1.56221004 4.97913996 37 P 0 0;1,3=1,5=0
P 2.41261004 4.85788002 37 P 0 0;1,3=1,5=0
P 2.34173996 4.85788002 37 P 0 0;1,3=1,5=0
P 2.27086998 4.85788002 37 P 0 0;1,3=1,5=0
P 2.20001004 4.85788002 37 P 0 0;1,3=1,5=0
P 2.12913996 4.85788002 37 P 0 0;1,3=1,5=0
P 2.05828002 4.85788002 37 P 0 0;1,3=1,5=0
P 1.98741004 4.85788002 37 P 0 0;1,3=1,5=0
P 1.91653996 4.85788002 37 P 0 0;1,3=1,5=0
P 1.84568002 4.85788002 37 P 0 0;1,3=1,5=0
P 1.77481004 4.85788002 37 P 0 0;1,3=1,5=0
P 1.70395 4.85788002 37 P 0 0;1,3=1,5=0
P 1.63308002 4.85788002 37 P 0 0;1,3=1,5=0
P 1.56221004 4.85788002 37 P 0 0;1,3=1,5=0
P 2.45985 4.77875 9 P 0 0;3=31,5=0
P 1.51496998 4.77875 9 P 0 0;3=31,5=0
P 2.44016998 5.05826998 9 P 0 0;3=31,5=0
P 1.53465 5.05826998 9 P 0 0;3=31,5=0
P 3.34098996 4.85788002 37 P 0 0;1,3=1,5=0
P 3.31736004 4.85788002 37 P 0 0;1,3=1,5=0
P 3.48271998 4.97913996 37 P 0 0;1,3=1,5=0
P 2.96303002 4.97913996 37 P 0 0;1,3=1,5=0
P 2.91578996 4.85788002 37 P 0 0;1,3=1,5=0
P 2.89216998 4.85788002 37 P 0 0;1,3=1,5=0
P 2.91578996 4.97913996 37 P 0 0;1,3=1,5=0
P 2.89216998 4.97913996 37 P 0 0;1,3=1,5=0
P 2.98666004 4.97913996 37 P 0 0;1,3=1,5=0
P 3.36461004 4.85788002 37 P 0 0;1,3=1,5=0
P 3.29373996 4.85788002 37 P 0 0;1,3=1,5=0
P 3.22288002 4.85788002 37 P 0 0;1,3=1,5=0
P 3.15201004 4.85788002 37 P 0 0;1,3=1,5=0
P 3.08113996 4.85788002 37 P 0 0;1,3=1,5=0
P 3.01028002 4.85788002 37 P 0 0;1,3=1,5=0
P 2.93941004 4.85788002 37 P 0 0;1,3=1,5=0
P 2.86855 4.85788002 37 P 0 0;1,3=1,5=0
P 2.79768002 4.85788002 37 P 0 0;1,3=1,5=0
P 2.72681004 4.85788002 37 P 0 0;1,3=1,5=0
P 3.60476998 4.77875 9 P 0 0;3=31,5=0
P 2.67956998 4.77875 9 P 0 0;3=31,5=0
P 3.60476998 5.05826998 9 P 0 0;3=31,5=0
P 2.69925 5.05826998 9 P 0 0;3=31,5=0
P 3.57721004 4.97913996 37 P 0 0;1,3=1,5=0
P 3.50633996 4.97913996 37 P 0 0;1,3=1,5=0
P 3.43546998 4.97913996 37 P 0 0;1,3=1,5=0
P 3.36461004 4.97913996 37 P 0 0;1,3=1,5=0
P 3.29373996 4.97913996 37 P 0 0;1,3=1,5=0
P 3.22288002 4.97913996 37 P 0 0;1,3=1,5=0
P 3.15201004 4.97913996 37 P 0 0;1,3=1,5=0
P 3.08113996 4.97913996 37 P 0 0;1,3=1,5=0
P 3.01028002 4.97913996 37 P 0 0;1,3=1,5=0
P 2.93941004 4.97913996 37 P 0 0;1,3=1,5=0
P 2.86855 4.97913996 37 P 0 0;1,3=1,5=0
P 2.79768002 4.97913996 37 P 0 0;1,3=1,5=0
P 2.72681004 4.97913996 37 P 0 0;1,3=1,5=0
P 3.57721004 4.85788002 37 P 0 0;1,3=1,5=0
P 3.50633996 4.85788002 37 P 0 0;1,3=1,5=0
P 3.43546998 4.85788002 37 P 0 0;1,3=1,5=0
P 8.25078996 4.97913996 37 P 0 0;1,3=1,5=0
P 8.22716998 4.97913996 37 P 0 0;1,3=1,5=0
P 8.17993002 4.85788002 37 P 0 0;1,3=1,5=0
P 8.1563 4.85788002 37 P 0 0;1,3=1,5=0
P 8.32166004 4.97913996 37 P 0 0;1,3=1,5=0
P 8.29803996 4.97913996 37 P 0 0;1,3=1,5=0
P 7.80196998 4.97913996 37 P 0 0;1,3=1,5=0
P 7.75473002 4.85788002 37 P 0 0;1,3=1,5=0
P 7.73111004 4.85788002 37 P 0 0;1,3=1,5=0
P 7.75473002 4.97913996 37 P 0 0;1,3=1,5=0
P 7.73111004 4.97913996 37 P 0 0;1,3=1,5=0
P 7.8256 4.97913996 37 P 0 0;1,3=1,5=0
P 8.20355 4.85788002 37 P 0 0;1,3=1,5=0
P 8.13268002 4.85788002 37 P 0 0;1,3=1,5=0
P 8.06181998 4.85788002 37 P 0 0;1,3=1,5=0
P 7.99095 4.85788002 37 P 0 0;1,3=1,5=0
P 7.92008002 4.85788002 37 P 0 0;1,3=1,5=0
P 7.84921998 4.85788002 37 P 0 0;1,3=1,5=0
P 7.77835 4.85788002 37 P 0 0;1,3=1,5=0
P 7.70748996 4.85788002 37 P 0 0;1,3=1,5=0
P 7.63661998 4.85788002 37 P 0 0;1,3=1,5=0
P 7.56575 4.85788002 37 P 0 0;1,3=1,5=0
P 8.46338996 4.77875 9 P 0 0;3=31,5=0
P 7.51851004 4.77875 9 P 0 0;3=31,5=0
P 8.44371004 5.05826998 9 P 0 0;3=31,5=0
P 7.53818996 5.05826998 9 P 0 0;3=31,5=0
P 8.41615 4.97913996 37 P 0 0;1,3=1,5=0
P 8.34528002 4.97913996 37 P 0 0;1,3=1,5=0
P 8.27441004 4.97913996 37 P 0 0;1,3=1,5=0
P 8.20355 4.97913996 37 P 0 0;1,3=1,5=0
P 8.13268002 4.97913996 37 P 0 0;1,3=1,5=0
P 8.06181998 4.97913996 37 P 0 0;1,3=1,5=0
P 7.99095 4.97913996 37 P 0 0;1,3=1,5=0
P 7.92008002 4.97913996 37 P 0 0;1,3=1,5=0
P 7.84921998 4.97913996 37 P 0 0;1,3=1,5=0
P 7.77835 4.97913996 37 P 0 0;1,3=1,5=0
P 7.70748996 4.97913996 37 P 0 0;1,3=1,5=0
P 7.63661998 4.97913996 37 P 0 0;1,3=1,5=0
P 7.56575 4.97913996 37 P 0 0;1,3=1,5=0
P 8.41615 4.85788002 37 P 0 0;1,3=1,5=0
P 8.34528002 4.85788002 37 P 0 0;1,3=1,5=0
P 8.27441004 4.85788002 37 P 0 0;1,3=1,5=0
P 9.34453002 4.85788002 37 P 0 0;1,3=1,5=0
P 9.3209 4.85788002 37 P 0 0;1,3=1,5=0
P 9.48626004 4.97913996 37 P 0 0;1,3=1,5=0
P 8.96656998 4.97913996 37 P 0 0;1,3=1,5=0
P 8.91933002 4.85788002 37 P 0 0;1,3=1,5=0
P 8.89571004 4.85788002 37 P 0 0;1,3=1,5=0
P 8.91933002 4.97913996 37 P 0 0;1,3=1,5=0
P 8.89571004 4.97913996 37 P 0 0;1,3=1,5=0
P 8.9902 4.97913996 37 P 0 0;1,3=1,5=0
P 9.36815 4.85788002 37 P 0 0;1,3=1,5=0
P 9.29728002 4.85788002 37 P 0 0;1,3=1,5=0
P 9.22641998 4.85788002 37 P 0 0;1,3=1,5=0
P 9.15555 4.85788002 37 P 0 0;1,3=1,5=0
P 9.08468002 4.85788002 37 P 0 0;1,3=1,5=0
P 9.01381998 4.85788002 37 P 0 0;1,3=1,5=0
P 8.94295 4.85788002 37 P 0 0;1,3=1,5=0
P 8.87208996 4.85788002 37 P 0 0;1,3=1,5=0
P 8.80121998 4.85788002 37 P 0 0;1,3=1,5=0
P 8.73035 4.85788002 37 P 0 0;1,3=1,5=0
P 9.60831004 4.77875 9 P 0 0;3=31,5=0
P 8.68311004 4.77875 9 P 0 0;3=31,5=0
P 9.60831004 5.05826998 9 P 0 0;3=31,5=0
P 8.70278996 5.05826998 9 P 0 0;3=31,5=0
P 9.58075 4.97913996 37 P 0 0;1,3=1,5=0
P 9.50988002 4.97913996 37 P 0 0;1,3=1,5=0
P 9.43901004 4.97913996 37 P 0 0;1,3=1,5=0
P 9.36815 4.97913996 37 P 0 0;1,3=1,5=0
P 9.29728002 4.97913996 37 P 0 0;1,3=1,5=0
P 9.22641998 4.97913996 37 P 0 0;1,3=1,5=0
P 9.15555 4.97913996 37 P 0 0;1,3=1,5=0
P 9.08468002 4.97913996 37 P 0 0;1,3=1,5=0
P 9.01381998 4.97913996 37 P 0 0;1,3=1,5=0
P 8.94295 4.97913996 37 P 0 0;1,3=1,5=0
P 8.87208996 4.97913996 37 P 0 0;1,3=1,5=0
P 8.80121998 4.97913996 37 P 0 0;1,3=1,5=0
P 8.73035 4.97913996 37 P 0 0;1,3=1,5=0
P 9.58075 4.85788002 37 P 0 0;1,3=1,5=0
P 9.50988002 4.85788002 37 P 0 0;1,3=1,5=0
P 9.43901004 4.85788002 37 P 0 0;1,3=1,5=0
P 10.82676998 5.49685 12 P 0 0;3=32,5=0
P 10.99213002 5.49685 12 P 0 0;3=32,5=0
P 11.15748002 5.49685 12 P 0 0;3=32,5=0
P 11.32283996 5.49685 12 P 0 0;3=32,5=0
P 11.48818996 5.49685 12 P 0 0;3=32,5=0
P 11.65353996 5.49685 12 P 0 0;3=32,5=0
P 11.8189 5.49685 12 P 0 0;3=32,5=0
P 11.98425 5.49685 12 P 0 0;3=32,5=0
P 12.14961004 5.49685 30 P 0 0;3=33,5=0
P 10.83661998 1.50786998 22 P 0 0;3=34,5=0
P 10.83661998 1.50788002 22 P 0 0;3=34,5=0
P 8.25 1.50788002 22 P 0 0;3=34,5=0
P 8.25 1.50786998 22 P 0 0;3=34,5=0
P 6.96456998 1.52756004 22 P 0 0;3=34,5=0
P 6.96456998 1.52756004 22 P 0 0;3=34,5=0
P 6.96456998 4.20471998 22 P 0 0;3=34,5=0
P 6.96456998 4.20473002 22 P 0 0;3=34,5=0
P 8.25 4.22441004 22 P 0 0;3=34,5=0
P 8.25 4.22441004 22 P 0 0;3=34,5=0
P 10.83661998 4.22441004 22 P 0 0;3=34,5=0
P 10.83661998 4.22441004 22 P 0 0;3=34,5=0
P 12.12205 4.20471998 22 P 0 0;3=34,5=0
P 12.12205 4.20473002 22 P 0 0;3=34,5=0
P 12.12205 1.52756004 22 P 0 0;3=34,5=0
P 12.12205 1.52756004 22 P 0 0;3=34,5=0
P 8.78543996 2.86613996 40 P 0 0;1,3=35,5=0
P 10.30118002 2.86613996 40 P 0 0;1,3=35,5=0
P 11.99213002 4.20473002 4 P 0 0;3=13,5=0
P 12.03018002 4.11286004 4 P 0 0;3=13,5=0
P 12.03018002 4.2966 4 P 0 0;3=13,5=0
P 12.21391998 4.11286004 4 P 0 0;3=13,5=0
P 12.25196998 4.20473002 4 P 0 0;3=13,5=0
P 12.21391998 4.2966 4 P 0 0;3=13,5=0
P 10.7067 4.22441004 4 P 0 0;3=13,5=0
P 10.74475 4.13253996 4 P 0 0;3=13,5=0
P 10.74475 4.31628002 4 P 0 0;3=13,5=0
P 10.92848996 4.13253996 4 P 0 0;3=13,5=0
P 10.96653996 4.22441004 4 P 0 0;3=13,5=0
P 10.92848996 4.31628002 4 P 0 0;3=13,5=0
P 8.12008002 4.22441004 4 P 0 0;3=13,5=0
P 8.15813002 4.13253996 4 P 0 0;3=13,5=0
P 8.15813002 4.31628002 4 P 0 0;3=13,5=0
P 8.34186998 4.13253996 4 P 0 0;3=13,5=0
P 8.37991998 4.22441004 4 P 0 0;3=13,5=0
P 8.34186998 4.31628002 4 P 0 0;3=13,5=0
P 6.83465 4.20473002 4 P 0 0;3=13,5=0
P 6.8727 4.11286004 4 P 0 0;3=13,5=0
P 6.8727 4.2966 4 P 0 0;3=13,5=0
P 7.05643996 4.11286004 4 P 0 0;3=13,5=0
P 7.09448996 4.20473002 4 P 0 0;3=13,5=0
P 7.05643996 4.2966 4 P 0 0;3=13,5=0
P 6.83465 1.52756004 4 P 0 0;3=13,5=0
P 6.8727 1.43568996 4 P 0 0;3=13,5=0
P 6.8727 1.61943002 4 P 0 0;3=13,5=0
P 7.05643996 1.43568996 4 P 0 0;3=13,5=0
P 7.09448996 1.52756004 4 P 0 0;3=13,5=0
P 7.05643996 1.61943002 4 P 0 0;3=13,5=0
P 8.15813002 1.416 4 P 0 0;3=13,5=0
P 8.12008002 1.50786998 4 P 0 0;3=13,5=0
P 8.15813002 1.59975 4 P 0 0;3=13,5=0
P 8.34186998 1.416 4 P 0 0;3=13,5=0
P 8.34186998 1.59975 4 P 0 0;3=13,5=0
P 8.37991998 1.50786998 4 P 0 0;3=13,5=0
P 10.74475 1.59975 4 P 0 0;3=13,5=0
P 10.92848996 1.59975 4 P 0 0;3=13,5=0
P 10.96653996 1.50786998 4 P 0 0;3=13,5=0
P 10.92848996 1.416 4 P 0 0;3=13,5=0
P 10.74475 1.416 4 P 0 0;3=13,5=0
P 10.7067 1.50786998 4 P 0 0;3=13,5=0
P 12.2126 1.43701004 4 P 0 0;3=13,5=0
P 12.25196998 1.52756004 4 P 0 0;3=13,5=0
P 12.2126 1.61811004 4 P 0 0;3=13,5=0
P 12.0315 1.61811004 4 P 0 0;3=13,5=0
P 11.99213002 1.52756004 4 P 0 0;3=13,5=0
P 12.0315 1.43701004 4 P 0 0;3=13,5=0
P 4.83268002 1.50786998 22 P 0 0;3=34,5=0
P 4.83268002 1.50788002 22 P 0 0;3=34,5=0
P 2.24606004 1.50788002 22 P 0 0;3=34,5=0
P 2.24606004 1.50786998 22 P 0 0;3=34,5=0
P 0.96063002 1.52756004 22 P 0 0;3=34,5=0
P 0.96063002 1.52756004 22 P 0 0;3=34,5=0
P 0.96063002 4.20471998 22 P 0 0;3=34,5=0
P 0.96063002 4.20473002 22 P 0 0;3=34,5=0
P 2.24606004 4.22441004 22 P 0 0;3=34,5=0
P 2.24606004 4.22441004 22 P 0 0;3=34,5=0
P 4.83268002 4.22441004 22 P 0 0;3=34,5=0
P 4.83268002 4.22441004 22 P 0 0;3=34,5=0
P 6.11811004 4.20471998 22 P 0 0;3=34,5=0
P 6.11811004 4.20473002 22 P 0 0;3=34,5=0
P 6.11811004 1.52756004 22 P 0 0;3=34,5=0
P 6.11811004 1.52756004 22 P 0 0;3=34,5=0
P 2.7815 2.86613996 40 P 0 0;1,3=35,5=0
P 4.29723996 2.86613996 40 P 0 0;1,3=35,5=0
P 5.98818996 4.20473002 4 P 0 0;3=13,5=0
P 6.02623996 4.11286004 4 P 0 0;3=13,5=0
P 6.02623996 4.2966 4 P 0 0;3=13,5=0
P 6.20998002 4.11286004 4 P 0 0;3=13,5=0
P 6.24803002 4.20473002 4 P 0 0;3=13,5=0
P 6.20998002 4.2966 4 P 0 0;3=13,5=0
P 4.70276004 4.22441004 4 P 0 0;3=13,5=0
P 4.74081004 4.13253996 4 P 0 0;3=13,5=0
P 4.74081004 4.31628002 4 P 0 0;3=13,5=0
P 4.92455 4.13253996 4 P 0 0;3=13,5=0
P 4.9626 4.22441004 4 P 0 0;3=13,5=0
P 4.92455 4.31628002 4 P 0 0;3=13,5=0
P 2.11613996 4.22441004 4 P 0 0;3=13,5=0
P 2.15418996 4.13253996 4 P 0 0;3=13,5=0
P 2.15418996 4.31628002 4 P 0 0;3=13,5=0
P 2.33793002 4.13253996 4 P 0 0;3=13,5=0
P 2.37598002 4.22441004 4 P 0 0;3=13,5=0
P 2.33793002 4.31628002 4 P 0 0;3=13,5=0
P 0.83071004 4.20473002 4 P 0 0;3=13,5=0
P 0.86876004 4.11286004 4 P 0 0;3=13,5=0
P 0.86876004 4.2966 4 P 0 0;3=13,5=0
P 1.0525 4.11286004 4 P 0 0;3=13,5=0
P 1.09055 4.20473002 4 P 0 0;3=13,5=0
P 1.0525 4.2966 4 P 0 0;3=13,5=0
P 0.83071004 1.52756004 4 P 0 0;3=13,5=0
P 0.86876004 1.43568996 4 P 0 0;3=13,5=0
P 0.86876004 1.61943002 4 P 0 0;3=13,5=0
P 1.0525 1.43568996 4 P 0 0;3=13,5=0
P 1.09055 1.52756004 4 P 0 0;3=13,5=0
P 1.0525 1.61943002 4 P 0 0;3=13,5=0
P 2.15418996 1.416 4 P 0 0;3=13,5=0
P 2.11613996 1.50786998 4 P 0 0;3=13,5=0
P 2.15418996 1.59975 4 P 0 0;3=13,5=0
P 2.33793002 1.416 4 P 0 0;3=13,5=0
P 2.33793002 1.59975 4 P 0 0;3=13,5=0
P 2.37598002 1.50786998 4 P 0 0;3=13,5=0
P 4.74081004 1.59975 4 P 0 0;3=13,5=0
P 4.92455 1.59975 4 P 0 0;3=13,5=0
P 4.9626 1.50786998 4 P 0 0;3=13,5=0
P 4.92455 1.416 4 P 0 0;3=13,5=0
P 4.74081004 1.416 4 P 0 0;3=13,5=0
P 4.70276004 1.50786998 4 P 0 0;3=13,5=0
P 6.20866004 1.43701004 4 P 0 0;3=13,5=0
P 6.24803002 1.52756004 4 P 0 0;3=13,5=0
P 6.20866004 1.61811004 4 P 0 0;3=13,5=0
P 6.02756004 1.61811004 4 P 0 0;3=13,5=0
P 5.98818996 1.52756004 4 P 0 0;3=13,5=0
P 6.02756004 1.43701004 4 P 0 0;3=13,5=0
P 12.59646998 0.8189 4 P 0 0;3=13,5=0
P 12.5571 0.72835 4 P 0 0;3=13,5=0
P 12.59646998 0.6378 4 P 0 0;3=13,5=0
P 12.68701998 0.72835 22 P 0 0;3=34,5=0
P 12.77756998 0.6378 4 P 0 0;3=13,5=0
P 12.81693996 0.72835 4 P 0 0;3=13,5=0
P 12.77756998 0.8189 4 P 0 0;3=13,5=0
P 12.68701998 0.72835 22 P 0 0;3=34,5=0
P 12.59646998 5.24803002 4 P 0 0;3=13,5=0
P 12.5571 5.15748002 4 P 0 0;3=13,5=0
P 12.59646998 5.06693002 4 P 0 0;3=13,5=0
P 12.68701998 5.15748002 22 P 0 0;3=34,5=0
P 12.77756998 5.06693002 4 P 0 0;3=13,5=0
P 12.81693996 5.15748002 4 P 0 0;3=13,5=0
P 12.77756998 5.24803002 4 P 0 0;3=13,5=0
P 12.68701998 5.15748002 22 P 0 0;3=34,5=0
P 0.1319 5.20866004 4 P 0 0;3=13,5=0
P 0.09253002 5.11811004 4 P 0 0;3=13,5=0
P 0.1319 5.02756004 4 P 0 0;3=13,5=0
P 0.22245 5.11811004 22 P 0 0;3=34,5=0
P 0.313 5.02756004 4 P 0 0;3=13,5=0
P 0.35236998 5.11811004 4 P 0 0;3=13,5=0
P 0.313 5.20866004 4 P 0 0;3=13,5=0
P 0.22245 5.11811004 22 P 0 0;3=34,5=0
P 0.1319 0.77953002 4 P 0 0;3=13,5=0
P 0.09253002 0.68898002 4 P 0 0;3=13,5=0
P 0.1319 0.59843002 4 P 0 0;3=13,5=0
P 0.22245 0.68898002 22 P 0 0;3=34,5=0
P 0.313 0.59843002 4 P 0 0;3=13,5=0
P 0.35236998 0.68898002 4 P 0 0;3=13,5=0
P 0.313 0.77953002 4 P 0 0;3=13,5=0
P 0.22245 0.68898002 22 P 0 0;3=34,5=0
P 12.04 4.96 29 P 0 0;1,3=21,5=0
P 12.2 4.96 29 P 0 0;1,3=21,5=0
P 12.12 4.993 25 P 0 0;1,3=4,5=0
P 10.51 5.18 29 P 0 0;1,3=21,5=0
P 10.51 5.26 29 P 0 0;1,3=21,5=0
P 10.543 5.32 25 P 0 0;1,3=4,5=0
P 10.80498996 5.56656004 4 P 0 0;3=13,5=1
P 10.84498996 5.56656004 4 P 0 0;3=13,5=1
P 10.80498996 5.42656004 4 P 0 0;3=13,5=1
P 10.84498996 5.42656004 4 P 0 0;3=13,5=1
P 11.01035 5.42656004 4 P 0 0;3=13,5=1
P 10.97035 5.42656004 4 P 0 0;3=13,5=1
P 11.01035 5.56656004 4 P 0 0;3=13,5=1
P 10.97035 5.56656004 4 P 0 0;3=13,5=1
P 11.17571004 5.42656004 4 P 0 0;3=13,5=1
P 11.13571004 5.42656004 4 P 0 0;3=13,5=1
P 11.17571004 5.56656004 4 P 0 0;3=13,5=1
P 11.13571004 5.56656004 4 P 0 0;3=13,5=1
P 11.34106998 5.42656004 4 P 0 0;3=13,5=1
P 11.30106998 5.42656004 4 P 0 0;3=13,5=1
P 11.34106998 5.56656004 4 P 0 0;3=13,5=1
P 11.30106998 5.56656004 4 P 0 0;3=13,5=1
P 11.50643002 5.42656004 4 P 0 0;3=13,5=1
P 11.46643002 5.42656004 4 P 0 0;3=13,5=1
P 11.50643002 5.56656004 4 P 0 0;3=13,5=1
P 11.46643002 5.56656004 4 P 0 0;3=13,5=1
P 11.67178996 5.42656004 4 P 0 0;3=13,5=1
P 11.63178996 5.42656004 4 P 0 0;3=13,5=1
P 11.67178996 5.56656004 4 P 0 0;3=13,5=1
P 11.63178996 5.56656004 4 P 0 0;3=13,5=1
P 11.83715 5.42656004 4 P 0 0;3=13,5=1
P 11.79715 5.42656004 4 P 0 0;3=13,5=1
P 11.83715 5.56656004 4 P 0 0;3=13,5=1
P 11.79715 5.56656004 4 P 0 0;3=13,5=1
P 12.00251004 5.42656004 4 P 0 0;3=13,5=1
P 11.96251004 5.42656004 4 P 0 0;3=13,5=1
P 12.00251004 5.56656004 4 P 0 0;3=13,5=1
P 11.96251004 5.56656004 4 P 0 0;3=13,5=1
P 12.16786998 5.42656004 4 P 0 0;3=13,5=1
P 12.12786998 5.42656004 4 P 0 0;3=13,5=1
P 12.16786998 5.56656004 4 P 0 0;3=13,5=1
P 12.12786998 5.56656004 4 P 0 0;3=13,5=1
P 7.32283996 0.23621998 4 P 0 0;3=13,5=0
P 7.28016998 0.33921998 4 P 0 0;3=13,5=0
P 7.17716998 0.23621998 23 P 0 0;3=36,5=0
P 7.28016998 0.13321998 4 P 0 0;3=13,5=0
P 7.17716998 0.23621998 23 P 0 0;3=36,5=0
P 7.07416998 0.13321998 4 P 0 0;3=13,5=0
P 7.0315 0.23621998 4 P 0 0;3=13,5=0
P 7.07416998 0.33921998 4 P 0 0;3=13,5=0
P 7.32283996 5.7874 4 P 0 0;3=13,5=0
P 7.28016998 5.8904 4 P 0 0;3=13,5=0
P 7.17716998 5.7874 23 P 0 0;3=36,5=0
P 7.28016998 5.6844 4 P 0 0;3=13,5=0
P 7.17716998 5.7874 23 P 0 0;3=36,5=0
P 7.07416998 5.6844 4 P 0 0;3=13,5=0
P 7.0315 5.7874 4 P 0 0;3=13,5=0
P 7.07416998 5.8904 4 P 0 0;3=13,5=0
P 2.22106004 3.54115 6 P 0 0;1,3=11,5=0
P 2.24606004 3.56615 3 P 0 0;3=12,5=1
P 8.2 3.26615 3 P 0 0;3=12,5=1
P 8.175 3.24115 6 P 0 0;1,3=11,5=0
P 7.65203996 5.0535 3 P 0 0;3=12,5=1
P 7.66023996 4.97913996 37 P 0 0;1,3=1,5=0
P 2.27106004 2.84115 6 P 0 0;1,3=11,5=0
P 2.29606004 2.86615 3 P 0 0;3=12,5=1
P 2.27106004 3.54115 6 P 0 0;1,3=11,5=0
P 2.29606004 3.56615 3 P 0 0;3=12,5=1
P 7.68386004 4.97913996 37 P 0 0;1,3=1,5=0
P 7.69203996 5.0535 3 P 0 0;3=12,5=1
P 8.2 3.31615 3 P 0 0;3=12,5=1
P 8.175 3.29115 6 P 0 0;1,3=11,5=0
P 1.33906004 4.69351004 1 P 0 0;3=0,5=1
P 1.30186004 4.79681998 39 P 0 0;1,3=20,5=0
P 1.33906004 4.66551004 25 P 0 0;1,3=4,5=0
P 0.80806998 5.53641998 49 P 0 0;1,3=16,5=0
P 0.83 5.417 25 P 0 0;1,3=4,5=0
P 0.68 5.147 25 P 0 0;1,3=4,5=0
P 0.80806998 5.46193996 1 P 0 0;3=0,5=1
P 3.733 5.075 4 P 0 0;3=13,5=1
P 3.77441004 4.63965 38 P 0 0;1,3=8,5=0
P 1.28906004 4.69351004 1 P 0 0;3=0,5=1
P 1.28906004 4.66551004 25 P 0 0;1,3=4,5=0
P 1.27626004 4.79681998 39 P 0 0;1,3=20,5=0
P 8.2 3.41615 3 P 0 0;3=12,5=1
P 8.175 3.39115 6 P 0 0;1,3=11,5=0
P 7.86465 5.169 3 P 0 0;3=12,5=1
P 7.87283996 4.97913996 37 P 0 0;1,3=1,5=0
P 3.9399 4.79498996 25 P 0 0;1,3=4,5=0
P 3.94 4.765 1 P 0 0;3=0,5=1
P 3.94 4.717 25 P 0 0;1,3=4,5=0
P 3.99965 4.71558996 48 P 0 0;1,3=8,5=0
P 2.34606004 3.26615 3 P 0 0;3=12,5=1
P 2.32106004 3.24115 6 P 0 0;1,3=11,5=0
P 2.39716998 4.742 3 P 0 0;3=12,5=1
P 2.38898002 4.85788002 37 P 0 0;1,3=1,5=0
P 8.2 3.46615 3 P 0 0;3=12,5=1
P 8.175 3.44115 6 P 0 0;1,3=11,5=0
P 7.90465 5.169 3 P 0 0;3=12,5=1
P 7.89646004 4.97913996 37 P 0 0;1,3=1,5=0
P 2.06646004 5.29 1 P 0 0;3=0,5=1
P 2.03465 4.97913996 37 P 0 0;1,3=1,5=0
P 2.34606004 3.31615 3 P 0 0;3=12,5=1
P 2.32106004 3.29115 6 P 0 0;1,3=11,5=0
P 2.35716998 4.742 3 P 0 0;3=12,5=1
P 2.36536004 4.85788002 37 P 0 0;1,3=1,5=0
P 1.33906004 5.15351004 1 P 0 0;3=0,5=1
P 1.33906004 5.12551004 25 P 0 0;1,3=4,5=0
P 3.105 4.47 4 P 0 0;3=13,5=1
P 3.12838996 4.85788002 37 P 0 0;1,3=1,5=0
P 8 3.46615 3 P 0 0;3=12,5=1
P 8.025 3.44115 6 P 0 0;1,3=11,5=0
P 7.93551004 5.0535 3 P 0 0;3=12,5=1
P 7.94371004 4.97913996 37 P 0 0;1,3=1,5=0
P 2.00146004 5.29 1 P 0 0;3=0,5=1
P 2.01103002 4.97913996 37 P 0 0;1,3=1,5=0
P 2.31811998 4.85788002 37 P 0 0;1,3=1,5=0
P 2.25855 4.667 3 P 0 0;3=12,5=1
P 2.37106004 3.29115 6 P 0 0;1,3=11,5=0
P 2.39606004 3.31615 3 P 0 0;3=12,5=1
P 1.18906004 5.12551004 25 P 0 0;1,3=4,5=0
P 1.18906004 5.15351004 1 P 0 0;3=0,5=1
P 3.07 4.42 4 P 0 0;3=13,5=1
P 3.10476998 4.85788002 37 P 0 0;1,3=1,5=0
P 8 3.51615 3 P 0 0;3=12,5=1
P 8.025 3.49115 6 P 0 0;1,3=11,5=0
P 7.97551004 5.0535 3 P 0 0;3=12,5=1
P 7.96733002 4.97913996 37 P 0 0;1,3=1,5=0
P 2.2945 4.85788002 37 P 0 0;1,3=1,5=0
P 2.21855 4.667 3 P 0 0;3=12,5=1
P 2.37106004 3.34115 6 P 0 0;1,3=11,5=0
P 2.39606004 3.36615 3 P 0 0;3=12,5=1
P 8.10906004 4.97913996 37 P 0 0;1,3=1,5=0
P 8.11725 5.169 3 P 0 0;3=12,5=1
P 8.4 3.46615 3 P 0 0;3=12,5=1
P 8.375 3.44115 6 P 0 0;1,3=11,5=0
P 3.60998996 0.62931998 43 P 0 0;1,3=28,5=0
P 3.635 0.715 1 P 0 0;3=0,5=1
P 3.60998996 0.7411 25 P 0 0;1,3=4,5=0
P 4.65768002 2.84115 6 P 0 0;1,3=11,5=0
P 4.63268002 2.81615 3 P 0 0;3=12,5=1
P 2.42106004 3.24115 6 P 0 0;1,3=11,5=0
P 2.44606004 3.26615 3 P 0 0;3=12,5=1
P 2.39716998 5.115 3 P 0 0;3=12,5=1
P 2.38898002 4.97913996 37 P 0 0;1,3=1,5=0
P 8.07725 5.169 3 P 0 0;3=12,5=1
P 8.08543996 4.97913996 37 P 0 0;1,3=1,5=0
P 8.4 3.51615 3 P 0 0;3=12,5=1
P 8.375 3.49115 6 P 0 0;1,3=11,5=0
P 2.42106004 3.29115 6 P 0 0;1,3=11,5=0
P 2.44606004 3.31615 3 P 0 0;3=12,5=1
P 2.35716998 5.115 3 P 0 0;3=12,5=1
P 2.36536004 4.97913996 37 P 0 0;1,3=1,5=0
P 8.475 3.44115 6 P 0 0;1,3=11,5=0
P 8.5 3.46615 3 P 0 0;3=12,5=1
P 8.03818996 4.85788002 37 P 0 0;1,3=1,5=0
P 8.07206998 4.66688996 3 P 0 0;3=12,5=1
P 2.25543996 4.78291998 3 P 0 0;3=12,5=1
P 2.47106004 3.29115 6 P 0 0;1,3=11,5=0
P 2.49606004 3.31615 3 P 0 0;3=12,5=1
P 2.24725 4.85788002 37 P 0 0;1,3=1,5=0
P 8.475 3.49115 6 P 0 0;1,3=11,5=0
P 8.5 3.51615 3 P 0 0;3=12,5=1
P 8.01456998 4.85788002 37 P 0 0;1,3=1,5=0
P 8.03206998 4.66688996 3 P 0 0;3=12,5=1
P 4.03666998 5.18321004 39 P 0 0;1,3=20,5=0
P 4.0599 5.32498996 25 P 0 0;1,3=4,5=0
P 4.02 4.42 1 P 0 0;3=0,5=1
P 4.60768002 2.79115 6 P 0 0;1,3=11,5=0
P 4.58268002 2.76615 3 P 0 0;3=12,5=1
P 2.21543996 4.78291998 3 P 0 0;3=12,5=1
P 2.47106004 3.34115 6 P 0 0;1,3=11,5=0
P 2.49606004 3.36615 3 P 0 0;3=12,5=1
P 2.22363002 4.85788002 37 P 0 0;1,3=1,5=0
P 8.325 3.39115 6 P 0 0;1,3=11,5=0
P 8.35 3.41615 3 P 0 0;3=12,5=1
P 8.10906004 4.85788002 37 P 0 0;1,3=1,5=0
P 8.11725 4.78291998 3 P 0 0;3=12,5=1
P 4.80768002 2.74115 6 P 0 0;1,3=11,5=0
P 4.78268002 2.71615 3 P 0 0;3=12,5=1
P 2.10551998 4.85788002 37 P 0 0;1,3=1,5=0
P 2.11371004 4.78291998 3 P 0 0;3=12,5=1
P 2.34606004 3.41615 3 P 0 0;3=12,5=1
P 2.32106004 3.39115 6 P 0 0;1,3=11,5=0
P 8.325 3.44115 6 P 0 0;1,3=11,5=0
P 8.35 3.46615 3 P 0 0;3=12,5=1
P 8.08543996 4.85788002 37 P 0 0;1,3=1,5=0
P 8.07725 4.78291998 3 P 0 0;3=12,5=1
P 5.05768002 2.74115 6 P 0 0;1,3=11,5=0
P 5.08268002 2.71615 3 P 0 0;3=12,5=1
P 4.01108002 4.96076998 39 P 0 0;1,3=20,5=0
P 4.0399 4.82898996 25 P 0 0;1,3=4,5=0
P 4.06 4.86 1 P 0 0;3=0,5=1
P 2.0819 4.85788002 37 P 0 0;1,3=1,5=0
P 2.07371004 4.78291998 3 P 0 0;3=12,5=1
P 2.34606004 3.46615 3 P 0 0;3=12,5=1
P 2.32106004 3.44115 6 P 0 0;1,3=11,5=0
P 2.17638996 4.97913996 37 P 0 0;1,3=1,5=0
P 2.18456998 5.0535 3 P 0 0;3=12,5=1
P 2.44606004 3.41615 3 P 0 0;3=12,5=1
P 2.42106004 3.39115 6 P 0 0;1,3=11,5=0
P 10.93661004 2.41615 3 P 0 0;3=12,5=1
P 10.91161004 2.44115 6 P 0 0;1,3=11,5=0
P 2.15276004 4.97913996 37 P 0 0;1,3=1,5=0
P 2.14456998 5.0535 3 P 0 0;3=12,5=1
P 2.42106004 3.44115 6 P 0 0;1,3=11,5=0
P 2.44606004 3.46615 3 P 0 0;3=12,5=1
P 10.93661004 2.46615 3 P 0 0;3=12,5=1
P 10.91161004 2.49115 6 P 0 0;1,3=11,5=0
P 8.5 3.31615 3 P 0 0;3=12,5=1
P 8.475 3.29115 6 P 0 0;1,3=11,5=0
P 8.25078996 4.85788002 37 P 0 0;1,3=1,5=0
P 8.25898002 4.78291998 3 P 0 0;3=12,5=1
P 4.85768002 2.74115 6 P 0 0;1,3=11,5=0
P 4.88268002 2.71615 3 P 0 0;3=12,5=1
P 2.06853002 4.66688996 3 P 0 0;3=12,5=1
P 2.03465 4.85788002 37 P 0 0;1,3=1,5=0
P 2.47106004 3.44115 6 P 0 0;1,3=11,5=0
P 2.49606004 3.46615 3 P 0 0;3=12,5=1
P 8.5 3.36615 3 P 0 0;3=12,5=1
P 8.475 3.34115 6 P 0 0;1,3=11,5=0
P 8.22716998 4.85788002 37 P 0 0;1,3=1,5=0
P 8.21898002 4.78291998 3 P 0 0;3=12,5=1
P 2.02853002 4.66688996 3 P 0 0;3=12,5=1
P 2.01103002 4.85788002 37 P 0 0;1,3=1,5=0
P 2.47106004 3.49115 6 P 0 0;1,3=11,5=0
P 2.49606004 3.51615 3 P 0 0;3=12,5=1
P 8.4 3.31615 3 P 0 0;3=12,5=1
P 8.375 3.29115 6 P 0 0;1,3=11,5=0
P 8.32166004 4.85788002 37 P 0 0;1,3=1,5=0
P 8.26208996 4.667 3 P 0 0;3=12,5=1
P 2.10551998 4.97913996 37 P 0 0;1,3=1,5=0
P 2.11371004 5.169 3 P 0 0;3=12,5=1
P 2.39606004 3.46615 3 P 0 0;3=12,5=1
P 2.37106004 3.44115 6 P 0 0;1,3=11,5=0
P 8.4 3.36615 3 P 0 0;3=12,5=1
P 8.375 3.34115 6 P 0 0;1,3=11,5=0
P 8.29803996 4.85788002 37 P 0 0;1,3=1,5=0
P 8.22208996 4.667 3 P 0 0;3=12,5=1
P 3.81998996 0.7411 25 P 0 0;1,3=4,5=0
P 3.80998996 0.62931998 43 P 0 0;1,3=28,5=0
P 3.84 0.69 1 P 0 0;3=0,5=1
P 4.70768002 2.79115 6 P 0 0;1,3=11,5=0
P 4.68268002 2.76615 3 P 0 0;3=12,5=1
P 2.0819 4.97913996 37 P 0 0;1,3=1,5=0
P 2.07371004 5.169 3 P 0 0;3=12,5=1
P 2.37106004 3.49115 6 P 0 0;1,3=11,5=0
P 2.39606004 3.51615 3 P 0 0;3=12,5=1
P 3.75998996 0.62931998 43 P 0 0;1,3=28,5=0
P 3.56 0.49 1 P 0 0;3=0,5=1
P 4.75768002 2.84115 6 P 0 0;1,3=11,5=0
P 4.73268002 2.81615 3 P 0 0;3=12,5=1
P 1.57765 5.169 3 P 0 0;3=12,5=1
P 2.02106004 3.29115 6 P 0 0;1,3=11,5=0
P 2.04606004 3.31615 3 P 0 0;3=12,5=1
P 1.58583996 4.97913996 37 P 0 0;1,3=1,5=0
P 9.10853996 4.47 4 P 0 0;3=13,5=1
P 7.3426 5.15351004 1 P 0 0;3=0,5=1
P 7.3426 5.12551004 25 P 0 0;1,3=4,5=0
P 9.13193002 4.85788002 37 P 0 0;1,3=1,5=0
P 3.66998996 0.7411 25 P 0 0;1,3=4,5=0
P 3.65998996 0.62931998 43 P 0 0;1,3=28,5=0
P 3.785 0.69 1 P 0 0;3=0,5=1
P 4.80768002 2.84115 6 P 0 0;1,3=11,5=0
P 4.78268002 2.81615 3 P 0 0;3=12,5=1
P 1.61765 5.169 3 P 0 0;3=12,5=1
P 2.02106004 3.34115 6 P 0 0;1,3=11,5=0
P 2.04606004 3.36615 3 P 0 0;3=12,5=1
P 1.60946004 4.97913996 37 P 0 0;1,3=1,5=0
P 0.82983996 5.2361 35 P 0 0;1,3=10,5=0
P 0.9 5.417 25 P 0 0;1,3=4,5=0
P 0.88681004 5.53641998 49 P 0 0;1,3=16,5=0
P 0.83 5.295 7 P 0 0;2,3=6,5=1
P 8.1 3.26615 3 P 0 0;3=12,5=1
P 8.075 3.24115 6 P 0 0;1,3=11,5=0
P 7.58118996 4.707 3 P 0 0;3=12,5=1
P 7.58938002 4.85788002 37 P 0 0;1,3=1,5=0
P 2.07106004 3.24115 6 P 0 0;1,3=11,5=0
P 2.09606004 3.26615 3 P 0 0;3=12,5=1
P 1.57765 4.707 3 P 0 0;3=12,5=1
P 1.58583996 4.85788002 37 P 0 0;1,3=1,5=0
P 5.05768002 1.99115 6 P 0 0;1,3=11,5=0
P 5.08268002 1.96615 3 P 0 0;3=12,5=1
P 8.1 3.31615 3 P 0 0;3=12,5=1
P 8.075 3.29115 6 P 0 0;1,3=11,5=0
P 7.62118996 4.707 3 P 0 0;3=12,5=1
P 7.613 4.85788002 37 P 0 0;1,3=1,5=0
P 3.75998996 0.3051 25 P 0 0;1,3=4,5=0
P 3.75998996 0.40688002 43 P 0 0;1,3=28,5=0
P 3.75998996 0.345 1 P 0 0;3=0,5=1
P 4.70768002 2.84115 6 P 0 0;1,3=11,5=0
P 4.68268002 2.81615 3 P 0 0;3=12,5=1
P 2.07106004 3.29115 6 P 0 0;1,3=11,5=0
P 2.09606004 3.31615 3 P 0 0;3=12,5=1
P 1.61765 4.707 3 P 0 0;3=12,5=1
P 1.60946004 4.85788002 37 P 0 0;1,3=1,5=0
P 0.52 5.591 27 P 0 0;1,3=23,5=0
P 0.58 5.591 1 P 0 0;3=0,5=1
P 11.67761998 2.85 4 P 0 0;3=13,5=1
P 11.865 4.455 1 P 0 0;3=0,5=1
P 5.67368996 2.85 4 P 0 0;3=13,5=1
P 5.855 3.07 4 P 0 0;3=13,5=1
P 5.8522 2.97 4 P 0 0;3=13,5=1
P 7.2926 5.15351004 4 P 0 0;3=13,5=1
P 7.2926 5.12551004 25 P 0 0;1,3=4,5=0
P 7.2426 5.15351004 4 P 0 0;3=13,5=1
P 7.2426 5.12551004 25 P 0 0;1,3=4,5=0
P 7.1926 4.95351004 4 P 0 0;3=13,5=1
P 7.1926 4.98151004 25 P 0 0;1,3=4,5=0
P 7.25421004 4.9602 39 P 0 0;1,3=20,5=0
P 7.42603996 5.15895 1 P 0 0;3=0,5=1
P 7.3926 5.12551004 25 P 0 0;1,3=4,5=0
P 3.94 4.627 25 P 0 0;1,3=4,5=0
P 3.94 4.655 4 P 0 0;3=13,5=1
P 3.94 4.683 25 P 0 0;1,3=4,5=0
P 3.77 4.765 4 P 0 0;3=13,5=1
P 3.77441004 4.72035 38 P 0 0;1,3=8,5=0
P 3.77 4.793 25 P 0 0;1,3=4,5=0
P 4.14 4.745 4 P 0 0;3=13,5=1
P 4.08035 4.71558996 48 P 0 0;1,3=8,5=0
P 4.14 4.717 25 P 0 0;1,3=4,5=0
P 4.76 5.375 4 P 0 0;3=13,5=1
P 4.76 5.408 25 P 0 0;1,3=4,5=0
P 4.9574 5.54685 42 P 0 0;1,3=5,5=0
P 4.96 5.5 4 P 0 0;3=13,5=1
P 5.16 5.555 4 P 0 0;3=13,5=1
P 5.09558996 5.55965 38 P 0 0;1,3=8,5=0
P 5.16 5.583 25 P 0 0;1,3=4,5=0
P 4.892 5.767 4 P 0 0;3=13,5=1
P 4.86 5.767 25 P 0 0;1,3=4,5=0
P 5.088 5.767 4 P 0 0;3=13,5=1
P 5.06 5.767 25 P 0 0;1,3=4,5=0
P 0.91 5.075 4 P 0 0;3=13,5=1
P 0.91 5.113 25 P 0 0;1,3=4,5=0
P 1.03 4.96 4 P 0 0;3=13,5=1
P 1.03 4.993 25 P 0 0;1,3=4,5=0
P 1.02558996 5.20965 38 P 0 0;1,3=8,5=0
P 1.03 5.155 4 P 0 0;3=13,5=1
P 1.03 5.127 25 P 0 0;1,3=4,5=0
P 1.38906004 5.12551004 25 P 0 0;1,3=4,5=0
P 1.38906004 5.15351004 1 P 0 0;3=0,5=1
P 1.23906004 5.15351004 4 P 0 0;3=13,5=1
P 1.23906004 5.12551004 25 P 0 0;1,3=4,5=0
P 1.28906004 5.15351004 4 P 0 0;3=13,5=1
P 1.28906004 5.12551004 25 P 0 0;1,3=4,5=0
P 1.25066998 4.9602 39 P 0 0;1,3=20,5=0
P 1.18906004 4.95351004 4 P 0 0;3=13,5=1
P 1.18906004 4.98151004 25 P 0 0;1,3=4,5=0
P 0.83 5.355 4 P 0 0;3=13,5=1
P 0.83 5.383 25 P 0 0;1,3=4,5=0
P 0.948 5.383 25 P 0 0;1,3=4,5=0
P 0.9 5.355 4 P 0 0;3=13,5=1
P 0.9 5.383 25 P 0 0;1,3=4,5=0
P 0.755 5.355 4 P 0 0;3=13,5=1
P 0.755 5.383 25 P 0 0;1,3=4,5=0
P 0.81016004 5.2361 35 P 0 0;1,3=10,5=0
P 0.73 5.205 4 P 0 0;3=13,5=1
P 0.73 5.233 25 P 0 0;1,3=4,5=0
P 0.79046998 5.2361 35 P 0 0;1,3=10,5=0
P 0.81016004 5.17 4 P 0 0;3=13,5=1
P 0.81016004 5.1239 35 P 0 0;1,3=10,5=0
P 1.094 5.356 1 P 0 0;3=0,5=1
P 1.094 5.383 25 P 0 0;1,3=4,5=0
P 1.044 5.448 4 P 0 0;3=13,5=1
P 1.044 5.417 25 P 0 0;1,3=4,5=0
P 1.4 5.46 4 P 0 0;3=13,5=1
P 1.32 5.46 4 P 0 0;3=13,5=1
P 1.31 5.417 25 P 0 0;1,3=4,5=0
P 1.46 5.417 25 P 0 0;1,3=4,5=0
P 1.41 5.417 25 P 0 0;1,3=4,5=0
P 1.36 5.417 25 P 0 0;1,3=4,5=0
P 1.43798996 5.46016004 4 P 0 0;3=13,5=1
P 1.43798996 5.53641998 49 P 0 0;1,3=16,5=0
P 1.35925 5.46016004 4 P 0 0;3=13,5=1
P 1.35925 5.53641998 49 P 0 0;1,3=16,5=0
P 0.89 5.885 4 P 0 0;3=13,5=1
P 0.89 5.857 25 P 0 0;1,3=4,5=0
P 0.81 5.885 4 P 0 0;3=13,5=1
P 0.81 5.857 25 P 0 0;1,3=4,5=0
P 0.73 5.885 4 P 0 0;3=13,5=1
P 0.73 5.857 25 P 0 0;1,3=4,5=0
P 0.97 5.885 4 P 0 0;3=13,5=1
P 0.97 5.857 25 P 0 0;1,3=4,5=0
P 1.04 5.885 4 P 0 0;3=13,5=1
P 1.04 5.857 25 P 0 0;1,3=4,5=0
P 1.12 5.885 4 P 0 0;3=13,5=1
P 1.12 5.857 25 P 0 0;1,3=4,5=0
P 4.96 5.442 25 P 0 0;1,3=4,5=0
P 8.15 3.31615 3 P 0 0;3=12,5=1
P 8.125 3.29115 6 P 0 0;1,3=11,5=0
P 7.65205 4.78291998 3 P 0 0;3=12,5=1
P 7.66023996 4.85788002 37 P 0 0;1,3=1,5=0
P 11.235 3.3 4 P 0 0;3=13,5=1
P 5.815 0.925 1 P 0 0;3=0,5=1
P 3.60998996 0.3051 25 P 0 0;1,3=4,5=0
P 3.60998996 0.40688002 43 P 0 0;1,3=28,5=0
P 3.635 0.49 1 P 0 0;3=0,5=1
P 4.60768002 2.84115 6 P 0 0;1,3=11,5=0
P 4.58268002 2.81615 3 P 0 0;3=12,5=1
P 2.17106004 3.24115 6 P 0 0;1,3=11,5=0
P 2.19606004 3.26615 3 P 0 0;3=12,5=1
P 1.6485 5.0535 3 P 0 0;3=12,5=1
P 1.6567 4.97913996 37 P 0 0;1,3=1,5=0
P 8.15 3.36615 3 P 0 0;3=12,5=1
P 8.125 3.34115 6 P 0 0;1,3=11,5=0
P 7.69205 4.78291998 3 P 0 0;3=12,5=1
P 7.68386004 4.85788002 37 P 0 0;1,3=1,5=0
P 2.17106004 3.29115 6 P 0 0;1,3=11,5=0
P 2.19606004 3.31615 3 P 0 0;3=12,5=1
P 1.6885 5.0535 3 P 0 0;3=12,5=1
P 1.68031998 4.97913996 37 P 0 0;1,3=1,5=0
P 8.1 3.41615 3 P 0 0;3=12,5=1
P 8.075 3.39115 6 P 0 0;1,3=11,5=0
P 7.80196998 4.85788002 37 P 0 0;1,3=1,5=0
P 7.79378996 4.78291998 3 P 0 0;3=12,5=1
P 2.12106004 3.29115 6 P 0 0;1,3=11,5=0
P 2.14606004 3.31615 3 P 0 0;3=12,5=1
P 1.64851004 4.78291998 3 P 0 0;3=12,5=1
P 1.6567 4.85788002 37 P 0 0;1,3=1,5=0
P 8.1 3.46615 3 P 0 0;3=12,5=1
P 8.075 3.44115 6 P 0 0;1,3=11,5=0
P 7.8256 4.85788002 37 P 0 0;1,3=1,5=0
P 7.83378996 4.78291998 3 P 0 0;3=12,5=1
P 2.12106004 3.34115 6 P 0 0;1,3=11,5=0
P 2.14606004 3.36615 3 P 0 0;3=12,5=1
P 1.68851004 4.78291998 3 P 0 0;3=12,5=1
P 1.68031998 4.85788002 37 P 0 0;1,3=1,5=0
P 0.73 4.96 1 P 0 0;3=0,5=1
P 0.73 4.993 25 P 0 0;1,3=4,5=0
P 3.795 4.6 4 P 0 0;3=13,5=1
P 3.8 4.63965 38 P 0 0;1,3=8,5=0
P 4.86 5.408 25 P 0 0;1,3=4,5=0
P 4.86 5.375 4 P 0 0;3=13,5=1
P 8.15 3.46615 3 P 0 0;3=12,5=1
P 8.125 3.44115 6 P 0 0;1,3=11,5=0
P 7.86465 4.657 3 P 0 0;3=12,5=1
P 7.87283996 4.85788002 37 P 0 0;1,3=1,5=0
P 2.07106004 3.39115 6 P 0 0;1,3=11,5=0
P 2.09606004 3.41615 3 P 0 0;3=12,5=1
P 1.79843002 4.85788002 37 P 0 0;1,3=1,5=0
P 1.79025 4.78291998 3 P 0 0;3=12,5=1
P 8.15 3.51615 3 P 0 0;3=12,5=1
P 8.125 3.49115 6 P 0 0;1,3=11,5=0
P 7.90465 4.657 3 P 0 0;3=12,5=1
P 7.89646004 4.85788002 37 P 0 0;1,3=1,5=0
P 2.09606004 3.46615 3 P 0 0;3=12,5=1
P 2.07106004 3.44115 6 P 0 0;1,3=11,5=0
P 1.82206004 4.85788002 37 P 0 0;1,3=1,5=0
P 1.83025 4.78291998 3 P 0 0;3=12,5=1
P 2.19606004 3.41615 3 P 0 0;3=12,5=1
P 2.17106004 3.39115 6 P 0 0;1,3=11,5=0
P 1.86111004 5.169 3 P 0 0;3=12,5=1
P 1.8693 4.97913996 37 P 0 0;1,3=1,5=0
P 2.17106004 3.44115 6 P 0 0;1,3=11,5=0
P 2.19606004 3.46615 3 P 0 0;3=12,5=1
P 1.90111004 5.169 3 P 0 0;3=12,5=1
P 1.89291998 4.97913996 37 P 0 0;1,3=1,5=0
P 6.82978002 4.53096998 7 P 0 0;2,3=6,5=1
P 6.87618996 4.61586998 51 P 0 0;1,3=22,5=0
P 6.74208996 4.6252 29 P 0 0;1,3=21,5=0
P 6.72708996 4.5652 4 P 0 0;3=13,5=1
P 6.76208996 4.5652 4 P 0 0;3=13,5=1
P 6.79708996 4.5652 4 P 0 0;3=13,5=1
P 6.83708996 4.5652 1 P 0 0;3=0,5=1
P 6.90208996 4.5652 4 P 0 0;3=13,5=1
P 6.87208996 4.5652 4 P 0 0;3=13,5=1
P 10.99998996 4.9531 4 P 0 0;3=13,5=1
P 11.03998996 4.9531 4 P 0 0;3=13,5=1
P 10.99998996 4.9131 4 P 0 0;3=13,5=1
P 11.03998996 4.9131 4 P 0 0;3=13,5=1
P 11.21998996 4.9531 4 P 0 0;3=13,5=1
P 11.17998996 4.9531 4 P 0 0;3=13,5=1
P 11.13498996 4.9531 4 P 0 0;3=13,5=1
P 11.08498996 4.9531 4 P 0 0;3=13,5=1
P 11.21998996 4.9131 4 P 0 0;3=13,5=1
P 11.17998996 4.9131 4 P 0 0;3=13,5=1
P 11.08498996 4.9131 4 P 0 0;3=13,5=1
P 11.13498996 4.9131 4 P 0 0;3=13,5=1
P 10.99998996 5.1631 4 P 0 0;3=13,5=1
P 11.03998996 5.1631 4 P 0 0;3=13,5=1
P 10.99998996 5.1231 4 P 0 0;3=13,5=1
P 10.99998996 5.0381 4 P 0 0;3=13,5=1
P 10.99998996 5.0831 4 P 0 0;3=13,5=1
P 10.99998996 4.9931 4 P 0 0;3=13,5=1
P 11.03998996 4.9931 4 P 0 0;3=13,5=1
P 11.03998996 5.0831 4 P 0 0;3=13,5=1
P 11.03998996 5.0381 4 P 0 0;3=13,5=1
P 11.03998996 5.1231 4 P 0 0;3=13,5=1
P 11.10998996 5.03983002 32 P 0 0;1,3=26,5=0
P 11.21998996 5.1631 4 P 0 0;3=13,5=1
P 11.17998996 5.1631 4 P 0 0;3=13,5=1
P 11.08498996 5.1631 4 P 0 0;3=13,5=1
P 11.13498996 5.1631 4 P 0 0;3=13,5=1
P 11.21998996 5.1231 4 P 0 0;3=13,5=1
P 11.21998996 5.0381 4 P 0 0;3=13,5=1
P 11.21998996 5.0831 4 P 0 0;3=13,5=1
P 11.21998996 4.9931 4 P 0 0;3=13,5=1
P 11.17998996 4.9931 4 P 0 0;3=13,5=1
P 11.17998996 5.1231 4 P 0 0;3=13,5=1
P 11.17998996 5.0831 4 P 0 0;3=13,5=1
P 11.17998996 5.0381 4 P 0 0;3=13,5=1
P 11.13498996 5.1231 4 P 0 0;3=13,5=1
P 11.08498996 5.1231 4 P 0 0;3=13,5=1
P 11.52873996 4.88 36 P 0 0;1,3=29,5=0
P 10.577 5.32 25 P 0 0;1,3=4,5=0
P 10.59 5.18 29 P 0 0;1,3=21,5=0
P 10.59 5.26 29 P 0 0;1,3=21,5=0
P 12.04 5.04 29 P 0 0;1,3=21,5=0
P 12.12 5.027 25 P 0 0;1,3=4,5=0
P 12.2 5.04 29 P 0 0;1,3=21,5=0
P 11.6269 4.90498996 4 P 0 0;3=13,5=1
P 11.6269 4.85498996 4 P 0 0;3=13,5=1
P 11.4269 4.80998996 4 P 0 0;3=13,5=1
P 11.4269 4.85498996 4 P 0 0;3=13,5=1
P 11.4269 4.90498996 4 P 0 0;3=13,5=1
P 11.4269 4.94998996 4 P 0 0;3=13,5=1
P 11.4769 4.94998996 4 P 0 0;3=13,5=1
P 11.4769 4.80998996 4 P 0 0;3=13,5=1
P 11.5269 4.94998996 4 P 0 0;3=13,5=1
P 11.5269 4.80998996 4 P 0 0;3=13,5=1
P 11.5769 4.94998996 4 P 0 0;3=13,5=1
P 11.6269 4.94998996 4 P 0 0;3=13,5=1
P 11.6269 4.80998996 4 P 0 0;3=13,5=1
P 11.5769 4.80998996 4 P 0 0;3=13,5=1
P 10.82676998 5.71338996 12 P 0 0;3=32,5=0
P 10.99213002 5.71338996 12 P 0 0;3=32,5=0
P 11.15748002 5.71338996 12 P 0 0;3=32,5=0
P 11.32283996 5.71338996 12 P 0 0;3=32,5=0
P 11.48818996 5.71338996 12 P 0 0;3=32,5=0
P 11.65353996 5.71338996 12 P 0 0;3=32,5=0
P 11.8189 5.71338996 12 P 0 0;3=32,5=0
P 11.98425 5.71338996 12 P 0 0;3=32,5=0
P 12.14961004 5.71338996 12 P 0 0;3=32,5=0
P 10.80498996 5.7831 4 P 0 0;3=13,5=1
P 10.84498996 5.7831 4 P 0 0;3=13,5=1
P 10.80498996 5.6431 4 P 0 0;3=13,5=1
P 10.84498996 5.6431 4 P 0 0;3=13,5=1
P 11.01035 5.6431 4 P 0 0;3=13,5=1
P 10.97035 5.6431 4 P 0 0;3=13,5=1
P 11.01035 5.7831 4 P 0 0;3=13,5=1
P 10.97035 5.7831 4 P 0 0;3=13,5=1
P 11.17571004 5.6431 4 P 0 0;3=13,5=1
P 11.13571004 5.6431 4 P 0 0;3=13,5=1
P 11.17571004 5.7831 4 P 0 0;3=13,5=1
P 11.13571004 5.7831 4 P 0 0;3=13,5=1
P 11.34106998 5.6431 4 P 0 0;3=13,5=1
P 11.30106998 5.6431 4 P 0 0;3=13,5=1
P 11.34106998 5.7831 4 P 0 0;3=13,5=1
P 11.30106998 5.7831 4 P 0 0;3=13,5=1
P 11.50643002 5.6431 4 P 0 0;3=13,5=1
P 11.46643002 5.6431 4 P 0 0;3=13,5=1
P 11.50643002 5.7831 4 P 0 0;3=13,5=1
P 11.46643002 5.7831 4 P 0 0;3=13,5=1
P 11.67178996 5.6431 4 P 0 0;3=13,5=1
P 11.63178996 5.6431 4 P 0 0;3=13,5=1
P 11.67178996 5.7831 4 P 0 0;3=13,5=1
P 11.63178996 5.7831 4 P 0 0;3=13,5=1
P 11.83715 5.6431 4 P 0 0;3=13,5=1
P 11.79715 5.6431 4 P 0 0;3=13,5=1
P 11.83715 5.7831 4 P 0 0;3=13,5=1
P 11.79715 5.7831 4 P 0 0;3=13,5=1
P 12.00251004 5.6431 4 P 0 0;3=13,5=1
P 11.96251004 5.6431 4 P 0 0;3=13,5=1
P 12.00251004 5.7831 4 P 0 0;3=13,5=1
P 11.96251004 5.7831 4 P 0 0;3=13,5=1
P 12.16786998 5.6431 4 P 0 0;3=13,5=1
P 12.12786998 5.6431 4 P 0 0;3=13,5=1
P 12.16786998 5.7831 4 P 0 0;3=13,5=1
P 12.12786998 5.7831 4 P 0 0;3=13,5=1
P 5.10605 5.03983002 32 P 0 0;1,3=26,5=0
P 5.03605 5.1631 4 P 0 0;3=13,5=1
P 5.03605 4.9931 4 P 0 0;3=13,5=1
P 5.03605 5.0831 4 P 0 0;3=13,5=1
P 5.03605 5.0381 4 P 0 0;3=13,5=1
P 5.03605 5.1231 4 P 0 0;3=13,5=1
P 5.21605 5.1631 4 P 0 0;3=13,5=1
P 5.17605 5.1631 4 P 0 0;3=13,5=1
P 5.08105 5.1631 4 P 0 0;3=13,5=1
P 5.13105 5.1631 4 P 0 0;3=13,5=1
P 5.21605 5.1231 4 P 0 0;3=13,5=1
P 5.21605 5.0381 4 P 0 0;3=13,5=1
P 5.21605 5.0831 4 P 0 0;3=13,5=1
P 5.21605 4.9931 4 P 0 0;3=13,5=1
P 5.17605 4.9931 4 P 0 0;3=13,5=1
P 5.17605 5.1231 4 P 0 0;3=13,5=1
P 5.17605 5.0831 4 P 0 0;3=13,5=1
P 5.17605 5.0381 4 P 0 0;3=13,5=1
P 5.13105 5.1231 4 P 0 0;3=13,5=1
P 5.08105 5.1231 4 P 0 0;3=13,5=1
P 4.99605 5.1631 4 P 0 0;3=13,5=1
P 4.99605 5.1231 4 P 0 0;3=13,5=1
P 4.99605 5.0381 4 P 0 0;3=13,5=1
P 4.99605 5.0831 4 P 0 0;3=13,5=1
P 4.99605 4.9931 4 P 0 0;3=13,5=1
P 5.03605 4.9531 4 P 0 0;3=13,5=1
P 5.03605 4.9131 4 P 0 0;3=13,5=1
P 5.21605 4.9531 4 P 0 0;3=13,5=1
P 5.17605 4.9531 4 P 0 0;3=13,5=1
P 5.13105 4.9531 4 P 0 0;3=13,5=1
P 5.08105 4.9531 4 P 0 0;3=13,5=1
P 5.21605 4.9131 4 P 0 0;3=13,5=1
P 5.17605 4.9131 4 P 0 0;3=13,5=1
P 5.08105 4.9131 4 P 0 0;3=13,5=1
P 5.13105 4.9131 4 P 0 0;3=13,5=1
P 4.99605 4.9531 4 P 0 0;3=13,5=1
P 4.99605 4.9131 4 P 0 0;3=13,5=1
P 5.205 5.205 7 P 0 0;2,3=6,5=1
P 6.34948996 4.99705 25 P 0 0;1,3=4,5=0
P 6.34948996 5.03 4 P 0 0;3=13,5=1
P 2.74225 5.14 3 P 0 0;3=12,5=1
P 2.75043996 4.97913996 37 P 0 0;1,3=1,5=0
P 2.02106004 3.59115 6 P 0 0;1,3=11,5=0
P 2.04606004 3.61615 3 P 0 0;3=12,5=1
P 2.12106004 3.44115 6 P 0 0;1,3=11,5=0
P 2.14606004 3.46615 3 P 0 0;3=12,5=1
P 1.86111004 4.657 3 P 0 0;3=12,5=1
P 1.8693 4.85788002 37 P 0 0;1,3=1,5=0
P 2.78225 5.14 3 P 0 0;3=12,5=1
P 2.77406004 4.97913996 37 P 0 0;1,3=1,5=0
P 2.02106004 3.64115 6 P 0 0;1,3=11,5=0
P 2.04606004 3.66615 3 P 0 0;3=12,5=1
P 2.14606004 3.51615 3 P 0 0;3=12,5=1
P 2.12106004 3.49115 6 P 0 0;1,3=11,5=0
P 1.90111004 4.657 3 P 0 0;3=12,5=1
P 1.89291998 4.85788002 37 P 0 0;1,3=1,5=0
P 1.94016998 4.97913996 37 P 0 0;1,3=1,5=0
P 1.93196998 5.0535 3 P 0 0;3=12,5=1
P 2.02106004 3.44115 6 P 0 0;1,3=11,5=0
P 1.99606004 3.46615 3 P 0 0;3=12,5=1
P 4.60768002 2.59115 6 P 0 0;1,3=11,5=0
P 4.58268002 2.56615 3 P 0 0;3=12,5=1
P 1.96378996 4.97913996 37 P 0 0;1,3=1,5=0
P 1.97196998 5.0535 3 P 0 0;3=12,5=1
P 2.02106004 3.49115 6 P 0 0;1,3=11,5=0
P 1.99606004 3.51615 3 P 0 0;3=12,5=1
P 2.88086998 5.17001998 3 P 0 0;3=12,5=1
P 2.12106004 3.59115 6 P 0 0;1,3=11,5=0
P 2.14606004 3.61615 3 P 0 0;3=12,5=1
P 2.8213 4.97913996 37 P 0 0;1,3=1,5=0
P 2.32106004 3.64115 6 P 0 0;1,3=11,5=0
P 2.34606004 3.66615 3 P 0 0;3=12,5=1
P 3.56176998 4.71973002 3 P 0 0;3=12,5=1
P 3.55358002 4.85788002 37 P 0 0;1,3=1,5=0
P 2.92086998 5.17001998 3 P 0 0;3=12,5=1
P 2.12106004 3.64115 6 P 0 0;1,3=11,5=0
P 2.14606004 3.66615 3 P 0 0;3=12,5=1
P 2.84491998 4.97913996 37 P 0 0;1,3=1,5=0
P 2.32106004 3.69115 6 P 0 0;1,3=11,5=0
P 2.34606004 3.71615 3 P 0 0;3=12,5=1
P 3.52176998 4.71973002 3 P 0 0;3=12,5=1
P 3.52996004 4.85788002 37 P 0 0;1,3=1,5=0
P 2.39606004 3.61615 3 P 0 0;3=12,5=1
P 2.37106004 3.59115 6 P 0 0;1,3=11,5=0
P 3.49091004 4.587 3 P 0 0;3=12,5=1
P 3.48271998 4.85788002 37 P 0 0;1,3=1,5=0
P 2.39606004 3.66615 3 P 0 0;3=12,5=1
P 2.37106004 3.64115 6 P 0 0;1,3=11,5=0
P 3.45091004 4.587 3 P 0 0;3=12,5=1
P 3.4591 4.85788002 37 P 0 0;1,3=1,5=0
P 2.47106004 3.59115 6 P 0 0;1,3=11,5=0
P 2.49606004 3.61615 3 P 0 0;3=12,5=1
P 3.55358002 4.97913996 37 P 0 0;1,3=1,5=0
P 3.56176998 5.14 3 P 0 0;3=12,5=1
P 2.49606004 3.66615 3 P 0 0;3=12,5=1
P 2.47106004 3.64115 6 P 0 0;1,3=11,5=0
P 3.52176998 5.14 3 P 0 0;3=12,5=1
P 3.52996004 4.97913996 37 P 0 0;1,3=1,5=0
P 2.44606004 3.66615 3 P 0 0;3=12,5=1
P 2.42106004 3.64115 6 P 0 0;1,3=11,5=0
P 3.42003996 4.78291998 3 P 0 0;3=12,5=1
P 3.41185 4.85788002 37 P 0 0;1,3=1,5=0
P 4.65768002 2.99115 6 P 0 0;1,3=11,5=0
P 4.60768002 3.09115 6 P 0 0;1,3=11,5=0
P 4.60768002 2.99115 6 P 0 0;1,3=11,5=0
P 4.65768002 3.09115 6 P 0 0;1,3=11,5=0
P 4.65768002 2.94115 6 P 0 0;1,3=11,5=0
P 4.60768002 2.94115 6 P 0 0;1,3=11,5=0
P 4.80768002 2.99115 6 P 0 0;1,3=11,5=0
P 4.80768002 3.09115 6 P 0 0;1,3=11,5=0
P 4.85768002 3.09115 6 P 0 0;1,3=11,5=0
P 4.85768002 2.99115 6 P 0 0;1,3=11,5=0
P 4.75768002 2.99115 6 P 0 0;1,3=11,5=0
P 4.75768002 3.09115 6 P 0 0;1,3=11,5=0
P 4.70768002 2.99115 6 P 0 0;1,3=11,5=0
P 4.70768002 3.09115 6 P 0 0;1,3=11,5=0
P 4.80768002 2.94115 6 P 0 0;1,3=11,5=0
P 4.85768002 2.94115 6 P 0 0;1,3=11,5=0
P 4.75768002 2.94115 6 P 0 0;1,3=11,5=0
P 4.70768002 2.94115 6 P 0 0;1,3=11,5=0
P 5.00768002 2.99115 6 P 0 0;1,3=11,5=0
P 5.00768002 3.09115 6 P 0 0;1,3=11,5=0
P 5.05768002 2.99115 6 P 0 0;1,3=11,5=0
P 5.05768002 3.09115 6 P 0 0;1,3=11,5=0
P 4.90768002 2.99115 6 P 0 0;1,3=11,5=0
P 4.90768002 3.09115 6 P 0 0;1,3=11,5=0
P 4.95768002 3.09115 6 P 0 0;1,3=11,5=0
P 4.95768002 2.99115 6 P 0 0;1,3=11,5=0
P 5.05768002 2.94115 6 P 0 0;1,3=11,5=0
P 5.00768002 2.94115 6 P 0 0;1,3=11,5=0
P 4.90768002 2.94115 6 P 0 0;1,3=11,5=0
P 4.95768002 2.94115 6 P 0 0;1,3=11,5=0
P 4.65768002 3.24115 6 P 0 0;1,3=11,5=0
P 4.60768002 3.29115 6 P 0 0;1,3=11,5=0
P 4.60768002 3.24115 6 P 0 0;1,3=11,5=0
P 4.65768002 3.29115 6 P 0 0;1,3=11,5=0
P 4.60768002 3.14115 6 P 0 0;1,3=11,5=0
P 4.65768002 3.14115 6 P 0 0;1,3=11,5=0
P 4.80768002 3.29115 6 P 0 0;1,3=11,5=0
P 4.80768002 3.24115 6 P 0 0;1,3=11,5=0
P 4.85768002 3.24115 6 P 0 0;1,3=11,5=0
P 4.85768002 3.29115 6 P 0 0;1,3=11,5=0
P 4.70768002 3.29115 6 P 0 0;1,3=11,5=0
P 4.70768002 3.24115 6 P 0 0;1,3=11,5=0
P 4.75768002 3.24115 6 P 0 0;1,3=11,5=0
P 4.75768002 3.29115 6 P 0 0;1,3=11,5=0
P 4.80768002 3.14115 6 P 0 0;1,3=11,5=0
P 4.85768002 3.14115 6 P 0 0;1,3=11,5=0
P 4.70768002 3.14115 6 P 0 0;1,3=11,5=0
P 4.75768002 3.14115 6 P 0 0;1,3=11,5=0
P 5.00768002 3.29115 6 P 0 0;1,3=11,5=0
P 5.05768002 3.29115 6 P 0 0;1,3=11,5=0
P 5.00768002 3.24115 6 P 0 0;1,3=11,5=0
P 5.05768002 3.24115 6 P 0 0;1,3=11,5=0
P 4.95768002 3.24115 6 P 0 0;1,3=11,5=0
P 4.95768002 3.29115 6 P 0 0;1,3=11,5=0
P 4.90768002 3.29115 6 P 0 0;1,3=11,5=0
P 4.90768002 3.24115 6 P 0 0;1,3=11,5=0
P 5.00768002 3.14115 6 P 0 0;1,3=11,5=0
P 5.05768002 3.14115 6 P 0 0;1,3=11,5=0
P 4.95768002 3.14115 6 P 0 0;1,3=11,5=0
P 4.90768002 3.14115 6 P 0 0;1,3=11,5=0
P 4.65768002 3.54115 6 P 0 0;1,3=11,5=0
P 4.65768002 3.59115 6 P 0 0;1,3=11,5=0
P 4.60768002 3.54115 6 P 0 0;1,3=11,5=0
P 4.60768002 3.59115 6 P 0 0;1,3=11,5=0
P 4.60768002 3.39115 6 P 0 0;1,3=11,5=0
P 4.65768002 3.44115 6 P 0 0;1,3=11,5=0
P 4.65768002 3.39115 6 P 0 0;1,3=11,5=0
P 4.60768002 3.44115 6 P 0 0;1,3=11,5=0
P 4.80768002 3.54115 6 P 0 0;1,3=11,5=0
P 4.80768002 3.59115 6 P 0 0;1,3=11,5=0
P 4.85768002 3.54115 6 P 0 0;1,3=11,5=0
P 4.85768002 3.59115 6 P 0 0;1,3=11,5=0
P 4.70768002 3.59115 6 P 0 0;1,3=11,5=0
P 4.70768002 3.54115 6 P 0 0;1,3=11,5=0
P 4.75768002 3.59115 6 P 0 0;1,3=11,5=0
P 4.75768002 3.54115 6 P 0 0;1,3=11,5=0
P 4.80768002 3.39115 6 P 0 0;1,3=11,5=0
P 4.80768002 3.44115 6 P 0 0;1,3=11,5=0
P 4.85768002 3.44115 6 P 0 0;1,3=11,5=0
P 4.85768002 3.39115 6 P 0 0;1,3=11,5=0
P 4.75768002 3.44115 6 P 0 0;1,3=11,5=0
P 4.70768002 3.44115 6 P 0 0;1,3=11,5=0
P 4.70768002 3.39115 6 P 0 0;1,3=11,5=0
P 4.75768002 3.39115 6 P 0 0;1,3=11,5=0
P 5.00768002 3.59115 6 P 0 0;1,3=11,5=0
P 5.05768002 3.59115 6 P 0 0;1,3=11,5=0
P 5.00768002 3.54115 6 P 0 0;1,3=11,5=0
P 5.05768002 3.54115 6 P 0 0;1,3=11,5=0
P 4.95768002 3.59115 6 P 0 0;1,3=11,5=0
P 4.95768002 3.54115 6 P 0 0;1,3=11,5=0
P 4.90768002 3.59115 6 P 0 0;1,3=11,5=0
P 4.90768002 3.54115 6 P 0 0;1,3=11,5=0
P 5.00768002 3.39115 6 P 0 0;1,3=11,5=0
P 5.05768002 3.39115 6 P 0 0;1,3=11,5=0
P 5.00768002 3.44115 6 P 0 0;1,3=11,5=0
P 5.05768002 3.44115 6 P 0 0;1,3=11,5=0
P 4.90768002 3.39115 6 P 0 0;1,3=11,5=0
P 4.90768002 3.44115 6 P 0 0;1,3=11,5=0
P 4.95768002 3.39115 6 P 0 0;1,3=11,5=0
P 4.95768002 3.44115 6 P 0 0;1,3=11,5=0
P 4.65768002 3.84115 6 P 0 0;1,3=11,5=0
P 4.65768002 3.74115 6 P 0 0;1,3=11,5=0
P 4.60768002 3.84115 6 P 0 0;1,3=11,5=0
P 4.60768002 3.74115 6 P 0 0;1,3=11,5=0
P 4.65768002 3.69115 6 P 0 0;1,3=11,5=0
P 4.60768002 3.69115 6 P 0 0;1,3=11,5=0
P 4.80768002 3.84115 6 P 0 0;1,3=11,5=0
P 4.80768002 3.74115 6 P 0 0;1,3=11,5=0
P 4.85768002 3.84115 6 P 0 0;1,3=11,5=0
P 4.85768002 3.74115 6 P 0 0;1,3=11,5=0
P 4.70768002 3.84115 6 P 0 0;1,3=11,5=0
P 4.70768002 3.74115 6 P 0 0;1,3=11,5=0
P 4.75768002 3.84115 6 P 0 0;1,3=11,5=0
P 4.75768002 3.74115 6 P 0 0;1,3=11,5=0
P 4.80768002 3.69115 6 P 0 0;1,3=11,5=0
P 4.85768002 3.69115 6 P 0 0;1,3=11,5=0
P 4.70768002 3.69115 6 P 0 0;1,3=11,5=0
P 4.75768002 3.69115 6 P 0 0;1,3=11,5=0
P 5.00768002 3.84115 6 P 0 0;1,3=11,5=0
P 5.00768002 3.74115 6 P 0 0;1,3=11,5=0
P 5.05768002 3.84115 6 P 0 0;1,3=11,5=0
P 5.05768002 3.74115 6 P 0 0;1,3=11,5=0
P 4.90768002 3.84115 6 P 0 0;1,3=11,5=0
P 4.95768002 3.74115 6 P 0 0;1,3=11,5=0
P 4.90768002 3.74115 6 P 0 0;1,3=11,5=0
P 4.95768002 3.84115 6 P 0 0;1,3=11,5=0
P 5.00768002 3.69115 6 P 0 0;1,3=11,5=0
P 5.05768002 3.69115 6 P 0 0;1,3=11,5=0
P 4.95768002 3.69115 6 P 0 0;1,3=11,5=0
P 4.90768002 3.69115 6 P 0 0;1,3=11,5=0
P 4.36305 4.74133996 52 P 0 0;1,3=25,5=0
P 4.75305 4.74133996 52 P 0 0;1,3=25,5=0
P 5.10605 4.75636998 32 P 0 0;1,3=26,5=0
P 4.30605 4.6631 4 P 0 0;3=13,5=1
P 4.34105 4.6431 4 P 0 0;3=13,5=1
P 4.38605 4.6431 4 P 0 0;3=13,5=1
P 4.42605 4.6631 4 P 0 0;3=13,5=1
P 4.46605 4.6631 4 P 0 0;3=13,5=1
P 4.30605 4.7031 4 P 0 0;3=13,5=1
P 4.42605 4.7031 4 P 0 0;3=13,5=1
P 4.46605 4.7031 4 P 0 0;3=13,5=1
P 4.26605 4.6631 4 P 0 0;3=13,5=1
P 4.26605 4.7031 4 P 0 0;3=13,5=1
P 4.65605 4.6631 4 P 0 0;3=13,5=1
P 4.69605 4.6631 4 P 0 0;3=13,5=1
P 4.65605 4.7031 4 P 0 0;3=13,5=1
P 4.69605 4.7031 4 P 0 0;3=13,5=1
P 4.73105 4.6431 4 P 0 0;3=13,5=1
P 4.81605 4.6631 4 P 0 0;3=13,5=1
P 4.85605 4.6631 4 P 0 0;3=13,5=1
P 4.81605 4.7031 4 P 0 0;3=13,5=1
P 4.85605 4.7031 4 P 0 0;3=13,5=1
P 4.77605 4.6431 4 P 0 0;3=13,5=1
P 5.17605 4.7131 4 P 0 0;3=13,5=1
P 5.17605 4.6731 4 P 0 0;3=13,5=1
P 5.08105 4.6731 4 P 0 0;3=13,5=1
P 5.13105 4.6731 4 P 0 0;3=13,5=1
P 5.03605 4.6731 4 P 0 0;3=13,5=1
P 5.03605 4.7131 4 P 0 0;3=13,5=1
P 4.30605 4.7481 4 P 0 0;3=13,5=1
P 4.30605 4.7931 4 P 0 0;3=13,5=1
P 4.30605 4.8381 4 P 0 0;3=13,5=1
P 4.38605 4.8381 4 P 0 0;3=13,5=1
P 4.34605 4.8381 4 P 0 0;3=13,5=1
P 4.46605 4.8381 4 P 0 0;3=13,5=1
P 4.42605 4.8381 4 P 0 0;3=13,5=1
P 4.42605 4.7931 4 P 0 0;3=13,5=1
P 4.42605 4.7481 4 P 0 0;3=13,5=1
P 4.46605 4.7931 4 P 0 0;3=13,5=1
P 4.46605 4.7481 4 P 0 0;3=13,5=1
P 4.26605 4.7481 4 P 0 0;3=13,5=1
P 4.26605 4.7931 4 P 0 0;3=13,5=1
P 4.26605 4.8381 4 P 0 0;3=13,5=1
P 4.65605 4.8381 4 P 0 0;3=13,5=1
P 4.65605 4.7931 4 P 0 0;3=13,5=1
P 4.65605 4.7481 4 P 0 0;3=13,5=1
P 4.69605 4.8381 4 P 0 0;3=13,5=1
P 4.69605 4.7931 4 P 0 0;3=13,5=1
P 4.69605 4.7481 4 P 0 0;3=13,5=1
P 4.73605 4.8381 4 P 0 0;3=13,5=1
P 4.81605 4.8381 4 P 0 0;3=13,5=1
P 4.81605 4.7931 4 P 0 0;3=13,5=1
P 4.81605 4.7481 4 P 0 0;3=13,5=1
P 4.85605 4.8381 4 P 0 0;3=13,5=1
P 4.85605 4.7931 4 P 0 0;3=13,5=1
P 4.85605 4.7481 4 P 0 0;3=13,5=1
P 4.77605 4.8381 4 P 0 0;3=13,5=1
P 5.08105 4.8431 4 P 0 0;3=13,5=1
P 5.13105 4.8431 4 P 0 0;3=13,5=1
P 5.17605 4.8431 4 P 0 0;3=13,5=1
P 5.17605 4.8031 4 P 0 0;3=13,5=1
P 5.17605 4.7581 4 P 0 0;3=13,5=1
P 5.03605 4.8431 4 P 0 0;3=13,5=1
P 5.03605 4.8031 4 P 0 0;3=13,5=1
P 5.03605 4.7581 4 P 0 0;3=13,5=1
P 4.58268002 2.96615 3 P 0 0;3=12,5=1
P 4.63268002 2.96615 3 P 0 0;3=12,5=1
P 4.63268002 3.11615 3 P 0 0;3=12,5=1
P 4.58268002 3.01615 3 P 0 0;3=12,5=1
P 4.58268002 3.11615 3 P 0 0;3=12,5=1
P 4.63268002 3.01615 3 P 0 0;3=12,5=1
P 4.63268002 3.31615 3 P 0 0;3=12,5=1
P 4.58268002 3.26615 3 P 0 0;3=12,5=1
P 4.58268002 3.31615 3 P 0 0;3=12,5=1
P 4.63268002 3.26615 3 P 0 0;3=12,5=1
P 4.63268002 3.16615 3 P 0 0;3=12,5=1
P 4.58268002 3.16615 3 P 0 0;3=12,5=1
P 4.58268002 3.46615 3 P 0 0;3=12,5=1
P 4.63268002 3.41615 3 P 0 0;3=12,5=1
P 4.63268002 3.46615 3 P 0 0;3=12,5=1
P 4.58268002 3.41615 3 P 0 0;3=12,5=1
P 4.58268002 3.61615 3 P 0 0;3=12,5=1
P 4.58268002 3.56615 3 P 0 0;3=12,5=1
P 4.63268002 3.61615 3 P 0 0;3=12,5=1
P 4.63268002 3.56615 3 P 0 0;3=12,5=1
P 4.58268002 3.71615 3 P 0 0;3=12,5=1
P 4.63268002 3.71615 3 P 0 0;3=12,5=1
P 4.58268002 3.76615 3 P 0 0;3=12,5=1
P 4.58268002 3.86615 3 P 0 0;3=12,5=1
P 4.63268002 3.76615 3 P 0 0;3=12,5=1
P 4.63268002 3.86615 3 P 0 0;3=12,5=1
P 4.68268002 2.96615 3 P 0 0;3=12,5=1
P 4.73268002 2.96615 3 P 0 0;3=12,5=1
P 4.78268002 2.96615 3 P 0 0;3=12,5=1
P 4.68268002 3.11615 3 P 0 0;3=12,5=1
P 4.68268002 3.01615 3 P 0 0;3=12,5=1
P 4.73268002 3.11615 3 P 0 0;3=12,5=1
P 4.73268002 3.01615 3 P 0 0;3=12,5=1
P 4.78268002 3.11615 3 P 0 0;3=12,5=1
P 4.78268002 3.01615 3 P 0 0;3=12,5=1
P 4.73268002 3.31615 3 P 0 0;3=12,5=1
P 4.73268002 3.26615 3 P 0 0;3=12,5=1
P 4.68268002 3.26615 3 P 0 0;3=12,5=1
P 4.68268002 3.31615 3 P 0 0;3=12,5=1
P 4.78268002 3.26615 3 P 0 0;3=12,5=1
P 4.78268002 3.31615 3 P 0 0;3=12,5=1
P 4.73268002 3.16615 3 P 0 0;3=12,5=1
P 4.68268002 3.16615 3 P 0 0;3=12,5=1
P 4.78268002 3.16615 3 P 0 0;3=12,5=1
P 4.73268002 3.41615 3 P 0 0;3=12,5=1
P 4.68268002 3.41615 3 P 0 0;3=12,5=1
P 4.68268002 3.46615 3 P 0 0;3=12,5=1
P 4.73268002 3.46615 3 P 0 0;3=12,5=1
P 4.78268002 3.46615 3 P 0 0;3=12,5=1
P 4.78268002 3.41615 3 P 0 0;3=12,5=1
P 4.73268002 3.56615 3 P 0 0;3=12,5=1
P 4.73268002 3.61615 3 P 0 0;3=12,5=1
P 4.68268002 3.56615 3 P 0 0;3=12,5=1
P 4.68268002 3.61615 3 P 0 0;3=12,5=1
P 4.78268002 3.61615 3 P 0 0;3=12,5=1
P 4.78268002 3.56615 3 P 0 0;3=12,5=1
P 4.73268002 3.71615 3 P 0 0;3=12,5=1
P 4.68268002 3.71615 3 P 0 0;3=12,5=1
P 4.78268002 3.71615 3 P 0 0;3=12,5=1
P 4.73268002 3.76615 3 P 0 0;3=12,5=1
P 4.73268002 3.86615 3 P 0 0;3=12,5=1
P 4.68268002 3.76615 3 P 0 0;3=12,5=1
P 4.68268002 3.86615 3 P 0 0;3=12,5=1
P 4.78268002 3.76615 3 P 0 0;3=12,5=1
P 4.78268002 3.86615 3 P 0 0;3=12,5=1
P 4.88268002 3.86615 3 P 0 0;3=12,5=1
P 4.83268002 3.86615 3 P 0 0;3=12,5=1
P 5.03268002 3.86615 3 P 0 0;3=12,5=1
P 4.93268002 3.86615 3 P 0 0;3=12,5=1
P 4.98268002 3.86615 3 P 0 0;3=12,5=1
P 4.88268002 3.76615 3 P 0 0;3=12,5=1
P 4.83268002 3.76615 3 P 0 0;3=12,5=1
P 5.03268002 3.76615 3 P 0 0;3=12,5=1
P 4.93268002 3.76615 3 P 0 0;3=12,5=1
P 4.98268002 3.76615 3 P 0 0;3=12,5=1
P 4.88268002 3.71615 3 P 0 0;3=12,5=1
P 4.83268002 3.71615 3 P 0 0;3=12,5=1
P 5.03268002 3.71615 3 P 0 0;3=12,5=1
P 4.93268002 3.71615 3 P 0 0;3=12,5=1
P 4.98268002 3.71615 3 P 0 0;3=12,5=1
P 4.88268002 3.61615 3 P 0 0;3=12,5=1
P 4.83268002 3.61615 3 P 0 0;3=12,5=1
P 5.03268002 3.61615 3 P 0 0;3=12,5=1
P 4.93268002 3.61615 3 P 0 0;3=12,5=1
P 4.98268002 3.61615 3 P 0 0;3=12,5=1
P 4.88268002 3.56615 3 P 0 0;3=12,5=1
P 4.83268002 3.56615 3 P 0 0;3=12,5=1
P 5.03268002 3.56615 3 P 0 0;3=12,5=1
P 4.93268002 3.56615 3 P 0 0;3=12,5=1
P 4.98268002 3.56615 3 P 0 0;3=12,5=1
P 4.88268002 3.46615 3 P 0 0;3=12,5=1
P 4.83268002 3.46615 3 P 0 0;3=12,5=1
P 5.03268002 3.46615 3 P 0 0;3=12,5=1
P 4.93268002 3.46615 3 P 0 0;3=12,5=1
P 4.98268002 3.46615 3 P 0 0;3=12,5=1
P 4.88268002 3.41615 3 P 0 0;3=12,5=1
P 4.83268002 3.41615 3 P 0 0;3=12,5=1
P 5.03268002 3.41615 3 P 0 0;3=12,5=1
P 4.93268002 3.41615 3 P 0 0;3=12,5=1
P 4.98268002 3.41615 3 P 0 0;3=12,5=1
P 4.88268002 3.31615 3 P 0 0;3=12,5=1
P 4.83268002 3.31615 3 P 0 0;3=12,5=1
P 5.03268002 3.31615 3 P 0 0;3=12,5=1
P 4.93268002 3.31615 3 P 0 0;3=12,5=1
P 4.98268002 3.31615 3 P 0 0;3=12,5=1
P 4.83268002 3.26615 3 P 0 0;3=12,5=1
P 4.88268002 3.26615 3 P 0 0;3=12,5=1
P 4.98268002 3.26615 3 P 0 0;3=12,5=1
P 4.93268002 3.26615 3 P 0 0;3=12,5=1
P 5.03268002 3.26615 3 P 0 0;3=12,5=1
P 4.83268002 3.16615 3 P 0 0;3=12,5=1
P 4.88268002 3.16615 3 P 0 0;3=12,5=1
P 4.98268002 3.16615 3 P 0 0;3=12,5=1
P 4.93268002 3.16615 3 P 0 0;3=12,5=1
P 5.03268002 3.16615 3 P 0 0;3=12,5=1
P 4.83268002 3.11615 3 P 0 0;3=12,5=1
P 4.88268002 3.11615 3 P 0 0;3=12,5=1
P 4.98268002 3.11615 3 P 0 0;3=12,5=1
P 4.93268002 3.11615 3 P 0 0;3=12,5=1
P 5.03268002 3.11615 3 P 0 0;3=12,5=1
P 4.83268002 3.01615 3 P 0 0;3=12,5=1
P 4.88268002 3.01615 3 P 0 0;3=12,5=1
P 4.98268002 3.01615 3 P 0 0;3=12,5=1
P 4.93268002 3.01615 3 P 0 0;3=12,5=1
P 5.03268002 3.01615 3 P 0 0;3=12,5=1
P 4.83268002 2.96615 3 P 0 0;3=12,5=1
P 4.88268002 2.96615 3 P 0 0;3=12,5=1
P 4.98268002 2.96615 3 P 0 0;3=12,5=1
P 4.93268002 2.96615 3 P 0 0;3=12,5=1
P 5.03268002 2.96615 3 P 0 0;3=12,5=1
P 2.42106004 3.69115 6 P 0 0;1,3=11,5=0
P 2.44606004 3.71615 3 P 0 0;3=12,5=1
P 3.38003996 4.78291998 3 P 0 0;3=12,5=1
P 3.38823002 4.85788002 37 P 0 0;1,3=1,5=0
P 2.17106004 3.79115 6 P 0 0;1,3=11,5=0
P 2.19606004 3.81615 3 P 0 0;3=12,5=1
P 3.02571004 4.667 3 P 0 0;3=12,5=1
P 3.0339 4.85788002 37 P 0 0;1,3=1,5=0
P 2.19606004 3.86615 3 P 0 0;3=12,5=1
P 2.17106004 3.84115 6 P 0 0;1,3=11,5=0
P 3.06571004 4.667 3 P 0 0;3=12,5=1
P 3.05751998 4.85788002 37 P 0 0;1,3=1,5=0
P 3.27831004 4.642 3 P 0 0;3=12,5=1
P 2.37106004 3.74115 6 P 0 0;1,3=11,5=0
P 2.39606004 3.76615 3 P 0 0;3=12,5=1
P 3.27011998 4.85788002 37 P 0 0;1,3=1,5=0
P 4.75768002 2.69115 6 P 0 0;1,3=11,5=0
P 4.73268002 2.66615 3 P 0 0;3=12,5=1
P 10.76161004 2.69115 6 P 0 0;1,3=11,5=0
P 10.73661004 2.66615 3 P 0 0;3=12,5=1
P 3.23831004 4.642 3 P 0 0;3=12,5=1
P 2.39606004 3.81615 3 P 0 0;3=12,5=1
P 2.37106004 3.79115 6 P 0 0;1,3=11,5=0
P 3.2465 4.85788002 37 P 0 0;1,3=1,5=0
P 5.00768002 2.64115 6 P 0 0;1,3=11,5=0
P 5.03268002 2.61615 3 P 0 0;3=12,5=1
P 3.34916998 5.1035 3 P 0 0;3=12,5=1
P 2.47106004 3.74115 6 P 0 0;1,3=11,5=0
P 2.49606004 3.76615 3 P 0 0;3=12,5=1
P 3.34098996 4.97913996 37 P 0 0;1,3=1,5=0
P 3.30916998 5.1035 3 P 0 0;3=12,5=1
P 2.47106004 3.79115 6 P 0 0;1,3=11,5=0
P 2.49606004 3.81615 3 P 0 0;3=12,5=1
P 3.31736004 4.97913996 37 P 0 0;1,3=1,5=0
P 11.01161004 2.64115 6 P 0 0;1,3=11,5=0
P 11.03661004 2.61615 3 P 0 0;3=12,5=1
P 2.74225 4.667 3 P 0 0;3=12,5=1
P 2.09606004 3.66615 3 P 0 0;3=12,5=1
P 2.07106004 3.64115 6 P 0 0;1,3=11,5=0
P 2.75043996 4.85788002 37 P 0 0;1,3=1,5=0
P 2.42106004 3.79115 6 P 0 0;1,3=11,5=0
P 2.44606004 3.81615 3 P 0 0;3=12,5=1
P 3.20743996 4.78291998 3 P 0 0;3=12,5=1
P 3.19925 4.85788002 37 P 0 0;1,3=1,5=0
P 2.78225 4.667 3 P 0 0;3=12,5=1
P 2.07106004 3.69115 6 P 0 0;1,3=11,5=0
P 2.09606004 3.71615 3 P 0 0;3=12,5=1
P 2.77406004 4.85788002 37 P 0 0;1,3=1,5=0
P 2.42106004 3.84115 6 P 0 0;1,3=11,5=0
P 2.44606004 3.86615 3 P 0 0;3=12,5=1
P 3.16743996 4.78291998 3 P 0 0;3=12,5=1
P 3.17563002 4.85788002 37 P 0 0;1,3=1,5=0
P 2.34606004 3.81615 3 P 0 0;3=12,5=1
P 2.32106004 3.79115 6 P 0 0;1,3=11,5=0
P 3.27831004 5.22001998 3 P 0 0;3=12,5=1
P 3.27011998 4.97913996 37 P 0 0;1,3=1,5=0
P 2.34606004 3.86615 3 P 0 0;3=12,5=1
P 2.32106004 3.84115 6 P 0 0;1,3=11,5=0
P 3.23831004 5.22001998 3 P 0 0;3=12,5=1
P 3.2465 4.97913996 37 P 0 0;1,3=1,5=0
P 4.65768002 2.64115 6 P 0 0;1,3=11,5=0
P 4.63268002 2.61615 3 P 0 0;3=12,5=1
P 10.96161004 2.64115 6 P 0 0;1,3=11,5=0
P 10.98661004 2.61615 3 P 0 0;3=12,5=1
P 2.19606004 3.66615 3 P 0 0;3=12,5=1
P 2.17106004 3.64115 6 P 0 0;1,3=11,5=0
P 2.81311004 4.78291998 3 P 0 0;3=12,5=1
P 2.8213 4.85788002 37 P 0 0;1,3=1,5=0
P 10.96161004 2.59115 6 P 0 0;1,3=11,5=0
P 10.98661004 2.56615 3 P 0 0;3=12,5=1
P 2.17106004 3.69115 6 P 0 0;1,3=11,5=0
P 2.19606004 3.71615 3 P 0 0;3=12,5=1
P 2.85311004 4.78291998 3 P 0 0;3=12,5=1
P 2.84491998 4.85788002 37 P 0 0;1,3=1,5=0
P 0.64808996 1.655 4 P 0 0;3=13,5=1
P 5.76 2.66 1 P 0 0;3=0,5=1
P 10.66161004 2.64115 6 P 0 0;1,3=11,5=0
P 10.63661004 2.61615 3 P 0 0;3=12,5=1
P 2.07106004 3.79115 6 P 0 0;1,3=11,5=0
P 2.09606004 3.81615 3 P 0 0;3=12,5=1
P 3.09656998 5.0535 3 P 0 0;3=12,5=1
P 3.10476998 4.97913996 37 P 0 0;1,3=1,5=0
P 2.09606004 3.86615 3 P 0 0;3=12,5=1
P 2.07106004 3.84115 6 P 0 0;1,3=11,5=0
P 3.13656998 5.0535 3 P 0 0;3=12,5=1
P 3.12838996 4.97913996 37 P 0 0;1,3=1,5=0
P 2.88708002 4.667 3 P 0 0;3=12,5=1
P 2.04606004 3.76615 3 P 0 0;3=12,5=1
P 2.02106004 3.74115 6 P 0 0;1,3=11,5=0
P 2.96303002 4.85788002 37 P 0 0;1,3=1,5=0
P 10.76161004 2.64115 6 P 0 0;1,3=11,5=0
P 10.73661004 2.61615 3 P 0 0;3=12,5=1
P 2.92708002 4.667 3 P 0 0;3=12,5=1
P 2.04606004 3.81615 3 P 0 0;3=12,5=1
P 2.02106004 3.79115 6 P 0 0;1,3=11,5=0
P 2.98666004 4.85788002 37 P 0 0;1,3=1,5=0
P 10.71161004 2.64115 6 P 0 0;1,3=11,5=0
P 10.68661004 2.61615 3 P 0 0;3=12,5=1
P 5.03268002 2.46615 3 P 0 0;3=12,5=1
P 5.00768002 2.44115 6 P 0 0;1,3=11,5=0
P 5.03268002 2.51615 3 P 0 0;3=12,5=1
P 5.00768002 2.49115 6 P 0 0;1,3=11,5=0
P 11.06161004 2.59115 6 P 0 0;1,3=11,5=0
P 11.08661004 2.56615 3 P 0 0;3=12,5=1
P 10.71161004 2.59115 6 P 0 0;1,3=11,5=0
P 10.68661004 2.56615 3 P 0 0;3=12,5=1
P 9.175 5.255 1 P 0 0;3=0,5=1
P 9.20278996 4.97913996 37 P 0 0;1,3=1,5=0
P 4.75768002 2.64115 6 P 0 0;1,3=11,5=0
P 4.73268002 2.61615 3 P 0 0;3=12,5=1
P 9.11853996 5.255 1 P 0 0;3=0,5=1
P 9.17916998 4.97913996 37 P 0 0;1,3=1,5=0
P 5.08268002 2.41615 3 P 0 0;3=12,5=1
P 5.05768002 2.44115 6 P 0 0;1,3=11,5=0
P 10.91161004 2.69115 6 P 0 0;1,3=11,5=0
P 10.93661004 2.66615 3 P 0 0;3=12,5=1
P 10.61161004 2.64115 6 P 0 0;1,3=11,5=0
P 10.58661004 2.61615 3 P 0 0;3=12,5=1
P 8.15 3.76615 3 P 0 0;3=12,5=1
P 8.125 3.74115 6 P 0 0;1,3=11,5=0
P 9.02925 5.165 3 P 0 0;3=12,5=1
P 9.03743996 4.97913996 37 P 0 0;1,3=1,5=0
P 4.95768002 2.24115 6 P 0 0;1,3=11,5=0
P 4.98268002 2.21615 3 P 0 0;3=12,5=1
P 10.61161004 2.59115 6 P 0 0;1,3=11,5=0
P 10.58661004 2.56615 3 P 0 0;3=12,5=1
P 8.15 3.81615 3 P 0 0;3=12,5=1
P 8.125 3.79115 6 P 0 0;1,3=11,5=0
P 9.06925 5.165 3 P 0 0;3=12,5=1
P 9.06106004 4.97913996 37 P 0 0;1,3=1,5=0
P 11.01161004 2.69115 6 P 0 0;1,3=11,5=0
P 11.03661004 2.66615 3 P 0 0;3=12,5=1
P 4.95768002 2.29115 6 P 0 0;1,3=11,5=0
P 4.98268002 2.26615 3 P 0 0;3=12,5=1
P 10.91161004 2.64115 6 P 0 0;1,3=11,5=0
P 10.93661004 2.61615 3 P 0 0;3=12,5=1
P 5.00768002 2.29115 6 P 0 0;1,3=11,5=0
P 5.03268002 2.26615 3 P 0 0;3=12,5=1
P 11.06161004 2.64115 6 P 0 0;1,3=11,5=0
P 11.08661004 2.61615 3 P 0 0;3=12,5=1
P 5.00768002 2.34115 6 P 0 0;1,3=11,5=0
P 5.03268002 2.31615 3 P 0 0;3=12,5=1
P 10.66161004 2.69115 6 P 0 0;1,3=11,5=0
P 10.63661004 2.66615 3 P 0 0;3=12,5=1
P 3.8399 4.82898996 25 P 0 0;1,3=4,5=0
P 3.88313002 4.96076998 39 P 0 0;1,3=20,5=0
P 3.84 4.87 7 P 0 0;2,3=6,5=1
P 3.8599 5.35898996 25 P 0 0;1,3=4,5=0
P 3.775 5.295 1 P 0 0;3=0,5=1
P 0.73 5.823 25 P 0 0;1,3=4,5=0
P 0.72933002 5.70373996 49 P 0 0;1,3=16,5=0
P 0.73 5.78 4 P 0 0;3=13,5=1
P 8.07 5.29 1 P 0 0;3=0,5=1
P 8.03818996 4.97913996 37 P 0 0;1,3=1,5=0
P 3.8399 4.765 1 P 0 0;3=0,5=1
P 0.81 5.823 25 P 0 0;1,3=4,5=0
P 0.80806998 5.70373996 49 P 0 0;1,3=16,5=0
P 0.81 5.78 4 P 0 0;3=13,5=1
P 3.8399 4.79498996 25 P 0 0;1,3=4,5=0
P 8.005 5.29 1 P 0 0;3=0,5=1
P 8.01456998 4.97913996 37 P 0 0;1,3=1,5=0
P 3.90871998 5.18321004 39 P 0 0;1,3=20,5=0
P 3.8599 5.32498996 25 P 0 0;1,3=4,5=0
P 3.8599 5.2751 7 P 0 0;2,3=6,5=1
P 11.08661004 1.91615 3 P 0 0;3=12,5=1
P 11.06161004 1.94115 6 P 0 0;1,3=11,5=0
P 4.95768002 1.94115 6 P 0 0;1,3=11,5=0
P 4.98268002 1.91615 3 P 0 0;3=12,5=1
P 4.95768002 1.99115 6 P 0 0;1,3=11,5=0
P 4.98268002 1.96615 3 P 0 0;3=12,5=1
P 4.90768002 1.89115 6 P 0 0;1,3=11,5=0
P 4.93268002 1.86615 3 P 0 0;3=12,5=1
P 4.90768002 1.94115 6 P 0 0;1,3=11,5=0
P 4.93268002 1.91615 3 P 0 0;3=12,5=1
P 3.8899 4.82898996 25 P 0 0;1,3=4,5=0
P 3.90871998 4.96076998 39 P 0 0;1,3=20,5=0
P 3.89 4.87 7 P 0 0;2,3=6,5=1
P 5.00768002 1.89115 6 P 0 0;1,3=11,5=0
P 5.03268002 1.86615 3 P 0 0;3=12,5=1
P 3.9099 5.32498996 25 P 0 0;1,3=4,5=0
P 3.93431004 5.18321004 39 P 0 0;1,3=20,5=0
P 3.9099 5.2751 7 P 0 0;2,3=6,5=1
P 5.05768002 1.94115 6 P 0 0;1,3=11,5=0
P 5.08268002 1.91615 3 P 0 0;3=12,5=1
P 5.05768002 2.59115 6 P 0 0;1,3=11,5=0
P 5.08268002 2.56615 3 P 0 0;3=12,5=1
P 8.15 2.51615 3 P 0 0;3=12,5=1
P 8.125 2.49115 6 P 0 0;1,3=11,5=0
P 4.95768002 2.64115 6 P 0 0;1,3=11,5=0
P 4.98268002 2.61615 3 P 0 0;3=12,5=1
P 10.71161004 2.74115 6 P 0 0;1,3=11,5=0
P 10.68661004 2.71615 3 P 0 0;3=12,5=1
P 10.96161004 2.74115 6 P 0 0;1,3=11,5=0
P 10.98661004 2.71615 3 P 0 0;3=12,5=1
P 10.81161004 2.74115 6 P 0 0;1,3=11,5=0
P 10.78661004 2.71615 3 P 0 0;3=12,5=1
P 4.90768002 2.69115 6 P 0 0;1,3=11,5=0
P 4.93268002 2.66615 3 P 0 0;3=12,5=1
P 10.86161004 2.74115 6 P 0 0;1,3=11,5=0
P 10.88661004 2.71615 3 P 0 0;3=12,5=1
P 10.71161004 2.79115 6 P 0 0;1,3=11,5=0
P 10.68661004 2.76615 3 P 0 0;3=12,5=1
P 9.60795 0.65065 43 P 0 0;1,3=28,5=0
P 9.64 0.71 1 P 0 0;3=0,5=1
P 9.61795 0.76243002 25 P 0 0;1,3=4,5=0
P 10.61161004 2.84115 6 P 0 0;1,3=11,5=0
P 10.58661004 2.81615 3 P 0 0;3=12,5=1
P 9.40795 0.42821004 43 P 0 0;1,3=28,5=0
P 9.43296004 0.49133002 1 P 0 0;3=0,5=1
P 9.40795 0.32643002 25 P 0 0;1,3=4,5=0
P 10.66161004 2.84115 6 P 0 0;1,3=11,5=0
P 9.40795 0.65065 43 P 0 0;1,3=28,5=0
P 9.43296004 0.73633002 1 P 0 0;3=0,5=1
P 9.40795 0.76243002 25 P 0 0;1,3=4,5=0
P 10.63661004 2.81615 3 P 0 0;3=12,5=1
P 4.70768002 2.59115 6 P 0 0;1,3=11,5=0
P 4.68268002 2.56615 3 P 0 0;3=12,5=1
P 10.71161004 2.84115 6 P 0 0;1,3=11,5=0
P 10.68661004 2.81615 3 P 0 0;3=12,5=1
P 9.55795 0.32643002 25 P 0 0;1,3=4,5=0
P 9.55795 0.42821004 43 P 0 0;1,3=28,5=0
P 9.55795 0.36633002 1 P 0 0;3=0,5=1
P 10.76161004 2.84115 6 P 0 0;1,3=11,5=0
P 10.73661004 2.81615 3 P 0 0;3=12,5=1
P 9.55795 0.65065 43 P 0 0;1,3=28,5=0
P 9.35796004 0.49133002 1 P 0 0;3=0,5=1
P 5.00768002 2.69115 6 P 0 0;1,3=11,5=0
P 5.03268002 2.66615 3 P 0 0;3=12,5=1
P 10.81161004 2.84115 6 P 0 0;1,3=11,5=0
P 10.78661004 2.81615 3 P 0 0;3=12,5=1
P 9.58296004 0.71133002 1 P 0 0;3=0,5=1
P 9.45795 0.65065 43 P 0 0;1,3=28,5=0
P 9.46795 0.76243002 25 P 0 0;1,3=4,5=0
P 5.05768002 2.64115 6 P 0 0;1,3=11,5=0
P 5.08268002 2.61615 3 P 0 0;3=12,5=1
P 11.08661004 1.96615 3 P 0 0;3=12,5=1
P 11.06161004 1.99115 6 P 0 0;1,3=11,5=0
P 11.03661004 1.86615 3 P 0 0;3=12,5=1
P 11.01161004 1.89115 6 P 0 0;1,3=11,5=0
P 11.03661004 1.91615 3 P 0 0;3=12,5=1
P 11.01161004 1.94115 6 P 0 0;1,3=11,5=0
P 10.93661004 1.86615 3 P 0 0;3=12,5=1
P 10.91161004 1.89115 6 P 0 0;1,3=11,5=0
P 10.93661004 1.91615 3 P 0 0;3=12,5=1
P 10.91161004 1.94115 6 P 0 0;1,3=11,5=0
P 10.98661004 1.91615 3 P 0 0;3=12,5=1
P 10.96161004 1.94115 6 P 0 0;1,3=11,5=0
P 10.98661004 1.96615 3 P 0 0;3=12,5=1
P 10.96161004 1.99115 6 P 0 0;1,3=11,5=0
P 4.90768002 2.64115 6 P 0 0;1,3=11,5=0
P 4.93268002 2.61615 3 P 0 0;3=12,5=1
P 11.03661004 2.01615 3 P 0 0;3=12,5=1
P 11.01161004 2.04115 6 P 0 0;1,3=11,5=0
P 11.03661004 2.06615 3 P 0 0;3=12,5=1
P 11.01161004 2.09115 6 P 0 0;1,3=11,5=0
P 10.93661004 2.01615 3 P 0 0;3=12,5=1
P 10.91161004 2.04115 6 P 0 0;1,3=11,5=0
P 10.93661004 2.06615 3 P 0 0;3=12,5=1
P 10.91161004 2.09115 6 P 0 0;1,3=11,5=0
P 10.98661004 2.06615 3 P 0 0;3=12,5=1
P 10.96161004 2.09115 6 P 0 0;1,3=11,5=0
P 10.98661004 2.11615 3 P 0 0;3=12,5=1
P 10.96161004 2.14115 6 P 0 0;1,3=11,5=0
P 11.08661004 2.06615 3 P 0 0;3=12,5=1
P 11.06161004 2.09115 6 P 0 0;1,3=11,5=0
P 11.08661004 2.11615 3 P 0 0;3=12,5=1
P 11.06161004 2.14115 6 P 0 0;1,3=11,5=0
P 3.115 5.255 1 P 0 0;3=0,5=1
P 3.17563002 4.97913996 37 P 0 0;1,3=1,5=0
P 4.65768002 2.69115 6 P 0 0;1,3=11,5=0
P 4.63268002 2.66615 3 P 0 0;3=12,5=1
P 11.08661004 2.21615 3 P 0 0;3=12,5=1
P 11.06161004 2.24115 6 P 0 0;1,3=11,5=0
P 4.95768002 2.59115 6 P 0 0;1,3=11,5=0
P 4.98268002 2.56615 3 P 0 0;3=12,5=1
P 11.08661004 2.26615 3 P 0 0;3=12,5=1
P 11.06161004 2.29115 6 P 0 0;1,3=11,5=0
P 11.03661004 2.26615 3 P 0 0;3=12,5=1
P 11.01161004 2.29115 6 P 0 0;1,3=11,5=0
P 2.14606004 3.76615 3 P 0 0;3=12,5=1
P 2.12106004 3.74115 6 P 0 0;1,3=11,5=0
P 3.02571004 5.165 3 P 0 0;3=12,5=1
P 3.0339 4.97913996 37 P 0 0;1,3=1,5=0
P 11.03661004 2.31615 3 P 0 0;3=12,5=1
P 11.01161004 2.34115 6 P 0 0;1,3=11,5=0
P 10.98661004 2.21615 3 P 0 0;3=12,5=1
P 10.96161004 2.24115 6 P 0 0;1,3=11,5=0
P 10.98661004 2.26615 3 P 0 0;3=12,5=1
P 10.96161004 2.29115 6 P 0 0;1,3=11,5=0
P 3.17146004 5.255 1 P 0 0;3=0,5=1
P 3.19925 4.97913996 37 P 0 0;1,3=1,5=0
P 4.70768002 2.64115 6 P 0 0;1,3=11,5=0
P 4.68268002 2.61615 3 P 0 0;3=12,5=1
P 10.93661004 2.26615 3 P 0 0;3=12,5=1
P 10.91161004 2.29115 6 P 0 0;1,3=11,5=0
P 10.58661004 2.76615 3 P 0 0;3=12,5=1
P 10.61161004 2.79115 6 P 0 0;1,3=11,5=0
P 3.98548996 5.18321004 39 P 0 0;1,3=20,5=0
P 4.0099 5.32498996 25 P 0 0;1,3=4,5=0
P 4 5.29 1 P 0 0;3=0,5=1
P 10.93661004 2.31615 3 P 0 0;3=12,5=1
P 10.91161004 2.34115 6 P 0 0;1,3=11,5=0
P 10.86161004 2.19115 6 P 0 0;1,3=11,5=0
P 10.88661004 2.16615 3 P 0 0;3=12,5=1
P 3.93431004 4.96076998 39 P 0 0;1,3=20,5=0
P 3.98548996 4.96076998 39 P 0 0;1,3=20,5=0
P 3.9399 4.82898996 25 P 0 0;1,3=4,5=0
P 3.94 4.87 7 P 0 0;2,3=6,5=1
P 10.76161004 1.94115 6 P 0 0;1,3=11,5=0
P 10.73661004 1.91615 3 P 0 0;3=12,5=1
P 10.395 1.28555 3 P 0 0;3=12,5=1
P 12.81495 1.96456998 8 P 0 0;3=2,5=0
P 9.42358002 5.22001998 3 P 0 0;3=12,5=1
P 8.98115 2.825 3 P 0 0;3=12,5=1
P 9.41538996 4.97913996 37 P 0 0;1,3=1,5=0
P 3.9599 5.18321004 39 P 0 0;1,3=20,5=0
P 4.01108002 5.18321004 39 P 0 0;1,3=20,5=0
P 3.9599 5.32498996 25 P 0 0;1,3=4,5=0
P 3.9599 5.275 7 P 0 0;2,3=6,5=1
P 4.60768002 2.64115 6 P 0 0;1,3=11,5=0
P 4.58268002 2.61615 3 P 0 0;3=12,5=1
P 9.38358002 5.22001998 3 P 0 0;3=12,5=1
P 8.98115 2.865 3 P 0 0;3=12,5=1
P 9.39176998 4.97913996 37 P 0 0;1,3=1,5=0
P 2.14606004 3.81615 3 P 0 0;3=12,5=1
P 2.12106004 3.79115 6 P 0 0;1,3=11,5=0
P 3.06571004 5.165 3 P 0 0;3=12,5=1
P 3.05751998 4.97913996 37 P 0 0;1,3=1,5=0
P 11.08661004 2.71615 3 P 0 0;3=12,5=1
P 11.06161004 2.74115 6 P 0 0;1,3=11,5=0
P 3.9599 4.96076998 39 P 0 0;1,3=20,5=0
P 3.9899 4.82898996 25 P 0 0;1,3=4,5=0
P 3.985 4.88998996 1 P 0 0;3=0,5=1
P 11.73316004 2.652 3 P 0 0;3=12,5=1
P 12.55905 4.40551004 8 P 0 0;3=2,5=0
P 11.73316004 2.612 3 P 0 0;3=12,5=1
P 12.63778996 4.44488002 8 P 0 0;3=2,5=0
P 8.3 2.86615 3 P 0 0;3=12,5=1
P 8.275 2.84115 6 P 0 0;1,3=11,5=0
P 4.80768002 2.19115 6 P 0 0;1,3=11,5=0
P 4.83268002 2.16615 3 P 0 0;3=12,5=1
P 0.69348996 1.90611998 3 P 0 0;3=12,5=1
P 11.73316004 2.492 3 P 0 0;3=12,5=1
P 12.55905 4.24803002 8 P 0 0;3=2,5=0
P 4.85768002 2.19115 6 P 0 0;1,3=11,5=0
P 4.88268002 2.16615 3 P 0 0;3=12,5=1
P 0.69348996 1.86611998 3 P 0 0;3=12,5=1
P 11.73316004 2.452 3 P 0 0;3=12,5=1
P 12.63778996 4.2874 8 P 0 0;3=2,5=0
P 8.25 2.86615 3 P 0 0;3=12,5=1
P 8.225 2.84115 6 P 0 0;1,3=11,5=0
P 12.55905 3.93306998 8 P 0 0;3=2,5=0
P 11.73316004 2.332 3 P 0 0;3=12,5=1
P 12.63778996 3.97243996 8 P 0 0;3=2,5=0
P 11.73316004 2.292 3 P 0 0;3=12,5=1
P 10.81161004 2.19115 6 P 0 0;1,3=11,5=0
P 10.83661004 2.16615 3 P 0 0;3=12,5=1
P 11.53316004 2.092 3 P 0 0;3=12,5=1
P 12.55905 3.77558996 8 P 0 0;3=2,5=0
P 11.53316004 2.052 3 P 0 0;3=12,5=1
P 12.63778996 3.81496004 8 P 0 0;3=2,5=0
P 12.81495 3.53936998 8 P 0 0;3=2,5=0
P 10.71161004 2.29115 6 P 0 0;1,3=11,5=0
P 10.68661004 2.26615 3 P 0 0;3=12,5=1
P 9.975 2.3758 3 P 0 0;3=12,5=1
P 12.81495 3.38188996 8 P 0 0;3=2,5=0
P 10.76161004 2.34115 6 P 0 0;1,3=11,5=0
P 10.73661004 2.31615 3 P 0 0;3=12,5=1
P 9.975 2.23955 3 P 0 0;3=12,5=1
P 12.81495 2.20078996 8 P 0 0;3=2,5=0
P 10.71161004 1.94115 6 P 0 0;1,3=11,5=0
P 10.68661004 1.91615 3 P 0 0;3=12,5=1
P 10.42445 1.395 3 P 0 0;3=12,5=1
P 12.81495 2.75196998 8 P 0 0;3=2,5=0
P 10.76161004 2.04115 6 P 0 0;1,3=11,5=0
P 10.73661004 2.01615 3 P 0 0;3=12,5=1
P 10.26025 1.82845 3 P 0 0;3=12,5=1
P 12.73621004 3.73621998 8 P 0 0;3=2,5=0
P 10.61161004 2.24115 6 P 0 0;1,3=11,5=0
P 10.58661004 2.21615 3 P 0 0;3=12,5=1
P 10.09 2.26825 3 P 0 0;3=12,5=1
P 10.76161004 2.44115 6 P 0 0;1,3=11,5=0
P 10.73661004 2.41615 3 P 0 0;3=12,5=1
P 10.09 2.69655 3 P 0 0;3=12,5=1
P 12.73621004 4.52361998 8 P 0 0;3=2,5=0
P 7.3426 4.66551004 25 P 0 0;1,3=4,5=0
P 7.3054 4.79681998 39 P 0 0;1,3=20,5=0
P 7.3426 4.69351004 1 P 0 0;3=0,5=1
P 11.73316004 1.532 3 P 0 0;3=12,5=1
P 12.55905 2.27953002 8 P 0 0;3=2,5=0
P 7.2926 4.66551004 25 P 0 0;1,3=4,5=0
P 7.2798 4.79681998 39 P 0 0;1,3=20,5=0
P 7.2926 4.69351004 1 P 0 0;3=0,5=1
P 12.73621004 3.57873996 8 P 0 0;3=2,5=0
P 10.71161004 2.24115 6 P 0 0;1,3=11,5=0
P 10.68661004 2.21615 3 P 0 0;3=12,5=1
P 9.975 2.3358 3 P 0 0;3=12,5=1
P 7.33098996 4.9602 39 P 0 0;1,3=20,5=0
P 7.3926 5.09151004 25 P 0 0;1,3=4,5=0
P 7.3926 5.04851004 7 P 0 0;2,3=6,5=1
P 12.73621004 3.42126004 8 P 0 0;3=2,5=0
P 10.76161004 2.29115 6 P 0 0;1,3=11,5=0
P 10.73661004 2.26615 3 P 0 0;3=12,5=1
P 9.975 2.19955 3 P 0 0;3=12,5=1
P 11.73316004 2.172 3 P 0 0;3=12,5=1
P 12.55905 3.46063002 8 P 0 0;3=2,5=0
P 4.95768002 2.39115 6 P 0 0;1,3=11,5=0
P 4.98268002 2.36615 3 P 0 0;3=12,5=1
P 10.76161004 1.89115 6 P 0 0;1,3=11,5=0
P 10.73661004 1.86615 3 P 0 0;3=12,5=1
P 10.395 1.32555 3 P 0 0;3=12,5=1
P 12.73621004 2.00393996 8 P 0 0;3=2,5=0
P 11.73316004 2.132 3 P 0 0;3=12,5=1
P 12.63778996 3.5 8 P 0 0;3=2,5=0
P 3.38003996 5.22001998 3 P 0 0;3=12,5=1
P 2.97721004 2.865 3 P 0 0;3=12,5=1
P 3.38823002 4.97913996 37 P 0 0;1,3=1,5=0
P 4.95768002 2.44115 6 P 0 0;1,3=11,5=0
P 4.98268002 2.41615 3 P 0 0;3=12,5=1
P 12.63778996 1.76771998 8 P 0 0;3=2,5=0
P 3.42003996 5.22001998 3 P 0 0;3=12,5=1
P 2.97721004 2.825 3 P 0 0;3=12,5=1
P 3.41185 4.97913996 37 P 0 0;1,3=1,5=0
P 4.85768002 2.84115 6 P 0 0;1,3=11,5=0
P 4.88268002 2.81615 3 P 0 0;3=12,5=1
P 4.90768002 2.84115 6 P 0 0;1,3=11,5=0
P 4.93268002 2.81615 3 P 0 0;3=12,5=1
P 4.95768002 2.84115 6 P 0 0;1,3=11,5=0
P 4.98268002 2.81615 3 P 0 0;3=12,5=1
P 5.00768002 2.84115 6 P 0 0;1,3=11,5=0
P 5.03268002 2.81615 3 P 0 0;3=12,5=1
P 5.05768002 2.84115 6 P 0 0;1,3=11,5=0
P 5.08268002 2.81615 3 P 0 0;3=12,5=1
P 11.03661004 2.81615 3 P 0 0;3=12,5=1
P 11.01161004 2.84115 6 P 0 0;1,3=11,5=0
P 11.08661004 2.81615 3 P 0 0;3=12,5=1
P 11.06161004 2.84115 6 P 0 0;1,3=11,5=0
P 10.98661004 2.81615 3 P 0 0;3=12,5=1
P 10.96161004 2.84115 6 P 0 0;1,3=11,5=0
P 10.93661004 2.81615 3 P 0 0;3=12,5=1
P 10.91161004 2.84115 6 P 0 0;1,3=11,5=0
P 10.88661004 2.81615 3 P 0 0;3=12,5=1
P 10.86161004 2.84115 6 P 0 0;1,3=11,5=0
P 5.27886004 3.0214 4 P 0 0;3=13,5=1
P 5.27886004 3.0564 4 P 0 0;3=13,5=1
P 5.27886004 3.1014 4 P 0 0;3=13,5=1
P 5.27886004 3.1364 4 P 0 0;3=13,5=1
P 5.27886004 2.9764 4 P 0 0;3=13,5=1
P 5.27886004 2.9414 4 P 0 0;3=13,5=1
P 5.27886004 3.2614 4 P 0 0;3=13,5=1
P 5.27886004 3.2964 4 P 0 0;3=13,5=1
P 5.27886004 3.2164 4 P 0 0;3=13,5=1
P 5.27886004 3.1814 4 P 0 0;3=13,5=1
P 11.28278996 3.1814 4 P 0 0;3=13,5=1
P 11.28278996 3.2164 4 P 0 0;3=13,5=1
P 11.28278996 3.2964 4 P 0 0;3=13,5=1
P 11.28278996 3.2614 4 P 0 0;3=13,5=1
P 11.28278996 2.9414 4 P 0 0;3=13,5=1
P 11.28278996 2.9764 4 P 0 0;3=13,5=1
P 11.28278996 3.1364 4 P 0 0;3=13,5=1
P 11.28278996 3.1014 4 P 0 0;3=13,5=1
P 11.28278996 3.0564 4 P 0 0;3=13,5=1
P 11.28278996 3.0214 4 P 0 0;3=13,5=1
P 6.42418996 5.09705 25 P 0 0;1,3=4,5=0
P 5.59708996 4.7302 4 P 0 0;3=13,5=1
P 5.57708996 4.6802 4 P 0 0;3=13,5=1
P 5.75708996 4.7302 4 P 0 0;3=13,5=1
P 5.83708996 4.7302 4 P 0 0;3=13,5=1
P 5.69708996 4.6802 4 P 0 0;3=13,5=1
P 5.73708996 4.6802 4 P 0 0;3=13,5=1
P 5.77708996 4.6802 4 P 0 0;3=13,5=1
P 5.81708996 4.6802 4 P 0 0;3=13,5=1
P 5.85708996 4.6802 4 P 0 0;3=13,5=1
P 5.67708996 4.7302 4 P 0 0;3=13,5=1
P 5.65708996 4.6802 4 P 0 0;3=13,5=1
P 5.61708996 4.6802 4 P 0 0;3=13,5=1
P 6.13708996 4.7602 4 P 0 0;3=13,5=1
P 6.09708996 4.6802 4 P 0 0;3=13,5=1
P 6.13708996 4.6402 4 P 0 0;3=13,5=1
P 6.13708996 4.6802 4 P 0 0;3=13,5=1
P 6.13708996 4.7202 4 P 0 0;3=13,5=1
P 5.91708996 4.7302 4 P 0 0;3=13,5=1
P 5.99708996 4.7302 4 P 0 0;3=13,5=1
P 6.07708996 4.7302 4 P 0 0;3=13,5=1
P 5.89708996 4.6802 4 P 0 0;3=13,5=1
P 5.93708996 4.6802 4 P 0 0;3=13,5=1
P 5.97708996 4.6802 4 P 0 0;3=13,5=1
P 6.01708996 4.6802 4 P 0 0;3=13,5=1
P 6.05708996 4.6802 4 P 0 0;3=13,5=1
P 5.59708996 4.7702 4 P 0 0;3=13,5=1
P 5.59708996 4.8102 4 P 0 0;3=13,5=1
P 5.75708996 4.8102 4 P 0 0;3=13,5=1
P 5.83708996 4.8102 4 P 0 0;3=13,5=1
P 5.75708996 4.7702 4 P 0 0;3=13,5=1
P 5.83708996 4.7702 4 P 0 0;3=13,5=1
P 5.67708996 4.8102 4 P 0 0;3=13,5=1
P 5.67708996 4.7702 4 P 0 0;3=13,5=1
P 6.13708996 4.9252 4 P 0 0;3=13,5=1
P 6.13708996 4.8402 4 P 0 0;3=13,5=1
P 6.13708996 4.8002 4 P 0 0;3=13,5=1
P 6.13708996 4.8852 4 P 0 0;3=13,5=1
P 5.91708996 4.8102 4 P 0 0;3=13,5=1
P 5.99708996 4.8102 4 P 0 0;3=13,5=1
P 5.91708996 4.7702 4 P 0 0;3=13,5=1
P 5.99708996 4.7702 4 P 0 0;3=13,5=1
P 6.07708996 4.8102 4 P 0 0;3=13,5=1
P 6.07708996 4.7702 4 P 0 0;3=13,5=1
P 5.53593996 4.6201 25 P 0 0;1,3=4,5=0
P 5.59778996 4.6352 29 P 0 0;1,3=21,5=0
P 5.49093996 4.6201 25 P 0 0;1,3=4,5=0
P 5.67708996 4.6352 29 P 0 0;1,3=21,5=0
P 5.83708996 4.6352 29 P 0 0;1,3=21,5=0
P 5.75708996 4.6352 29 P 0 0;1,3=21,5=0
P 6.07708996 4.6352 29 P 0 0;1,3=21,5=0
P 5.91708996 4.6352 29 P 0 0;1,3=21,5=0
P 5.99708996 4.6352 29 P 0 0;1,3=21,5=0
P 6.21193996 4.77205 50 P 0 0;1,3=24,5=0
P 4.90768002 2.29115 6 P 0 0;1,3=11,5=0
P 4.93268002 2.26615 3 P 0 0;3=12,5=1
P 4.90768002 2.34115 6 P 0 0;1,3=11,5=0
P 4.93268002 2.31615 3 P 0 0;3=12,5=1
P 5.05768002 2.39115 6 P 0 0;1,3=11,5=0
P 5.08268002 2.36615 3 P 0 0;3=12,5=1
P 12.81495 3.22441004 8 P 0 0;3=2,5=0
P 10.71161004 2.09115 6 P 0 0;1,3=11,5=0
P 10.68661004 2.06615 3 P 0 0;3=12,5=1
P 10.09 2.13095 3 P 0 0;3=12,5=1
P 10.66161004 2.34115 6 P 0 0;1,3=11,5=0
P 10.63661004 2.31615 3 P 0 0;3=12,5=1
P 10.09 2.40335 3 P 0 0;3=12,5=1
P 12.81495 3.85433002 8 P 0 0;3=2,5=0
P 11.73316004 2.012 3 P 0 0;3=12,5=1
P 12.63778996 3.1063 8 P 0 0;3=2,5=0
P 11.73316004 1.972 3 P 0 0;3=12,5=1
P 12.55905 3.14566998 8 P 0 0;3=2,5=0
P 11.53316004 1.732 3 P 0 0;3=12,5=1
P 12.55905 2.98818996 8 P 0 0;3=2,5=0
P 12.81495 3.69685 8 P 0 0;3=2,5=0
P 10.61161004 2.29115 6 P 0 0;1,3=11,5=0
P 10.58661004 2.26615 3 P 0 0;3=12,5=1
P 10.09 2.30825 3 P 0 0;3=12,5=1
P 11.53316004 1.772 3 P 0 0;3=12,5=1
P 12.63778996 2.94881998 8 P 0 0;3=2,5=0
P 12.81495 4.32676998 8 P 0 0;3=2,5=0
P 10.66161004 2.49115 6 P 0 0;1,3=11,5=0
P 10.63661004 2.46615 3 P 0 0;3=12,5=1
P 9.975 2.62445 3 P 0 0;3=12,5=1
P 12.63778996 2.79133996 8 P 0 0;3=2,5=0
P 11.73316004 1.852 3 P 0 0;3=12,5=1
P 12.55905 2.83071004 8 P 0 0;3=2,5=0
P 11.73316004 1.812 3 P 0 0;3=12,5=1
P 10.76161004 2.49115 6 P 0 0;1,3=11,5=0
P 10.73661004 2.46615 3 P 0 0;3=12,5=1
P 10.09 2.73655 3 P 0 0;3=12,5=1
P 12.81495 4.48425 8 P 0 0;3=2,5=0
P 10.66161004 2.29115 6 P 0 0;1,3=11,5=0
P 10.63661004 2.26615 3 P 0 0;3=12,5=1
P 10.09 2.44335 3 P 0 0;3=12,5=1
P 12.73621004 3.8937 8 P 0 0;3=2,5=0
P 10.58661004 2.41615 3 P 0 0;3=12,5=1
P 10.61161004 2.44115 6 P 0 0;1,3=11,5=0
P 9.975 2.5109 3 P 0 0;3=12,5=1
P 12.81495 4.16928996 8 P 0 0;3=2,5=0
P 1.025 -0.35 28 P 0 0;3=17,5=0
P 1.325 -0.35 28 P 0 0;3=17,5=0
P 1.175 -0.35 28 P 0 0;3=17,5=0
P 0.725 -0.35 28 P 0 0;3=17,5=0
P 0.875 -0.35 28 P 0 0;3=17,5=0
P 12.73621004 4.05118002 8 P 0 0;3=2,5=0
P 10.71161004 2.39115 6 P 0 0;1,3=11,5=0
P 10.68661004 2.36615 3 P 0 0;3=12,5=1
P 10.09 2.53845 3 P 0 0;3=12,5=1
P 12.81495 2.35826998 8 P 0 0;3=2,5=0
P 10.66161004 1.89115 6 P 0 0;1,3=11,5=0
P 10.63661004 1.86615 3 P 0 0;3=12,5=1
P 10.35543002 1.52156998 3 P 0 0;3=12,5=1
P 5.00768002 2.04115 6 P 0 0;1,3=11,5=0
P 5.03268002 2.01615 3 P 0 0;3=12,5=1
P 5.05768002 2.24115 6 P 0 0;1,3=11,5=0
P 5.08268002 2.21615 3 P 0 0;3=12,5=1
P 12.73621004 2.16141998 8 P 0 0;3=2,5=0
P 10.71161004 1.99115 6 P 0 0;1,3=11,5=0
P 10.68661004 1.96615 3 P 0 0;3=12,5=1
P 10.46445 1.395 3 P 0 0;3=12,5=1
P 0.82983996 5.1239 35 P 0 0;1,3=10
P 9.50795 0.42821004 43 P 0 0;1,3=28
P 9.60795 0.42821004 43 P 0 0;1,3=28
P 3.70998996 0.40688002 43 P 0 0;1,3=28
P 3.80998996 0.40688002 43 P 0 0;1,3=28
P 0.2 -0.293 17 P 0 0;3=37
P 12.27 0.29 17 P 0 0;3=37
P 0.66 0.29 17 P 0 0;3=37
P 0.2 5.82361998 17 P 0 0;3=37
P 0.5836 5.36731998 13 P 0 0;1,3=38
P 0.9211 0.2854 13 P 0 0;1,3=38
P 11.99518996 0.29 13 P 0 0;1,3=38
P 0.5 -0.293 13 P 0 0;1,3=38
P 12.4252 -0.293 13 P 0 0;1,3=38
P 0.5 6.31661998 13 P 0 0;1,3=38
P 12.4252 6.31661998 13 P 0 0;1,3=38
P 6.55228996 4.91705 46 P 0 0;1,3=19
P 6.69008996 4.9013 47 P 0 0;1,3=19
P 6.62118996 5.00562992 34 P 0 0;1,3=19
P 12.81495 1.57086998 8 P 0 0;3=2
P 12.73621004 1.5315 8 P 0 0;3=2
P 12.63778996 2.7126 8 P 0 0;3=2
P 12.55905 2.67323002 8 P 0 0;3=2
P 12.55905 1.64961004 8 P 0 0;3=2
P 12.63778996 1.61023996 8 P 0 0;3=2
P 12.55905 1.57086998 8 P 0 0;3=2
P 12.63778996 1.5315 8 P 0 0;3=2
P 12.73621004 1.68898002 8 P 0 0;3=2
P 12.81495 1.64961004 8 P 0 0;3=2
P 12.63778996 1.68898002 8 P 0 0;3=2
P 12.55905 1.72835 8 P 0 0;3=2
P 12.81495 1.72835 8 P 0 0;3=2
P 12.73621004 1.45276004 8 P 0 0;3=2
P 12.81495 1.41338996 8 P 0 0;3=2
P 12.73621004 1.37401998 28 P 0 0;3=18
P 12.63778996 1.45276004 8 P 0 0;3=2
P 12.55905 1.41338996 8 P 0 0;3=2
P 0.35038996 1.5315 8 P 0 0;3=2
P 0.27165 1.49213002 8 P 0 0;3=2
P 0.17323002 2.67323002 8 P 0 0;3=2
P 0.09448996 2.63386004 8 P 0 0;3=2
P 0.09448996 1.61023996 8 P 0 0;3=2
P 0.17323002 1.57086998 8 P 0 0;3=2
P 0.09448996 1.5315 8 P 0 0;3=2
P 0.17323002 1.49213002 8 P 0 0;3=2
P 0.27165 1.64961004 8 P 0 0;3=2
P 0.35038996 1.61023996 8 P 0 0;3=2
P 0.17323002 1.64961004 8 P 0 0;3=2
P 0.09448996 1.68898002 8 P 0 0;3=2
P 0.35038996 1.68898002 8 P 0 0;3=2
P 0.27165 1.41338996 8 P 0 0;3=2
P 0.35038996 1.37401998 8 P 0 0;3=2
P 0.27165 1.33465 28 P 0 0;3=18
P 0.17323002 1.41338996 8 P 0 0;3=2
P 0.09448996 1.37401998 8 P 0 0;3=2
P 10.02558996 4.73035 38 P 0 0;1,3=8
P 3.69558996 4.67035 38 P 0 0;1,3=8
P 10.20866004 5.4441 24 P 0 0;3=39
P 5.78346004 5.4441 24 P 0 0;3=39
P 12.7252 6.31661998 17 P 0 0;3=37
P 0.2 6.31661998 17 P 0 0;3=37
P 12.7252 -0.293 17 P 0 0;3=37
P 0.22245 4.87401004 15 P 0 0;3=14
P 5.09558996 5.64035 38 P 0 0;1,3=8
P 12.68701004 0.46063002 18 P 0 0;3=40
P 12.68701998 5.4252 18 P 0 0;3=40
P 0.22245 0.42126004 18 P 0 0;3=40
P 0.22255 5.38583002 18 P 0 0;3=40
L 1.88908002 -1.91246004 1.89293002 -1.91246004 0 P 0 
L 1.89126998 -1.91146004 1.89656998 -1.91146004 0 P 0 
L 1.89393996 -1.91046004 1.9155 -1.91046004 0 P 0 
L 1.91593996 -1.91246004 1.92048996 -1.91246004 0 P 0 
L 1.9126 -1.91146004 1.9184 -1.91146004 0 P 0 
L 1.89763002 -1.90946004 1.91016998 -1.90946004 0 P 0 
L 1.89053002 -1.96001004 1.8974 -1.96001004 0 P 0 
L 1.89053002 -1.95901004 1.8974 -1.95901004 0 P 0 
L 1.89053002 -1.95801004 1.8974 -1.95801004 0 P 0 
L 1.89053002 -1.95701004 1.8974 -1.95701004 0 P 0 
L 1.89053002 -1.95601004 1.8974 -1.95601004 0 P 0 
L 1.89053002 -1.95501004 1.8974 -1.95501004 0 P 0 
L 1.89053002 -1.95401004 1.8974 -1.95401004 0 P 0 
L 1.89053002 -1.95301004 1.89741004 -1.95301004 0 P 0 
L 1.89053002 -1.95201004 1.89741998 -1.95201004 0 P 0 
L 1.89053002 -1.95101004 1.89743996 -1.95101004 0 P 0 
L 1.89053002 -1.95001004 1.89745 -1.95001004 0 P 0 
L 1.89053002 -1.94901004 1.89746004 -1.94901004 0 P 0 
L 1.89053002 -1.94801004 1.89753002 -1.94801004 0 P 0 
L 1.89053002 -1.94701004 1.8977 -1.94701004 0 P 0 
L 1.89053002 -1.94601004 1.89798002 -1.94601004 0 P 0 
L 1.89053002 -1.94501004 1.89861004 -1.94501004 0 P 0 
L 1.89053002 -1.94401004 1.90005 -1.94401004 0 P 0 
L 1.89053002 -1.94301004 1.9113 -1.94301004 0 P 0 
L 1.89053002 -1.94201004 1.91168002 -1.94201004 0 P 0 
L 1.89053002 -1.94101004 1.91246998 -1.94101004 0 P 0 
L 1.89053002 -1.94001004 1.90093996 -1.94001004 0 P 0 
L 1.89053002 -1.93901004 1.89856004 -1.93901004 0 P 0 
L 1.89053002 -1.93801004 1.89786998 -1.93801004 0 P 0 
L 1.89053002 -1.93701004 1.89753996 -1.93701004 0 P 0 
L 1.89053002 -1.93601004 1.89746998 -1.93601004 0 P 0 
L 1.89053002 -1.93501004 1.89743996 -1.93501004 0 P 0 
L 1.89053002 -1.93401004 1.89741998 -1.93401004 0 P 0 
L 1.89053002 -1.93301004 1.8974 -1.93301004 0 P 0 
L 1.89053002 -1.93201004 1.8974 -1.93201004 0 P 0 
L 1.89053002 -1.93101004 1.8974 -1.93101004 0 P 0 
L 1.89053002 -1.93001004 1.8974 -1.93001004 0 P 0 
L 1.89053002 -1.92901004 1.8974 -1.92901004 0 P 0 
L 1.89053002 -1.92801004 1.89753002 -1.92801004 0 P 0 
L 1.89053002 -1.92701004 1.89793996 -1.92701004 0 P 0 
L 1.89053002 -1.92601004 1.91713002 -1.92601004 0 P 0 
L 1.89053002 -1.92501004 1.91628996 -1.92501004 0 P 0 
L 1.89053002 -1.92401004 1.91513996 -1.92401004 0 P 0 
L 1.89053002 -1.92301004 1.91321998 -1.92301004 0 P 0 
L 1.89053002 -1.92201004 1.90551004 -1.92201004 0 P 0 
L 1.89438996 -1.97246004 1.91331004 -1.97246004 0 P 0 
L 1.89106998 -1.97146004 1.89973002 -1.97146004 0 P 0 
L 1.88878002 -1.97046004 1.8949 -1.97046004 0 P 0 
L 1.88698002 -1.96946004 1.89206998 -1.96946004 0 P 0 
L 1.88546004 -1.96846004 1.88986998 -1.96846004 0 P 0 
L 1.88416998 -1.96746004 1.88808996 -1.96746004 0 P 0 
L 1.88288002 -1.96646004 1.88655 -1.96646004 0 P 0 
L 1.88176998 -1.96546004 1.88518002 -1.96546004 0 P 0 
L 1.88068996 -1.96446004 1.88393996 -1.96446004 0 P 0 
L 1.87968996 -1.96346004 1.88286004 -1.96346004 0 P 0 
L 1.87878002 -1.96246004 1.88186004 -1.96246004 0 P 0 
L 1.8786 -1.92046004 1.88126998 -1.92046004 0 P 0 
L 1.87946998 -1.91946004 1.88223002 -1.91946004 0 P 0 
L 1.88048002 -1.91846004 1.88321004 -1.91846004 0 P 0 
L 1.88153996 -1.91746004 1.88436998 -1.91746004 0 P 0 
L 1.88273002 -1.91646004 1.88558996 -1.91646004 0 P 0 
L 1.88406004 -1.91546004 1.88696998 -1.91546004 0 P 0 
L 1.88548996 -1.91446004 1.88853002 -1.91446004 0 P 0 
L 1.88718002 -1.91346004 1.89041998 -1.91346004 0 P 0 
L 1.90896004 -1.92963996 1.90921998 -1.92991998 0 P 0 
L 1.90921998 -1.92991998 1.90945 -1.93021998 0 P 0 
L 1.90945 -1.93021998 1.90966004 -1.93053002 0 P 0 
L 1.90966004 -1.93053002 1.90983002 -1.93086004 0 P 0 
L 1.90983002 -1.93086004 1.90998002 -1.93121004 0 P 0 
L 1.90998002 -1.93121004 1.9101 -1.93156998 0 P 0 
L 1.9101 -1.93156998 1.91018996 -1.93193996 0 P 0 
L 1.91018996 -1.93193996 1.91023996 -1.93231004 0 P 0 
L 1.91023996 -1.93231004 1.91026998 -1.93265 0 P 0 
L 1.91026998 -1.93265 1.91026004 -1.93298002 0 P 0 
L 1.91026004 -1.93298002 1.91023002 -1.93331004 0 P 0 
L 1.91023002 -1.93331004 1.91016998 -1.93363996 0 P 0 
L 1.91016998 -1.93363996 1.91008996 -1.93396004 0 P 0 
L 1.91008996 -1.93396004 1.90998002 -1.93428002 0 P 0 
L 1.90998002 -1.93428002 1.90983996 -1.93458002 0 P 0 
L 1.90983996 -1.93458002 1.90968996 -1.93486998 0 P 0 
L 1.90968996 -1.93486998 1.90951004 -1.93516004 0 P 0 
L 1.90951004 -1.93516004 1.90921004 -1.93556004 0 P 0 
L 1.90921004 -1.93556004 1.90888002 -1.93593002 0 P 0 
L 1.90888002 -1.93593002 1.90853002 -1.93626998 0 P 0 
L 1.90853002 -1.93626998 1.90815 -1.93658996 0 P 0 
L 1.90815 -1.93658996 1.90773996 -1.93686998 0 P 0 
L 1.90773996 -1.93686998 1.90731998 -1.93711998 0 P 0 
L 1.90731998 -1.93711998 1.90686998 -1.93733996 0 P 0 
L 1.90686998 -1.93733996 1.90615 -1.93761004 0 P 0 
L 1.90615 -1.93761004 1.90541998 -1.93783002 0 P 0 
L 1.90541998 -1.93783002 1.90466004 -1.93798002 0 P 0 
L 1.90466004 -1.93798002 1.9039 -1.93808002 0 P 0 
L 1.9039 -1.93808002 1.90311998 -1.9381 0 P 0 
L 1.90311998 -1.9381 1.90196004 -1.93808002 0 P 0 
L 1.90196004 -1.93808002 1.90078996 -1.93798996 0 P 0 
L 1.90078996 -1.93798996 1.90068002 -1.93798002 0 P 0 
L 1.90068002 -1.93798002 1.90058002 -1.93795 0 P 0 
L 1.90058002 -1.93795 1.90046998 -1.93791998 0 P 0 
L 1.90046998 -1.93791998 1.90038002 -1.93788002 0 P 0 
L 1.90038002 -1.93788002 1.90028002 -1.93783002 0 P 0 
L 1.90028002 -1.93783002 1.90018996 -1.93778002 0 P 0 
L 1.90018996 -1.93778002 1.9001 -1.93771004 0 P 0 
L 1.9001 -1.93771004 1.90001998 -1.93763996 0 P 0 
L 1.90001998 -1.93763996 1.89988002 -1.93748002 0 P 0 
L 1.89988002 -1.93748002 1.89978002 -1.93733996 0 P 0 
L 1.89978002 -1.93733996 1.89961998 -1.93703996 0 P 0 
L 1.89961998 -1.93703996 1.89956998 -1.93688002 0 P 0 
L 1.89956998 -1.93688002 1.89951998 -1.93671004 0 P 0 
L 1.89951998 -1.93671004 1.89948996 -1.93655 0 P 0 
L 1.89948996 -1.93655 1.89946998 -1.93636998 0 P 0 
L 1.89946998 -1.93636998 1.8994 -1.93323002 0 P 0 
L 1.8994 -1.93323002 1.8994 -1.92833002 0 P 0 
L 1.8994 -1.92833002 1.90353996 -1.92833002 0 P 0 
L 1.90353996 -1.92833002 1.90436998 -1.92835 0 P 0 
L 1.90436998 -1.92835 1.9052 -1.92843002 0 P 0 
L 1.9052 -1.92843002 1.90603002 -1.92853996 0 P 0 
L 1.90603002 -1.92853996 1.90683996 -1.92871004 0 P 0 
L 1.90683996 -1.92871004 1.90751004 -1.9289 0 P 0 
L 1.90751004 -1.9289 1.90818002 -1.92913002 0 P 0 
L 1.90818002 -1.92913002 1.90851998 -1.92928996 0 P 0 
L 1.90851998 -1.92928996 1.90868002 -1.92938996 0 P 0 
L 1.90868002 -1.92938996 1.90883002 -1.92951004 0 P 0 
L 1.90883002 -1.92951004 1.90896004 -1.92963996 0 P 0 
L 1.91188996 -1.96001004 1.91638996 -1.96001004 0 P 0 
L 1.91156998 -1.95901004 1.91926998 -1.95901004 0 P 0 
L 1.91125 -1.95801004 1.91891998 -1.95801004 0 P 0 
L 1.91091998 -1.95701004 1.91853002 -1.95701004 0 P 0 
L 1.9106 -1.95601004 1.91811004 -1.95601004 0 P 0 
L 1.91025 -1.95501004 1.91765 -1.95501004 0 P 0 
L 1.90988996 -1.95401004 1.91718996 -1.95401004 0 P 0 
L 1.90953002 -1.95301004 1.91673002 -1.95301004 0 P 0 
L 1.90918002 -1.95201004 1.91626998 -1.95201004 0 P 0 
L 1.90881998 -1.95101004 1.91576004 -1.95101004 0 P 0 
L 1.90841004 -1.95001004 1.91523996 -1.95001004 0 P 0 
L 1.90793996 -1.94901004 1.91471004 -1.94901004 0 P 0 
L 1.90738996 -1.94801004 1.91418002 -1.94801004 0 P 0 
L 1.90676998 -1.94701004 1.9136 -1.94701004 0 P 0 
L 1.90598996 -1.94601004 1.91261004 -1.94601004 0 P 0 
L 1.90495 -1.94501004 1.91175 -1.94501004 0 P 0 
L 1.90325 -1.94401004 1.91133002 -1.94401004 0 P 0 
L 1.90456004 -1.94001004 1.91383002 -1.94001004 0 P 0 
L 1.90801004 -1.93901004 1.91523002 -1.93901004 0 P 0 
L 1.90956998 -1.93801004 1.91635 -1.93801004 0 P 0 
L 1.9106 -1.93701004 1.91718002 -1.93701004 0 P 0 
L 1.91133996 -1.93601004 1.91781004 -1.93601004 0 P 0 
L 1.91183996 -1.93501004 1.91826004 -1.93501004 0 P 0 
L 1.91213002 -1.93401004 1.9186 -1.93401004 0 P 0 
L 1.91226004 -1.93301004 1.9188 -1.93301004 0 P 0 
L 1.91221998 -1.93201004 1.9189 -1.93201004 0 P 0 
L 1.91201998 -1.93101004 1.9189 -1.93101004 0 P 0 
L 1.91163996 -1.93001004 1.91878996 -1.93001004 0 P 0 
L 1.91105 -1.92901004 1.91856998 -1.92901004 0 P 0 
L 1.91013996 -1.92801004 1.91823002 -1.92801004 0 P 0 
L 1.90816998 -1.92701004 1.91776004 -1.92701004 0 P 0 
L 1.90313996 -1.94011004 1.90316998 -1.9401 0 P 0 
L 1.90316998 -1.9401 1.9032 -1.9401 0 P 0 
L 1.9032 -1.9401 1.90398002 -1.94006998 0 P 0 
L 1.90398002 -1.94006998 1.90406004 -1.94006998 0 P 0 
L 1.90406004 -1.94006998 1.90413996 -1.94006004 0 P 0 
L 1.90413996 -1.94006004 1.9049 -1.93996998 0 P 0 
L 1.9049 -1.93996998 1.90493996 -1.93996004 0 P 0 
L 1.90493996 -1.93996004 1.90498996 -1.93996004 0 P 0 
L 1.90498996 -1.93996004 1.90506998 -1.93993996 0 P 0 
L 1.90506998 -1.93993996 1.90581998 -1.93978002 0 P 0 
L 1.90581998 -1.93978002 1.90586004 -1.93978002 0 P 0 
L 1.90586004 -1.93978002 1.90593996 -1.93976004 0 P 0 
L 1.90593996 -1.93976004 1.90596998 -1.93973996 0 P 0 
L 1.90596998 -1.93973996 1.90671004 -1.93953002 0 P 0 
L 1.90671004 -1.93953002 1.90678996 -1.93951004 0 P 0 
L 1.90678996 -1.93951004 1.90758996 -1.93921004 0 P 0 
L 1.90758996 -1.93921004 1.90766004 -1.93916998 0 P 0 
L 1.90766004 -1.93916998 1.9077 -1.93915 0 P 0 
L 1.9077 -1.93915 1.90773996 -1.93913996 0 P 0 
L 1.90773996 -1.93913996 1.90818996 -1.93891998 0 P 0 
L 1.90818996 -1.93891998 1.90821998 -1.9389 0 P 0 
L 1.90821998 -1.9389 1.90826004 -1.93888996 0 P 0 
L 1.90826004 -1.93888996 1.90828996 -1.93886998 0 P 0 
L 1.90828996 -1.93886998 1.90833002 -1.93885 0 P 0 
L 1.90833002 -1.93885 1.90875 -1.9386 0 P 0 
L 1.90875 -1.9386 1.90883002 -1.93856004 0 P 0 
L 1.90883002 -1.93856004 1.90888996 -1.93851004 0 P 0 
L 1.90888996 -1.93851004 1.90928996 -1.93823002 0 P 0 
L 1.90928996 -1.93823002 1.90933002 -1.9382 0 P 0 
L 1.90933002 -1.9382 1.90936004 -1.93818002 0 P 0 
L 1.90936004 -1.93818002 1.90938996 -1.93815 0 P 0 
L 1.90938996 -1.93815 1.90941998 -1.93813002 0 P 0 
L 1.90941998 -1.93813002 1.9098 -1.93781998 0 P 0 
L 1.9098 -1.93781998 1.90986004 -1.93776004 0 P 0 
L 1.90986004 -1.93776004 1.90988996 -1.93773996 0 P 0 
L 1.90988996 -1.93773996 1.90991998 -1.93771004 0 P 0 
L 1.90991998 -1.93771004 1.91028002 -1.93736004 0 P 0 
L 1.91028002 -1.93736004 1.91038996 -1.93725 0 P 0 
L 1.91038996 -1.93725 1.91071004 -1.93688002 0 P 0 
L 1.91071004 -1.93688002 1.91073996 -1.93685 0 P 0 
L 1.91073996 -1.93685 1.91116004 -1.9363 0 P 0 
L 1.91116004 -1.9363 1.9112 -1.93623002 0 P 0 
L 1.9112 -1.93623002 1.91138002 -1.93595 0 P 0 
L 1.91138002 -1.93595 1.9114 -1.93591004 0 P 0 
L 1.9114 -1.93591004 1.91143996 -1.93585 0 P 0 
L 1.91143996 -1.93585 1.91146004 -1.93581004 0 P 0 
L 1.91146004 -1.93581004 1.91161004 -1.93551998 0 P 0 
L 1.91161004 -1.93551998 1.91163002 -1.93548996 0 P 0 
L 1.91163002 -1.93548996 1.91165 -1.93545 0 P 0 
L 1.91165 -1.93545 1.91166004 -1.93541004 0 P 0 
L 1.91166004 -1.93541004 1.91168002 -1.93538002 0 P 0 
L 1.91168002 -1.93538002 1.91181004 -1.93506998 0 P 0 
L 1.91181004 -1.93506998 1.91183996 -1.935 0 P 0 
L 1.91183996 -1.935 1.91186004 -1.93496004 0 P 0 
L 1.91186004 -1.93496004 1.91186998 -1.93493002 0 P 0 
L 1.91186998 -1.93493002 1.91198002 -1.93461004 0 P 0 
L 1.91198002 -1.93461004 1.91198996 -1.93456998 0 P 0 
L 1.91198996 -1.93456998 1.912 -1.93453996 0 P 0 
L 1.912 -1.93453996 1.9121 -1.93413996 0 P 0 
L 1.9121 -1.93413996 1.91211998 -1.9341 0 P 0 
L 1.91211998 -1.9341 1.91211998 -1.93406004 0 P 0 
L 1.91211998 -1.93406004 1.91213002 -1.93401998 0 P 0 
L 1.91213002 -1.93401998 1.91213996 -1.93398996 0 P 0 
L 1.91213996 -1.93398996 1.9122 -1.93366004 0 P 0 
L 1.9122 -1.93366004 1.91221004 -1.93358002 0 P 0 
L 1.91221004 -1.93358002 1.91221004 -1.93353996 0 P 0 
L 1.91221004 -1.93353996 1.91221998 -1.9335 0 P 0 
L 1.91221998 -1.9335 1.91225 -1.93316998 0 P 0 
L 1.91225 -1.93316998 1.91226004 -1.93308996 0 P 0 
L 1.91226004 -1.93308996 1.91226004 -1.93268002 0 P 0 
L 1.91226004 -1.93268002 1.91226998 -1.93263996 0 P 0 
L 1.91226998 -1.93263996 1.91226998 -1.9326 0 P 0 
L 1.91226998 -1.9326 1.91226004 -1.93251998 0 P 0 
L 1.91226004 -1.93251998 1.91223996 -1.93218996 0 P 0 
L 1.91223996 -1.93218996 1.91223996 -1.93215 0 P 0 
L 1.91223996 -1.93215 1.91223002 -1.9321 0 P 0 
L 1.91223002 -1.9321 1.91223002 -1.93206004 0 P 0 
L 1.91223002 -1.93206004 1.91221998 -1.93201998 0 P 0 
L 1.91221998 -1.93201998 1.91216998 -1.93163996 0 P 0 
L 1.91216998 -1.93163996 1.91216004 -1.9316 0 P 0 
L 1.91216004 -1.9316 1.91213996 -1.93151004 0 P 0 
L 1.91213996 -1.93151004 1.91213002 -1.93146998 0 P 0 
L 1.91213002 -1.93146998 1.91205 -1.93111004 0 P 0 
L 1.91205 -1.93111004 1.91203996 -1.93106004 0 P 0 
L 1.91203996 -1.93106004 1.91203002 -1.93101998 0 P 0 
L 1.91203002 -1.93101998 1.91201004 -1.93098002 0 P 0 
L 1.91201004 -1.93098002 1.912 -1.93093996 0 P 0 
L 1.912 -1.93093996 1.91188002 -1.93058002 0 P 0 
L 1.91188002 -1.93058002 1.91186998 -1.93053996 0 P 0 
L 1.91186998 -1.93053996 1.91185 -1.9305 0 P 0 
L 1.91185 -1.9305 1.91183996 -1.93046004 0 P 0 
L 1.91183996 -1.93046004 1.91181998 -1.93043002 0 P 0 
L 1.91181998 -1.93043002 1.91166998 -1.93008002 0 P 0 
L 1.91166998 -1.93008002 1.91166004 -1.93003996 0 P 0 
L 1.91166004 -1.93003996 1.9116 -1.92991998 0 P 0 
L 1.9116 -1.92991998 1.91141998 -1.92958996 0 P 0 
L 1.91141998 -1.92958996 1.9114 -1.92955 0 P 0 
L 1.9114 -1.92955 1.91138002 -1.92951998 0 P 0 
L 1.91138002 -1.92951998 1.91133002 -1.92945 0 P 0 
L 1.91133002 -1.92945 1.91113002 -1.92913002 0 P 0 
L 1.91113002 -1.92913002 1.91111004 -1.92908996 0 P 0 
L 1.91111004 -1.92908996 1.91108996 -1.92906004 0 P 0 
L 1.91108996 -1.92906004 1.91106004 -1.92901998 0 P 0 
L 1.91106004 -1.92901998 1.91103002 -1.92898996 0 P 0 
L 1.91103002 -1.92898996 1.9108 -1.92868996 0 P 0 
L 1.9108 -1.92868996 1.91076998 -1.92866004 0 P 0 
L 1.91076998 -1.92866004 1.91075 -1.92861998 0 P 0 
L 1.91075 -1.92861998 1.91068996 -1.92856004 0 P 0 
L 1.91068996 -1.92856004 1.91043002 -1.92828002 0 P 0 
L 1.91043002 -1.92828002 1.91035 -1.9282 0 P 0 
L 1.91035 -1.9282 1.91033002 -1.92816998 0 P 0 
L 1.91033002 -1.92816998 1.91018996 -1.92803996 0 P 0 
L 1.91018996 -1.92803996 1.91018002 -1.92803996 0 P 0 
L 1.91018002 -1.92803996 1.91016004 -1.92801998 0 P 0 
L 1.91016004 -1.92801998 1.91011998 -1.92798996 0 P 0 
L 1.91011998 -1.92798996 1.91006004 -1.92793002 0 P 0 
L 1.91006004 -1.92793002 1.90991004 -1.92781998 0 P 0 
L 1.90991004 -1.92781998 1.90988002 -1.9278 0 P 0 
L 1.90988002 -1.9278 1.90983996 -1.92776998 0 P 0 
L 1.90983996 -1.92776998 1.90976998 -1.92771998 0 P 0 
L 1.90976998 -1.92771998 1.90961004 -1.92761998 0 P 0 
L 1.90961004 -1.92761998 1.90953996 -1.92756998 0 P 0 
L 1.90953996 -1.92756998 1.9095 -1.92755 0 P 0 
L 1.9095 -1.92755 1.90946998 -1.92753002 0 P 0 
L 1.90946998 -1.92753002 1.9093 -1.92743996 0 P 0 
L 1.9093 -1.92743996 1.90926004 -1.92741998 0 P 0 
L 1.90926004 -1.92741998 1.90923002 -1.9274 0 P 0 
L 1.90923002 -1.9274 1.90915 -1.92736998 0 P 0 
L 1.90915 -1.92736998 1.90896998 -1.92728996 0 P 0 
L 1.90896998 -1.92728996 1.90893996 -1.92728002 0 P 0 
L 1.90893996 -1.92728002 1.9089 -1.92726004 0 P 0 
L 1.9089 -1.92726004 1.90886998 -1.92725 0 P 0 
L 1.90886998 -1.92725 1.90883002 -1.92723996 0 P 0 
L 1.90883002 -1.92723996 1.90816004 -1.92701004 0 P 0 
L 1.90816004 -1.92701004 1.90813996 -1.927 0 P 0 
L 1.90813996 -1.927 1.9081 -1.92698996 0 P 0 
L 1.9081 -1.92698996 1.90803996 -1.92696998 0 P 0 
L 1.90803996 -1.92696998 1.90736998 -1.92678002 0 P 0 
L 1.90736998 -1.92678002 1.90723996 -1.92675 0 P 0 
L 1.90723996 -1.92675 1.90643002 -1.92658996 0 P 0 
L 1.90643002 -1.92658996 1.90636998 -1.92656998 0 P 0 
L 1.90636998 -1.92656998 1.90633996 -1.92656998 0 P 0 
L 1.90633996 -1.92656998 1.90631004 -1.92656004 0 P 0 
L 1.90631004 -1.92656004 1.90548996 -1.92645 0 P 0 
L 1.90548996 -1.92645 1.90543996 -1.92643996 0 P 0 
L 1.90543996 -1.92643996 1.9054 -1.92643002 0 P 0 
L 1.9054 -1.92643002 1.90538002 -1.92643002 0 P 0 
L 1.90538002 -1.92643002 1.90455 -1.92636004 0 P 0 
L 1.90455 -1.92636004 1.90443002 -1.92636004 0 P 0 
L 1.90443002 -1.92636004 1.9036 -1.92633002 0 P 0 
L 1.9036 -1.92633002 1.8994 -1.92633002 0 P 0 
L 1.8994 -1.92633002 1.89798002 -1.92691004 0 P 0 
L 1.89798002 -1.92691004 1.8974 -1.92833002 0 P 0 
L 1.8974 -1.92833002 1.8974 -1.93328002 0 P 0 
L 1.8974 -1.93328002 1.89748002 -1.93643002 0 P 0 
L 1.89748002 -1.93643002 1.89748002 -1.93656004 0 P 0 
L 1.89748002 -1.93656004 1.8975 -1.93673002 0 P 0 
L 1.8975 -1.93673002 1.89751004 -1.93681004 0 P 0 
L 1.89751004 -1.93681004 1.89751998 -1.9369 0 P 0 
L 1.89751998 -1.9369 1.89755 -1.93706004 0 P 0 
L 1.89755 -1.93706004 1.89758002 -1.93718996 0 P 0 
L 1.89758002 -1.93718996 1.89758996 -1.93723002 0 P 0 
L 1.89758996 -1.93723002 1.89763002 -1.9374 0 P 0 
L 1.89763002 -1.9374 1.89763996 -1.93743996 0 P 0 
L 1.89763996 -1.93743996 1.89766004 -1.93748002 0 P 0 
L 1.89766004 -1.93748002 1.89768002 -1.93756004 0 P 0 
L 1.89768002 -1.93756004 1.89773996 -1.93771998 0 P 0 
L 1.89773996 -1.93771998 1.89776004 -1.93776004 0 P 0 
L 1.89776004 -1.93776004 1.89776998 -1.9378 0 P 0 
L 1.89776998 -1.9378 1.89781004 -1.93788002 0 P 0 
L 1.89781004 -1.93788002 1.89788002 -1.93803996 0 P 0 
L 1.89788002 -1.93803996 1.8979 -1.93808002 0 P 0 
L 1.8979 -1.93808002 1.89791998 -1.93811004 0 P 0 
L 1.89791998 -1.93811004 1.89796004 -1.93818996 0 P 0 
L 1.89796004 -1.93818996 1.89803996 -1.93833996 0 P 0 
L 1.89803996 -1.93833996 1.89813996 -1.93848002 0 P 0 
L 1.89813996 -1.93848002 1.89823002 -1.93861998 0 P 0 
L 1.89823002 -1.93861998 1.89828002 -1.93868996 0 P 0 
L 1.89828002 -1.93868996 1.89831004 -1.93873002 0 P 0 
L 1.89831004 -1.93873002 1.89833996 -1.93876004 0 P 0 
L 1.89833996 -1.93876004 1.8984 -1.93883996 0 P 0 
L 1.8984 -1.93883996 1.89848996 -1.93893002 0 P 0 
L 1.89848996 -1.93893002 1.89851004 -1.93896004 0 P 0 
L 1.89851004 -1.93896004 1.89868002 -1.93913002 0 P 0 
L 1.89868002 -1.93913002 1.89871004 -1.93915 0 P 0 
L 1.89871004 -1.93915 1.89878996 -1.93921998 0 P 0 
L 1.89878996 -1.93921998 1.89885 -1.93928002 0 P 0 
L 1.89885 -1.93928002 1.89888002 -1.9393 0 P 0 
L 1.89888002 -1.9393 1.89891998 -1.93931998 0 P 0 
L 1.89891998 -1.93931998 1.89901004 -1.93938996 0 P 0 
L 1.89901004 -1.93938996 1.89903996 -1.93941004 0 P 0 
L 1.89903996 -1.93941004 1.89906998 -1.93943996 0 P 0 
L 1.89906998 -1.93943996 1.8991 -1.93946004 0 P 0 
L 1.8991 -1.93946004 1.89913996 -1.93948002 0 P 0 
L 1.89913996 -1.93948002 1.89923002 -1.93953996 0 P 0 
L 1.89923002 -1.93953996 1.89926998 -1.93956004 0 P 0 
L 1.89926998 -1.93956004 1.8993 -1.93958002 0 P 0 
L 1.8993 -1.93958002 1.89933996 -1.9396 0 P 0 
L 1.89933996 -1.9396 1.89936998 -1.93961004 0 P 0 
L 1.89936998 -1.93961004 1.89938002 -1.93961004 0 P 0 
L 1.89938002 -1.93961004 1.89946998 -1.93966004 0 P 0 
L 1.89946998 -1.93966004 1.89953996 -1.9397 0 P 0 
L 1.89953996 -1.9397 1.89971998 -1.93976998 0 P 0 
L 1.89971998 -1.93976998 1.89975 -1.93978996 0 P 0 
L 1.89975 -1.93978996 1.89978996 -1.9398 0 P 0 
L 1.89978996 -1.9398 1.89986998 -1.93983002 0 P 0 
L 1.89986998 -1.93983002 1.89996998 -1.93986004 0 P 0 
L 1.89996998 -1.93986004 1.90001004 -1.93986998 0 P 0 
L 1.90001004 -1.93986998 1.90005 -1.93988996 0 P 0 
L 1.90005 -1.93988996 1.90013002 -1.9399 0 P 0 
L 1.90013002 -1.9399 1.90023002 -1.93993002 0 P 0 
L 1.90023002 -1.93993002 1.90023996 -1.93993002 0 P 0 
L 1.90023996 -1.93993002 1.90028002 -1.93993996 0 P 0 
L 1.90028002 -1.93993996 1.90031004 -1.93995 0 P 0 
L 1.90031004 -1.93995 1.90036004 -1.93995 0 P 0 
L 1.90036004 -1.93995 1.9004 -1.93996004 0 P 0 
L 1.9004 -1.93996004 1.9005 -1.93996998 0 P 0 
L 1.9005 -1.93996998 1.90061004 -1.93998996 0 P 0 
L 1.90061004 -1.93998996 1.90063996 -1.93998996 0 P 0 
L 1.90063996 -1.93998996 1.90181004 -1.94006998 0 P 0 
L 1.90181004 -1.94006998 1.90183996 -1.94008002 0 P 0 
L 1.90183996 -1.94008002 1.90191004 -1.94008002 0 P 0 
L 1.90191004 -1.94008002 1.90308002 -1.9401 0 P 0 
L 1.90308002 -1.9401 1.90311004 -1.9401 0 P 0 
L 1.90311004 -1.9401 1.90313996 -1.94011004 0 P 0 
L 1.90841004 -1.97146004 1.91683996 -1.97146004 0 P 0 
L 1.9135 -1.97046004 1.91931004 -1.97046004 0 P 0 
L 1.91655 -1.96946004 1.92131004 -1.96946004 0 P 0 
L 1.91891998 -1.96846004 1.92301004 -1.96846004 0 P 0 
L 1.92088996 -1.96746004 1.9245 -1.96746004 0 P 0 
L 1.92251004 -1.96646004 1.9258 -1.96646004 0 P 0 
L 1.92391004 -1.96546004 1.92696004 -1.96546004 0 P 0 
L 1.92513002 -1.96446004 1.92803002 -1.96446004 0 P 0 
L 1.9262 -1.96346004 1.92898996 -1.96346004 0 P 0 
L 1.92713996 -1.96246004 1.92986004 -1.96246004 0 P 0 
L 1.928 -1.96146004 1.93068996 -1.96146004 0 P 0 
L 1.92878002 -1.96046004 1.93143002 -1.96046004 0 P 0 
L 1.92951004 -1.95946004 1.93216004 -1.95946004 0 P 0 
L 1.93016998 -1.95846004 1.93278996 -1.95846004 0 P 0 
L 1.93078002 -1.95746004 1.93341004 -1.95746004 0 P 0 
L 1.93133002 -1.95646004 1.93396004 -1.95646004 0 P 0 
L 1.93185 -1.95546004 1.93448996 -1.95546004 0 P 0 
L 1.93231004 -1.95446004 1.93495 -1.95446004 0 P 0 
L 1.93275 -1.95346004 1.93541004 -1.95346004 0 P 0 
L 1.93311998 -1.95246004 1.93586004 -1.95246004 0 P 0 
L 1.93348002 -1.95146004 1.93628996 -1.95146004 0 P 0 
L 1.93376998 -1.95046004 1.93666004 -1.95046004 0 P 0 
L 1.93405 -1.94946004 1.93693002 -1.94946004 0 P 0 
L 1.93428002 -1.94846004 1.93715 -1.94846004 0 P 0 
L 1.93446998 -1.94746004 1.93733002 -1.94746004 0 P 0 
L 1.93466004 -1.94646004 1.93743002 -1.94646004 0 P 0 
L 1.93478996 -1.94546004 1.93748996 -1.94546004 0 P 0 
L 1.9349 -1.94446998 1.93751998 -1.94446998 0 P 0 
L 1.93496998 -1.94346004 1.93755 -1.94346004 0 P 0 
L 1.93501998 -1.94246004 1.93758002 -1.94246004 0 P 0 
L 1.93505 -1.94146998 1.93758996 -1.94146998 0 P 0 
L 1.93503002 -1.94046004 1.93755 -1.94046004 0 P 0 
L 1.935 -1.93946004 1.93751998 -1.93946004 0 P 0 
L 1.93491998 -1.93846004 1.93748002 -1.93846004 0 P 0 
L 1.93481004 -1.93746004 1.93738996 -1.93746004 0 P 0 
L 1.93468996 -1.93646004 1.93726998 -1.93646004 0 P 0 
L 1.93451004 -1.93546004 1.93716004 -1.93546004 0 P 0 
L 1.93433002 -1.93446004 1.93703996 -1.93446004 0 P 0 
L 1.93408996 -1.93346004 1.93685 -1.93346004 0 P 0 
L 1.93383002 -1.93246004 1.93666004 -1.93246004 0 P 0 
L 1.93353002 -1.93146004 1.93638996 -1.93146004 0 P 0 
L 1.9332 -1.93046004 1.93611998 -1.93046004 0 P 0 
L 1.93283996 -1.92946004 1.93576998 -1.92946004 0 P 0 
L 1.93241004 -1.92846004 1.93541004 -1.92846004 0 P 0 
L 1.93198996 -1.92746004 1.93498002 -1.92746004 0 P 0 
L 1.93146998 -1.92646004 1.93451004 -1.92646004 0 P 0 
L 1.93096004 -1.92546004 1.93398002 -1.92546004 0 P 0 
L 1.93035 -1.92446998 1.93338002 -1.92446998 0 P 0 
L 1.92973002 -1.92346004 1.93275 -1.92346004 0 P 0 
L 1.92903002 -1.92246004 1.93201004 -1.92246004 0 P 0 
L 1.92831004 -1.92146004 1.93125 -1.92146004 0 P 0 
L 1.92746998 -1.92046004 1.93041004 -1.92046004 0 P 0 
L 1.92661004 -1.91946004 1.92948996 -1.91946004 0 P 0 
L 1.92558996 -1.91846004 1.92851004 -1.91846004 0 P 0 
L 1.9245 -1.91746004 1.92741998 -1.91746004 0 P 0 
L 1.92328996 -1.91646004 1.92621998 -1.91646004 0 P 0 
L 1.92188002 -1.91546004 1.92491998 -1.91546004 0 P 0 
L 1.92026004 -1.91446004 1.92358996 -1.91446004 0 P 0 
L 1.91835 -1.91346004 1.92208002 -1.91346004 0 P 0 
L 1.82446998 -2.08323996 1.87608002 -2.08323996 0 P 0 
L 1.82403002 -2.08223996 1.87601004 -2.08223996 0 P 0 
L 1.8234 -2.08123996 1.87591004 -2.08123996 0 P 0 
L 1.82256004 -2.08023996 1.87578002 -2.08023996 0 P 0 
L 1.82166004 -2.07923996 1.87558996 -2.07923996 0 P 0 
L 1.82061998 -2.07823996 1.87533002 -2.07823996 0 P 0 
L 1.81946004 -2.07723996 1.87498996 -2.07723996 0 P 0 
L 1.81818002 -2.07623996 1.8746 -2.07623996 0 P 0 
L 1.8168 -2.07523996 1.87416998 -2.07523996 0 P 0 
L 1.81541998 -2.07423996 1.87371004 -2.07423996 0 P 0 
L 1.81403002 -2.07323996 1.87316998 -2.07323996 0 P 0 
L 1.81265 -2.07223996 1.87261004 -2.07223996 0 P 0 
L 1.81126998 -2.07123996 1.87196004 -2.07123996 0 P 0 
L 1.80986004 -2.07023996 1.87128002 -2.07023996 0 P 0 
L 1.80843996 -2.06923996 1.87051998 -2.06923996 0 P 0 
L 1.80703002 -2.06823996 1.8697 -2.06823996 0 P 0 
L 1.80561004 -2.06723996 1.86883002 -2.06723996 0 P 0 
L 1.8042 -2.06623996 1.86796004 -2.06623996 0 P 0 
L 1.80278002 -2.06523996 1.86705 -2.06523996 0 P 0 
L 1.80136004 -2.06423996 1.86608002 -2.06423996 0 P 0 
L 1.79995 -2.06323996 1.8651 -2.06323996 0 P 0 
L 1.79865 -2.06223996 1.86411004 -2.06223996 0 P 0 
L 1.79735 -2.06123996 1.86301998 -2.06123996 0 P 0 
L 1.79605 -2.06023996 1.86193002 -2.06023996 0 P 0 
L 1.79475 -2.05923996 1.86083996 -2.05923996 0 P 0 
L 1.79345 -2.05823996 1.85966998 -2.05823996 0 P 0 
L 1.79215 -2.05723996 1.85846004 -2.05723996 0 P 0 
L 1.79088002 -2.05623996 1.85726004 -2.05623996 0 P 0 
L 1.78971998 -2.05523996 1.85598996 -2.05523996 0 P 0 
L 1.78856004 -2.05423996 1.85461998 -2.05423996 0 P 0 
L 1.7874 -2.05323996 1.85326004 -2.05323996 0 P 0 
L 1.78623002 -2.05223996 1.8519 -2.05223996 0 P 0 
L 1.78506998 -2.05123996 1.85053996 -2.05123996 0 P 0 
L 1.78398002 -2.05023996 1.84918002 -2.05023996 0 P 0 
L 1.783 -2.04923996 1.84781004 -2.04923996 0 P 0 
L 1.87086004 -2.03023996 1.87535 -2.03023996 0 P 0 
L 1.91633002 -1.91473002 1.9183 -1.91565 0 P 0 
L 1.9183 -1.91565 1.92018996 -1.91673002 0 P 0 
L 1.92018996 -1.91673002 1.92196998 -1.91796998 0 P 0 
L 1.92196998 -1.91796998 1.92365 -1.91936004 0 P 0 
L 1.92365 -1.91936004 1.9252 -1.92088002 0 P 0 
L 1.9252 -1.92088002 1.92661004 -1.92253996 0 P 0 
L 1.92661004 -1.92253996 1.92795 -1.92436998 0 P 0 
L 1.92795 -1.92436998 1.92913996 -1.9263 0 P 0 
L 1.92913996 -1.9263 1.93018002 -1.92831998 0 P 0 
L 1.93018002 -1.92831998 1.93106998 -1.93041004 0 P 0 
L 1.93106998 -1.93041004 1.93178996 -1.93256004 0 P 0 
L 1.93178996 -1.93256004 1.93236004 -1.93476004 0 P 0 
L 1.93236004 -1.93476004 1.93276004 -1.93703996 0 P 0 
L 1.93276004 -1.93703996 1.93298996 -1.93933996 0 P 0 
L 1.93298996 -1.93933996 1.93306004 -1.94165 0 P 0 
L 1.93306004 -1.94165 1.93295 -1.94396998 0 P 0 
L 1.93295 -1.94396998 1.93268002 -1.94626004 0 P 0 
L 1.93268002 -1.94626004 1.93223002 -1.94853996 0 P 0 
L 1.93223002 -1.94853996 1.93161998 -1.95071998 0 P 0 
L 1.93161998 -1.95071998 1.93085 -1.95285 0 P 0 
L 1.93085 -1.95285 1.92991004 -1.95491004 0 P 0 
L 1.92991004 -1.95491004 1.92881004 -1.95688996 0 P 0 
L 1.92881004 -1.95688996 1.92756004 -1.95878002 0 P 0 
L 1.92756004 -1.95878002 1.92616004 -1.96056998 0 P 0 
L 1.92616004 -1.96056998 1.92493996 -1.9619 0 P 0 
L 1.92493996 -1.9619 1.92361998 -1.96313996 0 P 0 
L 1.92361998 -1.96313996 1.9222 -1.96426004 0 P 0 
L 1.9222 -1.96426004 1.9207 -1.96526998 0 P 0 
L 1.9207 -1.96526998 1.91911004 -1.96616998 0 P 0 
L 1.91911004 -1.96616998 1.91686998 -1.96721004 0 P 0 
L 1.91686998 -1.96721004 1.91456004 -1.96806998 0 P 0 
L 1.91456004 -1.96806998 1.91218996 -1.96876004 0 P 0 
L 1.91218996 -1.96876004 1.90975 -1.96926998 0 P 0 
L 1.90975 -1.96926998 1.90725 -1.9696 0 P 0 
L 1.90725 -1.9696 1.90473002 -1.96973996 0 P 0 
L 1.90473002 -1.96973996 1.9022 -1.96968996 0 P 0 
L 1.9022 -1.96968996 1.89966998 -1.96945 0 P 0 
L 1.89966998 -1.96945 1.89778002 -1.96913002 0 P 0 
L 1.89778002 -1.96913002 1.89591998 -1.96868996 0 P 0 
L 1.89591998 -1.96868996 1.8941 -1.96811004 0 P 0 
L 1.8941 -1.96811004 1.89231004 -1.96741004 0 P 0 
L 1.89231004 -1.96741004 1.89058002 -1.96658002 0 P 0 
L 1.89058002 -1.96658002 1.88875 -1.96553996 0 P 0 
L 1.88875 -1.96553996 1.88698996 -1.96435 0 P 0 
L 1.88698996 -1.96435 1.88533996 -1.96303002 0 P 0 
L 1.88533996 -1.96303002 1.88378996 -1.9616 0 P 0 
L 1.88378996 -1.9616 1.88235 -1.96003996 0 P 0 
L 1.88235 -1.96003996 1.88103002 -1.95838996 0 P 0 
L 1.88103002 -1.95838996 1.87983996 -1.95663002 0 P 0 
L 1.87983996 -1.95663002 1.87861998 -1.95446998 0 P 0 
L 1.87861998 -1.95446998 1.87758002 -1.9522 0 P 0 
L 1.87758002 -1.9522 1.87673996 -1.94986004 0 P 0 
L 1.87673996 -1.94986004 1.8761 -1.94745 0 P 0 
L 1.8761 -1.94745 1.87568002 -1.945 0 P 0 
L 1.87568002 -1.945 1.87546004 -1.94248996 0 P 0 
L 1.87546004 -1.94248996 1.87546004 -1.93998996 0 P 0 
L 1.87546004 -1.93998996 1.87566998 -1.93748996 0 P 0 
L 1.87566998 -1.93748996 1.87608996 -1.93501998 0 P 0 
L 1.87608996 -1.93501998 1.87671998 -1.9326 0 P 0 
L 1.87671998 -1.9326 1.87755 -1.93023002 0 P 0 
L 1.87755 -1.93023002 1.8786 -1.92793002 0 P 0 
L 1.8786 -1.92793002 1.87981998 -1.92575 0 P 0 
L 1.87981998 -1.92575 1.88123002 -1.92368002 0 P 0 
L 1.88123002 -1.92368002 1.88281004 -1.92175 0 P 0 
L 1.88281004 -1.92175 1.88455 -1.91996004 0 P 0 
L 1.88455 -1.91996004 1.88643002 -1.91831998 0 P 0 
L 1.88643002 -1.91831998 1.88845 -1.91686004 0 P 0 
L 1.88845 -1.91686004 1.88986998 -1.91598996 0 P 0 
L 1.88986998 -1.91598996 1.89135 -1.91523002 0 P 0 
L 1.89135 -1.91523002 1.89288002 -1.91458996 0 P 0 
L 1.89288002 -1.91458996 1.89446998 -1.91406004 0 P 0 
L 1.89446998 -1.91406004 1.89688996 -1.91343996 0 P 0 
L 1.89688996 -1.91343996 1.89935 -1.91298996 0 P 0 
L 1.89935 -1.91298996 1.90183996 -1.91271004 0 P 0 
L 1.90183996 -1.91271004 1.9044 -1.91261004 0 P 0 
L 1.9044 -1.91261004 1.90695 -1.91268002 0 P 0 
L 1.90695 -1.91268002 1.90948996 -1.91291998 0 P 0 
L 1.90948996 -1.91291998 1.91181998 -1.91331998 0 P 0 
L 1.91181998 -1.91331998 1.91408996 -1.91393002 0 P 0 
L 1.91408996 -1.91393002 1.91633002 -1.91473002 0 P 0 
L 1.89498002 -1.90801998 1.8922 -1.90893002 0 P 0 
L 1.8922 -1.90893002 1.88948002 -1.91003002 0 P 0 
L 1.88948002 -1.91003002 1.88686004 -1.91133002 0 P 0 
L 1.88686004 -1.91133002 1.88431004 -1.91283996 0 P 0 
L 1.88431004 -1.91283996 1.88201004 -1.91446004 0 P 0 
L 1.88201004 -1.91446004 1.87985 -1.91626998 0 P 0 
L 1.87985 -1.91626998 1.87785 -1.91826004 0 P 0 
L 1.87785 -1.91826004 1.87601998 -1.92041004 0 P 0 
L 1.87601998 -1.92041004 1.87441004 -1.92266998 0 P 0 
L 1.87441004 -1.92266998 1.87298996 -1.92505 0 P 0 
L 1.87298996 -1.92505 1.87178002 -1.92756004 0 P 0 
L 1.87178002 -1.92756004 1.87078996 -1.93015 0 P 0 
L 1.87078996 -1.93015 1.87 -1.93286998 0 P 0 
L 1.87 -1.93286998 1.86943996 -1.93563996 0 P 0 
L 1.86943996 -1.93563996 1.86908996 -1.93845 0 P 0 
L 1.86908996 -1.93845 1.86898002 -1.94128996 0 P 0 
L 1.86898002 -1.94128996 1.86911998 -1.94485 0 P 0 
L 1.86911998 -1.94485 1.86953996 -1.94841004 0 P 0 
L 1.86953996 -1.94841004 1.86996004 -1.95048996 0 P 0 
L 1.86996004 -1.95048996 1.87053002 -1.95251998 0 P 0 
L 1.87053002 -1.95251998 1.87125 -1.95451998 0 P 0 
L 1.87125 -1.95451998 1.87211004 -1.95643002 0 P 0 
L 1.87211004 -1.95643002 1.8731 -1.95826004 0 P 0 
L 1.8731 -1.95826004 1.87423996 -1.96001998 0 P 0 
L 1.87423996 -1.96001998 1.87636998 -1.96278996 0 P 0 
L 1.87636998 -1.96278996 1.87871998 -1.96536998 0 P 0 
L 1.87871998 -1.96536998 1.88145 -1.96788002 0 P 0 
L 1.88145 -1.96788002 1.88436998 -1.97015 0 P 0 
L 1.88436998 -1.97015 1.88621004 -1.97135 0 P 0 
L 1.88621004 -1.97135 1.88813002 -1.97238002 0 P 0 
L 1.88813002 -1.97238002 1.89013002 -1.97326004 0 P 0 
L 1.89013002 -1.97326004 1.89228002 -1.97398996 0 P 0 
L 1.89228002 -1.97398996 1.89446998 -1.97455 0 P 0 
L 1.89446998 -1.97455 1.89671004 -1.97493996 0 P 0 
L 1.89671004 -1.97493996 1.90076998 -1.97533996 0 P 0 
L 1.90076998 -1.97533996 1.90485 -1.97546998 0 P 0 
L 1.90485 -1.97546998 1.90821004 -1.97531998 0 P 0 
L 1.90821004 -1.97531998 1.91153996 -1.97488996 0 P 0 
L 1.91153996 -1.97488996 1.91481998 -1.97418996 0 P 0 
L 1.91481998 -1.97418996 1.9171 -1.9735 0 P 0 
L 1.9171 -1.9735 1.91933002 -1.97266004 0 P 0 
L 1.91933002 -1.97266004 1.92148002 -1.97166004 0 P 0 
L 1.92148002 -1.97166004 1.92356998 -1.97048996 0 P 0 
L 1.92356998 -1.97048996 1.92553996 -1.96918996 0 P 0 
L 1.92553996 -1.96918996 1.92741004 -1.96773996 0 P 0 
L 1.92741004 -1.96773996 1.92916004 -1.96616998 0 P 0 
L 1.92916004 -1.96616998 1.93081004 -1.96446004 0 P 0 
L 1.93081004 -1.96446004 1.93236998 -1.96256998 0 P 0 
L 1.93236998 -1.96256998 1.93381004 -1.96058996 0 P 0 
L 1.93381004 -1.96058996 1.93511998 -1.95851004 0 P 0 
L 1.93511998 -1.95851004 1.93628996 -1.95633996 0 P 0 
L 1.93628996 -1.95633996 1.93803996 -1.95251998 0 P 0 
L 1.93803996 -1.95251998 1.93858002 -1.95101998 0 P 0 
L 1.93858002 -1.95101998 1.93898996 -1.94948002 0 P 0 
L 1.93898996 -1.94948002 1.93928996 -1.94786998 0 P 0 
L 1.93928996 -1.94786998 1.93946004 -1.94625 0 P 0 
L 1.93946004 -1.94625 1.9396 -1.94178002 0 P 0 
L 1.9396 -1.94178002 1.93946004 -1.93803996 0 P 0 
L 1.93946004 -1.93803996 1.93905 -1.9343 0 P 0 
L 1.93905 -1.9343 1.93863996 -1.93213996 0 P 0 
L 1.93863996 -1.93213996 1.93808002 -1.93001998 0 P 0 
L 1.93808002 -1.93001998 1.93736004 -1.92795 0 P 0 
L 1.93736004 -1.92795 1.93653002 -1.92601004 0 P 0 
L 1.93653002 -1.92601004 1.93555 -1.92415 0 P 0 
L 1.93555 -1.92415 1.93441998 -1.92236004 0 P 0 
L 1.93441998 -1.92236004 1.9331 -1.92056004 0 P 0 
L 1.9331 -1.92056004 1.93166998 -1.91885 0 P 0 
L 1.93166998 -1.91885 1.93011998 -1.91723002 0 P 0 
L 1.93011998 -1.91723002 1.92896004 -1.91615 0 P 0 
L 1.92896004 -1.91615 1.92775 -1.91511004 0 P 0 
L 1.92775 -1.91511004 1.92493002 -1.91295 0 P 0 
L 1.92493002 -1.91295 1.9221 -1.91108002 0 P 0 
L 1.9221 -1.91108002 1.92095 -1.91043002 0 P 0 
L 1.92095 -1.91043002 1.91975 -1.90985 0 P 0 
L 1.91975 -1.90985 1.91796004 -1.90913996 0 P 0 
L 1.91796004 -1.90913996 1.91613002 -1.90856004 0 P 0 
L 1.91613002 -1.90856004 1.91423996 -1.9081 0 P 0 
L 1.91423996 -1.9081 1.91086004 -1.90751998 0 P 0 
L 1.91086004 -1.90751998 1.90743002 -1.90716004 0 P 0 
L 1.90743002 -1.90716004 1.90401004 -1.90701004 0 P 0 
L 1.90401004 -1.90701004 1.90058002 -1.90708002 0 P 0 
L 1.90058002 -1.90708002 1.8987 -1.90726004 0 P 0 
L 1.8987 -1.90726004 1.89683002 -1.90756998 0 P 0 
L 1.89683002 -1.90756998 1.89498002 -1.90801998 0 P 0 
L 1.86643002 -2.02923996 1.87525 -2.02923996 0 P 0 
L 1.86176998 -2.02823996 1.87515 -2.02823996 0 P 0 
L 1.85588996 -2.02723996 1.87505 -2.02723996 0 P 0 
L 1.78365 -2.00523996 1.87281004 -2.00523996 0 P 0 
L 1.78451004 -2.00423996 1.87271004 -2.00423996 0 P 0 
L 1.78546998 -2.00323996 1.87261004 -2.00323996 0 P 0 
L 1.78655 -2.00223996 1.8725 -2.00223996 0 P 0 
L 1.78776004 -2.00123996 1.8724 -2.00123996 0 P 0 
L 1.78915 -2.00023996 1.8723 -2.00023996 0 P 0 
L 1.79078996 -1.99923996 1.8722 -1.99923996 0 P 0 
L 1.79263996 -1.99823996 1.87208996 -1.99823996 0 P 0 
L 1.79458996 -1.99723996 1.87198996 -1.99723996 0 P 0 
L 1.79686998 -1.99623996 1.87188002 -1.99623996 0 P 0 
L 1.79946004 -1.99523996 1.87178002 -1.99523996 0 P 0 
L 1.80231004 -1.99423996 1.86961998 -1.99423996 0 P 0 
L 1.80596004 -1.99323996 1.86218002 -1.99323996 0 P 0 
L 1.81051004 -1.99223996 1.85398002 -1.99223996 0 P 0 
L 1.81676004 -1.99123996 1.84395 -1.99123996 0 P 0 
L 1.87786998 -1.96146004 1.88093996 -1.96146004 0 P 0 
L 1.8771 -1.96046004 1.88013002 -1.96046004 0 P 0 
L 1.87633996 -1.95946004 1.87933996 -1.95946004 0 P 0 
L 1.87561998 -1.95846004 1.87866998 -1.95846004 0 P 0 
L 1.87496998 -1.95746004 1.87801998 -1.95746004 0 P 0 
L 1.8744 -1.95646004 1.87745 -1.95646004 0 P 0 
L 1.87386998 -1.95546004 1.87688002 -1.95546004 0 P 0 
L 1.87341998 -1.95446004 1.87641998 -1.95446004 0 P 0 
L 1.87298996 -1.95346004 1.87596004 -1.95346004 0 P 0 
L 1.87263002 -1.95246004 1.87555 -1.95246004 0 P 0 
L 1.87231004 -1.95146004 1.87518996 -1.95146004 0 P 0 
L 1.87203002 -1.95046004 1.87483002 -1.95046004 0 P 0 
L 1.87178996 -1.94946004 1.87456998 -1.94946004 0 P 0 
L 1.87158996 -1.94846004 1.87431004 -1.94846004 0 P 0 
L 1.87143996 -1.94746004 1.87408002 -1.94746004 0 P 0 
L 1.87133002 -1.94646004 1.8739 -1.94646004 0 P 0 
L 1.87121004 -1.94546004 1.87373002 -1.94546004 0 P 0 
L 1.8711 -1.94446998 1.87361998 -1.94446998 0 P 0 
L 1.87106998 -1.94346004 1.87353996 -1.94346004 0 P 0 
L 1.87103002 -1.94246004 1.87346004 -1.94246004 0 P 0 
L 1.87098996 -1.94146998 1.87346004 -1.94146998 0 P 0 
L 1.87101004 -1.94046004 1.87346004 -1.94046004 0 P 0 
L 1.87106004 -1.93946004 1.87348996 -1.93946004 0 P 0 
L 1.87111004 -1.93846004 1.87358002 -1.93846004 0 P 0 
L 1.87123002 -1.93746004 1.87366004 -1.93746004 0 P 0 
L 1.87135 -1.93646004 1.87381998 -1.93646004 0 P 0 
L 1.87151004 -1.93546004 1.87398996 -1.93546004 0 P 0 
L 1.87171998 -1.93446004 1.87416998 -1.93446004 0 P 0 
L 1.87191998 -1.93346004 1.87443002 -1.93346004 0 P 0 
L 1.8722 -1.93246004 1.87468996 -1.93246004 0 P 0 
L 1.87248996 -1.93146004 1.875 -1.93146004 0 P 0 
L 1.87281004 -1.93046004 1.87535 -1.93046004 0 P 0 
L 1.87318996 -1.92946004 1.87571004 -1.92946004 0 P 0 
L 1.87356998 -1.92846004 1.87616004 -1.92846004 0 P 0 
L 1.87405 -1.92746004 1.87661004 -1.92746004 0 P 0 
L 1.87453002 -1.92646004 1.87711998 -1.92646004 0 P 0 
L 1.87506998 -1.92546004 1.87768996 -1.92546004 0 P 0 
L 1.87566004 -1.92446998 1.87826998 -1.92446998 0 P 0 
L 1.87628996 -1.92346004 1.87896004 -1.92346004 0 P 0 
L 1.87701004 -1.92246004 1.87963996 -1.92246004 0 P 0 
L 1.87775 -1.92146004 1.88046004 -1.92146004 0 P 0 
L 1.90483996 -1.97346004 1.9009 -1.97333996 0 P 0 
L 1.9009 -1.97333996 1.89698002 -1.97295 0 P 0 
L 1.89698002 -1.97295 1.89488996 -1.97258996 0 P 0 
L 1.89488996 -1.97258996 1.89285 -1.97206998 0 P 0 
L 1.89285 -1.97206998 1.89086004 -1.97138996 0 P 0 
L 1.89086004 -1.97138996 1.889 -1.97058002 0 P 0 
L 1.889 -1.97058002 1.88723002 -1.96961998 0 P 0 
L 1.88723002 -1.96961998 1.88553002 -1.96851998 0 P 0 
L 1.88553002 -1.96851998 1.88273996 -1.96636004 0 P 0 
L 1.88273996 -1.96636004 1.88013996 -1.96396004 0 P 0 
L 1.88013996 -1.96396004 1.8779 -1.9615 0 P 0 
L 1.8779 -1.9615 1.87588002 -1.95886998 0 P 0 
L 1.87588002 -1.95886998 1.87483002 -1.95723996 0 P 0 
L 1.87483002 -1.95723996 1.8739 -1.95553996 0 P 0 
L 1.8739 -1.95553996 1.87311004 -1.95376998 0 P 0 
L 1.87311004 -1.95376998 1.87243002 -1.95191004 0 P 0 
L 1.87243002 -1.95191004 1.8719 -1.95001998 0 P 0 
L 1.8719 -1.95001998 1.87151998 -1.9481 0 P 0 
L 1.87151998 -1.9481 1.87111004 -1.94468996 0 P 0 
L 1.87111004 -1.94468996 1.87098002 -1.94128996 0 P 0 
L 1.87098002 -1.94128996 1.87108996 -1.93861004 0 P 0 
L 1.87108996 -1.93861004 1.87141004 -1.93596998 0 P 0 
L 1.87141004 -1.93596998 1.87195 -1.93335 0 P 0 
L 1.87195 -1.93335 1.87268996 -1.93078996 0 P 0 
L 1.87268996 -1.93078996 1.87361998 -1.92835 0 P 0 
L 1.87361998 -1.92835 1.87475 -1.926 0 P 0 
L 1.87475 -1.926 1.87608996 -1.92376004 0 P 0 
L 1.87608996 -1.92376004 1.8776 -1.92163996 0 P 0 
L 1.8776 -1.92163996 1.87931998 -1.91961998 0 P 0 
L 1.87931998 -1.91961998 1.8812 -1.91775 0 P 0 
L 1.8812 -1.91775 1.88323002 -1.91605 0 P 0 
L 1.88323002 -1.91605 1.8854 -1.91451998 0 P 0 
L 1.8854 -1.91451998 1.88781004 -1.91308996 0 P 0 
L 1.88781004 -1.91308996 1.89031004 -1.91186004 0 P 0 
L 1.89031004 -1.91186004 1.89288002 -1.9108 0 P 0 
L 1.89288002 -1.9108 1.89553002 -1.90995 0 P 0 
L 1.89553002 -1.90995 1.89723002 -1.90953002 0 P 0 
L 1.89723002 -1.90953002 1.89896004 -1.90923996 0 P 0 
L 1.89896004 -1.90923996 1.90068996 -1.90908002 0 P 0 
L 1.90068996 -1.90908002 1.90398996 -1.90901004 0 P 0 
L 1.90398996 -1.90901004 1.90728002 -1.90915 0 P 0 
L 1.90728002 -1.90915 1.91058996 -1.90951004 0 P 0 
L 1.91058996 -1.90951004 1.91383996 -1.91006004 0 P 0 
L 1.91383996 -1.91006004 1.91558996 -1.91048996 0 P 0 
L 1.91558996 -1.91048996 1.91728996 -1.91101998 0 P 0 
L 1.91728996 -1.91101998 1.91895 -1.91168002 0 P 0 
L 1.91895 -1.91168002 1.92001998 -1.9122 0 P 0 
L 1.92001998 -1.9122 1.92105 -1.91278996 0 P 0 
L 1.92105 -1.91278996 1.92376998 -1.91458002 0 P 0 
L 1.92376998 -1.91458002 1.92648996 -1.91666998 0 P 0 
L 1.92648996 -1.91666998 1.92763002 -1.91763996 0 P 0 
L 1.92763002 -1.91763996 1.92871004 -1.91865 0 P 0 
L 1.92871004 -1.91865 1.93018002 -1.92018996 0 P 0 
L 1.93018002 -1.92018996 1.93153002 -1.9218 0 P 0 
L 1.93153002 -1.9218 1.93276998 -1.92348996 0 P 0 
L 1.93276998 -1.92348996 1.93381004 -1.92515 0 P 0 
L 1.93381004 -1.92515 1.93471998 -1.92686998 0 P 0 
L 1.93471998 -1.92686998 1.9355 -1.92866998 0 P 0 
L 1.9355 -1.92866998 1.93616998 -1.93061004 0 P 0 
L 1.93616998 -1.93061004 1.93668996 -1.93258002 0 P 0 
L 1.93668996 -1.93258002 1.93706998 -1.93458996 0 P 0 
L 1.93706998 -1.93458996 1.93746998 -1.93818996 0 P 0 
L 1.93746998 -1.93818996 1.9376 -1.94178996 0 P 0 
L 1.9376 -1.94178996 1.93746004 -1.94611004 0 P 0 
L 1.93746004 -1.94611004 1.93731004 -1.94758996 0 P 0 
L 1.93731004 -1.94758996 1.93705 -1.94903996 0 P 0 
L 1.93705 -1.94903996 1.93666998 -1.95041998 0 P 0 
L 1.93666998 -1.95041998 1.93618002 -1.95176004 0 P 0 
L 1.93618002 -1.95176004 1.9345 -1.95545 0 P 0 
L 1.9345 -1.95545 1.93338996 -1.9575 0 P 0 
L 1.93338996 -1.9575 1.93216004 -1.95946998 0 P 0 
L 1.93216004 -1.95946998 1.93078996 -1.96133996 0 P 0 
L 1.93078996 -1.96133996 1.92931004 -1.96311998 0 P 0 
L 1.92931004 -1.96311998 1.92776998 -1.96473002 0 P 0 
L 1.92776998 -1.96473002 1.92613002 -1.96621004 0 P 0 
L 1.92613002 -1.96621004 1.92438002 -1.96756004 0 P 0 
L 1.92438002 -1.96756004 1.92253002 -1.96878002 0 P 0 
L 1.92253002 -1.96878002 1.92056998 -1.96986998 0 P 0 
L 1.92056998 -1.96986998 1.91855 -1.97081998 0 P 0 
L 1.91855 -1.97081998 1.91646004 -1.97161004 0 P 0 
L 1.91646004 -1.97161004 1.91433002 -1.97223996 0 P 0 
L 1.91433002 -1.97223996 1.9112 -1.97291004 0 P 0 
L 1.9112 -1.97291004 1.90803996 -1.97331998 0 P 0 
L 1.90803996 -1.97331998 1.90483996 -1.97346004 0 P 0 
L 1.90476004 -1.97173996 1.9048 -1.97173996 0 P 0 
L 1.9048 -1.97173996 1.90483996 -1.97173002 0 P 0 
L 1.90483996 -1.97173002 1.90736004 -1.9716 0 P 0 
L 1.90736004 -1.9716 1.9074 -1.97158996 0 P 0 
L 1.9074 -1.97158996 1.90746998 -1.97158996 0 P 0 
L 1.90746998 -1.97158996 1.90751004 -1.97158002 0 P 0 
L 1.90751004 -1.97158002 1.91001004 -1.97126004 0 P 0 
L 1.91001004 -1.97126004 1.91005 -1.97125 0 P 0 
L 1.91005 -1.97125 1.91008002 -1.97123996 0 P 0 
L 1.91008002 -1.97123996 1.91011998 -1.97123996 0 P 0 
L 1.91011998 -1.97123996 1.91016004 -1.97123002 0 P 0 
L 1.91016004 -1.97123002 1.9126 -1.97071998 0 P 0 
L 1.9126 -1.97071998 1.9126 -1.97071004 0 P 0 
L 1.9126 -1.97071004 1.91266998 -1.97071004 0 P 0 
L 1.91266998 -1.97071004 1.91271004 -1.97068996 0 P 0 
L 1.91271004 -1.97068996 1.91275 -1.97068002 0 P 0 
L 1.91275 -1.97068002 1.91511998 -1.96998996 0 P 0 
L 1.91511998 -1.96998996 1.91515 -1.96998996 0 P 0 
L 1.91515 -1.96998996 1.91518996 -1.96996998 0 P 0 
L 1.91518996 -1.96996998 1.91523002 -1.96996004 0 P 0 
L 1.91523002 -1.96996004 1.91526004 -1.96995 0 P 0 
L 1.91526004 -1.96995 1.91756998 -1.96908002 0 P 0 
L 1.91756998 -1.96908002 1.91761004 -1.96906998 0 P 0 
L 1.91761004 -1.96906998 1.91768002 -1.96903996 0 P 0 
L 1.91768002 -1.96903996 1.91771004 -1.96901998 0 P 0 
L 1.91771004 -1.96901998 1.91995 -1.96798002 0 P 0 
L 1.91995 -1.96798002 1.92001998 -1.96795 0 P 0 
L 1.92001998 -1.96795 1.92005 -1.96793002 0 P 0 
L 1.92005 -1.96793002 1.92008996 -1.96791004 0 P 0 
L 1.92008996 -1.96791004 1.92168002 -1.96701998 0 P 0 
L 1.92168002 -1.96701998 1.92171998 -1.967 0 P 0 
L 1.92171998 -1.967 1.92175 -1.96698002 0 P 0 
L 1.92175 -1.96698002 1.92178996 -1.96695 0 P 0 
L 1.92178996 -1.96695 1.92181998 -1.96693002 0 P 0 
L 1.92181998 -1.96693002 1.92331998 -1.96591998 0 P 0 
L 1.92331998 -1.96591998 1.92336004 -1.9659 0 P 0 
L 1.92336004 -1.9659 1.92341998 -1.96586004 0 P 0 
L 1.92341998 -1.96586004 1.92345 -1.96583002 0 P 0 
L 1.92345 -1.96583002 1.92486004 -1.9647 0 P 0 
L 1.92486004 -1.9647 1.92493002 -1.96465 0 P 0 
L 1.92493002 -1.96465 1.92496004 -1.96463002 0 P 0 
L 1.92496004 -1.96463002 1.92498996 -1.9646 0 P 0 
L 1.92498996 -1.9646 1.92631004 -1.96336998 0 P 0 
L 1.92631004 -1.96336998 1.9264 -1.96328002 0 P 0 
L 1.9264 -1.96328002 1.92641998 -1.96325 0 P 0 
L 1.92641998 -1.96325 1.92763996 -1.96191998 0 P 0 
L 1.92763996 -1.96191998 1.92766998 -1.96188996 0 P 0 
L 1.92766998 -1.96188996 1.92768996 -1.96186004 0 P 0 
L 1.92768996 -1.96186004 1.92771998 -1.96183002 0 P 0 
L 1.92771998 -1.96183002 1.92773996 -1.9618 0 P 0 
L 1.92773996 -1.9618 1.92913996 -1.96001004 0 P 0 
L 1.92913996 -1.96001004 1.92918996 -1.95995 0 P 0 
L 1.92918996 -1.95995 1.92921004 -1.95991004 0 P 0 
L 1.92921004 -1.95991004 1.92923002 -1.95988002 0 P 0 
L 1.92923002 -1.95988002 1.93048002 -1.95798996 0 P 0 
L 1.93048002 -1.95798996 1.93051998 -1.95793002 0 P 0 
L 1.93051998 -1.95793002 1.93053996 -1.95788996 0 P 0 
L 1.93053996 -1.95788996 1.93056004 -1.95786004 0 P 0 
L 1.93056004 -1.95786004 1.93166004 -1.95588002 0 P 0 
L 1.93166004 -1.95588002 1.93171004 -1.95576998 0 P 0 
L 1.93171004 -1.95576998 1.93173002 -1.95573996 0 P 0 
L 1.93173002 -1.95573996 1.93266998 -1.95366998 0 P 0 
L 1.93266998 -1.95366998 1.93271004 -1.95356998 0 P 0 
L 1.93271004 -1.95356998 1.93273002 -1.95353002 0 P 0 
L 1.93273002 -1.95353002 1.9335 -1.9514 0 P 0 
L 1.9335 -1.9514 1.93351004 -1.95136998 0 P 0 
L 1.93351004 -1.95136998 1.93353002 -1.95133002 0 P 0 
L 1.93353002 -1.95133002 1.93355 -1.95125 0 P 0 
L 1.93355 -1.95125 1.93416004 -1.94906998 0 P 0 
L 1.93416004 -1.94906998 1.93416998 -1.94903002 0 P 0 
L 1.93416998 -1.94903002 1.93418002 -1.949 0 P 0 
L 1.93418002 -1.949 1.93418002 -1.94896004 0 P 0 
L 1.93418002 -1.94896004 1.93418996 -1.94891998 0 P 0 
L 1.93418996 -1.94891998 1.93463996 -1.94665 0 P 0 
L 1.93463996 -1.94665 1.93463996 -1.94661004 0 P 0 
L 1.93463996 -1.94661004 1.93465 -1.94656998 0 P 0 
L 1.93465 -1.94656998 1.93466004 -1.9465 0 P 0 
L 1.93466004 -1.9465 1.93493996 -1.9442 0 P 0 
L 1.93493996 -1.9442 1.93493996 -1.94413002 0 P 0 
L 1.93493996 -1.94413002 1.93495 -1.94408996 0 P 0 
L 1.93495 -1.94408996 1.93495 -1.94406004 0 P 0 
L 1.93495 -1.94406004 1.93505 -1.94173996 0 P 0 
L 1.93505 -1.94173996 1.93506004 -1.94171004 0 P 0 
L 1.93506004 -1.94171004 1.93506004 -1.9416 0 P 0 
L 1.93506004 -1.9416 1.93498996 -1.93928996 0 P 0 
L 1.93498996 -1.93928996 1.93498996 -1.93921004 0 P 0 
L 1.93498996 -1.93921004 1.93498002 -1.93913996 0 P 0 
L 1.93498002 -1.93913996 1.93475 -1.93683996 0 P 0 
L 1.93475 -1.93683996 1.93473996 -1.93676998 0 P 0 
L 1.93473996 -1.93676998 1.93473002 -1.93673002 0 P 0 
L 1.93473002 -1.93673002 1.93473002 -1.93668996 0 P 0 
L 1.93473002 -1.93668996 1.93433002 -1.93441004 0 P 0 
L 1.93433002 -1.93441004 1.93431998 -1.93436998 0 P 0 
L 1.93431998 -1.93436998 1.93431004 -1.93433996 0 P 0 
L 1.93431004 -1.93433996 1.93428996 -1.93426004 0 P 0 
L 1.93428996 -1.93426004 1.93373002 -1.93206004 0 P 0 
L 1.93373002 -1.93206004 1.93368996 -1.93191998 0 P 0 
L 1.93368996 -1.93191998 1.93296004 -1.92976998 0 P 0 
L 1.93296004 -1.92976998 1.93293996 -1.9297 0 P 0 
L 1.93293996 -1.9297 1.93291004 -1.92963002 0 P 0 
L 1.93291004 -1.92963002 1.93201998 -1.92753996 0 P 0 
L 1.93201998 -1.92753996 1.93196998 -1.92743002 0 P 0 
L 1.93196998 -1.92743002 1.93196004 -1.9274 0 P 0 
L 1.93196004 -1.9274 1.93091998 -1.92538996 0 P 0 
L 1.93091998 -1.92538996 1.9309 -1.92536004 0 P 0 
L 1.9309 -1.92536004 1.93088002 -1.92531998 0 P 0 
L 1.93088002 -1.92531998 1.93086004 -1.92528996 0 P 0 
L 1.93086004 -1.92528996 1.93083996 -1.92525 0 P 0 
L 1.93083996 -1.92525 1.92965 -1.92331998 0 P 0 
L 1.92965 -1.92331998 1.92956998 -1.9232 0 P 0 
L 1.92956998 -1.9232 1.92823002 -1.92136004 0 P 0 
L 1.92823002 -1.92136004 1.92818002 -1.9213 0 P 0 
L 1.92818002 -1.9213 1.92816004 -1.92126998 0 P 0 
L 1.92816004 -1.92126998 1.92813002 -1.92123996 0 P 0 
L 1.92813002 -1.92123996 1.92671998 -1.91958002 0 P 0 
L 1.92671998 -1.91958002 1.9266 -1.91946004 0 P 0 
L 1.9266 -1.91946004 1.92505 -1.91793002 0 P 0 
L 1.92505 -1.91793002 1.92498996 -1.91786998 0 P 0 
L 1.92498996 -1.91786998 1.92493002 -1.91781998 0 P 0 
L 1.92493002 -1.91781998 1.92325 -1.91643002 0 P 0 
L 1.92325 -1.91643002 1.92318996 -1.91636998 0 P 0 
L 1.92318996 -1.91636998 1.92311998 -1.91631998 0 P 0 
L 1.92311998 -1.91631998 1.92133002 -1.91508002 0 P 0 
L 1.92133002 -1.91508002 1.92126004 -1.91503996 0 P 0 
L 1.92126004 -1.91503996 1.92121998 -1.91501004 0 P 0 
L 1.92121998 -1.91501004 1.92118002 -1.91498996 0 P 0 
L 1.92118002 -1.91498996 1.91928996 -1.91391004 0 P 0 
L 1.91928996 -1.91391004 1.91926004 -1.91388996 0 P 0 
L 1.91926004 -1.91388996 1.91913996 -1.91383002 0 P 0 
L 1.91913996 -1.91383002 1.91716998 -1.91291004 0 P 0 
L 1.91716998 -1.91291004 1.91711998 -1.91288996 0 P 0 
L 1.91711998 -1.91288996 1.91705 -1.91286004 0 P 0 
L 1.91705 -1.91286004 1.917 -1.91285 0 P 0 
L 1.917 -1.91285 1.91476998 -1.91203996 0 P 0 
L 1.91476998 -1.91203996 1.91468996 -1.91201998 0 P 0 
L 1.91468996 -1.91201998 1.91465 -1.912 0 P 0 
L 1.91465 -1.912 1.9146 -1.91198996 0 P 0 
L 1.9146 -1.91198996 1.91233002 -1.91138996 0 P 0 
L 1.91233002 -1.91138996 1.91228002 -1.91138002 0 P 0 
L 1.91228002 -1.91138002 1.91223996 -1.91136998 0 P 0 
L 1.91223996 -1.91136998 1.91216004 -1.91136004 0 P 0 
L 1.91216004 -1.91136004 1.90983002 -1.91095 0 P 0 
L 1.90983002 -1.91095 1.9098 -1.91093996 0 P 0 
L 1.9098 -1.91093996 1.90976004 -1.91093996 0 P 0 
L 1.90976004 -1.91093996 1.90971998 -1.91093002 0 P 0 
L 1.90971998 -1.91093002 1.90968002 -1.91093002 0 P 0 
L 1.90968002 -1.91093002 1.90713996 -1.91068996 0 P 0 
L 1.90713996 -1.91068996 1.9071 -1.91068002 0 P 0 
L 1.9071 -1.91068002 1.907 -1.91068002 0 P 0 
L 1.907 -1.91068002 1.90445 -1.91061004 0 P 0 
L 1.90445 -1.91061004 1.90431004 -1.91061004 0 P 0 
L 1.90431004 -1.91061004 1.90176004 -1.91071004 0 P 0 
L 1.90176004 -1.91071004 1.90173002 -1.91071998 0 P 0 
L 1.90173002 -1.91071998 1.90166004 -1.91071998 0 P 0 
L 1.90166004 -1.91071998 1.90161998 -1.91073002 0 P 0 
L 1.90161998 -1.91073002 1.89913002 -1.911 0 P 0 
L 1.89913002 -1.911 1.89906004 -1.91101004 0 P 0 
L 1.89906004 -1.91101004 1.89901998 -1.91101998 0 P 0 
L 1.89901998 -1.91101998 1.89898996 -1.91101998 0 P 0 
L 1.89898996 -1.91101998 1.89653002 -1.91146998 0 P 0 
L 1.89653002 -1.91146998 1.8965 -1.91148002 0 P 0 
L 1.8965 -1.91148002 1.89646004 -1.91148002 0 P 0 
L 1.89646004 -1.91148002 1.8964 -1.9115 0 P 0 
L 1.8964 -1.9115 1.89396998 -1.91211998 0 P 0 
L 1.89396998 -1.91211998 1.89393996 -1.91213002 0 P 0 
L 1.89393996 -1.91213002 1.89383002 -1.91216004 0 P 0 
L 1.89383002 -1.91216004 1.89225 -1.91268996 0 P 0 
L 1.89225 -1.91268996 1.89218002 -1.91271998 0 P 0 
L 1.89218002 -1.91271998 1.89211004 -1.91273996 0 P 0 
L 1.89211004 -1.91273996 1.8921 -1.91273996 0 P 0 
L 1.8921 -1.91273996 1.89058002 -1.91338996 0 P 0 
L 1.89058002 -1.91338996 1.89043996 -1.91345 0 P 0 
L 1.89043996 -1.91345 1.88896004 -1.91421004 0 P 0 
L 1.88896004 -1.91421004 1.88893002 -1.91423002 0 P 0 
L 1.88893002 -1.91423002 1.8889 -1.91423996 0 P 0 
L 1.8889 -1.91423996 1.88886004 -1.91426004 0 P 0 
L 1.88886004 -1.91426004 1.88883002 -1.91428002 0 P 0 
L 1.88883002 -1.91428002 1.88741004 -1.91515 0 P 0 
L 1.88741004 -1.91515 1.88733996 -1.91518996 0 P 0 
L 1.88733996 -1.91518996 1.88728002 -1.91523996 0 P 0 
L 1.88728002 -1.91523996 1.88526004 -1.9167 0 P 0 
L 1.88526004 -1.9167 1.88521998 -1.91673002 0 P 0 
L 1.88521998 -1.91673002 1.88518996 -1.91675 0 P 0 
L 1.88518996 -1.91675 1.88516004 -1.91678002 0 P 0 
L 1.88516004 -1.91678002 1.88511998 -1.91681004 0 P 0 
L 1.88511998 -1.91681004 1.88323002 -1.91845 0 P 0 
L 1.88323002 -1.91845 1.8832 -1.91846998 0 P 0 
L 1.8832 -1.91846998 1.88311004 -1.91856004 0 P 0 
L 1.88311004 -1.91856004 1.88136998 -1.92036004 0 P 0 
L 1.88136998 -1.92036004 1.88128002 -1.92045 0 P 0 
L 1.88128002 -1.92045 1.88125 -1.92048996 0 P 0 
L 1.88125 -1.92048996 1.87968002 -1.92241998 0 P 0 
L 1.87968002 -1.92241998 1.87965 -1.92245 0 P 0 
L 1.87965 -1.92245 1.87961998 -1.92248996 0 P 0 
L 1.87961998 -1.92248996 1.87956998 -1.92256004 0 P 0 
L 1.87956998 -1.92256004 1.87816998 -1.92461998 0 P 0 
L 1.87816998 -1.92461998 1.8781 -1.92473002 0 P 0 
L 1.8781 -1.92473002 1.87808002 -1.92476998 0 P 0 
L 1.87808002 -1.92476998 1.87685 -1.92695 0 P 0 
L 1.87685 -1.92695 1.87683002 -1.92698996 0 P 0 
L 1.87683002 -1.92698996 1.87681004 -1.92701998 0 P 0 
L 1.87681004 -1.92701998 1.87678996 -1.92706998 0 P 0 
L 1.87678996 -1.92706998 1.87676998 -1.92711004 0 P 0 
L 1.87676998 -1.92711004 1.87573002 -1.92941004 0 P 0 
L 1.87573002 -1.92941004 1.87571004 -1.92945 0 P 0 
L 1.87571004 -1.92945 1.8757 -1.92948996 0 P 0 
L 1.8757 -1.92948996 1.87568002 -1.92951998 0 P 0 
L 1.87568002 -1.92951998 1.87566998 -1.92956998 0 P 0 
L 1.87566998 -1.92956998 1.87483996 -1.93193002 0 P 0 
L 1.87483996 -1.93193002 1.87481004 -1.93201004 0 P 0 
L 1.87481004 -1.93201004 1.87478996 -1.93208996 0 P 0 
L 1.87478996 -1.93208996 1.87416004 -1.93451998 0 P 0 
L 1.87416004 -1.93451998 1.87413996 -1.93456004 0 P 0 
L 1.87413996 -1.93456004 1.87413002 -1.9346 0 P 0 
L 1.87413002 -1.9346 1.87413002 -1.93463996 0 P 0 
L 1.87413002 -1.93463996 1.87411998 -1.93468002 0 P 0 
L 1.87411998 -1.93468002 1.8737 -1.93715 0 P 0 
L 1.8737 -1.93715 1.87368996 -1.93718996 0 P 0 
L 1.87368996 -1.93718996 1.87368002 -1.93723996 0 P 0 
L 1.87368002 -1.93723996 1.87368002 -1.93731998 0 P 0 
L 1.87368002 -1.93731998 1.87346998 -1.93981998 0 P 0 
L 1.87346998 -1.93981998 1.87346004 -1.93986004 0 P 0 
L 1.87346004 -1.93986004 1.87346004 -1.94258002 0 P 0 
L 1.87346004 -1.94258002 1.87346998 -1.94266004 0 P 0 
L 1.87346998 -1.94266004 1.87368002 -1.94516998 0 P 0 
L 1.87368002 -1.94516998 1.87368996 -1.94521004 0 P 0 
L 1.87368996 -1.94521004 1.87368996 -1.94525 0 P 0 
L 1.87368996 -1.94525 1.87371004 -1.94533996 0 P 0 
L 1.87371004 -1.94533996 1.87413996 -1.94778996 0 P 0 
L 1.87413996 -1.94778996 1.87413996 -1.94783996 0 P 0 
L 1.87413996 -1.94783996 1.87416998 -1.94796004 0 P 0 
L 1.87416998 -1.94796004 1.87481004 -1.95036998 0 P 0 
L 1.87481004 -1.95036998 1.87483996 -1.95048996 0 P 0 
L 1.87483996 -1.95048996 1.87486004 -1.95053002 0 P 0 
L 1.87486004 -1.95053002 1.8757 -1.95288002 0 P 0 
L 1.8757 -1.95288002 1.87571004 -1.95291998 0 P 0 
L 1.87571004 -1.95291998 1.87575 -1.953 0 P 0 
L 1.87575 -1.953 1.87576004 -1.95303996 0 P 0 
L 1.87576004 -1.95303996 1.8768 -1.9553 0 P 0 
L 1.8768 -1.9553 1.87686004 -1.95541998 0 P 0 
L 1.87686004 -1.95541998 1.87688002 -1.95545 0 P 0 
L 1.87688002 -1.95545 1.8781 -1.95761004 0 P 0 
L 1.8781 -1.95761004 1.87811998 -1.95761004 0 P 0 
L 1.87811998 -1.95761004 1.8781 -1.95761998 0 P 0 
L 1.8781 -1.95761998 1.87813996 -1.95768996 0 P 0 
L 1.87813996 -1.95768996 1.87816998 -1.95771998 0 P 0 
L 1.87816998 -1.95771998 1.87818996 -1.95775 0 P 0 
L 1.87818996 -1.95775 1.87938002 -1.95951004 0 P 0 
L 1.87938002 -1.95951004 1.87943996 -1.9596 0 P 0 
L 1.87943996 -1.9596 1.87946998 -1.95963002 0 P 0 
L 1.87946998 -1.95963002 1.88078002 -1.96128996 0 P 0 
L 1.88078002 -1.96128996 1.88081004 -1.96131998 0 P 0 
L 1.88081004 -1.96131998 1.88083002 -1.96135 0 P 0 
L 1.88083002 -1.96135 1.88086004 -1.96136998 0 P 0 
L 1.88086004 -1.96136998 1.88088002 -1.9614 0 P 0 
L 1.88088002 -1.9614 1.88231998 -1.96295 0 P 0 
L 1.88231998 -1.96295 1.88233996 -1.96298002 0 P 0 
L 1.88233996 -1.96298002 1.8824 -1.96303996 0 P 0 
L 1.8824 -1.96303996 1.88243002 -1.96306004 0 P 0 
L 1.88243002 -1.96306004 1.88398002 -1.9645 0 P 0 
L 1.88398002 -1.9645 1.88401004 -1.96451998 0 P 0 
L 1.88401004 -1.96451998 1.88403002 -1.96455 0 P 0 
L 1.88403002 -1.96455 1.88406998 -1.96458002 0 P 0 
L 1.88406998 -1.96458002 1.88408996 -1.9646 0 P 0 
L 1.88408996 -1.9646 1.88575 -1.96591004 0 P 0 
L 1.88575 -1.96591004 1.88578002 -1.96593996 0 P 0 
L 1.88578002 -1.96593996 1.88586998 -1.966 0 P 0 
L 1.88586998 -1.966 1.88761998 -1.96718996 0 P 0 
L 1.88761998 -1.96718996 1.88766004 -1.96721004 0 P 0 
L 1.88766004 -1.96721004 1.88775 -1.96726998 0 P 0 
L 1.88775 -1.96726998 1.88958996 -1.96831998 0 P 0 
L 1.88958996 -1.96831998 1.88965 -1.96836004 0 P 0 
L 1.88965 -1.96836004 1.88968002 -1.96836998 0 P 0 
L 1.88968002 -1.96836998 1.88971998 -1.96838996 0 P 0 
L 1.88971998 -1.96838996 1.89145 -1.96921998 0 P 0 
L 1.89145 -1.96921998 1.89151004 -1.96925 0 P 0 
L 1.89151004 -1.96925 1.89155 -1.96926004 0 P 0 
L 1.89155 -1.96926004 1.89158002 -1.96926998 0 P 0 
L 1.89158002 -1.96926998 1.89336004 -1.96996998 0 P 0 
L 1.89336004 -1.96996998 1.89336004 -1.96998002 0 P 0 
L 1.89336004 -1.96998002 1.89346004 -1.97001004 0 P 0 
L 1.89346004 -1.97001004 1.89348996 -1.97001998 0 P 0 
L 1.89348996 -1.97001998 1.89531998 -1.9706 0 P 0 
L 1.89531998 -1.9706 1.89536004 -1.97061004 0 P 0 
L 1.89536004 -1.97061004 1.89541998 -1.97063002 0 P 0 
L 1.89541998 -1.97063002 1.89546004 -1.97063002 0 P 0 
L 1.89546004 -1.97063002 1.89731998 -1.97108002 0 P 0 
L 1.89731998 -1.97108002 1.89741998 -1.9711 0 P 0 
L 1.89741998 -1.9711 1.89746004 -1.9711 0 P 0 
L 1.89746004 -1.9711 1.89746004 -1.97111004 0 P 0 
L 1.89746004 -1.97111004 1.89933996 -1.97141998 0 P 0 
L 1.89933996 -1.97141998 1.89936998 -1.97143002 0 P 0 
L 1.89936998 -1.97143002 1.89941004 -1.97143002 0 P 0 
L 1.89941004 -1.97143002 1.89945 -1.97143996 0 P 0 
L 1.89945 -1.97143996 1.89948002 -1.97143996 0 P 0 
L 1.89948002 -1.97143996 1.90201004 -1.97168002 0 P 0 
L 1.90201004 -1.97168002 1.90205 -1.97168002 0 P 0 
L 1.90205 -1.97168002 1.90208996 -1.97168996 0 P 0 
L 1.90208996 -1.97168996 1.90216004 -1.97168996 0 P 0 
L 1.90216004 -1.97168996 1.90468996 -1.97173996 0 P 0 
L 1.90468996 -1.97173996 1.90476004 -1.97173996 0 P 0 
L 1.80616004 -2.12823996 1.83348996 -2.12823996 0 P 0 
L 1.79591998 -2.12723996 1.8396 -2.12723996 0 P 0 
L 1.78818002 -2.12623996 1.84465 -2.12623996 0 P 0 
L 1.82003996 -2.09123996 1.87618996 -2.09123996 0 P 0 
L 1.82198996 -2.09023996 1.8762 -2.09023996 0 P 0 
L 1.82325 -2.08923996 1.8762 -2.08923996 0 P 0 
L 1.82411998 -2.08823996 1.87618996 -2.08823996 0 P 0 
L 1.82463002 -2.08723996 1.87616998 -2.08723996 0 P 0 
L 1.82488002 -2.08623996 1.87615 -2.08623996 0 P 0 
L 1.82493002 -2.08523996 1.87613002 -2.08523996 0 P 0 
L 1.82476998 -2.08423996 1.87611004 -2.08423996 0 P 0 
L 1.64846004 -2.08295 1.73316998 -2.08295 0 P 0 
L 1.64811998 -2.08195 1.73356998 -2.08195 0 P 0 
L 1.64776998 -2.08095 1.73398002 -2.08095 0 P 0 
L 1.64743002 -2.07995 1.73438002 -2.07995 0 P 0 
L 1.64708996 -2.07895 1.73478996 -2.07895 0 P 0 
L 1.64673996 -2.07795 1.7352 -2.07795 0 P 0 
L 1.6464 -2.07695 1.7356 -2.07695 0 P 0 
L 1.64605 -2.07595 1.73601004 -2.07595 0 P 0 
L 1.64571004 -2.07495 1.73641004 -2.07495 0 P 0 
L 1.64536004 -2.07395 1.73681004 -2.07395 0 P 0 
L 1.64501998 -2.07295 1.73721998 -2.07295 0 P 0 
L 1.64466998 -2.07195 1.73761998 -2.07195 0 P 0 
L 1.64433002 -2.07095 1.73803002 -2.07095 0 P 0 
L 1.64398002 -2.06995 1.69251004 -2.06995 0 P 0 
L 1.69583002 -2.06995 1.73843996 -2.06995 0 P 0 
L 1.64363002 -2.06895 1.69168002 -2.06895 0 P 0 
L 1.69671998 -2.06895 1.73883996 -2.06895 0 P 0 
L 1.64328996 -2.06795 1.69136004 -2.06795 0 P 0 
L 1.69708996 -2.06795 1.73925 -2.06795 0 P 0 
L 1.64293996 -2.06695 1.69108002 -2.06695 0 P 0 
L 1.69738002 -2.06695 1.73965 -2.06695 0 P 0 
L 1.64258996 -2.06595 1.6908 -2.06595 0 P 0 
L 1.69768002 -2.06595 1.74006004 -2.06595 0 P 0 
L 1.64223996 -2.06495 1.69051998 -2.06495 0 P 0 
L 1.69796998 -2.06495 1.74046004 -2.06495 0 P 0 
L 1.6419 -2.06395 1.69023002 -2.06395 0 P 0 
L 1.69826998 -2.06395 1.74086004 -2.06395 0 P 0 
L 1.64155 -2.06295 1.68996004 -2.06295 0 P 0 
L 1.69856004 -2.06295 1.74126998 -2.06295 0 P 0 
L 1.6412 -2.06195 1.68966998 -2.06195 0 P 0 
L 1.69886004 -2.06195 1.74168002 -2.06195 0 P 0 
L 1.64085 -2.06095 1.68938996 -2.06095 0 P 0 
L 1.69915 -2.06095 1.74208002 -2.06095 0 P 0 
L 1.6405 -2.05995 1.68911004 -2.05995 0 P 0 
L 1.69945 -2.05995 1.74248002 -2.05995 0 P 0 
L 1.64016004 -2.05895 1.68883002 -2.05895 0 P 0 
L 1.69973996 -2.05895 1.74288996 -2.05895 0 P 0 
L 1.63981004 -2.05795 1.68855 -2.05795 0 P 0 
L 1.70003996 -2.05795 1.74328996 -2.05795 0 P 0 
L 1.63946004 -2.05695 1.68826998 -2.05695 0 P 0 
L 1.70033002 -2.05695 1.7437 -2.05695 0 P 0 
L 1.63911004 -2.05595 1.68798996 -2.05595 0 P 0 
L 1.70063002 -2.05595 1.7441 -2.05595 0 P 0 
L 1.63876998 -2.05495 1.68771004 -2.05495 0 P 0 
L 1.70091998 -2.05495 1.74451004 -2.05495 0 P 0 
L 1.63841998 -2.05395 1.68741998 -2.05395 0 P 0 
L 1.70121998 -2.05395 1.74491004 -2.05395 0 P 0 
L 1.63806998 -2.05295 1.68713996 -2.05295 0 P 0 
L 1.70151004 -2.05295 1.74531004 -2.05295 0 P 0 
L 1.63771998 -2.05195 1.68686004 -2.05195 0 P 0 
L 1.70181004 -2.05195 1.74571998 -2.05195 0 P 0 
L 1.63738002 -2.05095 1.68658002 -2.05095 0 P 0 
L 1.7021 -2.05095 1.74611998 -2.05095 0 P 0 
L 1.63703002 -2.04995 1.6863 -2.04995 0 P 0 
L 1.7024 -2.04995 1.74653002 -2.04995 0 P 0 
L 1.63668002 -2.04895 1.68601998 -2.04895 0 P 0 
L 1.70268996 -2.04895 1.74693002 -2.04895 0 P 0 
L 1.63633002 -2.04795 1.68573996 -2.04795 0 P 0 
L 1.70298996 -2.04795 1.74733002 -2.04795 0 P 0 
L 1.63598002 -2.04695 1.68546004 -2.04695 0 P 0 
L 1.70328002 -2.04695 1.74773996 -2.04695 0 P 0 
L 1.63563996 -2.04595 1.68518002 -2.04595 0 P 0 
L 1.70358002 -2.04595 1.74813996 -2.04595 0 P 0 
L 1.63528996 -2.04495 1.6849 -2.04495 0 P 0 
L 1.70386998 -2.04495 1.74855 -2.04495 0 P 0 
L 1.63493996 -2.04395 1.68461004 -2.04395 0 P 0 
L 1.70416998 -2.04395 1.74895 -2.04395 0 P 0 
L 1.63458996 -2.04295 1.68433002 -2.04295 0 P 0 
L 1.70446004 -2.04295 1.74936004 -2.04295 0 P 0 
L 1.63425 -2.04195 1.68405 -2.04195 0 P 0 
L 1.70475 -2.04195 1.74976004 -2.04195 0 P 0 
L 1.6339 -2.04095 1.68376998 -2.04095 0 P 0 
L 1.70503002 -2.04095 1.75016004 -2.04095 0 P 0 
L 1.63355 -2.03995 1.68348996 -2.03995 0 P 0 
L 1.70531998 -2.03995 1.75056998 -2.03995 0 P 0 
L 1.6332 -2.03895 1.68321004 -2.03895 0 P 0 
L 1.7056 -2.03895 1.75096998 -2.03895 0 P 0 
L 1.63286004 -2.03795 1.68293002 -2.03795 0 P 0 
L 1.70588996 -2.03795 1.75138002 -2.03795 0 P 0 
L 1.63251004 -2.03695 1.68266004 -2.03695 0 P 0 
L 1.70618002 -2.03695 1.75178002 -2.03695 0 P 0 
L 1.63216004 -2.03595 1.68238002 -2.03595 0 P 0 
L 1.70646998 -2.03595 1.75218996 -2.03595 0 P 0 
L 1.63181004 -2.03495 1.6821 -2.03495 0 P 0 
L 1.70675 -2.03495 1.75258996 -2.03495 0 P 0 
L 1.63146998 -2.03395 1.68183002 -2.03395 0 P 0 
L 1.70703996 -2.03395 1.75298996 -2.03395 0 P 0 
L 1.63111998 -2.03295 1.68155 -2.03295 0 P 0 
L 1.70733002 -2.03295 1.7534 -2.03295 0 P 0 
L 1.63076998 -2.03195 1.68126998 -2.03195 0 P 0 
L 1.70761004 -2.03195 1.75381004 -2.03195 0 P 0 
L 1.63041998 -2.03095 1.68098996 -2.03095 0 P 0 
L 1.7079 -2.03095 1.75421004 -2.03095 0 P 0 
L 1.63006998 -2.02995 1.68071004 -2.02995 0 P 0 
L 1.70818996 -2.02995 1.75461004 -2.02995 0 P 0 
L 1.62973002 -2.02895 1.68043996 -2.02895 0 P 0 
L 1.70846998 -2.02895 1.75501998 -2.02895 0 P 0 
L 1.62938002 -2.02795 1.68016004 -2.02795 0 P 0 
L 1.70876004 -2.02795 1.75541998 -2.02795 0 P 0 
L 1.62903002 -2.02695 1.67988002 -2.02695 0 P 0 
L 1.70905 -2.02695 1.75583002 -2.02695 0 P 0 
L 1.62868002 -2.02595 1.6796 -2.02595 0 P 0 
L 1.70933996 -2.02595 1.75623002 -2.02595 0 P 0 
L 1.62831004 -2.02495 1.67933002 -2.02495 0 P 0 
L 1.70961998 -2.02495 1.75663996 -2.02495 0 P 0 
L 1.62793996 -2.02395 1.67905 -2.02395 0 P 0 
L 1.70991004 -2.02395 1.75703996 -2.02395 0 P 0 
L 1.62756998 -2.02295 1.67876998 -2.02295 0 P 0 
L 1.7102 -2.02295 1.75743996 -2.02295 0 P 0 
L 1.6272 -2.02195 1.6785 -2.02195 0 P 0 
L 1.71048002 -2.02195 1.75785 -2.02195 0 P 0 
L 1.62683002 -2.02095 1.67821998 -2.02095 0 P 0 
L 1.71076004 -2.02095 1.75825 -2.02095 0 P 0 
L 1.62646998 -2.01995 1.67793996 -2.01995 0 P 0 
L 1.71101004 -2.01995 1.75866004 -2.01995 0 P 0 
L 1.6261 -2.01895 1.67766004 -2.01895 0 P 0 
L 1.71126998 -2.01895 1.75906004 -2.01895 0 P 0 
L 1.62573002 -2.01795 1.67738996 -2.01795 0 P 0 
L 1.71151998 -2.01795 1.75946998 -2.01795 0 P 0 
L 1.62536004 -2.01695 1.67711004 -2.01695 0 P 0 
L 1.71176998 -2.01695 1.75986998 -2.01695 0 P 0 
L 1.62498996 -2.01595 1.67683002 -2.01595 0 P 0 
L 1.71203002 -2.01595 1.76026998 -2.01595 0 P 0 
L 1.62461998 -2.01495 1.67656004 -2.01495 0 P 0 
L 1.71228002 -2.01495 1.76068002 -2.01495 0 P 0 
L 1.62425 -2.01395 1.67628002 -2.01395 0 P 0 
L 1.71253996 -2.01395 1.76108002 -2.01395 0 P 0 
L 1.62388002 -2.01295 1.67601998 -2.01295 0 P 0 
L 1.71278996 -2.01295 1.76148996 -2.01295 0 P 0 
L 1.62351004 -2.01195 1.67576998 -2.01195 0 P 0 
L 1.71305 -2.01195 1.76188996 -2.01195 0 P 0 
L 1.62313996 -2.01095 1.67551998 -2.01095 0 P 0 
L 1.7133 -2.01095 1.76228996 -2.01095 0 P 0 
L 1.62276998 -2.00995 1.67528002 -2.00995 0 P 0 
L 1.71355 -2.00995 1.7627 -2.00995 0 P 0 
L 1.6224 -2.00895 1.67503002 -2.00895 0 P 0 
L 1.71381004 -2.00895 1.7631 -2.00895 0 P 0 
L 1.62203002 -2.00795 1.67478996 -2.00795 0 P 0 
L 1.71406004 -2.00795 1.76351004 -2.00795 0 P 0 
L 1.62166004 -2.00695 1.67453996 -2.00695 0 P 0 
L 1.71431004 -2.00695 1.76391004 -2.00695 0 P 0 
L 1.62128996 -2.00595 1.67428996 -2.00595 0 P 0 
L 1.71453996 -2.00595 1.76431998 -2.00595 0 P 0 
L 1.62091004 -2.00495 1.67405 -2.00495 0 P 0 
L 1.71476998 -2.00495 1.76471998 -2.00495 0 P 0 
L 1.62051998 -2.00395 1.6738 -2.00395 0 P 0 
L 1.715 -2.00395 1.76511998 -2.00395 0 P 0 
L 1.62013002 -2.00295 1.67355 -2.00295 0 P 0 
L 1.71523002 -2.00295 1.76553002 -2.00295 0 P 0 
L 1.61973996 -2.00195 1.67331004 -2.00195 0 P 0 
L 1.71546004 -2.00195 1.76593996 -2.00195 0 P 0 
L 1.61935 -2.00095 1.67306004 -2.00095 0 P 0 
L 1.71568996 -2.00095 1.76633996 -2.00095 0 P 0 
L 1.61896004 -1.99995 1.67283996 -1.99995 0 P 0 
L 1.71591998 -1.99995 1.76673996 -1.99995 0 P 0 
L 1.61856998 -1.99895 1.67261998 -1.99895 0 P 0 
L 1.71613996 -1.99895 1.76715 -1.99895 0 P 0 
L 1.71638002 -1.99795 1.76755 -1.99795 0 P 0 
L 1.7166 -1.99695 1.76796004 -1.99695 0 P 0 
L 1.71683002 -1.99595 1.76836004 -1.99595 0 P 0 
L 1.71866998 -1.99495 1.76876998 -1.99495 0 P 0 
L 1.78213996 -2.04823996 1.84641998 -2.04823996 0 P 0 
L 1.78138002 -2.04723996 1.84498996 -2.04723996 0 P 0 
L 1.78071004 -2.04623996 1.84356004 -2.04623996 0 P 0 
L 1.7801 -2.04523996 1.84213996 -2.04523996 0 P 0 
L 1.77956004 -2.04423996 1.84071004 -2.04423996 0 P 0 
L 1.77908996 -2.04323996 1.83928002 -2.04323996 0 P 0 
L 1.77866004 -2.04223996 1.83786004 -2.04223996 0 P 0 
L 1.77831004 -2.04123996 1.83658996 -2.04123996 0 P 0 
L 1.77796004 -2.04023996 1.83536004 -2.04023996 0 P 0 
L 1.77761004 -2.03923996 1.83428002 -2.03923996 0 P 0 
L 1.77733996 -2.03823996 1.83321998 -2.03823996 0 P 0 
L 1.77706998 -2.03723996 1.83236998 -2.03723996 0 P 0 
L 1.7768 -2.03623996 1.83171004 -2.03623996 0 P 0 
L 1.7766 -2.03523996 1.83121004 -2.03523996 0 P 0 
L 1.77641004 -2.03423996 1.83085 -2.03423996 0 P 0 
L 1.77621004 -2.03323996 1.83071004 -2.03323996 0 P 0 
L 1.77608002 -2.03223996 1.83076998 -2.03223996 0 P 0 
L 1.77596004 -2.03123996 1.83106004 -2.03123996 0 P 0 
L 1.77583996 -2.03023996 1.83158996 -2.03023996 0 P 0 
L 1.77576004 -2.02923996 1.83238002 -2.02923996 0 P 0 
L 1.7757 -2.02823996 1.83356998 -2.02823996 0 P 0 
L 1.7757 -2.02723996 1.83591998 -2.02723996 0 P 0 
L 1.77571998 -2.02623996 1.87495 -2.02623996 0 P 0 
L 1.7758 -2.02523996 1.87485 -2.02523996 0 P 0 
L 1.77588996 -2.02423996 1.87475 -2.02423996 0 P 0 
L 1.77605 -2.02323996 1.87465 -2.02323996 0 P 0 
L 1.77621004 -2.02223996 1.87455 -2.02223996 0 P 0 
L 1.7764 -2.02123996 1.87445 -2.02123996 0 P 0 
L 1.77665 -2.02023996 1.87433996 -2.02023996 0 P 0 
L 1.7769 -2.01923996 1.87425 -2.01923996 0 P 0 
L 1.7772 -2.01823996 1.87413996 -2.01823996 0 P 0 
L 1.77753002 -2.01723996 1.87405 -2.01723996 0 P 0 
L 1.77786004 -2.01623996 1.87393996 -2.01623996 0 P 0 
L 1.77823002 -2.01523996 1.87383996 -2.01523996 0 P 0 
L 1.77863996 -2.01423996 1.87373996 -2.01423996 0 P 0 
L 1.77903996 -2.01323996 1.87363996 -2.01323996 0 P 0 
L 1.7795 -2.01223996 1.87353996 -2.01223996 0 P 0 
L 1.77998996 -2.01123996 1.87343996 -2.01123996 0 P 0 
L 1.78046998 -2.01023996 1.87333002 -2.01023996 0 P 0 
L 1.78103996 -2.00923996 1.87323002 -2.00923996 0 P 0 
L 1.78161004 -2.00823996 1.87311998 -2.00823996 0 P 0 
L 1.78221004 -2.00723996 1.87301998 -2.00723996 0 P 0 
L 1.78288002 -2.00623996 1.87291998 -2.00623996 0 P 0 
L 1.64213996 -2.14795 1.70566004 -2.14795 0 P 0 
L 1.64518996 -2.14695 1.7062 -2.14695 0 P 0 
L 1.64728996 -2.14595 1.70673996 -2.14595 0 P 0 
L 1.64906998 -2.14495 1.70728002 -2.14495 0 P 0 
L 1.65058002 -2.14395 1.70783002 -2.14395 0 P 0 
L 1.6519 -2.14295 1.70836998 -2.14295 0 P 0 
L 1.65311998 -2.14195 1.70881998 -2.14195 0 P 0 
L 1.65416998 -2.14095 1.70926998 -2.14095 0 P 0 
L 1.65508996 -2.13995 1.70973002 -2.13995 0 P 0 
L 1.65588002 -2.13895 1.71018002 -2.13895 0 P 0 
L 1.65658002 -2.13795 1.71063002 -2.13795 0 P 0 
L 1.65726998 -2.13695 1.71108996 -2.13695 0 P 0 
L 1.65791998 -2.13595 1.71153996 -2.13595 0 P 0 
L 1.65853002 -2.13495 1.71198996 -2.13495 0 P 0 
L 1.65913002 -2.13395 1.71245 -2.13395 0 P 0 
L 1.65968002 -2.13295 1.7129 -2.13295 0 P 0 
L 1.66021998 -2.13195 1.71331004 -2.13195 0 P 0 
L 1.66071998 -2.13095 1.71371998 -2.13095 0 P 0 
L 1.66121004 -2.12995 1.71411998 -2.12995 0 P 0 
L 1.66166998 -2.12895 1.71453002 -2.12895 0 P 0 
L 1.66201004 -2.12795 1.71493996 -2.12795 0 P 0 
L 1.66223996 -2.12695 1.71533996 -2.12695 0 P 0 
L 1.66235 -2.12595 1.71575 -2.12595 0 P 0 
L 1.66236004 -2.12495 1.71615 -2.12495 0 P 0 
L 1.66228002 -2.12395 1.71656004 -2.12395 0 P 0 
L 1.66211998 -2.12295 1.71696004 -2.12295 0 P 0 
L 1.66188002 -2.12195 1.71736004 -2.12195 0 P 0 
L 1.66156004 -2.12095 1.71776998 -2.12095 0 P 0 
L 1.66121004 -2.11995 1.71818002 -2.11995 0 P 0 
L 1.66086998 -2.11895 1.71858002 -2.11895 0 P 0 
L 1.66053002 -2.11795 1.71898996 -2.11795 0 P 0 
L 1.66018002 -2.11695 1.71938996 -2.11695 0 P 0 
L 1.65983996 -2.11595 1.7198 -2.11595 0 P 0 
L 1.65948996 -2.11495 1.7202 -2.11495 0 P 0 
L 1.65913996 -2.11395 1.72061004 -2.11395 0 P 0 
L 1.6588 -2.11295 1.72101004 -2.11295 0 P 0 
L 1.65846004 -2.11195 1.72141998 -2.11195 0 P 0 
L 1.65811004 -2.11095 1.72181998 -2.11095 0 P 0 
L 1.65776998 -2.10995 1.72223002 -2.10995 0 P 0 
L 1.65741998 -2.10895 1.72263002 -2.10895 0 P 0 
L 1.65708002 -2.10795 1.72303996 -2.10795 0 P 0 
L 1.65673002 -2.10695 1.72343996 -2.10695 0 P 0 
L 1.65638996 -2.10595 1.72385 -2.10595 0 P 0 
L 1.65605 -2.10495 1.72425 -2.10495 0 P 0 
L 1.6557 -2.10395 1.72466004 -2.10395 0 P 0 
L 1.65536004 -2.10295 1.72506998 -2.10295 0 P 0 
L 1.65501004 -2.10195 1.72546998 -2.10195 0 P 0 
L 1.65466998 -2.10095 1.72588002 -2.10095 0 P 0 
L 1.65431998 -2.09995 1.72628002 -2.09995 0 P 0 
L 1.65398002 -2.09895 1.72668996 -2.09895 0 P 0 
L 1.65363002 -2.09795 1.72708996 -2.09795 0 P 0 
L 1.65328996 -2.09695 1.72748996 -2.09695 0 P 0 
L 1.65293996 -2.09595 1.7279 -2.09595 0 P 0 
L 1.6526 -2.09495 1.72831004 -2.09495 0 P 0 
L 1.65225 -2.09395 1.72871004 -2.09395 0 P 0 
L 1.65191004 -2.09295 1.72911998 -2.09295 0 P 0 
L 1.65156998 -2.09195 1.72951998 -2.09195 0 P 0 
L 1.65121998 -2.09095 1.72993002 -2.09095 0 P 0 
L 1.65088002 -2.08995 1.73033002 -2.08995 0 P 0 
L 1.65053002 -2.08895 1.73073996 -2.08895 0 P 0 
L 1.65018996 -2.08795 1.73113996 -2.08795 0 P 0 
L 1.64983996 -2.08695 1.73155 -2.08695 0 P 0 
L 1.6495 -2.08595 1.73195 -2.08595 0 P 0 
L 1.64915 -2.08495 1.73236004 -2.08495 0 P 0 
L 1.64881004 -2.08395 1.73276004 -2.08395 0 P 0 
L 1.81726998 -1.98915 1.81196004 -1.9899 0 P 0 
L 1.81196004 -1.9899 1.80668996 -1.99096998 0 P 0 
L 1.80668996 -1.99096998 1.8019 -1.99226004 0 P 0 
L 1.8019 -1.99226004 1.79718996 -1.99391004 0 P 0 
L 1.79718996 -1.99391004 1.79316004 -1.99568002 0 P 0 
L 1.79316004 -1.99568002 1.78926998 -1.99778002 0 P 0 
L 1.78926998 -1.99778002 1.78771004 -1.99878002 0 P 0 
L 1.78771004 -1.99878002 1.78623002 -1.99988002 0 P 0 
L 1.78623002 -1.99988002 1.78481004 -2.00108002 0 P 0 
L 1.78481004 -2.00108002 1.78346998 -2.00238996 0 P 0 
L 1.78346998 -2.00238996 1.78228996 -2.00371998 0 P 0 
L 1.78228996 -2.00371998 1.78121004 -2.00513002 0 P 0 
L 1.78121004 -2.00513002 1.78023002 -2.00661004 0 P 0 
L 1.78023002 -2.00661004 1.77868002 -2.00933996 0 P 0 
L 1.77868002 -2.00933996 1.77731998 -2.01216998 0 P 0 
L 1.77731998 -2.01216998 1.77611004 -2.01516004 0 P 0 
L 1.77611004 -2.01516004 1.77508996 -2.01823002 0 P 0 
L 1.77508996 -2.01823002 1.77436998 -2.02111004 0 P 0 
L 1.77436998 -2.02111004 1.77388996 -2.02406004 0 P 0 
L 1.77388996 -2.02406004 1.77371998 -2.02603996 0 P 0 
L 1.77371998 -2.02603996 1.77368996 -2.02801998 0 P 0 
L 1.77368996 -2.02801998 1.7738 -2.03001998 0 P 0 
L 1.7738 -2.03001998 1.7742 -2.03338996 0 P 0 
L 1.7742 -2.03338996 1.77485 -2.03671004 0 P 0 
L 1.77485 -2.03671004 1.77573002 -2.03993996 0 P 0 
L 1.77573002 -2.03993996 1.77683996 -2.04308002 0 P 0 
L 1.77683996 -2.04308002 1.7776 -2.04481998 0 P 0 
L 1.7776 -2.04481998 1.7785 -2.04648996 0 P 0 
L 1.7785 -2.04648996 1.77953002 -2.04808996 0 P 0 
L 1.77953002 -2.04808996 1.78061004 -2.04953996 0 P 0 
L 1.78061004 -2.04953996 1.78181004 -2.05091004 0 P 0 
L 1.78181004 -2.05091004 1.78311004 -2.05218996 0 P 0 
L 1.78311004 -2.05218996 1.78988996 -2.05801998 0 P 0 
L 1.78988996 -2.05801998 1.79883996 -2.06491004 0 P 0 
L 1.79883996 -2.06491004 1.80976998 -2.07261004 0 P 0 
L 1.80976998 -2.07261004 1.81753002 -2.07823002 0 P 0 
L 1.81753002 -2.07823002 1.81896998 -2.07943002 0 P 0 
L 1.81896998 -2.07943002 1.82033002 -2.08073002 0 P 0 
L 1.82033002 -2.08073002 1.82156998 -2.08213996 0 P 0 
L 1.82156998 -2.08213996 1.82186004 -2.08251004 0 P 0 
L 1.82186004 -2.08251004 1.82211004 -2.0829 0 P 0 
L 1.82211004 -2.0829 1.82233002 -2.08331004 0 P 0 
L 1.82233002 -2.08331004 1.82253002 -2.08373996 0 P 0 
L 1.82253002 -2.08373996 1.82268002 -2.08418002 0 P 0 
L 1.82268002 -2.08418002 1.82281004 -2.08463002 0 P 0 
L 1.82281004 -2.08463002 1.8229 -2.0851 0 P 0 
L 1.8229 -2.0851 1.82293002 -2.08533996 0 P 0 
L 1.82293002 -2.08533996 1.82293996 -2.08558996 0 P 0 
L 1.82293996 -2.08558996 1.82291998 -2.08583996 0 P 0 
L 1.82291998 -2.08583996 1.82288002 -2.08608002 0 P 0 
L 1.82288002 -2.08608002 1.82283002 -2.08631998 0 P 0 
L 1.82283002 -2.08631998 1.82275 -2.08656004 0 P 0 
L 1.82275 -2.08656004 1.82265 -2.08678996 0 P 0 
L 1.82265 -2.08678996 1.82253996 -2.087 0 P 0 
L 1.82253996 -2.087 1.8224 -2.08721004 0 P 0 
L 1.8224 -2.08721004 1.82225 -2.08741004 0 P 0 
L 1.82225 -2.08741004 1.82208996 -2.08758996 0 P 0 
L 1.82208996 -2.08758996 1.8216 -2.08803996 0 P 0 
L 1.8216 -2.08803996 1.82106998 -2.08845 0 P 0 
L 1.82106998 -2.08845 1.82051004 -2.08881004 0 P 0 
L 1.82051004 -2.08881004 1.81991998 -2.08911998 0 P 0 
L 1.81991998 -2.08911998 1.81931004 -2.08936998 0 P 0 
L 1.81931004 -2.08936998 1.81868002 -2.08958002 0 P 0 
L 1.81868002 -2.08958002 1.81803002 -2.08973002 0 P 0 
L 1.81803002 -2.08973002 1.81736004 -2.08981998 0 P 0 
L 1.81736004 -2.08981998 1.81293002 -2.09001998 0 P 0 
L 1.81293002 -2.09001998 1.80846998 -2.08986004 0 P 0 
L 1.80846998 -2.08986004 1.80256998 -2.08923002 0 P 0 
L 1.80256998 -2.08923002 1.79668002 -2.08818996 0 P 0 
L 1.79668002 -2.08818996 1.78223002 -2.08458002 0 P 0 
L 1.78223002 -2.08458002 1.77788996 -2.08338002 0 P 0 
L 1.77788996 -2.08338002 1.77415 -2.08246004 0 P 0 
L 1.77415 -2.08246004 1.77095 -2.08175 0 P 0 
L 1.77095 -2.08175 1.7709 -2.08173996 0 P 0 
L 1.7709 -2.08173996 1.77076998 -2.08173996 0 P 0 
L 1.77076998 -2.08173996 1.77068996 -2.08176004 0 P 0 
L 1.77068996 -2.08176004 1.77053002 -2.08183996 0 P 0 
L 1.77053002 -2.08183996 1.77043002 -2.08193996 0 P 0 
L 1.77043002 -2.08193996 1.77036998 -2.08201998 0 P 0 
L 1.77036998 -2.08201998 1.77031998 -2.08211998 0 P 0 
L 1.77031998 -2.08211998 1.7703 -2.08216998 0 P 0 
L 1.7703 -2.08216998 1.77028996 -2.08223002 0 P 0 
L 1.77028996 -2.08223002 1.77028002 -2.08228002 0 P 0 
L 1.77028002 -2.08228002 1.77028002 -2.08238996 0 P 0 
L 1.77028002 -2.08238996 1.77056998 -2.08838996 0 P 0 
L 1.77056998 -2.08838996 1.77096004 -2.09526004 0 P 0 
L 1.77096004 -2.09526004 1.77153996 -2.1033 0 P 0 
L 1.77153996 -2.1033 1.77236004 -2.11291004 0 P 0 
L 1.77236004 -2.11291004 1.77311004 -2.1194 0 P 0 
L 1.77311004 -2.1194 1.77383002 -2.12398002 0 P 0 
L 1.77383002 -2.12398002 1.77386004 -2.12411004 0 P 0 
L 1.77386004 -2.12411004 1.7739 -2.12423002 0 P 0 
L 1.7739 -2.12423002 1.77395 -2.12436004 0 P 0 
L 1.77395 -2.12436004 1.77401004 -2.12448002 0 P 0 
L 1.77401004 -2.12448002 1.77408002 -2.12458996 0 P 0 
L 1.77408002 -2.12458996 1.77416004 -2.1247 0 P 0 
L 1.77416004 -2.1247 1.77425 -2.1248 0 P 0 
L 1.77425 -2.1248 1.77435 -2.12488996 0 P 0 
L 1.77435 -2.12488996 1.77445 -2.12496998 0 P 0 
L 1.77445 -2.12496998 1.77456998 -2.12505 0 P 0 
L 1.77456998 -2.12505 1.77571004 -2.12568996 0 P 0 
L 1.77571004 -2.12568996 1.7769 -2.12623996 0 P 0 
L 1.7769 -2.12623996 1.77813002 -2.12668996 0 P 0 
L 1.77813002 -2.12668996 1.7794 -2.12703996 0 P 0 
L 1.7794 -2.12703996 1.78068996 -2.12728996 0 P 0 
L 1.78068996 -2.12728996 1.79791998 -2.12951004 0 P 0 
L 1.79791998 -2.12951004 1.81536004 -2.13106004 0 P 0 
L 1.81536004 -2.13106004 1.82125 -2.13123996 0 P 0 
L 1.82125 -2.13123996 1.82716004 -2.13098996 0 P 0 
L 1.82716004 -2.13098996 1.83583996 -2.12998002 0 P 0 
L 1.83583996 -2.12998002 1.84445 -2.12836004 0 P 0 
L 1.84445 -2.12836004 1.84911998 -2.12711004 0 P 0 
L 1.84911998 -2.12711004 1.85366004 -2.12548002 0 P 0 
L 1.85366004 -2.12548002 1.85806998 -2.12348002 0 P 0 
L 1.85806998 -2.12348002 1.86078996 -2.12196998 0 P 0 
L 1.86078996 -2.12196998 1.8634 -2.12026998 0 P 0 
L 1.8634 -2.12026998 1.86586998 -2.11836998 0 P 0 
L 1.86586998 -2.11836998 1.86821004 -2.11628002 0 P 0 
L 1.86821004 -2.11628002 1.87026004 -2.11413002 0 P 0 
L 1.87026004 -2.11413002 1.8721 -2.11181998 0 P 0 
L 1.8721 -2.11181998 1.87375 -2.10936004 0 P 0 
L 1.87375 -2.10936004 1.87516998 -2.10673996 0 P 0 
L 1.87516998 -2.10673996 1.87605 -2.10483996 0 P 0 
L 1.87605 -2.10483996 1.87683996 -2.10291004 0 P 0 
L 1.87683996 -2.10291004 1.8772 -2.10188002 0 P 0 
L 1.8772 -2.10188002 1.87748996 -2.10083002 0 P 0 
L 1.87748996 -2.10083002 1.87771004 -2.09976998 0 P 0 
L 1.87771004 -2.09976998 1.87798002 -2.09788996 0 P 0 
L 1.87798002 -2.09788996 1.87811998 -2.09601004 0 P 0 
L 1.87811998 -2.09601004 1.87821004 -2.08966998 0 P 0 
L 1.87821004 -2.08966998 1.8781 -2.08353996 0 P 0 
L 1.8781 -2.08353996 1.87798002 -2.08166004 0 P 0 
L 1.87798002 -2.08166004 1.87773002 -2.07976998 0 P 0 
L 1.87773002 -2.07976998 1.87753002 -2.07873996 0 P 0 
L 1.87753002 -2.07873996 1.87726998 -2.07773996 0 P 0 
L 1.87726998 -2.07773996 1.87695 -2.07673996 0 P 0 
L 1.87695 -2.07673996 1.87628996 -2.07505 0 P 0 
L 1.87628996 -2.07505 1.87553002 -2.07338002 0 P 0 
L 1.87553002 -2.07338002 1.87441004 -2.07133996 0 P 0 
L 1.87441004 -2.07133996 1.87313996 -2.06938002 0 P 0 
L 1.87313996 -2.06938002 1.87171004 -2.06751004 0 P 0 
L 1.87171004 -2.06751004 1.8688 -2.06416004 0 P 0 
L 1.8688 -2.06416004 1.86566998 -2.06095 0 P 0 
L 1.86566998 -2.06095 1.86181998 -2.05741998 0 P 0 
L 1.86181998 -2.05741998 1.85778002 -2.05406998 0 P 0 
L 1.85778002 -2.05406998 1.84833996 -2.04715 0 P 0 
L 1.84833996 -2.04715 1.83913996 -2.0407 0 P 0 
L 1.83913996 -2.0407 1.83686004 -2.0389 0 P 0 
L 1.83686004 -2.0389 1.83471998 -2.03691998 0 P 0 
L 1.83471998 -2.03691998 1.83428002 -2.03643002 0 P 0 
L 1.83428002 -2.03643002 1.83386998 -2.0359 0 P 0 
L 1.83386998 -2.0359 1.83351004 -2.03535 0 P 0 
L 1.83351004 -2.03535 1.83318996 -2.03476004 0 P 0 
L 1.83318996 -2.03476004 1.83291998 -2.03415 0 P 0 
L 1.83291998 -2.03415 1.83283996 -2.03393996 0 P 0 
L 1.83283996 -2.03393996 1.83278002 -2.03371004 0 P 0 
L 1.83278002 -2.03371004 1.83273002 -2.03348996 0 P 0 
L 1.83273002 -2.03348996 1.83271004 -2.03326004 0 P 0 
L 1.83271004 -2.03326004 1.8327 -2.03303002 0 P 0 
L 1.8327 -2.03303002 1.83271004 -2.0328 0 P 0 
L 1.83271004 -2.0328 1.83275 -2.03258002 0 P 0 
L 1.83275 -2.03258002 1.83278996 -2.03235 0 P 0 
L 1.83278996 -2.03235 1.83286004 -2.03213002 0 P 0 
L 1.83286004 -2.03213002 1.83293996 -2.03191998 0 P 0 
L 1.83293996 -2.03191998 1.83305 -2.03171004 0 P 0 
L 1.83305 -2.03171004 1.83325 -2.03135 0 P 0 
L 1.83325 -2.03135 1.83348996 -2.03101998 0 P 0 
L 1.83348996 -2.03101998 1.83375 -2.03071004 0 P 0 
L 1.83375 -2.03071004 1.83403002 -2.03041004 0 P 0 
L 1.83403002 -2.03041004 1.83433996 -2.03015 0 P 0 
L 1.83433996 -2.03015 1.83466998 -2.02991004 0 P 0 
L 1.83466998 -2.02991004 1.83501998 -2.02968996 0 P 0 
L 1.83501998 -2.02968996 1.83538002 -2.02951004 0 P 0 
L 1.83538002 -2.02951004 1.83576004 -2.02936004 0 P 0 
L 1.83576004 -2.02936004 1.83615 -2.02923996 0 P 0 
L 1.83615 -2.02923996 1.83655 -2.02915 0 P 0 
L 1.83655 -2.02915 1.8392 -2.02873996 0 P 0 
L 1.8392 -2.02873996 1.84188002 -2.0285 0 P 0 
L 1.84188002 -2.0285 1.84458002 -2.02841004 0 P 0 
L 1.84458002 -2.02841004 1.84993996 -2.02858002 0 P 0 
L 1.84993996 -2.02858002 1.85526998 -2.02916004 0 P 0 
L 1.85526998 -2.02916004 1.86155 -2.03023002 0 P 0 
L 1.86155 -2.03023002 1.86778002 -2.03158002 0 P 0 
L 1.86778002 -2.03158002 1.8713 -2.03238996 0 P 0 
L 1.8713 -2.03238996 1.87428996 -2.03303002 0 P 0 
L 1.87428996 -2.03303002 1.8769 -2.03356004 0 P 0 
L 1.8769 -2.03356004 1.87691998 -2.03356998 0 P 0 
L 1.87691998 -2.03356998 1.87696004 -2.03356998 0 P 0 
L 1.87696004 -2.03356998 1.87696998 -2.03356004 0 P 0 
L 1.87696998 -2.03356004 1.87701004 -2.03356004 0 P 0 
L 1.87701004 -2.03356004 1.87703996 -2.03353996 0 P 0 
L 1.87703996 -2.03353996 1.87706004 -2.03353002 0 P 0 
L 1.87706004 -2.03353002 1.87706998 -2.03351998 0 P 0 
L 1.87706998 -2.03351998 1.87708996 -2.03351004 0 P 0 
L 1.87708996 -2.03351004 1.8771 -2.03348996 0 P 0 
L 1.8771 -2.03348996 1.87711004 -2.03348002 0 P 0 
L 1.87711004 -2.03348002 1.87721998 -2.0333 0 P 0 
L 1.87721998 -2.0333 1.87731998 -2.0331 0 P 0 
L 1.87731998 -2.0331 1.8774 -2.0329 0 P 0 
L 1.8774 -2.0329 1.87746004 -2.03268996 0 P 0 
L 1.87746004 -2.03268996 1.87751004 -2.03248002 0 P 0 
L 1.87751004 -2.03248002 1.87753002 -2.03226998 0 P 0 
L 1.87753002 -2.03226998 1.87753996 -2.03205 0 P 0 
L 1.87753996 -2.03205 1.87753002 -2.03183002 0 P 0 
L 1.87753002 -2.03183002 1.87565 -2.01323996 0 P 0 
L 1.87565 -2.01323996 1.87371004 -1.99451998 0 P 0 
L 1.87371004 -1.99451998 1.8737 -1.99438996 0 P 0 
L 1.8737 -1.99438996 1.87366998 -1.99426998 0 P 0 
L 1.87366998 -1.99426998 1.87363002 -1.99415 0 P 0 
L 1.87363002 -1.99415 1.87358002 -1.99403002 0 P 0 
L 1.87358002 -1.99403002 1.87351998 -1.99391004 0 P 0 
L 1.87351998 -1.99391004 1.87346004 -1.9938 0 P 0 
L 1.87346004 -1.9938 1.87338002 -1.9937 0 P 0 
L 1.87338002 -1.9937 1.87328996 -1.9936 0 P 0 
L 1.87328996 -1.9936 1.8732 -1.99351004 0 P 0 
L 1.8732 -1.99351004 1.8731 -1.99343002 0 P 0 
L 1.8731 -1.99343002 1.87298996 -1.99335 0 P 0 
L 1.87298996 -1.99335 1.87248002 -1.99305 0 P 0 
L 1.87248002 -1.99305 1.87193996 -1.99278002 0 P 0 
L 1.87193996 -1.99278002 1.87136998 -1.99256998 0 P 0 
L 1.87136998 -1.99256998 1.87078996 -1.99241004 0 P 0 
L 1.87078996 -1.99241004 1.8702 -1.9923 0 P 0 
L 1.8702 -1.9923 1.85876004 -1.99076004 0 P 0 
L 1.85876004 -1.99076004 1.84691998 -1.98943002 0 P 0 
L 1.84691998 -1.98943002 1.83693002 -1.98876004 0 P 0 
L 1.83693002 -1.98876004 1.8318 -1.98863002 0 P 0 
L 1.8318 -1.98863002 1.82623002 -1.98866998 0 P 0 
L 1.82623002 -1.98866998 1.82106004 -1.98883996 0 P 0 
L 1.82106004 -1.98883996 1.81726998 -1.98915 0 P 0 
L 1.78061004 -2.12523996 1.84838002 -2.12523996 0 P 0 
L 1.77733002 -2.12423996 1.85121004 -2.12423996 0 P 0 
L 1.77573996 -2.12323996 1.85376998 -2.12323996 0 P 0 
L 1.77558002 -2.12223996 1.85596998 -2.12223996 0 P 0 
L 1.77541998 -2.12123996 1.85798996 -2.12123996 0 P 0 
L 1.77526998 -2.12023996 1.85978996 -2.12023996 0 P 0 
L 1.77511004 -2.11923996 1.86131998 -2.11923996 0 P 0 
L 1.77498996 -2.11823996 1.86276004 -2.11823996 0 P 0 
L 1.77486998 -2.11723996 1.86406998 -2.11723996 0 P 0 
L 1.77475 -2.11623996 1.86526004 -2.11623996 0 P 0 
L 1.77463996 -2.11523996 1.86638002 -2.11523996 0 P 0 
L 1.77451998 -2.11423996 1.8674 -2.11423996 0 P 0 
L 1.77441004 -2.11323996 1.86835 -2.11323996 0 P 0 
L 1.77431004 -2.11223996 1.86921004 -2.11223996 0 P 0 
L 1.77421998 -2.11123996 1.87001004 -2.11123996 0 P 0 
L 1.77413996 -2.11023996 1.87075 -2.11023996 0 P 0 
L 1.77405 -2.10923996 1.87141998 -2.10923996 0 P 0 
L 1.77396998 -2.10823996 1.87208002 -2.10823996 0 P 0 
L 1.77388002 -2.10723996 1.87261998 -2.10723996 0 P 0 
L 1.7738 -2.10623996 1.87316998 -2.10623996 0 P 0 
L 1.77371004 -2.10523996 1.87366004 -2.10523996 0 P 0 
L 1.77363002 -2.10423996 1.87411998 -2.10423996 0 P 0 
L 1.77353996 -2.10323996 1.87453996 -2.10323996 0 P 0 
L 1.77346998 -2.10223996 1.87495 -2.10223996 0 P 0 
L 1.7734 -2.10123996 1.8753 -2.10123996 0 P 0 
L 1.77333002 -2.10023996 1.87556998 -2.10023996 0 P 0 
L 1.77325 -2.09923996 1.87576998 -2.09923996 0 P 0 
L 1.77318002 -2.09823996 1.87591998 -2.09823996 0 P 0 
L 1.77311004 -2.09723996 1.87603002 -2.09723996 0 P 0 
L 1.77303996 -2.09623996 1.8761 -2.09623996 0 P 0 
L 1.77296998 -2.09523996 1.87613002 -2.09523996 0 P 0 
L 1.77291004 -2.09423996 1.87613996 -2.09423996 0 P 0 
L 1.77285 -2.09323996 1.87616004 -2.09323996 0 P 0 
L 1.77278996 -2.09223996 1.87616998 -2.09223996 0 P 0 
L 1.77273002 -2.09123996 1.80256998 -2.09123996 0 P 0 
L 1.77268002 -2.09023996 1.7968 -2.09023996 0 P 0 
L 1.77261998 -2.08923996 1.79263002 -2.08923996 0 P 0 
L 1.77256004 -2.08823996 1.78861998 -2.08823996 0 P 0 
L 1.77251004 -2.08723996 1.7846 -2.08723996 0 P 0 
L 1.77246004 -2.08623996 1.7807 -2.08623996 0 P 0 
L 1.77241998 -2.08523996 1.77705 -2.08523996 0 P 0 
L 1.77236998 -2.08423996 1.77293996 -2.08423996 0 P 0 
L 1.62463996 -2.18195 1.65948996 -2.18195 0 P 0 
L 1.61963996 -2.18095 1.66483002 -2.18095 0 P 0 
L 1.61818002 -1.99795 1.6724 -1.99795 0 P 0 
L 1.61778996 -1.99695 1.67218002 -1.99695 0 P 0 
L 1.6174 -1.99595 1.67196004 -1.99595 0 P 0 
L 1.61701004 -1.99495 1.67173996 -1.99495 0 P 0 
L 1.61391998 -2.15695 1.70026004 -2.15695 0 P 0 
L 1.61386004 -2.15595 1.70088002 -2.15595 0 P 0 
L 1.61381004 -2.15495 1.70151004 -2.15495 0 P 0 
L 1.61375 -2.15395 1.70213996 -2.15395 0 P 0 
L 1.6137 -2.15295 1.70276004 -2.15295 0 P 0 
L 1.61365 -2.15195 1.70338996 -2.15195 0 P 0 
L 1.6136 -2.15095 1.70401004 -2.15095 0 P 0 
L 1.61355 -2.14995 1.70456998 -2.14995 0 P 0 
L 1.61348996 -2.14895 1.70511998 -2.14895 0 P 0 
L 1.61343996 -2.14795 1.61738002 -2.14795 0 P 0 
L 1.55341004 -2.08286998 1.60538002 -2.08286998 0 P 0 
L 1.55286004 -2.08186998 1.60526998 -2.08186998 0 P 0 
L 1.5521 -2.08086998 1.6051 -2.08086998 0 P 0 
L 1.55126998 -2.07986998 1.6049 -2.07986998 0 P 0 
L 1.55033996 -2.07886998 1.60463996 -2.07886998 0 P 0 
L 1.54928996 -2.07786998 1.60433002 -2.07786998 0 P 0 
L 1.54806998 -2.07686998 1.60398996 -2.07686998 0 P 0 
L 1.5467 -2.07586998 1.60356998 -2.07586998 0 P 0 
L 1.54531004 -2.07486998 1.6031 -2.07486998 0 P 0 
L 1.54391004 -2.07386998 1.60258996 -2.07386998 0 P 0 
L 1.54251004 -2.07286998 1.60201004 -2.07286998 0 P 0 
L 1.54111998 -2.07186998 1.60138002 -2.07186998 0 P 0 
L 1.53971998 -2.07086998 1.60068002 -2.07086998 0 P 0 
L 1.53833002 -2.06986998 1.59993002 -2.06986998 0 P 0 
L 1.53693002 -2.06886998 1.59908002 -2.06886998 0 P 0 
L 1.53556004 -2.06786998 1.59821004 -2.06786998 0 P 0 
L 1.53418996 -2.06686998 1.59733996 -2.06686998 0 P 0 
L 1.53281998 -2.06586998 1.59646998 -2.06586998 0 P 0 
L 1.53145 -2.06486998 1.5955 -2.06486998 0 P 0 
L 1.53008002 -2.06386998 1.59453002 -2.06386998 0 P 0 
L 1.52871004 -2.06286998 1.59356004 -2.06286998 0 P 0 
L 1.52733996 -2.06186998 1.59253002 -2.06186998 0 P 0 
L 1.52596998 -2.06086998 1.59145 -2.06086998 0 P 0 
L 1.5246 -2.05986998 1.59038002 -2.05986998 0 P 0 
L 1.52323002 -2.05886998 1.5893 -2.05886998 0 P 0 
L 1.52186004 -2.05786998 1.58813996 -2.05786998 0 P 0 
L 1.52053996 -2.05686998 1.58696004 -2.05686998 0 P 0 
L 1.51935 -2.05586998 1.58576998 -2.05586998 0 P 0 
L 1.51816004 -2.05486998 1.58456998 -2.05486998 0 P 0 
L 1.51706998 -2.05386998 1.58321004 -2.05386998 0 P 0 
L 1.51603996 -2.05286998 1.58185 -2.05286998 0 P 0 
L 1.51501998 -2.05186998 1.58048996 -2.05186998 0 P 0 
L 1.51408996 -2.05086998 1.57913002 -2.05086998 0 P 0 
L 1.5132 -2.04986998 1.57776998 -2.04986998 0 P 0 
L 1.51231998 -2.04886998 1.57641998 -2.04886998 0 P 0 
L 1.51151004 -2.04786998 1.57505 -2.04786998 0 P 0 
L 1.51075 -2.04686998 1.57365 -2.04686998 0 P 0 
L 1.51008002 -2.04586998 1.57223002 -2.04586998 0 P 0 
L 1.50945 -2.04486998 1.57081004 -2.04486998 0 P 0 
L 1.50888002 -2.04386998 1.56938996 -2.04386998 0 P 0 
L 1.50836004 -2.04286998 1.56796998 -2.04286998 0 P 0 
L 1.5079 -2.04186998 1.56655 -2.04186998 0 P 0 
L 1.50748002 -2.04086998 1.56518996 -2.04086998 0 P 0 
L 1.50708996 -2.03986998 1.564 -2.03986998 0 P 0 
L 1.50676004 -2.03886998 1.56296998 -2.03886998 0 P 0 
L 1.50641998 -2.03786998 1.56206004 -2.03786998 0 P 0 
L 1.50616998 -2.03686998 1.56125 -2.03686998 0 P 0 
L 1.50591004 -2.03586998 1.56066998 -2.03586998 0 P 0 
L 1.5057 -2.03486998 1.56031998 -2.03486998 0 P 0 
L 1.50551998 -2.03386998 1.56016004 -2.03386998 0 P 0 
L 1.50533996 -2.03286998 1.56016998 -2.03286998 0 P 0 
L 1.50523996 -2.03186998 1.56036004 -2.03186998 0 P 0 
L 1.50513002 -2.03086998 1.56071998 -2.03086998 0 P 0 
L 1.50506998 -2.02986998 1.56131004 -2.02986998 0 P 0 
L 1.50503996 -2.02886998 1.5622 -2.02886998 0 P 0 
L 1.50501004 -2.02786998 1.56355 -2.02786998 0 P 0 
L 1.50501998 -2.02686998 1.5657 -2.02686998 0 P 0 
L 1.50506998 -2.02586998 1.60378996 -2.02586998 0 P 0 
L 1.50511998 -2.02486998 1.60371004 -2.02486998 0 P 0 
L 1.50521004 -2.02386998 1.60363996 -2.02386998 0 P 0 
L 1.50533996 -2.02286998 1.60356998 -2.02286998 0 P 0 
L 1.50546998 -2.02186998 1.6035 -2.02186998 0 P 0 
L 1.50563996 -2.02086998 1.60343002 -2.02086998 0 P 0 
L 1.50585 -2.01986998 1.60336004 -2.01986998 0 P 0 
L 1.50606004 -2.01886998 1.60328996 -2.01886998 0 P 0 
L 1.50633002 -2.01786998 1.60321998 -2.01786998 0 P 0 
L 1.50661998 -2.01686998 1.60315 -2.01686998 0 P 0 
L 1.50691004 -2.01586998 1.60308002 -2.01586998 0 P 0 
L 1.50726998 -2.01486998 1.603 -2.01486998 0 P 0 
L 1.50766004 -2.01386998 1.60293002 -2.01386998 0 P 0 
L 1.50808996 -2.01286998 1.60285 -2.01286998 0 P 0 
L 1.50856998 -2.01186998 1.60278002 -2.01186998 0 P 0 
L 1.50908996 -2.01086998 1.6027 -2.01086998 0 P 0 
L 1.50966004 -2.00986998 1.60261998 -2.00986998 0 P 0 
L 1.51028996 -2.00886998 1.60255 -2.00886998 0 P 0 
L 1.51096998 -2.00786998 1.60246998 -2.00786998 0 P 0 
L 1.51171998 -2.00686998 1.6024 -2.00686998 0 P 0 
L 1.51253996 -2.00586998 1.60233002 -2.00586998 0 P 0 
L 1.51343996 -2.00486998 1.60225 -2.00486998 0 P 0 
L 1.5144 -2.00386998 1.60218002 -2.00386998 0 P 0 
L 1.51551998 -2.00286998 1.6021 -2.00286998 0 P 0 
L 1.51663996 -2.00186998 1.60203002 -2.00186998 0 P 0 
L 1.51795 -2.00086998 1.60195 -2.00086998 0 P 0 
L 1.51928996 -1.99986998 1.60183996 -1.99986998 0 P 0 
L 1.52086998 -1.99886998 1.60173002 -1.99886998 0 P 0 
L 1.52258996 -1.99786998 1.60156998 -1.99786998 0 P 0 
L 1.52451004 -1.99686998 1.60138996 -1.99686998 0 P 0 
L 1.52686998 -1.99586998 1.60106998 -1.99586998 0 P 0 
L 1.52976004 -1.99486998 1.59943996 -1.99486998 0 P 0 
L 1.53283002 -1.99386998 1.59543002 -1.99386998 0 P 0 
L 1.53678996 -1.99286998 1.59003996 -1.99286998 0 P 0 
L 1.54173996 -1.99186998 1.58073996 -1.99186998 0 P 0 
L 1.55036998 -1.99086998 1.56493002 -1.99086998 0 P 0 
L 1.6036 -2.03086998 1.60413996 -2.03086998 0 P 0 
L 1.59891004 -2.02986998 1.60406998 -2.02986998 0 P 0 
L 1.59435 -2.02886998 1.604 -2.02886998 0 P 0 
L 1.58838996 -2.02786998 1.60393002 -2.02786998 0 P 0 
L 1.57981004 -2.02686998 1.60386004 -2.02686998 0 P 0 
L 1.54575 -1.98923996 1.53931998 -1.99021998 0 P 0 
L 1.53931998 -1.99021998 1.53298996 -1.99171998 0 P 0 
L 1.53298996 -1.99171998 1.52678996 -1.99373996 0 P 0 
L 1.52678996 -1.99373996 1.52376998 -1.995 0 P 0 
L 1.52376998 -1.995 1.52086998 -1.99651004 0 P 0 
L 1.52086998 -1.99651004 1.5181 -1.99826004 0 P 0 
L 1.5181 -1.99826004 1.51548002 -2.00023002 0 P 0 
L 1.51548002 -2.00023002 1.51301004 -2.00243002 0 P 0 
L 1.51301004 -2.00243002 1.51128996 -2.00423002 0 P 0 
L 1.51128996 -2.00423002 1.50971998 -2.00616004 0 P 0 
L 1.50971998 -2.00616004 1.50831004 -2.00821004 0 P 0 
L 1.50831004 -2.00821004 1.50706998 -2.01036998 0 P 0 
L 1.50706998 -2.01036998 1.50598996 -2.01261998 0 P 0 
L 1.50598996 -2.01261998 1.50508996 -2.01496998 0 P 0 
L 1.50508996 -2.01496998 1.5042 -2.01801004 0 P 0 
L 1.5042 -2.01801004 1.50355 -2.02111004 0 P 0 
L 1.50355 -2.02111004 1.50313996 -2.02426004 0 P 0 
L 1.50313996 -2.02426004 1.50298996 -2.02743002 0 P 0 
L 1.50298996 -2.02743002 1.50308996 -2.03063002 0 P 0 
L 1.50308996 -2.03063002 1.50338002 -2.03326998 0 P 0 
L 1.50338002 -2.03326998 1.50385 -2.03588002 0 P 0 
L 1.50385 -2.03588002 1.50451004 -2.03845 0 P 0 
L 1.50451004 -2.03845 1.50535 -2.04096998 0 P 0 
L 1.50535 -2.04096998 1.50633002 -2.0433 0 P 0 
L 1.50633002 -2.0433 1.5075 -2.04553002 0 P 0 
L 1.5075 -2.04553002 1.50883996 -2.04766998 0 P 0 
L 1.50883996 -2.04766998 1.51036998 -2.04968996 0 P 0 
L 1.51036998 -2.04968996 1.51323002 -2.05291998 0 P 0 
L 1.51323002 -2.05291998 1.51631998 -2.05593996 0 P 0 
L 1.51631998 -2.05593996 1.51961998 -2.05871004 0 P 0 
L 1.51961998 -2.05871004 1.53591004 -2.0706 0 P 0 
L 1.53591004 -2.0706 1.54668002 -2.07831004 0 P 0 
L 1.54668002 -2.07831004 1.54793996 -2.07933996 0 P 0 
L 1.54793996 -2.07933996 1.54911998 -2.08046998 0 P 0 
L 1.54911998 -2.08046998 1.55021004 -2.08168002 0 P 0 
L 1.55021004 -2.08168002 1.5512 -2.08298996 0 P 0 
L 1.5512 -2.08298996 1.55136004 -2.08323002 0 P 0 
L 1.55136004 -2.08323002 1.5515 -2.08348002 0 P 0 
L 1.5515 -2.08348002 1.55161004 -2.08373996 0 P 0 
L 1.55161004 -2.08373996 1.5517 -2.08401998 0 P 0 
L 1.5517 -2.08401998 1.55176998 -2.0843 0 P 0 
L 1.55176998 -2.0843 1.55181004 -2.08458002 0 P 0 
L 1.55181004 -2.08458002 1.55183002 -2.08486998 0 P 0 
L 1.55183002 -2.08486998 1.55181998 -2.08516004 0 P 0 
L 1.55181998 -2.08516004 1.55178996 -2.08545 0 P 0 
L 1.55178996 -2.08545 1.55173996 -2.08573002 0 P 0 
L 1.55173996 -2.08573002 1.55166004 -2.086 0 P 0 
L 1.55166004 -2.086 1.55156004 -2.08628002 0 P 0 
L 1.55156004 -2.08628002 1.55136998 -2.08666998 0 P 0 
L 1.55136998 -2.08666998 1.55115 -2.08703996 0 P 0 
L 1.55115 -2.08703996 1.5509 -2.08738996 0 P 0 
L 1.5509 -2.08738996 1.55063002 -2.08771998 0 P 0 
L 1.55063002 -2.08771998 1.55033002 -2.08803002 0 P 0 
L 1.55033002 -2.08803002 1.55 -2.08831004 0 P 0 
L 1.55 -2.08831004 1.54966004 -2.08856004 0 P 0 
L 1.54966004 -2.08856004 1.54928996 -2.08878996 0 P 0 
L 1.54928996 -2.08878996 1.5489 -2.08898996 0 P 0 
L 1.5489 -2.08898996 1.54786004 -2.08941004 0 P 0 
L 1.54786004 -2.08941004 1.54678996 -2.08973996 0 P 0 
L 1.54678996 -2.08973996 1.54568002 -2.08998002 0 P 0 
L 1.54568002 -2.08998002 1.54456998 -2.09011998 0 P 0 
L 1.54456998 -2.09011998 1.54343996 -2.09016998 0 P 0 
L 1.54343996 -2.09016998 1.53906998 -2.09003002 0 P 0 
L 1.53906998 -2.09003002 1.53468002 -2.08961998 0 P 0 
L 1.53468002 -2.08961998 1.52908996 -2.08878996 0 P 0 
L 1.52908996 -2.08878996 1.52351004 -2.08766004 0 P 0 
L 1.52351004 -2.08766004 1.51005 -2.08418996 0 P 0 
L 1.51005 -2.08418996 1.50631004 -2.08318002 0 P 0 
L 1.50631004 -2.08318002 1.50308002 -2.08238996 0 P 0 
L 1.50308002 -2.08238996 1.50033996 -2.08183002 0 P 0 
L 1.50033996 -2.08183002 1.5003 -2.08181998 0 P 0 
L 1.5003 -2.08181998 1.50016004 -2.08181998 0 P 0 
L 1.50016004 -2.08181998 1.50011998 -2.08183002 0 P 0 
L 1.50011998 -2.08183002 1.50006998 -2.08183996 0 P 0 
L 1.50006998 -2.08183996 1.50003002 -2.08186004 0 P 0 
L 1.50003002 -2.08186004 1.49998996 -2.08186998 0 P 0 
L 1.49998996 -2.08186998 1.49995 -2.08188996 0 P 0 
L 1.49995 -2.08188996 1.49991004 -2.08191998 0 P 0 
L 1.49991004 -2.08191998 1.49988002 -2.08195 0 P 0 
L 1.49988002 -2.08195 1.49983996 -2.08198002 0 P 0 
L 1.49983996 -2.08198002 1.4997 -2.08213996 0 P 0 
L 1.4997 -2.08213996 1.49956004 -2.08231998 0 P 0 
L 1.49956004 -2.08231998 1.49943996 -2.0825 0 P 0 
L 1.49943996 -2.0825 1.49933996 -2.0827 0 P 0 
L 1.49933996 -2.0827 1.49925 -2.0829 0 P 0 
L 1.49925 -2.0829 1.49918996 -2.08311004 0 P 0 
L 1.49918996 -2.08311004 1.49913996 -2.08333002 0 P 0 
L 1.49913996 -2.08333002 1.49911004 -2.08355 0 P 0 
L 1.49911004 -2.08355 1.4991 -2.08376998 0 P 0 
L 1.4991 -2.08376998 1.49911004 -2.08398996 0 P 0 
L 1.49911004 -2.08398996 1.50071004 -2.10395 0 P 0 
L 1.50071004 -2.10395 1.5024 -2.12403996 0 P 0 
L 1.5024 -2.12403996 1.50241998 -2.12418002 0 P 0 
L 1.50241998 -2.12418002 1.50246004 -2.12431004 0 P 0 
L 1.50246004 -2.12431004 1.50248996 -2.12445 0 P 0 
L 1.50248996 -2.12445 1.50255 -2.12456998 0 P 0 
L 1.50255 -2.12456998 1.50261004 -2.1247 0 P 0 
L 1.50261004 -2.1247 1.50276998 -2.12491998 0 P 0 
L 1.50276998 -2.12491998 1.50286004 -2.12501998 0 P 0 
L 1.50286004 -2.12501998 1.50296998 -2.12511998 0 P 0 
L 1.50296998 -2.12511998 1.50308002 -2.12521004 0 P 0 
L 1.50308002 -2.12521004 1.50318996 -2.12528002 0 P 0 
L 1.50318996 -2.12528002 1.50331998 -2.12535 0 P 0 
L 1.50331998 -2.12535 1.50343996 -2.1254 0 P 0 
L 1.50343996 -2.1254 1.50391998 -2.12556004 0 P 0 
L 1.50391998 -2.12556004 1.5044 -2.12568996 0 P 0 
L 1.5044 -2.12568996 1.50848002 -2.12648996 0 P 0 
L 1.50848002 -2.12648996 1.51328996 -2.12738002 0 P 0 
L 1.51328996 -2.12738002 1.51873996 -2.12833996 0 P 0 
L 1.51873996 -2.12833996 1.52606004 -2.12945 0 P 0 
L 1.52606004 -2.12945 1.53343996 -2.13023002 0 P 0 
L 1.53343996 -2.13023002 1.54886998 -2.13086998 0 P 0 
L 1.54886998 -2.13086998 1.56305 -2.1303 0 P 0 
L 1.56305 -2.1303 1.56666004 -2.12988996 0 P 0 
L 1.56666004 -2.12988996 1.57023002 -2.12926998 0 P 0 
L 1.57023002 -2.12926998 1.5738 -2.12843002 0 P 0 
L 1.5738 -2.12843002 1.57945 -2.12668996 0 P 0 
L 1.57945 -2.12668996 1.58498002 -2.12456998 0 P 0 
L 1.58498002 -2.12456998 1.58793996 -2.12318002 0 P 0 
L 1.58793996 -2.12318002 1.59078996 -2.12156004 0 P 0 
L 1.59078996 -2.12156004 1.59348996 -2.11971998 0 P 0 
L 1.59348996 -2.11971998 1.59525 -2.11833002 0 P 0 
L 1.59525 -2.11833002 1.5969 -2.11681998 0 P 0 
L 1.5969 -2.11681998 1.59846004 -2.11521004 0 P 0 
L 1.59846004 -2.11521004 1.59991004 -2.11348002 0 P 0 
L 1.59991004 -2.11348002 1.60175 -2.11093996 0 P 0 
L 1.60175 -2.11093996 1.60338002 -2.10826998 0 P 0 
L 1.60338002 -2.10826998 1.60481004 -2.10548002 0 P 0 
L 1.60481004 -2.10548002 1.60573002 -2.10321004 0 P 0 
L 1.60573002 -2.10321004 1.60646004 -2.10088002 0 P 0 
L 1.60646004 -2.10088002 1.60698002 -2.09848996 0 P 0 
L 1.60698002 -2.09848996 1.60756004 -2.09421998 0 P 0 
L 1.60756004 -2.09421998 1.6078 -2.08991004 0 P 0 
L 1.6078 -2.08991004 1.60768996 -2.08565 0 P 0 
L 1.60768996 -2.08565 1.60723002 -2.08141998 0 P 0 
L 1.60723002 -2.08141998 1.60691998 -2.07968002 0 P 0 
L 1.60691998 -2.07968002 1.60646998 -2.07796998 0 P 0 
L 1.60646998 -2.07796998 1.60591998 -2.0763 0 P 0 
L 1.60591998 -2.0763 1.60523002 -2.07466998 0 P 0 
L 1.60523002 -2.07466998 1.60411998 -2.07246998 0 P 0 
L 1.60411998 -2.07246998 1.60281004 -2.07038002 0 P 0 
L 1.60281004 -2.07038002 1.60131998 -2.06838996 0 P 0 
L 1.60131998 -2.06838996 1.59803996 -2.06461998 0 P 0 
L 1.59803996 -2.06461998 1.59455 -2.06101998 0 P 0 
L 1.59455 -2.06101998 1.59031998 -2.05708996 0 P 0 
L 1.59031998 -2.05708996 1.58586004 -2.05333996 0 P 0 
L 1.58586004 -2.05333996 1.57588002 -2.04598996 0 P 0 
L 1.57588002 -2.04598996 1.56685 -2.03963996 0 P 0 
L 1.56685 -2.03963996 1.56578002 -2.03878996 0 P 0 
L 1.56578002 -2.03878996 1.56476998 -2.03786004 0 P 0 
L 1.56476998 -2.03786004 1.56383002 -2.03686998 0 P 0 
L 1.56383002 -2.03686998 1.56295 -2.0358 0 P 0 
L 1.56295 -2.0358 1.56276998 -2.03555 0 P 0 
L 1.56276998 -2.03555 1.56261004 -2.03528002 0 P 0 
L 1.56261004 -2.03528002 1.56246998 -2.035 0 P 0 
L 1.56246998 -2.035 1.56236004 -2.03471998 0 P 0 
L 1.56236004 -2.03471998 1.56226998 -2.03441998 0 P 0 
L 1.56226998 -2.03441998 1.5622 -2.03411998 0 P 0 
L 1.5622 -2.03411998 1.56216004 -2.03381998 0 P 0 
L 1.56216004 -2.03381998 1.56213996 -2.03351004 0 P 0 
L 1.56213996 -2.03351004 1.56215 -2.0332 0 P 0 
L 1.56215 -2.0332 1.56218002 -2.03288996 0 P 0 
L 1.56218002 -2.03288996 1.56225 -2.03253996 0 P 0 
L 1.56225 -2.03253996 1.56233996 -2.03221004 0 P 0 
L 1.56233996 -2.03221004 1.56246004 -2.03186998 0 P 0 
L 1.56246004 -2.03186998 1.56261004 -2.03156004 0 P 0 
L 1.56261004 -2.03156004 1.56278996 -2.03125 0 P 0 
L 1.56278996 -2.03125 1.56298002 -2.03096004 0 P 0 
L 1.56298002 -2.03096004 1.56321004 -2.03068996 0 P 0 
L 1.56321004 -2.03068996 1.56345 -2.03043996 0 P 0 
L 1.56345 -2.03043996 1.56371004 -2.0302 0 P 0 
L 1.56371004 -2.0302 1.56416004 -2.02986004 0 P 0 
L 1.56416004 -2.02986004 1.56463002 -2.02955 0 P 0 
L 1.56463002 -2.02955 1.56511998 -2.02928002 0 P 0 
L 1.56511998 -2.02928002 1.56561998 -2.02903002 0 P 0 
L 1.56561998 -2.02903002 1.56611998 -2.02883996 0 P 0 
L 1.56611998 -2.02883996 1.56663996 -2.02866998 0 P 0 
L 1.56663996 -2.02866998 1.56716004 -2.02855 0 P 0 
L 1.56716004 -2.02855 1.5677 -2.02846998 0 P 0 
L 1.5677 -2.02846998 1.56926998 -2.02835 0 P 0 
L 1.56926998 -2.02835 1.57085 -2.02833996 0 P 0 
L 1.57085 -2.02833996 1.57725 -2.02866998 0 P 0 
L 1.57725 -2.02866998 1.58205 -2.02906004 0 P 0 
L 1.58205 -2.02906004 1.58746998 -2.02975 0 P 0 
L 1.58746998 -2.02975 1.59271004 -2.03056998 0 P 0 
L 1.59271004 -2.03056998 1.59681004 -2.03143002 0 P 0 
L 1.59681004 -2.03143002 1.60016004 -2.03221998 0 P 0 
L 1.60016004 -2.03221998 1.60308002 -2.03281004 0 P 0 
L 1.60308002 -2.03281004 1.60553996 -2.03323996 0 P 0 
L 1.60553996 -2.03323996 1.60568996 -2.03323996 0 P 0 
L 1.60568996 -2.03323996 1.60576998 -2.03321998 0 P 0 
L 1.60576998 -2.03321998 1.60586004 -2.03316004 0 P 0 
L 1.60586004 -2.03316004 1.6059 -2.03313996 0 P 0 
L 1.6059 -2.03313996 1.60591998 -2.03311004 0 P 0 
L 1.60591998 -2.03311004 1.60598996 -2.03303996 0 P 0 
L 1.60598996 -2.03303996 1.60605 -2.03296998 0 P 0 
L 1.60605 -2.03296998 1.6061 -2.03288996 0 P 0 
L 1.6061 -2.03288996 1.60618002 -2.03273002 0 P 0 
L 1.60618002 -2.03273002 1.60621004 -2.03263002 0 P 0 
L 1.60621004 -2.03263002 1.60623002 -2.03253996 0 P 0 
L 1.60623002 -2.03253996 1.60625 -2.03236004 0 P 0 
L 1.60625 -2.03236004 1.60623996 -2.03226004 0 P 0 
L 1.60623996 -2.03226004 1.60508002 -2.01578002 0 P 0 
L 1.60508002 -2.01578002 1.60393996 -2.00068002 0 P 0 
L 1.60393996 -2.00068002 1.60368002 -1.99833996 0 P 0 
L 1.60368002 -1.99833996 1.60326998 -1.99601004 0 P 0 
L 1.60326998 -1.99601004 1.60321004 -1.99576998 0 P 0 
L 1.60321004 -1.99576998 1.60313996 -1.99553002 0 P 0 
L 1.60313996 -1.99553002 1.60303996 -1.9953 0 P 0 
L 1.60303996 -1.9953 1.60293002 -1.99508002 0 P 0 
L 1.60293002 -1.99508002 1.60281004 -1.99486004 0 P 0 
L 1.60281004 -1.99486004 1.60261998 -1.9946 0 P 0 
L 1.60261998 -1.9946 1.60241004 -1.99435 0 P 0 
L 1.60241004 -1.99435 1.60218002 -1.99411998 0 P 0 
L 1.60218002 -1.99411998 1.60191998 -1.99391004 0 P 0 
L 1.60191998 -1.99391004 1.60161004 -1.99368996 0 P 0 
L 1.60161004 -1.99368996 1.60128996 -1.99348996 0 P 0 
L 1.60128996 -1.99348996 1.60095 -1.99331998 0 P 0 
L 1.60095 -1.99331998 1.6006 -1.99316004 0 P 0 
L 1.6006 -1.99316004 1.59966004 -1.99283002 0 P 0 
L 1.59966004 -1.99283002 1.59871004 -1.99255 0 P 0 
L 1.59871004 -1.99255 1.5933 -1.99135 0 P 0 
L 1.5933 -1.99135 1.5878 -1.9905 0 P 0 
L 1.5878 -1.9905 1.57285 -1.98915 0 P 0 
L 1.57285 -1.98915 1.55763996 -1.98861004 0 P 0 
L 1.55763996 -1.98861004 1.55171004 -1.98876004 0 P 0 
L 1.55171004 -1.98876004 1.54575 -1.98923996 0 P 0 
L 1.53011998 -2.12786998 1.5666 -2.12786998 0 P 0 
L 1.52236004 -2.12686998 1.57168002 -2.12686998 0 P 0 
L 1.51621998 -2.12586998 1.5753 -2.12586998 0 P 0 
L 1.51071004 -2.12486998 1.57856004 -2.12486998 0 P 0 
L 1.50553002 -2.12386998 1.58121004 -2.12386998 0 P 0 
L 1.50431004 -2.12286998 1.58381998 -2.12286998 0 P 0 
L 1.50423002 -2.12186998 1.58601998 -2.12186998 0 P 0 
L 1.50413996 -2.12086998 1.58796004 -2.12086998 0 P 0 
L 1.50406004 -2.11986998 1.58971004 -2.11986998 0 P 0 
L 1.50396998 -2.11886998 1.59118002 -2.11886998 0 P 0 
L 1.50388996 -2.11786998 1.5926 -2.11786998 0 P 0 
L 1.50381004 -2.11686998 1.59386004 -2.11686998 0 P 0 
L 1.50371998 -2.11586998 1.59496998 -2.11586998 0 P 0 
L 1.50363996 -2.11486998 1.59601004 -2.11486998 0 P 0 
L 1.50355 -2.11386998 1.59696998 -2.11386998 0 P 0 
L 1.50346998 -2.11286998 1.59781004 -2.11286998 0 P 0 
L 1.50338002 -2.11186998 1.5986 -2.11186998 0 P 0 
L 1.5033 -2.11086998 1.59933002 -2.11086998 0 P 0 
L 1.50321004 -2.10986998 1.60005 -2.10986998 0 P 0 
L 1.50313002 -2.10886998 1.60066998 -2.10886998 0 P 0 
L 1.50305 -2.10786998 1.60128002 -2.10786998 0 P 0 
L 1.50296004 -2.10686998 1.60185 -2.10686998 0 P 0 
L 1.50288002 -2.10586998 1.60236004 -2.10586998 0 P 0 
L 1.50278996 -2.10486998 1.60286998 -2.10486998 0 P 0 
L 1.50271004 -2.10386998 1.6033 -2.10386998 0 P 0 
L 1.50263002 -2.10286998 1.60371004 -2.10286998 0 P 0 
L 1.50255 -2.10186998 1.60405 -2.10186998 0 P 0 
L 1.50246998 -2.10086998 1.60436004 -2.10086998 0 P 0 
L 1.50238996 -2.09986998 1.60463002 -2.09986998 0 P 0 
L 1.50231004 -2.09886998 1.60485 -2.09886998 0 P 0 
L 1.50223002 -2.09786998 1.60505 -2.09786998 0 P 0 
L 1.50215 -2.09686998 1.60518002 -2.09686998 0 P 0 
L 1.50206998 -2.09586998 1.60531998 -2.09586998 0 P 0 
L 1.50198996 -2.09486998 1.60545 -2.09486998 0 P 0 
L 1.50191004 -2.09386998 1.60558002 -2.09386998 0 P 0 
L 1.50183002 -2.09286998 1.60563002 -2.09286998 0 P 0 
L 1.50175 -2.09186998 1.53725 -2.09186998 0 P 0 
L 1.54638996 -2.09186998 1.60568996 -2.09186998 0 P 0 
L 1.50166998 -2.09086998 1.5295 -2.09086998 0 P 0 
L 1.54956998 -2.09086998 1.60573996 -2.09086998 0 P 0 
L 1.50158996 -2.08986998 1.52436004 -2.08986998 0 P 0 
L 1.55125 -2.08986998 1.60578996 -2.08986998 0 P 0 
L 1.50151004 -2.08886998 1.52021004 -2.08886998 0 P 0 
L 1.55226998 -2.08886998 1.60576998 -2.08886998 0 P 0 
L 1.50143002 -2.08786998 1.51633002 -2.08786998 0 P 0 
L 1.55298002 -2.08786998 1.60573996 -2.08786998 0 P 0 
L 1.50133996 -2.08686998 1.51246004 -2.08686998 0 P 0 
L 1.55346998 -2.08686998 1.60571998 -2.08686998 0 P 0 
L 1.50126998 -2.08586998 1.50861998 -2.08586998 0 P 0 
L 1.55375 -2.08586998 1.60568996 -2.08586998 0 P 0 
L 1.50118002 -2.08486998 1.50481004 -2.08486998 0 P 0 
L 1.55383002 -2.08486998 1.60558996 -2.08486998 0 P 0 
L 1.55371998 -2.08386998 1.60548996 -2.08386998 0 P 0 
L 1.54886998 -2.12886998 1.53358996 -2.12823996 0 P 0 
L 1.53358996 -2.12823996 1.52631998 -2.12746998 0 P 0 
L 1.52631998 -2.12746998 1.51906004 -2.12636998 0 P 0 
L 1.51906004 -2.12636998 1.51363002 -2.12541004 0 P 0 
L 1.51363002 -2.12541004 1.50886998 -2.12451998 0 P 0 
L 1.50886998 -2.12451998 1.50483996 -2.12373996 0 P 0 
L 1.50483996 -2.12373996 1.50448996 -2.12365 0 P 0 
L 1.50448996 -2.12365 1.50438002 -2.12361004 0 P 0 
L 1.50438002 -2.12361004 1.5027 -2.10378002 0 P 0 
L 1.5027 -2.10378002 1.50111998 -2.08403002 0 P 0 
L 1.50111998 -2.08403002 1.50263996 -2.08433996 0 P 0 
L 1.50263996 -2.08433996 1.50581004 -2.08511004 0 P 0 
L 1.50581004 -2.08511004 1.50955 -2.08611998 0 P 0 
L 1.50955 -2.08611998 1.52306004 -2.08961004 0 P 0 
L 1.52306004 -2.08961004 1.52311004 -2.08961998 0 P 0 
L 1.52311004 -2.08961998 1.52875 -2.09076004 0 P 0 
L 1.52875 -2.09076004 1.5288 -2.09076004 0 P 0 
L 1.5288 -2.09076004 1.53443996 -2.09161004 0 P 0 
L 1.53443996 -2.09161004 1.53893996 -2.09203002 0 P 0 
L 1.53893996 -2.09203002 1.54346004 -2.09216998 0 P 0 
L 1.54346004 -2.09216998 1.54473996 -2.09211004 0 P 0 
L 1.54473996 -2.09211004 1.54603002 -2.09195 0 P 0 
L 1.54603002 -2.09195 1.54728996 -2.09166998 0 P 0 
L 1.54728996 -2.09166998 1.54853002 -2.09128996 0 P 0 
L 1.54853002 -2.09128996 1.54973002 -2.09081004 0 P 0 
L 1.54973002 -2.09081004 1.55026998 -2.09053996 0 P 0 
L 1.55026998 -2.09053996 1.55076998 -2.09023002 0 P 0 
L 1.55076998 -2.09023002 1.55118002 -2.08991998 0 P 0 
L 1.55118002 -2.08991998 1.55118002 -2.08991004 0 P 0 
L 1.55118002 -2.08991004 1.5512 -2.08991004 0 P 0 
L 1.5512 -2.08991004 1.55125 -2.08986998 0 P 0 
L 1.55125 -2.08986998 1.55131004 -2.08981998 0 P 0 
L 1.55131004 -2.08981998 1.55126998 -2.08978002 0 P 0 
L 1.55126998 -2.08978002 1.55136004 -2.08978002 0 P 0 
L 1.55136004 -2.08978002 1.5517 -2.08948996 0 P 0 
L 1.5517 -2.08948996 1.55206004 -2.08911998 0 P 0 
L 1.55206004 -2.08911998 1.55205 -2.08911004 0 P 0 
L 1.55205 -2.08911004 1.55206004 -2.08911004 0 P 0 
L 1.55206004 -2.08911004 1.55211998 -2.08906004 0 P 0 
L 1.55211998 -2.08906004 1.55248996 -2.08861004 0 P 0 
L 1.55248996 -2.08861004 1.55283996 -2.08811998 0 P 0 
L 1.55283996 -2.08811998 1.55313996 -2.08761004 0 P 0 
L 1.55313996 -2.08761004 1.5534 -2.08706998 0 P 0 
L 1.5534 -2.08706998 1.55356004 -2.08663002 0 P 0 
L 1.55356004 -2.08663002 1.55368996 -2.08618996 0 P 0 
L 1.55368996 -2.08618996 1.55376998 -2.08573996 0 P 0 
L 1.55376998 -2.08573996 1.55378002 -2.08565 0 P 0 
L 1.55378002 -2.08565 1.55381998 -2.08528002 0 P 0 
L 1.55381998 -2.08528002 1.55383002 -2.08481998 0 P 0 
L 1.55383002 -2.08481998 1.5538 -2.08436998 0 P 0 
L 1.5538 -2.08436998 1.55373002 -2.08391998 0 P 0 
L 1.55373002 -2.08391998 1.55361998 -2.08346998 0 P 0 
L 1.55361998 -2.08346998 1.55348002 -2.08303996 0 P 0 
L 1.55348002 -2.08303996 1.5533 -2.08261004 0 P 0 
L 1.5533 -2.08261004 1.55308996 -2.08221004 0 P 0 
L 1.55308996 -2.08221004 1.55283996 -2.08183002 0 P 0 
L 1.55283996 -2.08183002 1.55175 -2.0804 0 P 0 
L 1.55175 -2.0804 1.55055 -2.07908002 0 P 0 
L 1.55055 -2.07908002 1.54926004 -2.07783996 0 P 0 
L 1.54926004 -2.07783996 1.54788996 -2.07671998 0 P 0 
L 1.54788996 -2.07671998 1.53706998 -2.06898002 0 P 0 
L 1.53706998 -2.06898002 1.52085 -2.05713996 0 P 0 
L 1.52085 -2.05713996 1.51766004 -2.05445 0 P 0 
L 1.51766004 -2.05445 1.51468002 -2.05153996 0 P 0 
L 1.51468002 -2.05153996 1.51191998 -2.04841998 0 P 0 
L 1.51191998 -2.04841998 1.51048996 -2.04651998 0 P 0 
L 1.51048996 -2.04651998 1.50923002 -2.04453002 0 P 0 
L 1.50923002 -2.04453002 1.50813996 -2.04245 0 P 0 
L 1.50813996 -2.04245 1.50721998 -2.04026004 0 P 0 
L 1.50721998 -2.04026004 1.50643002 -2.03788002 0 P 0 
L 1.50643002 -2.03788002 1.50581004 -2.03545 0 P 0 
L 1.50581004 -2.03545 1.50536004 -2.03298996 0 P 0 
L 1.50536004 -2.03298996 1.50508996 -2.0305 0 P 0 
L 1.50508996 -2.0305 1.50498996 -2.02745 0 P 0 
L 1.50498996 -2.02745 1.50513996 -2.02443996 0 P 0 
L 1.50513996 -2.02443996 1.50551998 -2.02145 0 P 0 
L 1.50551998 -2.02145 1.50613996 -2.0185 0 P 0 
L 1.50613996 -2.0185 1.50698996 -2.01561004 0 P 0 
L 1.50698996 -2.01561004 1.50783002 -2.01341004 0 P 0 
L 1.50783002 -2.01341004 1.50883002 -2.0113 0 P 0 
L 1.50883002 -2.0113 1.51 -2.00928002 0 P 0 
L 1.51 -2.00928002 1.51133002 -2.00736004 0 P 0 
L 1.51133002 -2.00736004 1.5128 -2.00555 0 P 0 
L 1.5128 -2.00555 1.5144 -2.00386004 0 P 0 
L 1.5144 -2.00386004 1.51675 -2.00176998 0 P 0 
L 1.51675 -2.00176998 1.51923002 -1.9999 0 P 0 
L 1.51923002 -1.9999 1.52186004 -1.99823996 0 P 0 
L 1.52186004 -1.99823996 1.52461998 -1.99681004 0 P 0 
L 1.52461998 -1.99681004 1.52748996 -1.99561004 0 P 0 
L 1.52748996 -1.99561004 1.53353002 -1.99363996 0 P 0 
L 1.53353002 -1.99363996 1.5397 -1.99218002 0 P 0 
L 1.5397 -1.99218002 1.54598002 -1.99123002 0 P 0 
L 1.54598002 -1.99123002 1.55181004 -1.99075 0 P 0 
L 1.55181004 -1.99075 1.55763002 -1.99061998 0 P 0 
L 1.55763002 -1.99061998 1.57273002 -1.99113996 0 P 0 
L 1.57273002 -1.99113996 1.58755 -1.99248996 0 P 0 
L 1.58755 -1.99248996 1.59293002 -1.99331998 0 P 0 
L 1.59293002 -1.99331998 1.59821004 -1.99448996 0 P 0 
L 1.59821004 -1.99448996 1.59905 -1.99473002 0 P 0 
L 1.59905 -1.99473002 1.59986004 -1.99501998 0 P 0 
L 1.59986004 -1.99501998 1.60008002 -1.99511998 0 P 0 
L 1.60008002 -1.99511998 1.6003 -1.99523002 0 P 0 
L 1.6003 -1.99523002 1.60051004 -1.99536004 0 P 0 
L 1.60051004 -1.99536004 1.60071004 -1.9955 0 P 0 
L 1.60071004 -1.9955 1.60083002 -1.99561004 0 P 0 
L 1.60083002 -1.99561004 1.60093996 -1.99571004 0 P 0 
L 1.60093996 -1.99571004 1.60103996 -1.99583002 0 P 0 
L 1.60103996 -1.99583002 1.60111998 -1.99595 0 P 0 
L 1.60111998 -1.99595 1.60116998 -1.99601998 0 P 0 
L 1.60116998 -1.99601998 1.60121004 -1.99611004 0 P 0 
L 1.60121004 -1.99611004 1.60125 -1.99621004 0 P 0 
L 1.60125 -1.99621004 1.60128002 -1.9963 0 P 0 
L 1.60128002 -1.9963 1.60131004 -1.99641004 0 P 0 
L 1.60131004 -1.99641004 1.6017 -1.99861998 0 P 0 
L 1.6017 -1.99861998 1.60195 -2.00086998 0 P 0 
L 1.60195 -2.00086998 1.60308002 -2.01593002 0 P 0 
L 1.60308002 -2.01593002 1.60415 -2.03096998 0 P 0 
L 1.60415 -2.03096998 1.60345 -2.03083996 0 P 0 
L 1.60345 -2.03083996 1.60058996 -2.03026004 0 P 0 
L 1.60058996 -2.03026004 1.59723002 -2.02948002 0 P 0 
L 1.59723002 -2.02948002 1.59721998 -2.02948002 0 P 0 
L 1.59721998 -2.02948002 1.59306998 -2.0286 0 P 0 
L 1.59306998 -2.0286 1.58776004 -2.02776998 0 P 0 
L 1.58776004 -2.02776998 1.58226004 -2.02708002 0 P 0 
L 1.58226004 -2.02708002 1.57738002 -2.02666998 0 P 0 
L 1.57738002 -2.02666998 1.5709 -2.02633996 0 P 0 
L 1.5709 -2.02633996 1.56918996 -2.02635 0 P 0 
L 1.56918996 -2.02635 1.56746998 -2.02648996 0 P 0 
L 1.56746998 -2.02648996 1.56678996 -2.02658996 0 P 0 
L 1.56678996 -2.02658996 1.56611998 -2.02673996 0 P 0 
L 1.56611998 -2.02673996 1.56546004 -2.02695 0 P 0 
L 1.56546004 -2.02695 1.56481998 -2.0272 0 P 0 
L 1.56481998 -2.0272 1.56418996 -2.0275 0 P 0 
L 1.56418996 -2.0275 1.56358002 -2.02785 0 P 0 
L 1.56358002 -2.02785 1.563 -2.02823002 0 P 0 
L 1.563 -2.02823002 1.56245 -2.02865 0 P 0 
L 1.56245 -2.02865 1.56206998 -2.02898996 0 P 0 
L 1.56206998 -2.02898996 1.56171004 -2.02936004 0 P 0 
L 1.56171004 -2.02936004 1.56138002 -2.02976004 0 P 0 
L 1.56138002 -2.02976004 1.56108996 -2.03018996 0 P 0 
L 1.56108996 -2.03018996 1.56083002 -2.03063996 0 P 0 
L 1.56083002 -2.03063996 1.56061998 -2.0311 0 P 0 
L 1.56061998 -2.0311 1.56043996 -2.03158996 0 P 0 
L 1.56043996 -2.03158996 1.5603 -2.03208002 0 P 0 
L 1.5603 -2.03208002 1.5602 -2.0326 0 P 0 
L 1.5602 -2.0326 1.56015 -2.03308002 0 P 0 
L 1.56015 -2.03308002 1.56013996 -2.03353996 0 P 0 
L 1.56013996 -2.03353996 1.56016004 -2.03391004 0 P 0 
L 1.56016004 -2.03391004 1.56048002 -2.03391004 0 P 0 
L 1.56048002 -2.03391004 1.56016004 -2.03393002 0 P 0 
L 1.56016004 -2.03393002 1.56016998 -2.03401004 0 P 0 
L 1.56016998 -2.03401004 1.56023002 -2.03448002 0 P 0 
L 1.56023002 -2.03448002 1.56025 -2.03456004 0 P 0 
L 1.56025 -2.03456004 1.56033002 -2.03493002 0 P 0 
L 1.56033002 -2.03493002 1.56046998 -2.03538002 0 P 0 
L 1.56046998 -2.03538002 1.56063996 -2.03581998 0 P 0 
L 1.56063996 -2.03581998 1.56085 -2.03623996 0 P 0 
L 1.56085 -2.03623996 1.56108996 -2.03663996 0 P 0 
L 1.56108996 -2.03663996 1.56136004 -2.03701998 0 P 0 
L 1.56136004 -2.03701998 1.56233002 -2.03818996 0 P 0 
L 1.56233002 -2.03818996 1.56336998 -2.03928996 0 P 0 
L 1.56336998 -2.03928996 1.56448002 -2.04031004 0 P 0 
L 1.56448002 -2.04031004 1.56566004 -2.04123996 0 P 0 
L 1.56566004 -2.04123996 1.57471004 -2.04761998 0 P 0 
L 1.57471004 -2.04761998 1.58461998 -2.05491004 0 P 0 
L 1.58461998 -2.05491004 1.58898996 -2.05858996 0 P 0 
L 1.58898996 -2.05858996 1.59315 -2.06245 0 P 0 
L 1.59315 -2.06245 1.59656998 -2.06596998 0 P 0 
L 1.59656998 -2.06596998 1.59976004 -2.06965 0 P 0 
L 1.59976004 -2.06965 1.60116004 -2.07151004 0 P 0 
L 1.60116004 -2.07151004 1.60238002 -2.07346004 0 P 0 
L 1.60238002 -2.07346004 1.60341998 -2.0755 0 P 0 
L 1.60341998 -2.0755 1.60403996 -2.077 0 P 0 
L 1.60403996 -2.077 1.60456004 -2.07853996 0 P 0 
L 1.60456004 -2.07853996 1.60496004 -2.08011004 0 P 0 
L 1.60496004 -2.08011004 1.60525 -2.0817 0 P 0 
L 1.60525 -2.0817 1.60568996 -2.08578002 0 P 0 
L 1.60568996 -2.08578002 1.60578996 -2.08988002 0 P 0 
L 1.60578996 -2.08988002 1.60556998 -2.09403002 0 P 0 
L 1.60556998 -2.09403002 1.60501004 -2.09813996 0 P 0 
L 1.60501004 -2.09813996 1.60451998 -2.10036998 0 P 0 
L 1.60451998 -2.10036998 1.60383996 -2.10253996 0 P 0 
L 1.60383996 -2.10253996 1.60298996 -2.10465 0 P 0 
L 1.60298996 -2.10465 1.60163996 -2.1073 0 P 0 
L 1.60163996 -2.1073 1.60008002 -2.10983002 0 P 0 
L 1.60008002 -2.10983002 1.59833002 -2.11225 0 P 0 
L 1.59833002 -2.11225 1.59696998 -2.11386998 0 P 0 
L 1.59696998 -2.11386998 1.59551004 -2.11538996 0 P 0 
L 1.59551004 -2.11538996 1.59395 -2.1168 0 P 0 
L 1.59395 -2.1168 1.59231004 -2.11811004 0 P 0 
L 1.59231004 -2.11811004 1.58973002 -2.11986004 0 P 0 
L 1.58973002 -2.11986004 1.58701998 -2.1214 0 P 0 
L 1.58701998 -2.1214 1.5842 -2.12273002 0 P 0 
L 1.5842 -2.12273002 1.5788 -2.1248 0 P 0 
L 1.5788 -2.1248 1.57326998 -2.12648996 0 P 0 
L 1.57326998 -2.12648996 1.56983002 -2.12731004 0 P 0 
L 1.56983002 -2.12731004 1.56638002 -2.12791004 0 P 0 
L 1.56638002 -2.12791004 1.56288996 -2.1283 0 P 0 
L 1.56288996 -2.1283 1.54886998 -2.12886998 0 P 0 
L 1.35851998 -2.06545 1.47866004 -2.06545 0 P 0 
L 1.35936004 -2.06445 1.47871004 -2.06445 0 P 0 
L 1.36041004 -2.06345 1.47875 -2.06345 0 P 0 
L 1.36163996 -2.06245 1.4788 -2.06245 0 P 0 
L 1.36293996 -2.06145 1.47883996 -2.06145 0 P 0 
L 1.36436004 -2.06045 1.47888996 -2.06045 0 P 0 
L 1.36598002 -2.05945 1.47893996 -2.05945 0 P 0 
L 1.36776004 -2.05845 1.47898996 -2.05845 0 P 0 
L 1.36971004 -2.05745 1.47903002 -2.05745 0 P 0 
L 1.37166004 -2.05645 1.47908002 -2.05645 0 P 0 
L 1.37391004 -2.05545 1.47911998 -2.05545 0 P 0 
L 1.37616998 -2.05445 1.47916998 -2.05445 0 P 0 
L 1.37873002 -2.05345 1.47921004 -2.05345 0 P 0 
L 1.38136004 -2.05245 1.47926004 -2.05245 0 P 0 
L 1.36875 -2.03345 1.37108996 -2.03345 0 P 0 
L 1.36886004 -2.03245 1.37385 -2.03245 0 P 0 
L 1.36896998 -2.03145 1.37678002 -2.03145 0 P 0 
L 1.36908996 -2.03045 1.3797 -2.03045 0 P 0 
L 1.36921004 -2.02945 1.38261998 -2.02945 0 P 0 
L 1.36933002 -2.02845 1.38638996 -2.02845 0 P 0 
L 1.36946004 -2.02745 1.39023996 -2.02745 0 P 0 
L 1.36958002 -2.02645 1.39503002 -2.02645 0 P 0 
L 1.3697 -2.02545 1.40068002 -2.02545 0 P 0 
L 1.36981998 -2.02445 1.41053996 -2.02445 0 P 0 
L 1.36993996 -2.02345 1.47993996 -2.02345 0 P 0 
L 1.37008002 -2.02245 1.47988002 -2.02245 0 P 0 
L 1.37021004 -2.02145 1.47978002 -2.02145 0 P 0 
L 1.37033996 -2.02045 1.47968002 -2.02045 0 P 0 
L 1.37046998 -2.01945 1.47953002 -2.01945 0 P 0 
L 1.3706 -2.01845 1.47936004 -2.01845 0 P 0 
L 1.37073002 -2.01745 1.47918002 -2.01745 0 P 0 
L 1.37086004 -2.01645 1.47893002 -2.01645 0 P 0 
L 1.37098996 -2.01545 1.47868002 -2.01545 0 P 0 
L 1.37113002 -2.01445 1.4784 -2.01445 0 P 0 
L 1.37126998 -2.01345 1.47806004 -2.01345 0 P 0 
L 1.3714 -2.01245 1.47773002 -2.01245 0 P 0 
L 1.37153996 -2.01145 1.47733002 -2.01145 0 P 0 
L 1.37168002 -2.01045 1.47691004 -2.01045 0 P 0 
L 1.37181004 -2.00945 1.47641004 -2.00945 0 P 0 
L 1.37195 -2.00845 1.47588996 -2.00845 0 P 0 
L 1.37208002 -2.00745 1.47528002 -2.00745 0 P 0 
L 1.37221004 -2.00645 1.47463996 -2.00645 0 P 0 
L 1.37235 -2.00545 1.47391998 -2.00545 0 P 0 
L 1.37248996 -2.00445 1.47311004 -2.00445 0 P 0 
L 1.37261998 -2.00345 1.47225 -2.00345 0 P 0 
L 1.37276004 -2.00245 1.47126998 -2.00245 0 P 0 
L 1.3729 -2.00145 1.4702 -2.00145 0 P 0 
L 1.37303002 -2.00045 1.46903996 -2.00045 0 P 0 
L 1.37316998 -1.99945 1.46775 -1.99945 0 P 0 
L 1.3733 -1.99845 1.46625 -1.99845 0 P 0 
L 1.37343996 -1.99745 1.46455 -1.99745 0 P 0 
L 1.37356998 -1.99645 1.46253996 -1.99645 0 P 0 
L 1.37753002 -1.99545 1.46041004 -1.99545 0 P 0 
L 1.38218996 -1.99445 1.45781004 -1.99445 0 P 0 
L 1.42925 -2.08345 1.47785 -2.08345 0 P 0 
L 1.42931998 -2.08245 1.47788996 -2.08245 0 P 0 
L 1.42938002 -2.08145 1.47793002 -2.08145 0 P 0 
L 1.42945 -2.08045 1.47796998 -2.08045 0 P 0 
L 1.42951004 -2.07945 1.47801004 -2.07945 0 P 0 
L 1.42958002 -2.07845 1.47806004 -2.07845 0 P 0 
L 1.42963996 -2.07745 1.4781 -2.07745 0 P 0 
L 1.4297 -2.07645 1.47815 -2.07645 0 P 0 
L 1.42976998 -2.07545 1.4782 -2.07545 0 P 0 
L 1.42983002 -2.07445 1.47825 -2.07445 0 P 0 
L 1.4299 -2.07345 1.47828996 -2.07345 0 P 0 
L 1.42963996 -2.07245 1.47833996 -2.07245 0 P 0 
L 1.42918996 -2.07145 1.47838002 -2.07145 0 P 0 
L 1.38425 -2.05145 1.47931004 -2.05145 0 P 0 
L 1.38731998 -2.05045 1.47933996 -2.05045 0 P 0 
L 1.39088002 -2.04945 1.47938002 -2.04945 0 P 0 
L 1.3947 -2.04845 1.47941004 -2.04845 0 P 0 
L 1.39851004 -2.04745 1.47945 -2.04745 0 P 0 
L 1.40233002 -2.04645 1.47948002 -2.04645 0 P 0 
L 1.40608002 -2.04545 1.47951004 -2.04545 0 P 0 
L 1.40983002 -2.04445 1.47955 -2.04445 0 P 0 
L 1.41306998 -2.04345 1.47958996 -2.04345 0 P 0 
L 1.41591998 -2.04245 1.47961998 -2.04245 0 P 0 
L 1.41876998 -2.04145 1.47965 -2.04145 0 P 0 
L 1.42133996 -2.04045 1.47968996 -2.04045 0 P 0 
L 1.42361998 -2.03945 1.47971998 -2.03945 0 P 0 
L 1.42591004 -2.03845 1.47975 -2.03845 0 P 0 
L 1.42805 -2.03745 1.47978002 -2.03745 0 P 0 
L 1.42936004 -2.03645 1.47981004 -2.03645 0 P 0 
L 1.43003002 -2.03545 1.47983002 -2.03545 0 P 0 
L 1.43081998 -2.03445 1.47986004 -2.03445 0 P 0 
L 1.43121004 -2.03345 1.47988002 -2.03345 0 P 0 
L 1.43141998 -2.03245 1.4799 -2.03245 0 P 0 
L 1.43146998 -2.03145 1.47993002 -2.03145 0 P 0 
L 1.43136004 -2.03045 1.47996004 -2.03045 0 P 0 
L 1.43108002 -2.02945 1.47998002 -2.02945 0 P 0 
L 1.4306 -2.02845 1.48001004 -2.02845 0 P 0 
L 1.42986998 -2.02745 1.48001004 -2.02745 0 P 0 
L 1.42875 -2.02645 1.47998996 -2.02645 0 P 0 
L 1.42658996 -2.02545 1.47996998 -2.02545 0 P 0 
L 1.42203996 -2.02445 1.47996004 -2.02445 0 P 0 
L 1.38748002 -1.99345 1.45483002 -1.99345 0 P 0 
L 1.39331998 -1.99245 1.45108996 -1.99245 0 P 0 
L 1.40051004 -1.99145 1.44503002 -1.99145 0 P 0 
L 1.38096998 -2.12745 1.4051 -2.12745 0 P 0 
L 1.37671004 -2.12645 1.41113996 -2.12645 0 P 0 
L 1.3736 -2.12545 1.41238996 -2.12545 0 P 0 
L 1.37096998 -2.12445 1.41268002 -2.12445 0 P 0 
L 1.36876998 -2.12345 1.41296998 -2.12345 0 P 0 
L 1.36685 -2.12245 1.41326998 -2.12245 0 P 0 
L 1.36516004 -2.12145 1.41356004 -2.12145 0 P 0 
L 1.36366004 -2.12045 1.41385 -2.12045 0 P 0 
L 1.36225 -2.11945 1.41413996 -2.11945 0 P 0 
L 1.361 -2.11845 1.41443002 -2.11845 0 P 0 
L 1.35983002 -2.11745 1.41471998 -2.11745 0 P 0 
L 1.35876004 -2.11645 1.41501004 -2.11645 0 P 0 
L 1.42661998 -2.12445 1.47693002 -2.12445 0 P 0 
L 1.42665 -2.12345 1.47693002 -2.12345 0 P 0 
L 1.4267 -2.12245 1.47693002 -2.12245 0 P 0 
L 1.42675 -2.12145 1.47693002 -2.12145 0 P 0 
L 1.42681004 -2.12045 1.47693002 -2.12045 0 P 0 
L 1.42686998 -2.11945 1.47693002 -2.11945 0 P 0 
L 1.42691998 -2.11845 1.47693002 -2.11845 0 P 0 
L 1.42698996 -2.11745 1.47693002 -2.11745 0 P 0 
L 1.42705 -2.11645 1.47693002 -2.11645 0 P 0 
L 1.42711004 -2.11545 1.47693002 -2.11545 0 P 0 
L 1.42716998 -2.11445 1.47693002 -2.11445 0 P 0 
L 1.42723002 -2.11345 1.47693996 -2.11345 0 P 0 
L 1.4273 -2.11245 1.47695 -2.11245 0 P 0 
L 1.42736998 -2.11145 1.47696004 -2.11145 0 P 0 
L 1.42743996 -2.11045 1.47698002 -2.11045 0 P 0 
L 1.42751004 -2.10945 1.47698996 -2.10945 0 P 0 
L 1.42758002 -2.10845 1.47701004 -2.10845 0 P 0 
L 1.42765 -2.10745 1.47703002 -2.10745 0 P 0 
L 1.42771004 -2.10645 1.47703996 -2.10645 0 P 0 
L 1.42778002 -2.10545 1.47706998 -2.10545 0 P 0 
L 1.42783996 -2.10445 1.4771 -2.10445 0 P 0 
L 1.42791004 -2.10345 1.47713002 -2.10345 0 P 0 
L 1.42798002 -2.10245 1.47716004 -2.10245 0 P 0 
L 1.42805 -2.10145 1.4772 -2.10145 0 P 0 
L 1.42811004 -2.10045 1.47723002 -2.10045 0 P 0 
L 1.40953002 -2.09945 1.41973002 -2.09945 0 P 0 
L 1.42818002 -2.09945 1.47726004 -2.09945 0 P 0 
L 1.41618002 -2.09845 1.41996998 -2.09845 0 P 0 
L 1.42825 -2.09845 1.47728996 -2.09845 0 P 0 
L 1.42831998 -2.09745 1.47733002 -2.09745 0 P 0 
L 1.42838996 -2.09645 1.47736004 -2.09645 0 P 0 
L 1.42846004 -2.09545 1.47738996 -2.09545 0 P 0 
L 1.42851998 -2.09445 1.47741998 -2.09445 0 P 0 
L 1.42858996 -2.09345 1.47746004 -2.09345 0 P 0 
L 1.42866004 -2.09245 1.4775 -2.09245 0 P 0 
L 1.42873002 -2.09145 1.47753996 -2.09145 0 P 0 
L 1.42878996 -2.09045 1.47758002 -2.09045 0 P 0 
L 1.42886004 -2.08945 1.47761998 -2.08945 0 P 0 
L 1.42893002 -2.08845 1.47766004 -2.08845 0 P 0 
L 1.42898996 -2.08745 1.4777 -2.08745 0 P 0 
L 1.42906004 -2.08645 1.47773002 -2.08645 0 P 0 
L 1.42911998 -2.08545 1.47776998 -2.08545 0 P 0 
L 1.42918996 -2.08445 1.47781004 -2.08445 0 P 0 
L 1.61686004 -2.17995 1.66846004 -2.17995 0 P 0 
L 1.61591004 -2.17895 1.67158996 -2.17895 0 P 0 
L 1.61553996 -2.17795 1.67431998 -2.17795 0 P 0 
L 1.61526998 -2.17695 1.67675 -2.17695 0 P 0 
L 1.61508002 -2.17595 1.67903996 -2.17595 0 P 0 
L 1.61496998 -2.17495 1.68108002 -2.17495 0 P 0 
L 1.61491004 -2.17395 1.68295 -2.17395 0 P 0 
L 1.61485 -2.17295 1.68458996 -2.17295 0 P 0 
L 1.61478996 -2.17195 1.6861 -2.17195 0 P 0 
L 1.61473002 -2.17095 1.6875 -2.17095 0 P 0 
L 1.61466998 -2.16995 1.68876998 -2.16995 0 P 0 
L 1.61461004 -2.16895 1.68998002 -2.16895 0 P 0 
L 1.61455 -2.16795 1.69108002 -2.16795 0 P 0 
L 1.61448996 -2.16695 1.69211998 -2.16695 0 P 0 
L 1.61443002 -2.16595 1.69316004 -2.16595 0 P 0 
L 1.61436998 -2.16495 1.69411998 -2.16495 0 P 0 
L 1.61431004 -2.16395 1.69498996 -2.16395 0 P 0 
L 1.61425 -2.16295 1.69586004 -2.16295 0 P 0 
L 1.61418996 -2.16195 1.69673002 -2.16195 0 P 0 
L 1.61413002 -2.16095 1.69746998 -2.16095 0 P 0 
L 1.61406998 -2.15995 1.6982 -2.15995 0 P 0 
L 1.61401998 -2.15895 1.69893996 -2.15895 0 P 0 
L 1.61396998 -2.15795 1.69963002 -2.15795 0 P 0 
L 1.64433002 -2.18295 1.63151004 -2.18271004 0 P 0 
L 1.63151004 -2.18271004 1.62658002 -2.18226998 0 P 0 
L 1.62658002 -2.18226998 1.62168996 -2.18146998 0 P 0 
L 1.62168996 -2.18146998 1.6201 -2.1811 0 P 0 
L 1.6201 -2.1811 1.61853996 -2.18061004 0 P 0 
L 1.61853996 -2.18061004 1.61701004 -2.18001998 0 P 0 
L 1.61701004 -2.18001998 1.61686004 -2.17995 0 P 0 
L 1.61686004 -2.17995 1.61671004 -2.17986998 0 P 0 
L 1.61671004 -2.17986998 1.61656998 -2.17976998 0 P 0 
L 1.61656998 -2.17976998 1.61643996 -2.17966998 0 P 0 
L 1.61643996 -2.17966998 1.61631998 -2.17955 0 P 0 
L 1.61631998 -2.17955 1.61621004 -2.17943002 0 P 0 
L 1.61621004 -2.17943002 1.6161 -2.1793 0 P 0 
L 1.6161 -2.1793 1.61601004 -2.17915 0 P 0 
L 1.61601004 -2.17915 1.61593002 -2.179 0 P 0 
L 1.61593002 -2.179 1.61586004 -2.17885 0 P 0 
L 1.61586004 -2.17885 1.61553002 -2.17791004 0 P 0 
L 1.61553002 -2.17791004 1.61526998 -2.17696004 0 P 0 
L 1.61526998 -2.17696004 1.61508996 -2.17598996 0 P 0 
L 1.61508996 -2.17598996 1.61496998 -2.17496998 0 P 0 
L 1.61496998 -2.17496998 1.61408002 -2.16011004 0 P 0 
L 1.61408002 -2.16011004 1.61341998 -2.14758996 0 P 0 
L 1.61341998 -2.14758996 1.6202 -2.14821004 0 P 0 
L 1.6202 -2.14821004 1.62023002 -2.14821004 0 P 0 
L 1.62023002 -2.14821004 1.63216998 -2.14893996 0 P 0 
L 1.63216998 -2.14893996 1.6349 -2.14893002 0 P 0 
L 1.6349 -2.14893002 1.63761998 -2.14873002 0 P 0 
L 1.63761998 -2.14873002 1.64031998 -2.14835 0 P 0 
L 1.64031998 -2.14835 1.64198996 -2.14798996 0 P 0 
L 1.64198996 -2.14798996 1.64363002 -2.14751998 0 P 0 
L 1.64363002 -2.14751998 1.64523002 -2.14693002 0 P 0 
L 1.64523002 -2.14693002 1.64678996 -2.14623002 0 P 0 
L 1.64678996 -2.14623002 1.64888002 -2.14506998 0 P 0 
L 1.64888002 -2.14506998 1.65086998 -2.14376004 0 P 0 
L 1.65086998 -2.14376004 1.65093996 -2.14371004 0 P 0 
L 1.65093996 -2.14371004 1.65275 -2.14228996 0 P 0 
L 1.65275 -2.14228996 1.6539 -2.14123996 0 P 0 
L 1.6539 -2.14123996 1.65496004 -2.14011004 0 P 0 
L 1.65496004 -2.14011004 1.65591998 -2.13891004 0 P 0 
L 1.65591998 -2.13891004 1.65755 -2.13653996 0 P 0 
L 1.65755 -2.13653996 1.65901998 -2.13415 0 P 0 
L 1.65901998 -2.13415 1.65903002 -2.13413002 0 P 0 
L 1.65903002 -2.13413002 1.66035 -2.13171998 0 P 0 
L 1.66035 -2.13171998 1.66155 -2.12925 0 P 0 
L 1.66155 -2.12925 1.66183996 -2.12851998 0 P 0 
L 1.66183996 -2.12851998 1.66206998 -2.12776004 0 P 0 
L 1.66206998 -2.12776004 1.66223996 -2.12696998 0 P 0 
L 1.66223996 -2.12696998 1.66233996 -2.12618002 0 P 0 
L 1.66233996 -2.12618002 1.66236998 -2.12538996 0 P 0 
L 1.66236998 -2.12538996 1.66233002 -2.12436004 0 P 0 
L 1.66233002 -2.12436004 1.66221004 -2.12335 0 P 0 
L 1.66221004 -2.12335 1.662 -2.12235 0 P 0 
L 1.662 -2.12235 1.66171004 -2.12141004 0 P 0 
L 1.66171004 -2.12141004 1.64438996 -2.07113002 0 P 0 
L 1.64438996 -2.07113002 1.62871998 -2.02606004 0 P 0 
L 1.62871998 -2.02606004 1.62116004 -2.00558996 0 P 0 
L 1.62116004 -2.00558996 1.62116004 -2.00556998 0 P 0 
L 1.62116004 -2.00556998 1.61681004 -1.99443996 0 P 0 
L 1.61681004 -1.99443996 1.67163002 -1.99443996 0 P 0 
L 1.67163002 -1.99443996 1.67301004 -2.00076004 0 P 0 
L 1.67301004 -2.00076004 1.67613002 -2.01341998 0 P 0 
L 1.67613002 -2.01341998 1.68331004 -2.03931998 0 P 0 
L 1.68331004 -2.03931998 1.69153002 -2.06856998 0 P 0 
L 1.69153002 -2.06856998 1.6916 -2.06876004 0 P 0 
L 1.6916 -2.06876004 1.69168996 -2.06896998 0 P 0 
L 1.69168996 -2.06896998 1.69181004 -2.06918002 0 P 0 
L 1.69181004 -2.06918002 1.69193002 -2.06936998 0 P 0 
L 1.69193002 -2.06936998 1.69208002 -2.06956004 0 P 0 
L 1.69208002 -2.06956004 1.69223996 -2.06973002 0 P 0 
L 1.69223996 -2.06973002 1.69241998 -2.06988002 0 P 0 
L 1.69241998 -2.06988002 1.6926 -2.07001998 0 P 0 
L 1.6926 -2.07001998 1.6928 -2.07015 0 P 0 
L 1.6928 -2.07015 1.69301004 -2.07025 0 P 0 
L 1.69301004 -2.07025 1.69323002 -2.07033996 0 P 0 
L 1.69323002 -2.07033996 1.69346004 -2.07041004 0 P 0 
L 1.69346004 -2.07041004 1.69368002 -2.07045 0 P 0 
L 1.69368002 -2.07045 1.69391998 -2.07048002 0 P 0 
L 1.69391998 -2.07048002 1.69413996 -2.07048996 0 P 0 
L 1.69413996 -2.07048996 1.6944 -2.07048002 0 P 0 
L 1.6944 -2.07048002 1.69465 -2.07045 0 P 0 
L 1.69465 -2.07045 1.69488996 -2.07038996 0 P 0 
L 1.69488996 -2.07038996 1.69513996 -2.07031998 0 P 0 
L 1.69513996 -2.07031998 1.69536998 -2.07021998 0 P 0 
L 1.69536998 -2.07021998 1.69558996 -2.0701 0 P 0 
L 1.69558996 -2.0701 1.69581004 -2.06996998 0 P 0 
L 1.69581004 -2.06996998 1.69601004 -2.06981998 0 P 0 
L 1.69601004 -2.06981998 1.6962 -2.06965 0 P 0 
L 1.6962 -2.06965 1.69636998 -2.06946004 0 P 0 
L 1.69636998 -2.06946004 1.69653002 -2.06926004 0 P 0 
L 1.69653002 -2.06926004 1.69666004 -2.06905 0 P 0 
L 1.69666004 -2.06905 1.69678996 -2.06883002 0 P 0 
L 1.69678996 -2.06883002 1.69688002 -2.0686 0 P 0 
L 1.69688002 -2.0686 1.69695 -2.0684 0 P 0 
L 1.69695 -2.0684 1.70426004 -2.04365 0 P 0 
L 1.70426004 -2.04365 1.70426004 -2.04363002 0 P 0 
L 1.70426004 -2.04363002 1.71066998 -2.0213 0 P 0 
L 1.71066998 -2.0213 1.71068002 -2.02126004 0 P 0 
L 1.71068002 -2.02126004 1.71431998 -2.00693996 0 P 0 
L 1.71431998 -2.00693996 1.71706004 -1.99496998 0 P 0 
L 1.71706004 -1.99496998 1.74335 -1.9947 0 P 0 
L 1.74335 -1.9947 1.75403002 -1.99461004 0 P 0 
L 1.75403002 -1.99461004 1.76301004 -1.99465 0 P 0 
L 1.76301004 -1.99465 1.76886004 -1.99471004 0 P 0 
L 1.76886004 -1.99471004 1.76883996 -1.99476004 0 P 0 
L 1.76883996 -1.99476004 1.74021004 -2.06556004 0 P 0 
L 1.74021004 -2.06556004 1.71298002 -2.13276998 0 P 0 
L 1.71298002 -2.13276998 1.70836998 -2.14293996 0 P 0 
L 1.70836998 -2.14293996 1.70413996 -2.15076004 0 P 0 
L 1.70413996 -2.15076004 1.69941998 -2.15828996 0 P 0 
L 1.69941998 -2.15828996 1.6967 -2.16198996 0 P 0 
L 1.6967 -2.16198996 1.6937 -2.16541998 0 P 0 
L 1.6937 -2.16541998 1.69041998 -2.1686 0 P 0 
L 1.69041998 -2.1686 1.68793996 -2.17063002 0 P 0 
L 1.68793996 -2.17063002 1.68535 -2.17248002 0 P 0 
L 1.68535 -2.17248002 1.68263996 -2.17413996 0 P 0 
L 1.68263996 -2.17413996 1.67981004 -2.17561004 0 P 0 
L 1.67981004 -2.17561004 1.67525 -2.17761004 0 P 0 
L 1.67525 -2.17761004 1.6706 -2.17931998 0 P 0 
L 1.6706 -2.17931998 1.66586004 -2.18073002 0 P 0 
L 1.66586004 -2.18073002 1.66141998 -2.1817 0 P 0 
L 1.66141998 -2.1817 1.65691998 -2.18228996 0 P 0 
L 1.65691998 -2.18228996 1.64433002 -2.18295 0 P 0 
L 1.61928996 -2.00628002 1.62683996 -2.02673002 0 P 0 
L 1.62683996 -2.02673002 1.6425 -2.07178002 0 P 0 
L 1.6425 -2.07178002 1.65981004 -2.12201998 0 P 0 
L 1.65981004 -2.12201998 1.66006004 -2.12283996 0 P 0 
L 1.66006004 -2.12283996 1.66023002 -2.12368002 0 P 0 
L 1.66023002 -2.12368002 1.66033996 -2.12451998 0 P 0 
L 1.66033996 -2.12451998 1.66036998 -2.12538002 0 P 0 
L 1.66036998 -2.12538002 1.66033996 -2.12601004 0 P 0 
L 1.66033996 -2.12601004 1.66026998 -2.12663996 0 P 0 
L 1.66026998 -2.12663996 1.66013996 -2.12725 0 P 0 
L 1.66013996 -2.12725 1.65995 -2.12786004 0 P 0 
L 1.65995 -2.12786004 1.65971004 -2.12843996 0 P 0 
L 1.65971004 -2.12843996 1.65856998 -2.1308 0 P 0 
L 1.65856998 -2.1308 1.6573 -2.13313002 0 P 0 
L 1.6573 -2.13313002 1.65586998 -2.13545 0 P 0 
L 1.65586998 -2.13545 1.65431004 -2.13771998 0 P 0 
L 1.65431004 -2.13771998 1.65343996 -2.1388 0 P 0 
L 1.65343996 -2.1388 1.65248996 -2.13981998 0 P 0 
L 1.65248996 -2.13981998 1.65146004 -2.14076004 0 P 0 
L 1.65146004 -2.14076004 1.64971004 -2.14213002 0 P 0 
L 1.64971004 -2.14213002 1.64785 -2.14336004 0 P 0 
L 1.64785 -2.14336004 1.64588996 -2.14443996 0 P 0 
L 1.64588996 -2.14443996 1.64446998 -2.14508002 0 P 0 
L 1.64446998 -2.14508002 1.64301004 -2.14561998 0 P 0 
L 1.64301004 -2.14561998 1.64151004 -2.14605 0 P 0 
L 1.64151004 -2.14605 1.63996998 -2.14636998 0 P 0 
L 1.63996998 -2.14636998 1.63741004 -2.14673996 0 P 0 
L 1.63741004 -2.14673996 1.63483002 -2.14693002 0 P 0 
L 1.63483002 -2.14693002 1.63223002 -2.14693996 0 P 0 
L 1.63223002 -2.14693996 1.62036004 -2.14621998 0 P 0 
L 1.62036004 -2.14621998 1.6113 -2.14538002 0 P 0 
L 1.6113 -2.14538002 1.61208996 -2.16023002 0 P 0 
L 1.61208996 -2.16023002 1.61298002 -2.17515 0 P 0 
L 1.61298002 -2.17515 1.6131 -2.17628002 0 P 0 
L 1.6131 -2.17628002 1.61331998 -2.17741004 0 P 0 
L 1.61331998 -2.17741004 1.61361998 -2.17851004 0 P 0 
L 1.61361998 -2.17851004 1.614 -2.17958996 0 P 0 
L 1.614 -2.17958996 1.61413996 -2.17988996 0 P 0 
L 1.61413996 -2.17988996 1.61428996 -2.18018002 0 P 0 
L 1.61428996 -2.18018002 1.61446998 -2.18045 0 P 0 
L 1.61446998 -2.18045 1.61466998 -2.18071004 0 P 0 
L 1.61466998 -2.18071004 1.61488996 -2.18095 0 P 0 
L 1.61488996 -2.18095 1.61511998 -2.18116998 0 P 0 
L 1.61511998 -2.18116998 1.61538002 -2.18138002 0 P 0 
L 1.61538002 -2.18138002 1.61565 -2.18156004 0 P 0 
L 1.61565 -2.18156004 1.61593002 -2.18173002 0 P 0 
L 1.61593002 -2.18173002 1.61623002 -2.18186004 0 P 0 
L 1.61623002 -2.18186004 1.61788002 -2.1825 0 P 0 
L 1.61788002 -2.1825 1.61956998 -2.18301998 0 P 0 
L 1.61956998 -2.18301998 1.6213 -2.18343002 0 P 0 
L 1.6213 -2.18343002 1.62633002 -2.18426004 0 P 0 
L 1.62633002 -2.18426004 1.6314 -2.18471004 0 P 0 
L 1.6314 -2.18471004 1.64436004 -2.18495 0 P 0 
L 1.64436004 -2.18495 1.65711004 -2.18428002 0 P 0 
L 1.65711004 -2.18428002 1.66176998 -2.18366998 0 P 0 
L 1.66176998 -2.18366998 1.66636004 -2.18266998 0 P 0 
L 1.66636004 -2.18266998 1.67123002 -2.18121004 0 P 0 
L 1.67123002 -2.18121004 1.676 -2.17946998 0 P 0 
L 1.676 -2.17946998 1.68068002 -2.17741998 0 P 0 
L 1.68068002 -2.17741998 1.68361998 -2.17588002 0 P 0 
L 1.68361998 -2.17588002 1.68646004 -2.17415 0 P 0 
L 1.68646004 -2.17415 1.68916004 -2.17221998 0 P 0 
L 1.68916004 -2.17221998 1.69175 -2.17008996 0 P 0 
L 1.69175 -2.17008996 1.69515 -2.1668 0 P 0 
L 1.69515 -2.1668 1.69826004 -2.16323996 0 P 0 
L 1.69826004 -2.16323996 1.70108002 -2.15941998 0 P 0 
L 1.70108002 -2.15941998 1.70586004 -2.15176998 0 P 0 
L 1.70586004 -2.15176998 1.71016004 -2.14383002 0 P 0 
L 1.71016004 -2.14383002 1.71481998 -2.13356004 0 P 0 
L 1.71481998 -2.13356004 1.74206998 -2.06631004 0 P 0 
L 1.74206998 -2.06631004 1.77071004 -1.99548002 0 P 0 
L 1.77071004 -1.99548002 1.77088002 -1.99498996 0 P 0 
L 1.77088002 -1.99498996 1.77101998 -1.99448996 0 P 0 
L 1.77101998 -1.99448996 1.77111998 -1.99398996 0 P 0 
L 1.77111998 -1.99398996 1.77118002 -1.99346998 0 P 0 
L 1.77118002 -1.99346998 1.7712 -1.99295 0 P 0 
L 1.7712 -1.99295 1.7712 -1.99293002 0 P 0 
L 1.7712 -1.99293002 1.77118996 -1.99286998 0 P 0 
L 1.77118996 -1.99286998 1.77118002 -1.99286004 0 P 0 
L 1.77118002 -1.99286004 1.77118002 -1.99283996 0 P 0 
L 1.77118002 -1.99283996 1.77111004 -1.99276998 0 P 0 
L 1.77111004 -1.99276998 1.77106998 -1.99275 0 P 0 
L 1.77106998 -1.99275 1.77106004 -1.99273996 0 P 0 
L 1.77106004 -1.99273996 1.771 -1.99273002 0 P 0 
L 1.771 -1.99273002 1.77098002 -1.99273002 0 P 0 
L 1.77098002 -1.99273002 1.76301004 -1.99265 0 P 0 
L 1.76301004 -1.99265 1.75401998 -1.99261004 0 P 0 
L 1.75401998 -1.99261004 1.74333002 -1.9927 0 P 0 
L 1.74333002 -1.9927 1.71546004 -1.99298996 0 P 0 
L 1.71546004 -1.99298996 1.71236998 -2.00646998 0 P 0 
L 1.71236998 -2.00646998 1.70873996 -2.02078002 0 P 0 
L 1.70873996 -2.02078002 1.70233996 -2.04308002 0 P 0 
L 1.70233996 -2.04308002 1.69505 -2.0678 0 P 0 
L 1.69505 -2.0678 1.69501998 -2.06788002 0 P 0 
L 1.69501998 -2.06788002 1.69498996 -2.06795 0 P 0 
L 1.69498996 -2.06795 1.69495 -2.06801998 0 P 0 
L 1.69495 -2.06801998 1.69485 -2.06816004 0 P 0 
L 1.69485 -2.06816004 1.69478996 -2.06821998 0 P 0 
L 1.69478996 -2.06821998 1.69466998 -2.06831998 0 P 0 
L 1.69466998 -2.06831998 1.69453002 -2.0684 0 P 0 
L 1.69453002 -2.0684 1.69445 -2.06843002 0 P 0 
L 1.69445 -2.06843002 1.69438002 -2.06846004 0 P 0 
L 1.69438002 -2.06846004 1.69428996 -2.06846998 0 P 0 
L 1.69428996 -2.06846998 1.69421004 -2.06848996 0 P 0 
L 1.69421004 -2.06848996 1.69406998 -2.06848996 0 P 0 
L 1.69406998 -2.06848996 1.69395 -2.06846998 0 P 0 
L 1.69395 -2.06846998 1.69383002 -2.06843002 0 P 0 
L 1.69383002 -2.06843002 1.69373002 -2.06836998 0 P 0 
L 1.69373002 -2.06836998 1.69363002 -2.06828996 0 P 0 
L 1.69363002 -2.06828996 1.69358996 -2.06823996 0 P 0 
L 1.69358996 -2.06823996 1.69355 -2.0682 0 P 0 
L 1.69355 -2.0682 1.69351998 -2.06815 0 P 0 
L 1.69351998 -2.06815 1.69346004 -2.06803996 0 P 0 
L 1.69346004 -2.06803996 1.69343996 -2.06798002 0 P 0 
L 1.69343996 -2.06798002 1.68523002 -2.03878002 0 P 0 
L 1.68523002 -2.03878002 1.67806998 -2.01291998 0 P 0 
L 1.67806998 -2.01291998 1.67496004 -2.00031004 0 P 0 
L 1.67496004 -2.00031004 1.67323002 -1.99243996 0 P 0 
L 1.67323002 -1.99243996 1.61388002 -1.99243996 0 P 0 
L 1.61388002 -1.99243996 1.61928996 -2.00628002 0 P 0 
L 1.35018002 -2.08345 1.39488996 -2.08345 0 P 0 
L 1.35026004 -2.08245 1.39586004 -2.08245 0 P 0 
L 1.35041004 -2.08145 1.39708996 -2.08145 0 P 0 
L 1.35058996 -2.08045 1.39853002 -2.08045 0 P 0 
L 1.35083996 -2.07945 1.40031998 -2.07945 0 P 0 
L 1.35116998 -2.07845 1.40271004 -2.07845 0 P 0 
L 1.35158002 -2.07745 1.40561998 -2.07745 0 P 0 
L 1.35203002 -2.07645 1.4092 -2.07645 0 P 0 
L 1.35248002 -2.07545 1.41288996 -2.07545 0 P 0 
L 1.35293002 -2.07445 1.4164 -2.07445 0 P 0 
L 1.35338996 -2.07345 1.41975 -2.07345 0 P 0 
L 1.35393996 -2.07245 1.42293996 -2.07245 0 P 0 
L 1.35448996 -2.07145 1.42606998 -2.07145 0 P 0 
L 1.35505 -2.07045 1.47843002 -2.07045 0 P 0 
L 1.3557 -2.06945 1.47846998 -2.06945 0 P 0 
L 1.35635 -2.06845 1.47851998 -2.06845 0 P 0 
L 1.35701998 -2.06745 1.47856998 -2.06745 0 P 0 
L 1.35776998 -2.06645 1.47861004 -2.06645 0 P 0 
L 1.29346998 -2.00516004 1.33388996 -2.00516004 0 P 0 
L 1.29448996 -2.00416004 1.33385 -2.00416004 0 P 0 
L 1.29551004 -2.00316004 1.33381004 -2.00316004 0 P 0 
L 1.29653996 -2.00216004 1.33376004 -2.00216004 0 P 0 
L 1.29756004 -2.00116004 1.33371004 -2.00116004 0 P 0 
L 1.29861998 -2.00016004 1.33366004 -2.00016004 0 P 0 
L 1.29973002 -1.99916004 1.3336 -1.99916004 0 P 0 
L 1.30101004 -1.99816004 1.33355 -1.99816004 0 P 0 
L 1.30238996 -1.99716004 1.3335 -1.99716004 0 P 0 
L 1.30393996 -1.99616004 1.33345 -1.99616004 0 P 0 
L 1.30571004 -1.99516004 1.33338996 -1.99516004 0 P 0 
L 1.3077 -1.99416004 1.33333002 -1.99416004 0 P 0 
L 1.31001004 -1.99316004 1.33328002 -1.99316004 0 P 0 
L 1.31288002 -1.99216004 1.33321998 -1.99216004 0 P 0 
L 1.31688996 -1.99116004 1.33316004 -1.99116004 0 P 0 
L 1.39798996 -1.98971998 1.39326998 -1.99043002 0 P 0 
L 1.39326998 -1.99043002 1.38806998 -1.9913 0 P 0 
L 1.38806998 -1.9913 1.38316004 -1.9922 0 P 0 
L 1.38316004 -1.9922 1.37946004 -1.99296998 0 P 0 
L 1.37946004 -1.99296998 1.3718 -1.99466998 0 P 0 
L 1.3718 -1.99466998 1.36896004 -2.01553996 0 P 0 
L 1.36896004 -2.01553996 1.36791004 -2.02358996 0 P 0 
L 1.36791004 -2.02358996 1.36708002 -2.03043002 0 P 0 
L 1.36708002 -2.03043002 1.36638996 -2.03646004 0 P 0 
L 1.36638996 -2.03646004 1.36638002 -2.03648996 0 P 0 
L 1.36638002 -2.03648996 1.36638996 -2.03653002 0 P 0 
L 1.36638996 -2.03653002 1.36638996 -2.03656998 0 P 0 
L 1.36638996 -2.03656998 1.3664 -2.03663996 0 P 0 
L 1.3664 -2.03663996 1.36641998 -2.03666998 0 P 0 
L 1.36641998 -2.03666998 1.36643002 -2.03671004 0 P 0 
L 1.36643002 -2.03671004 1.36648996 -2.0368 0 P 0 
L 1.36648996 -2.0368 1.36656004 -2.03686004 0 P 0 
L 1.36656004 -2.03686004 1.3666 -2.03688996 0 P 0 
L 1.3666 -2.03688996 1.36663002 -2.03691004 0 P 0 
L 1.36663002 -2.03691004 1.36666004 -2.03691004 0 P 0 
L 1.36666004 -2.03691004 1.36671004 -2.03693002 0 P 0 
L 1.36671004 -2.03693002 1.36676998 -2.03693002 0 P 0 
L 1.36676998 -2.03693002 1.36685 -2.03691998 0 P 0 
L 1.36685 -2.03691998 1.36895 -2.03628002 0 P 0 
L 1.36895 -2.03628002 1.37143002 -2.03545 0 P 0 
L 1.37143002 -2.03545 1.37428996 -2.03441004 0 P 0 
L 1.37428996 -2.03441004 1.38346004 -2.03126998 0 P 0 
L 1.38346004 -2.03126998 1.39251998 -2.02891998 0 P 0 
L 1.39251998 -2.02891998 1.40156004 -2.02731998 0 P 0 
L 1.40156004 -2.02731998 1.41068002 -2.02643996 0 P 0 
L 1.41068002 -2.02643996 1.41566998 -2.02628002 0 P 0 
L 1.41566998 -2.02628002 1.42066004 -2.02633996 0 P 0 
L 1.42066004 -2.02633996 1.42221004 -2.02646998 0 P 0 
L 1.42221004 -2.02646998 1.42375 -2.02671998 0 P 0 
L 1.42375 -2.02671998 1.42525 -2.0271 0 P 0 
L 1.42525 -2.0271 1.42671998 -2.02761004 0 P 0 
L 1.42671998 -2.02761004 1.42706004 -2.02776004 0 P 0 
L 1.42706004 -2.02776004 1.42738002 -2.02793002 0 P 0 
L 1.42738002 -2.02793002 1.42768002 -2.02813996 0 P 0 
L 1.42768002 -2.02813996 1.42796998 -2.02836004 0 P 0 
L 1.42796998 -2.02836004 1.42823002 -2.02861004 0 P 0 
L 1.42823002 -2.02861004 1.42848002 -2.02888996 0 P 0 
L 1.42848002 -2.02888996 1.4287 -2.02918002 0 P 0 
L 1.4287 -2.02918002 1.42888996 -2.02948996 0 P 0 
L 1.42888996 -2.02948996 1.42906004 -2.02981004 0 P 0 
L 1.42906004 -2.02981004 1.4292 -2.03015 0 P 0 
L 1.4292 -2.03015 1.42931998 -2.0305 0 P 0 
L 1.42931998 -2.0305 1.4294 -2.03086004 0 P 0 
L 1.4294 -2.03086004 1.42945 -2.03121998 0 P 0 
L 1.42945 -2.03121998 1.42946998 -2.03158002 0 P 0 
L 1.42946998 -2.03158002 1.42946004 -2.03195 0 P 0 
L 1.42946004 -2.03195 1.42941998 -2.03231004 0 P 0 
L 1.42941998 -2.03231004 1.42935 -2.03266998 0 P 0 
L 1.42935 -2.03266998 1.42925 -2.03301998 0 P 0 
L 1.42925 -2.03301998 1.42911998 -2.03336004 0 P 0 
L 1.42911998 -2.03336004 1.42896004 -2.03368996 0 P 0 
L 1.42896004 -2.03368996 1.42875 -2.03405 0 P 0 
L 1.42875 -2.03405 1.42851004 -2.03438996 0 P 0 
L 1.42851004 -2.03438996 1.42825 -2.03471004 0 P 0 
L 1.42825 -2.03471004 1.42796004 -2.03501004 0 P 0 
L 1.42796004 -2.03501004 1.42765 -2.03528996 0 P 0 
L 1.42765 -2.03528996 1.42731998 -2.03553996 0 P 0 
L 1.42731998 -2.03553996 1.42696998 -2.03576004 0 P 0 
L 1.42696998 -2.03576004 1.4266 -2.03596004 0 P 0 
L 1.4266 -2.03596004 1.41951004 -2.03906004 0 P 0 
L 1.41951004 -2.03906004 1.4109 -2.04208996 0 P 0 
L 1.4109 -2.04208996 1.40178002 -2.04451998 0 P 0 
L 1.40178002 -2.04451998 1.3878 -2.04818996 0 P 0 
L 1.3878 -2.04818996 1.38176998 -2.05015 0 P 0 
L 1.38176998 -2.05015 1.3758 -2.05243002 0 P 0 
L 1.3758 -2.05243002 1.37086998 -2.0546 0 P 0 
L 1.37086998 -2.0546 1.36603996 -2.05708002 0 P 0 
L 1.36603996 -2.05708002 1.36356004 -2.05856004 0 P 0 
L 1.36356004 -2.05856004 1.36118996 -2.06023002 0 P 0 
L 1.36118996 -2.06023002 1.35895 -2.06206004 0 P 0 
L 1.35895 -2.06206004 1.35805 -2.06291004 0 P 0 
L 1.35805 -2.06291004 1.35721998 -2.06385 0 P 0 
L 1.35721998 -2.06385 1.35518996 -2.06655 0 P 0 
L 1.35518996 -2.06655 1.3532 -2.06961998 0 P 0 
L 1.3532 -2.06961998 1.35156004 -2.07263002 0 P 0 
L 1.35156004 -2.07263002 1.34951004 -2.07718002 0 P 0 
L 1.34951004 -2.07718002 1.34911004 -2.07825 0 P 0 
L 1.34911004 -2.07825 1.34878996 -2.07935 0 P 0 
L 1.34878996 -2.07935 1.34853002 -2.08046998 0 P 0 
L 1.34853002 -2.08046998 1.34825 -2.08238002 0 P 0 
L 1.34825 -2.08238002 1.34811998 -2.08431004 0 P 0 
L 1.34811998 -2.08431004 1.348 -2.09128996 0 P 0 
L 1.348 -2.09128996 1.3481 -2.09761004 0 P 0 
L 1.3481 -2.09761004 1.34823002 -2.09961004 0 P 0 
L 1.34823002 -2.09961004 1.34846998 -2.10161004 0 P 0 
L 1.34846998 -2.10161004 1.34876998 -2.10321998 0 P 0 
L 1.34876998 -2.10321998 1.3492 -2.10478996 0 P 0 
L 1.3492 -2.10478996 1.3498 -2.10648996 0 P 0 
L 1.3498 -2.10648996 1.3505 -2.10815 0 P 0 
L 1.3505 -2.10815 1.35178996 -2.11066004 0 P 0 
L 1.35178996 -2.11066004 1.35328002 -2.11305 0 P 0 
L 1.35328002 -2.11305 1.35496998 -2.1153 0 P 0 
L 1.35496998 -2.1153 1.35685 -2.1174 0 P 0 
L 1.35685 -2.1174 1.35891998 -2.11933996 0 P 0 
L 1.35891998 -2.11933996 1.36126998 -2.12121998 0 P 0 
L 1.36126998 -2.12121998 1.36373996 -2.12293002 0 P 0 
L 1.36373996 -2.12293002 1.36633002 -2.12446004 0 P 0 
L 1.36633002 -2.12446004 1.36901004 -2.1258 0 P 0 
L 1.36901004 -2.1258 1.3718 -2.12695 0 P 0 
L 1.3718 -2.12695 1.37578996 -2.12828002 0 P 0 
L 1.37578996 -2.12828002 1.37986998 -2.12928996 0 P 0 
L 1.37986998 -2.12928996 1.38401998 -2.12998996 0 P 0 
L 1.38401998 -2.12998996 1.3882 -2.13036004 0 P 0 
L 1.3882 -2.13036004 1.39443002 -2.13045 0 P 0 
L 1.39443002 -2.13045 1.40066004 -2.13006998 0 P 0 
L 1.40066004 -2.13006998 1.40685 -2.12923002 0 P 0 
L 1.40685 -2.12923002 1.41371004 -2.12801998 0 P 0 
L 1.41371004 -2.12801998 1.41583002 -2.12081004 0 P 0 
L 1.41583002 -2.12081004 1.41953996 -2.10798996 0 P 0 
L 1.41953996 -2.10798996 1.42135 -2.10126998 0 P 0 
L 1.42135 -2.10126998 1.42236998 -2.097 0 P 0 
L 1.42236998 -2.097 1.42238996 -2.09691004 0 P 0 
L 1.42238996 -2.09691004 1.4224 -2.09681998 0 P 0 
L 1.4224 -2.09681998 1.4224 -2.09673996 0 P 0 
L 1.4224 -2.09673996 1.42238002 -2.09656004 0 P 0 
L 1.42238002 -2.09656004 1.42235 -2.09648002 0 P 0 
L 1.42235 -2.09648002 1.42233002 -2.09638996 0 P 0 
L 1.42233002 -2.09638996 1.42225 -2.09623002 0 P 0 
L 1.42225 -2.09623002 1.4222 -2.09616004 0 P 0 
L 1.4222 -2.09616004 1.42213996 -2.09608996 0 P 0 
L 1.42213996 -2.09608996 1.42208996 -2.09601998 0 P 0 
L 1.42208996 -2.09601998 1.42203996 -2.09598996 0 P 0 
L 1.42203996 -2.09598996 1.42198996 -2.09595 0 P 0 
L 1.42198996 -2.09595 1.42188996 -2.09588996 0 P 0 
L 1.42188996 -2.09588996 1.42183002 -2.09586004 0 P 0 
L 1.42183002 -2.09586004 1.42178002 -2.09585 0 P 0 
L 1.42178002 -2.09585 1.42171998 -2.09583002 0 P 0 
L 1.42171998 -2.09583002 1.42166004 -2.09581998 0 P 0 
L 1.42166004 -2.09581998 1.42153996 -2.09581998 0 P 0 
L 1.42153996 -2.09581998 1.41978002 -2.09591004 0 P 0 
L 1.41978002 -2.09591004 1.41763996 -2.09615 0 P 0 
L 1.41763996 -2.09615 1.41521998 -2.09658002 0 P 0 
L 1.41521998 -2.09658002 1.4107 -2.09733002 0 P 0 
L 1.4107 -2.09733002 1.40613002 -2.09775 0 P 0 
L 1.40613002 -2.09775 1.40481004 -2.09778002 0 P 0 
L 1.40481004 -2.09778002 1.40348996 -2.09771998 0 P 0 
L 1.40348996 -2.09771998 1.40216998 -2.09756004 0 P 0 
L 1.40216998 -2.09756004 1.40086998 -2.0973 0 P 0 
L 1.40086998 -2.0973 1.39958996 -2.09695 0 P 0 
L 1.39958996 -2.09695 1.39895 -2.09671998 0 P 0 
L 1.39895 -2.09671998 1.39831998 -2.09643002 0 P 0 
L 1.39831998 -2.09643002 1.39773002 -2.0961 0 P 0 
L 1.39773002 -2.0961 1.39716004 -2.09571004 0 P 0 
L 1.39716004 -2.09571004 1.39663002 -2.09528002 0 P 0 
L 1.39663002 -2.09528002 1.39613996 -2.0948 0 P 0 
L 1.39613996 -2.0948 1.39568002 -2.09428002 0 P 0 
L 1.39568002 -2.09428002 1.39533996 -2.09381998 0 P 0 
L 1.39533996 -2.09381998 1.39505 -2.09333996 0 P 0 
L 1.39505 -2.09333996 1.39478996 -2.09281998 0 P 0 
L 1.39478996 -2.09281998 1.39456998 -2.09228996 0 P 0 
L 1.39456998 -2.09228996 1.3944 -2.09173996 0 P 0 
L 1.3944 -2.09173996 1.39428002 -2.09118996 0 P 0 
L 1.39428002 -2.09118996 1.39421004 -2.09061998 0 P 0 
L 1.39421004 -2.09061998 1.39418002 -2.09003996 0 P 0 
L 1.39418002 -2.09003996 1.39421004 -2.08943002 0 P 0 
L 1.39421004 -2.08943002 1.39428002 -2.08883002 0 P 0 
L 1.39428002 -2.08883002 1.39441004 -2.08823002 0 P 0 
L 1.39441004 -2.08823002 1.3946 -2.08765 0 P 0 
L 1.3946 -2.08765 1.39483002 -2.08708002 0 P 0 
L 1.39483002 -2.08708002 1.39511004 -2.08653996 0 P 0 
L 1.39511004 -2.08653996 1.39555 -2.08583996 0 P 0 
L 1.39555 -2.08583996 1.39603996 -2.08518002 0 P 0 
L 1.39603996 -2.08518002 1.39658002 -2.08456004 0 P 0 
L 1.39658002 -2.08456004 1.39716004 -2.08396998 0 P 0 
L 1.39716004 -2.08396998 1.39778002 -2.08343002 0 P 0 
L 1.39778002 -2.08343002 1.39878996 -2.08266998 0 P 0 
L 1.39878996 -2.08266998 1.39985 -2.08196998 0 P 0 
L 1.39985 -2.08196998 1.40096004 -2.08135 0 P 0 
L 1.40096004 -2.08135 1.40211998 -2.08081004 0 P 0 
L 1.40211998 -2.08081004 1.40503002 -2.07971004 0 P 0 
L 1.40503002 -2.07971004 1.40801998 -2.07881998 0 P 0 
L 1.40801998 -2.07881998 1.41128996 -2.07796004 0 P 0 
L 1.41128996 -2.07796004 1.41506004 -2.07691998 0 P 0 
L 1.41506004 -2.07691998 1.41871998 -2.07585 0 P 0 
L 1.41871998 -2.07585 1.42165 -2.07495 0 P 0 
L 1.42165 -2.07495 1.42791998 -2.07295 0 P 0 
L 1.42791998 -2.07295 1.42731998 -2.08241004 0 P 0 
L 1.42731998 -2.08241004 1.42701004 -2.08708002 0 P 0 
L 1.42701004 -2.08708002 1.42658002 -2.09353996 0 P 0 
L 1.42658002 -2.09353996 1.4261 -2.10055 0 P 0 
L 1.4261 -2.10055 1.42566998 -2.10706004 0 P 0 
L 1.42566998 -2.10706004 1.42525 -2.11306004 0 P 0 
L 1.42525 -2.11306004 1.42491998 -2.11851998 0 P 0 
L 1.42491998 -2.11851998 1.42466004 -2.1231 0 P 0 
L 1.42466004 -2.1231 1.42461004 -2.12471004 0 P 0 
L 1.42461004 -2.12471004 1.4246 -2.12716004 0 P 0 
L 1.4246 -2.12716004 1.47893002 -2.12716004 0 P 0 
L 1.47893002 -2.12716004 1.47893002 -2.11358002 0 P 0 
L 1.47893002 -2.11358002 1.47905 -2.10616998 0 P 0 
L 1.47905 -2.10616998 1.47943996 -2.09385 0 P 0 
L 1.47943996 -2.09385 1.48 -2.07968996 0 P 0 
L 1.48 -2.07968996 1.48066004 -2.0655 0 P 0 
L 1.48066004 -2.0655 1.4813 -2.05168996 0 P 0 
L 1.4813 -2.05168996 1.48175 -2.03873996 0 P 0 
L 1.48175 -2.03873996 1.48201998 -2.02785 0 P 0 
L 1.48201998 -2.02785 1.48191998 -2.02286004 0 P 0 
L 1.48191998 -2.02286004 1.48165 -2.01995 0 P 0 
L 1.48165 -2.01995 1.48115 -2.01708002 0 P 0 
L 1.48115 -2.01708002 1.48043996 -2.01425 0 P 0 
L 1.48043996 -2.01425 1.47951004 -2.01146998 0 P 0 
L 1.47951004 -2.01146998 1.47866998 -2.00946998 0 P 0 
L 1.47866998 -2.00946998 1.47768002 -2.00753996 0 P 0 
L 1.47768002 -2.00753996 1.47655 -2.00568002 0 P 0 
L 1.47655 -2.00568002 1.47528002 -2.00391998 0 P 0 
L 1.47528002 -2.00391998 1.47388002 -2.00225 0 P 0 
L 1.47388002 -2.00225 1.47228996 -2.00063002 0 P 0 
L 1.47228996 -2.00063002 1.4706 -1.99911998 0 P 0 
L 1.4706 -1.99911998 1.4688 -1.99773002 0 P 0 
L 1.4688 -1.99773002 1.46691004 -1.99648002 0 P 0 
L 1.46691004 -1.99648002 1.46491998 -1.99535 0 P 0 
L 1.46491998 -1.99535 1.46098996 -1.99351004 0 P 0 
L 1.46098996 -1.99351004 1.45693002 -1.99196998 0 P 0 
L 1.45693002 -1.99196998 1.45276004 -1.99076004 0 P 0 
L 1.45276004 -1.99076004 1.44953996 -1.99006004 0 P 0 
L 1.44953996 -1.99006004 1.44628996 -1.98956004 0 P 0 
L 1.44628996 -1.98956004 1.44298002 -1.98923996 0 P 0 
L 1.44298002 -1.98923996 1.42695 -1.98856998 0 P 0 
L 1.42695 -1.98856998 1.41038996 -1.98865 0 P 0 
L 1.41038996 -1.98865 1.4042 -1.98901004 0 P 0 
L 1.4042 -1.98901004 1.39798996 -1.98971998 0 P 0 
L 1.35778996 -2.11545 1.4153 -2.11545 0 P 0 
L 1.35688996 -2.11445 1.41558996 -2.11445 0 P 0 
L 1.35608002 -2.11345 1.41588002 -2.11345 0 P 0 
L 1.35533002 -2.11245 1.41616998 -2.11245 0 P 0 
L 1.35463996 -2.11145 1.41646004 -2.11145 0 P 0 
L 1.35401004 -2.11045 1.41675 -2.11045 0 P 0 
L 1.35341004 -2.10945 1.41703996 -2.10945 0 P 0 
L 1.3529 -2.10845 1.41733002 -2.10845 0 P 0 
L 1.35238002 -2.10745 1.41761998 -2.10745 0 P 0 
L 1.35195 -2.10645 1.41788002 -2.10645 0 P 0 
L 1.35155 -2.10545 1.41816004 -2.10545 0 P 0 
L 1.3512 -2.10445 1.41841998 -2.10445 0 P 0 
L 1.35091004 -2.10345 1.41868996 -2.10345 0 P 0 
L 1.35066004 -2.10245 1.41896004 -2.10245 0 P 0 
L 1.35046998 -2.10145 1.41923002 -2.10145 0 P 0 
L 1.35033996 -2.10045 1.41948996 -2.10045 0 P 0 
L 1.35021998 -2.09945 1.40141004 -2.09945 0 P 0 
L 1.35016004 -2.09845 1.39791004 -2.09845 0 P 0 
L 1.3501 -2.09745 1.39616004 -2.09745 0 P 0 
L 1.35008002 -2.09645 1.39496004 -2.09645 0 P 0 
L 1.35006998 -2.09545 1.39406004 -2.09545 0 P 0 
L 1.35005 -2.09445 1.39338002 -2.09445 0 P 0 
L 1.35003996 -2.09345 1.39288002 -2.09345 0 P 0 
L 1.35001998 -2.09245 1.39253002 -2.09245 0 P 0 
L 1.35001004 -2.09145 1.3923 -2.09145 0 P 0 
L 1.35001998 -2.09045 1.3922 -2.09045 0 P 0 
L 1.35003002 -2.08945 1.3922 -2.08945 0 P 0 
L 1.35005 -2.08845 1.39231998 -2.08845 0 P 0 
L 1.35006998 -2.08745 1.39256004 -2.08745 0 P 0 
L 1.35008002 -2.08645 1.39293002 -2.08645 0 P 0 
L 1.3501 -2.08545 1.39343002 -2.08545 0 P 0 
L 1.35011004 -2.08445 1.39408996 -2.08445 0 P 0 
L 1.39438002 -2.12845 1.3883 -2.12836004 0 P 0 
L 1.3883 -2.12836004 1.38426998 -2.128 0 P 0 
L 1.38426998 -2.128 1.38028002 -2.12733002 0 P 0 
L 1.38028002 -2.12733002 1.37635 -2.12636004 0 P 0 
L 1.37635 -2.12636004 1.37248996 -2.12508002 0 P 0 
L 1.37248996 -2.12508002 1.36983996 -2.12398002 0 P 0 
L 1.36983996 -2.12398002 1.36728996 -2.1227 0 P 0 
L 1.36728996 -2.1227 1.36481998 -2.12123996 0 P 0 
L 1.36481998 -2.12123996 1.36246004 -2.11961004 0 P 0 
L 1.36246004 -2.11961004 1.36023002 -2.11781998 0 P 0 
L 1.36023002 -2.11781998 1.35828996 -2.116 0 P 0 
L 1.35828996 -2.116 1.35651998 -2.11403002 0 P 0 
L 1.35651998 -2.11403002 1.35493002 -2.11191004 0 P 0 
L 1.35493002 -2.11191004 1.35353002 -2.10966998 0 P 0 
L 1.35353002 -2.10966998 1.35231004 -2.10731004 0 P 0 
L 1.35231004 -2.10731004 1.35166998 -2.10576998 0 P 0 
L 1.35166998 -2.10576998 1.35111004 -2.1042 0 P 0 
L 1.35111004 -2.1042 1.35071998 -2.10276004 0 P 0 
L 1.35071998 -2.10276004 1.35045 -2.1013 0 P 0 
L 1.35045 -2.1013 1.35021998 -2.09943002 0 P 0 
L 1.35021998 -2.09943002 1.3501 -2.09753002 0 P 0 
L 1.3501 -2.09753002 1.35001004 -2.09128002 0 P 0 
L 1.35001004 -2.09128002 1.35011998 -2.0844 0 P 0 
L 1.35011998 -2.0844 1.35023996 -2.08258996 0 P 0 
L 1.35023996 -2.08258996 1.3505 -2.08083996 0 P 0 
L 1.3505 -2.08083996 1.35071998 -2.07985 0 P 0 
L 1.35071998 -2.07985 1.35101004 -2.07888002 0 P 0 
L 1.35101004 -2.07888002 1.35136004 -2.07793002 0 P 0 
L 1.35136004 -2.07793002 1.35335 -2.07351998 0 P 0 
L 1.35335 -2.07351998 1.35491998 -2.07065 0 P 0 
L 1.35491998 -2.07065 1.35683002 -2.0677 0 P 0 
L 1.35683002 -2.0677 1.35876998 -2.06511004 0 P 0 
L 1.35876998 -2.06511004 1.35948996 -2.0643 0 P 0 
L 1.35948996 -2.0643 1.36026998 -2.06356004 0 P 0 
L 1.36026998 -2.06356004 1.3624 -2.06181998 0 P 0 
L 1.3624 -2.06181998 1.36465 -2.06023996 0 P 0 
L 1.36465 -2.06023996 1.36701004 -2.05883002 0 P 0 
L 1.36701004 -2.05883002 1.37173002 -2.05641004 0 P 0 
L 1.37173002 -2.05641004 1.37656004 -2.05426998 0 P 0 
L 1.37656004 -2.05426998 1.38243002 -2.05203996 0 P 0 
L 1.38243002 -2.05203996 1.38836004 -2.0501 0 P 0 
L 1.38836004 -2.0501 1.4023 -2.04645 0 P 0 
L 1.4023 -2.04645 1.41148996 -2.044 0 P 0 
L 1.41148996 -2.044 1.42016998 -2.04095 0 P 0 
L 1.42016998 -2.04095 1.42016998 -2.04093996 0 P 0 
L 1.42016998 -2.04093996 1.42021004 -2.04093996 0 P 0 
L 1.42021004 -2.04093996 1.42023996 -2.04093002 0 P 0 
L 1.42023996 -2.04093002 1.42746998 -2.03776004 0 P 0 
L 1.42746998 -2.03776004 1.42753002 -2.03773002 0 P 0 
L 1.42753002 -2.03773002 1.42796998 -2.03748996 0 P 0 
L 1.42796998 -2.03748996 1.42846004 -2.03718996 0 P 0 
L 1.42846004 -2.03718996 1.42891998 -2.03683996 0 P 0 
L 1.42891998 -2.03683996 1.42935 -2.03646004 0 P 0 
L 1.42935 -2.03646004 1.42975 -2.03603996 0 P 0 
L 1.42975 -2.03603996 1.43011004 -2.0356 0 P 0 
L 1.43011004 -2.0356 1.43016004 -2.03553002 0 P 0 
L 1.43016004 -2.03553002 1.4299 -2.03535 0 P 0 
L 1.4299 -2.03535 1.43028002 -2.03535 0 P 0 
L 1.43028002 -2.03535 1.43043996 -2.03513002 0 P 0 
L 1.43043996 -2.03513002 1.43048002 -2.03506004 0 P 0 
L 1.43048002 -2.03506004 1.43041998 -2.03501998 0 P 0 
L 1.43041998 -2.03501998 1.4305 -2.03501998 0 P 0 
L 1.4305 -2.03501998 1.43073002 -2.03463002 0 P 0 
L 1.43073002 -2.03463002 1.43096004 -2.03415 0 P 0 
L 1.43096004 -2.03415 1.43115 -2.03365 0 P 0 
L 1.43115 -2.03365 1.4313 -2.03313002 0 P 0 
L 1.4313 -2.03313002 1.4314 -2.03261004 0 P 0 
L 1.4314 -2.03261004 1.43146004 -2.03208002 0 P 0 
L 1.43146004 -2.03208002 1.43146998 -2.03155 0 P 0 
L 1.43146998 -2.03155 1.43143996 -2.03101004 0 P 0 
L 1.43143996 -2.03101004 1.43143002 -2.03093002 0 P 0 
L 1.43143002 -2.03093002 1.43136004 -2.03048996 0 P 0 
L 1.43136004 -2.03048996 1.43125 -2.02996998 0 P 0 
L 1.43125 -2.02996998 1.43108002 -2.02946004 0 P 0 
L 1.43108002 -2.02946004 1.43086998 -2.02896004 0 P 0 
L 1.43086998 -2.02896004 1.43063002 -2.02848996 0 P 0 
L 1.43063002 -2.02848996 1.43033996 -2.02803996 0 P 0 
L 1.43033996 -2.02803996 1.43001998 -2.02761004 0 P 0 
L 1.43001998 -2.02761004 1.42966004 -2.02721004 0 P 0 
L 1.42966004 -2.02721004 1.42928002 -2.02685 0 P 0 
L 1.42928002 -2.02685 1.42886004 -2.02651998 0 P 0 
L 1.42886004 -2.02651998 1.42841998 -2.02623002 0 P 0 
L 1.42841998 -2.02623002 1.42795 -2.02596998 0 P 0 
L 1.42795 -2.02596998 1.42746004 -2.02575 0 P 0 
L 1.42746004 -2.02575 1.42583002 -2.02518002 0 P 0 
L 1.42583002 -2.02518002 1.42416004 -2.02476004 0 P 0 
L 1.42416004 -2.02476004 1.42245 -2.02448002 0 P 0 
L 1.42245 -2.02448002 1.42075 -2.02435 0 P 0 
L 1.42075 -2.02435 1.41565 -2.02428002 0 P 0 
L 1.41565 -2.02428002 1.4156 -2.02428002 0 P 0 
L 1.4156 -2.02428002 1.41055 -2.02445 0 P 0 
L 1.41055 -2.02445 1.41048002 -2.02445 0 P 0 
L 1.41048002 -2.02445 1.40128996 -2.02533996 0 P 0 
L 1.40128996 -2.02533996 1.39208996 -2.02696998 0 P 0 
L 1.39208996 -2.02696998 1.38288002 -2.02936004 0 P 0 
L 1.38288002 -2.02936004 1.37363002 -2.03251998 0 P 0 
L 1.37363002 -2.03251998 1.37076998 -2.03356004 0 P 0 
L 1.37076998 -2.03356004 1.36865 -2.03426998 0 P 0 
L 1.36865 -2.03426998 1.36906004 -2.03066998 0 P 0 
L 1.36906004 -2.03066998 1.36988996 -2.02383996 0 P 0 
L 1.36988996 -2.02383996 1.37095 -2.01581004 0 P 0 
L 1.37095 -2.01581004 1.37358996 -1.99631998 0 P 0 
L 1.37358996 -1.99631998 1.37988002 -1.99491998 0 P 0 
L 1.37988002 -1.99491998 1.38353996 -1.99416998 0 P 0 
L 1.38353996 -1.99416998 1.38841998 -1.99326998 0 P 0 
L 1.38841998 -1.99326998 1.39358002 -1.9924 0 P 0 
L 1.39358002 -1.9924 1.39825 -1.9917 0 P 0 
L 1.39825 -1.9917 1.40436998 -1.991 0 P 0 
L 1.40436998 -1.991 1.41045 -1.99065 0 P 0 
L 1.41045 -1.99065 1.42691004 -1.99056998 0 P 0 
L 1.42691004 -1.99056998 1.44283996 -1.99123996 0 P 0 
L 1.44283996 -1.99123996 1.44603996 -1.99153996 0 P 0 
L 1.44603996 -1.99153996 1.44918002 -1.99203002 0 P 0 
L 1.44918002 -1.99203002 1.45226004 -1.9927 0 P 0 
L 1.45226004 -1.9927 1.4563 -1.99386998 0 P 0 
L 1.4563 -1.99386998 1.46021004 -1.99535 0 P 0 
L 1.46021004 -1.99535 1.464 -1.99713002 0 P 0 
L 1.464 -1.99713002 1.46586004 -1.99818996 0 P 0 
L 1.46586004 -1.99818996 1.46763996 -1.99936004 0 P 0 
L 1.46763996 -1.99936004 1.46931998 -2.00066004 0 P 0 
L 1.46931998 -2.00066004 1.47091004 -2.00206998 0 P 0 
L 1.47091004 -2.00206998 1.47238996 -2.00358996 0 P 0 
L 1.47238996 -2.00358996 1.4737 -2.00515 0 P 0 
L 1.4737 -2.00515 1.47488002 -2.00678996 0 P 0 
L 1.47488002 -2.00678996 1.47593996 -2.00851004 0 P 0 
L 1.47593996 -2.00851004 1.47686004 -2.01031004 0 P 0 
L 1.47686004 -2.01031004 1.47763996 -2.01216998 0 P 0 
L 1.47763996 -2.01216998 1.47851998 -2.01481004 0 P 0 
L 1.47851998 -2.01481004 1.47918996 -2.01748996 0 P 0 
L 1.47918996 -2.01748996 1.47966004 -2.02021998 0 P 0 
L 1.47966004 -2.02021998 1.47993002 -2.02296998 0 P 0 
L 1.47993002 -2.02296998 1.48001998 -2.02783996 0 P 0 
L 1.48001998 -2.02783996 1.47975 -2.03868996 0 P 0 
L 1.47975 -2.03868996 1.4793 -2.05161004 0 P 0 
L 1.4793 -2.05161004 1.47866004 -2.06543002 0 P 0 
L 1.47866004 -2.06543002 1.47801004 -2.07961004 0 P 0 
L 1.47801004 -2.07961004 1.47743996 -2.09378996 0 P 0 
L 1.47743996 -2.09378996 1.47705 -2.10613002 0 P 0 
L 1.47705 -2.10613002 1.47693002 -2.11356004 0 P 0 
L 1.47693002 -2.11356004 1.47693002 -2.12516004 0 P 0 
L 1.47693002 -2.12516004 1.42661004 -2.12516004 0 P 0 
L 1.42661004 -2.12516004 1.42661004 -2.12473996 0 P 0 
L 1.42661004 -2.12473996 1.42666004 -2.12318002 0 P 0 
L 1.42666004 -2.12318002 1.42691004 -2.11863996 0 P 0 
L 1.42691004 -2.11863996 1.42725 -2.1132 0 P 0 
L 1.42725 -2.1132 1.42766004 -2.1072 0 P 0 
L 1.42766004 -2.1072 1.42766004 -2.10718996 0 P 0 
L 1.42766004 -2.10718996 1.4281 -2.10068996 0 P 0 
L 1.4281 -2.10068996 1.42858002 -2.09368002 0 P 0 
L 1.42858002 -2.09368002 1.42901004 -2.08721004 0 P 0 
L 1.42901004 -2.08721004 1.42901004 -2.0872 0 P 0 
L 1.42901004 -2.0872 1.42931004 -2.08256004 0 P 0 
L 1.42931004 -2.08256004 1.42991998 -2.07308002 0 P 0 
L 1.42991998 -2.07308002 1.42916004 -2.07136998 0 P 0 
L 1.42916004 -2.07136998 1.42731998 -2.07105 0 P 0 
L 1.42731998 -2.07105 1.42105 -2.07303996 0 P 0 
L 1.42105 -2.07303996 1.41815 -2.07393002 0 P 0 
L 1.41815 -2.07393002 1.41451004 -2.075 0 P 0 
L 1.41451004 -2.075 1.41076004 -2.07603002 0 P 0 
L 1.41076004 -2.07603002 1.40748002 -2.0769 0 P 0 
L 1.40748002 -2.0769 1.40438996 -2.07781004 0 P 0 
L 1.40438996 -2.07781004 1.40431998 -2.07783996 0 P 0 
L 1.40431998 -2.07783996 1.40133996 -2.07896998 0 P 0 
L 1.40133996 -2.07896998 1.40005 -2.07956998 0 P 0 
L 1.40005 -2.07956998 1.39881998 -2.08026004 0 P 0 
L 1.39881998 -2.08026004 1.39763996 -2.08103002 0 P 0 
L 1.39763996 -2.08103002 1.39651998 -2.08188002 0 P 0 
L 1.39651998 -2.08188002 1.39578996 -2.08251004 0 P 0 
L 1.39578996 -2.08251004 1.39573996 -2.08256004 0 P 0 
L 1.39573996 -2.08256004 1.3951 -2.08318996 0 P 0 
L 1.3951 -2.08318996 1.39446998 -2.08393002 0 P 0 
L 1.39446998 -2.08393002 1.3939 -2.08471004 0 P 0 
L 1.3939 -2.08471004 1.39336998 -2.08553996 0 P 0 
L 1.39336998 -2.08553996 1.39301004 -2.08623996 0 P 0 
L 1.39301004 -2.08623996 1.39271004 -2.08696998 0 P 0 
L 1.39271004 -2.08696998 1.39248002 -2.08771998 0 P 0 
L 1.39248002 -2.08771998 1.39231004 -2.08848996 0 P 0 
L 1.39231004 -2.08848996 1.39221004 -2.08926004 0 P 0 
L 1.39221004 -2.08926004 1.39218002 -2.09003996 0 P 0 
L 1.39218002 -2.09003996 1.39221004 -2.0908 0 P 0 
L 1.39221004 -2.0908 1.39231004 -2.09153002 0 P 0 
L 1.39231004 -2.09153002 1.39246998 -2.09226004 0 P 0 
L 1.39246998 -2.09226004 1.39268996 -2.09296998 0 P 0 
L 1.39268996 -2.09296998 1.39296004 -2.09365 0 P 0 
L 1.39296004 -2.09365 1.3933 -2.09431004 0 P 0 
L 1.3933 -2.09431004 1.39368996 -2.09493996 0 P 0 
L 1.39368996 -2.09493996 1.39411998 -2.09553996 0 P 0 
L 1.39411998 -2.09553996 1.39468996 -2.09618002 0 P 0 
L 1.39468996 -2.09618002 1.3953 -2.09678002 0 P 0 
L 1.3953 -2.09678002 1.39596004 -2.09731998 0 P 0 
L 1.39596004 -2.09731998 1.39666998 -2.0978 0 P 0 
L 1.39666998 -2.0978 1.39673996 -2.09783996 0 P 0 
L 1.39673996 -2.09783996 1.39741004 -2.09821998 0 P 0 
L 1.39741004 -2.09821998 1.39748996 -2.09825 0 P 0 
L 1.39748996 -2.09825 1.39818996 -2.09856998 0 P 0 
L 1.39818996 -2.09856998 1.39898996 -2.09886004 0 P 0 
L 1.39898996 -2.09886004 1.39906998 -2.09888002 0 P 0 
L 1.39906998 -2.09888002 1.40043996 -2.09888002 0 P 0 
L 1.40043996 -2.09888002 1.40033996 -2.09923002 0 P 0 
L 1.40033996 -2.09923002 1.40041998 -2.09925 0 P 0 
L 1.40041998 -2.09925 1.40186004 -2.09953002 0 P 0 
L 1.40186004 -2.09953002 1.40331004 -2.09971004 0 P 0 
L 1.40331004 -2.09971004 1.40478002 -2.09978002 0 P 0 
L 1.40478002 -2.09978002 1.40625 -2.09975 0 P 0 
L 1.40625 -2.09975 1.41096004 -2.09931004 0 P 0 
L 1.41096004 -2.09931004 1.41556998 -2.09855 0 P 0 
L 1.41556998 -2.09855 1.41791998 -2.09813002 0 P 0 
L 1.41791998 -2.09813002 1.41995 -2.09791004 0 P 0 
L 1.41995 -2.09791004 1.4201 -2.0979 0 P 0 
L 1.4201 -2.0979 1.41941004 -2.10078002 0 P 0 
L 1.41941004 -2.10078002 1.41761004 -2.10745 0 P 0 
L 1.41761004 -2.10745 1.41391004 -2.12025 0 P 0 
L 1.41391004 -2.12025 1.41215 -2.12626998 0 P 0 
L 1.41215 -2.12626998 1.40655 -2.12725 0 P 0 
L 1.40655 -2.12725 1.40046004 -2.12808002 0 P 0 
L 1.40046004 -2.12808002 1.39438002 -2.12845 0 P 0 
L 1.15303002 -2.08283002 1.20788996 -2.08283002 0 P 0 
L 1.15398996 -2.08183002 1.20795 -2.08183002 0 P 0 
L 1.15483002 -2.08083002 1.208 -2.08083002 0 P 0 
L 1.15555 -2.07983002 1.20805 -2.07983002 0 P 0 
L 1.15621998 -2.07883002 1.2081 -2.07883002 0 P 0 
L 1.15681998 -2.07783002 1.20816004 -2.07783002 0 P 0 
L 1.15733002 -2.07683002 1.20821004 -2.07683002 0 P 0 
L 1.15778996 -2.07583002 1.20826004 -2.07583002 0 P 0 
L 1.15818002 -2.07483002 1.20831004 -2.07483002 0 P 0 
L 1.15853996 -2.07383002 1.20836998 -2.07383002 0 P 0 
L 1.15881998 -2.07283002 1.20841998 -2.07283002 0 P 0 
L 1.1591 -2.07183002 1.20846998 -2.07183002 0 P 0 
L 1.15938002 -2.07083002 1.20853002 -2.07083002 0 P 0 
L 1.1596 -2.06983002 1.20858002 -2.06983002 0 P 0 
L 1.15981004 -2.06883002 1.20863996 -2.06883002 0 P 0 
L 1.16001004 -2.06783002 1.20868996 -2.06783002 0 P 0 
L 1.1602 -2.06683002 1.20875 -2.06683002 0 P 0 
L 1.16033996 -2.06583002 1.2088 -2.06583002 0 P 0 
L 1.16048996 -2.06483002 1.20886004 -2.06483002 0 P 0 
L 1.16063996 -2.06383002 1.20891998 -2.06383002 0 P 0 
L 1.16078002 -2.06283002 1.20896998 -2.06283002 0 P 0 
L 1.16088996 -2.06183002 1.20903002 -2.06183002 0 P 0 
L 1.16098996 -2.06083002 1.20908002 -2.06083002 0 P 0 
L 1.16108996 -2.05983002 1.20913996 -2.05983002 0 P 0 
L 1.16118002 -2.05883002 1.20918996 -2.05883002 0 P 0 
L 1.16128002 -2.05783002 1.20925 -2.05783002 0 P 0 
L 1.16133996 -2.05683002 1.2093 -2.05683002 0 P 0 
L 1.1614 -2.05583002 1.20936004 -2.05583002 0 P 0 
L 1.16146004 -2.05483002 1.20941004 -2.05483002 0 P 0 
L 1.16151998 -2.05383002 1.20946998 -2.05383002 0 P 0 
L 1.16158002 -2.05283002 1.20951998 -2.05283002 0 P 0 
L 1.16163996 -2.05183002 1.20958002 -2.05183002 0 P 0 
L 1.1617 -2.05083002 1.20963996 -2.05083002 0 P 0 
L 1.16175 -2.04983002 1.2097 -2.04983002 0 P 0 
L 1.16181004 -2.04883002 1.20975 -2.04883002 0 P 0 
L 1.16186998 -2.04783002 1.20981004 -2.04783002 0 P 0 
L 1.16193002 -2.04683002 1.20986998 -2.04683002 0 P 0 
L 1.16198996 -2.04583002 1.20993002 -2.04583002 0 P 0 
L 1.16205 -2.04483002 1.20998996 -2.04483002 0 P 0 
L 1.16211004 -2.04383002 1.21005 -2.04383002 0 P 0 
L 1.16215 -2.04283002 1.2101 -2.04283002 0 P 0 
L 1.1622 -2.04183002 1.21016004 -2.04183002 0 P 0 
L 1.16225 -2.04083002 1.21021998 -2.04083002 0 P 0 
L 1.16228996 -2.03983002 1.21028002 -2.03983002 0 P 0 
L 1.16233996 -2.03883002 1.21033996 -2.03883002 0 P 0 
L 1.16238002 -2.03783002 1.2104 -2.03783002 0 P 0 
L 1.16243002 -2.03683002 1.21046004 -2.03683002 0 P 0 
L 1.16246998 -2.03583002 1.21051004 -2.03583002 0 P 0 
L 1.16251998 -2.03483002 1.21056998 -2.03483002 0 P 0 
L 1.16256998 -2.03383002 1.21063996 -2.03383002 0 P 0 
L 1.16261004 -2.03283002 1.2107 -2.03283002 0 P 0 
L 1.16266004 -2.03183002 1.21076004 -2.03183002 0 P 0 
L 1.1627 -2.03083002 1.21083002 -2.03083002 0 P 0 
L 1.16015 -1.97631004 1.17066004 -1.97631004 0 P 0 
L 1.15961998 -1.97531004 1.17026004 -1.97531004 0 P 0 
L 1.1591 -1.97431004 1.16986998 -1.97431004 0 P 0 
L 1.15856998 -1.97331004 1.16946998 -1.97331004 0 P 0 
L 1.15803996 -1.97231004 1.16903002 -1.97231004 0 P 0 
L 1.15746998 -1.97131004 1.16858996 -1.97131004 0 P 0 
L 1.1569 -1.97031004 1.16815 -1.97031004 0 P 0 
L 1.15631998 -1.96931004 1.16771004 -1.96931004 0 P 0 
L 1.15573996 -1.96831004 1.16726998 -1.96831004 0 P 0 
L 1.15516004 -1.96731004 1.16681998 -1.96731004 0 P 0 
L 1.15458996 -1.96631004 1.16638002 -1.96631004 0 P 0 
L 1.15398002 -1.96531004 1.16593996 -1.96531004 0 P 0 
L 1.1533 -1.96431004 1.16548996 -1.96431004 0 P 0 
L 1.15261998 -1.96331004 1.16503002 -1.96331004 0 P 0 
L 1.15193996 -1.96231004 1.16448002 -1.96231004 0 P 0 
L 1.15126004 -1.96131004 1.16393002 -1.96131004 0 P 0 
L 1.15058002 -1.96031004 1.16338002 -1.96031004 0 P 0 
L 1.1499 -1.95931004 1.16283002 -1.95931004 0 P 0 
L 1.1491 -1.95831004 1.16228996 -1.95831004 0 P 0 
L 1.14831004 -1.95731004 1.16173996 -1.95731004 0 P 0 
L 1.14751004 -1.95631004 1.16118996 -1.95631004 0 P 0 
L 1.14671004 -1.95531004 1.16063996 -1.95531004 0 P 0 
L 1.14591998 -1.95431004 1.16008996 -1.95431004 0 P 0 
L 1.14511998 -1.95331004 1.15943996 -1.95331004 0 P 0 
L 1.1442 -1.95231004 1.15878002 -1.95231004 0 P 0 
L 1.14326998 -1.95131004 1.15811004 -1.95131004 0 P 0 
L 1.14233996 -1.95031004 1.15745 -1.95031004 0 P 0 
L 1.14141004 -1.94931004 1.15678002 -1.94931004 0 P 0 
L 1.14048996 -1.94831004 1.15611998 -1.94831004 0 P 0 
L 1.1395 -1.94731004 1.15545 -1.94731004 0 P 0 
L 1.13843002 -1.94631004 1.15478996 -1.94631004 0 P 0 
L 1.13736004 -1.94531004 1.15411998 -1.94531004 0 P 0 
L 1.13628996 -1.94431004 1.15333002 -1.94431004 0 P 0 
L 1.13521004 -1.94331004 1.15253002 -1.94331004 0 P 0 
L 1.13413996 -1.94231004 1.15173996 -1.94231004 0 P 0 
L 1.13306998 -1.94131004 1.15093996 -1.94131004 0 P 0 
L 1.132 -1.94031004 1.15013996 -1.94031004 0 P 0 
L 1.13081004 -1.93931004 1.14935 -1.93931004 0 P 0 
L 1.12958002 -1.93831004 1.14855 -1.93831004 0 P 0 
L 1.12833996 -1.93731004 1.14775 -1.93731004 0 P 0 
L 1.1271 -1.93631004 1.14688996 -1.93631004 0 P 0 
L 1.12586004 -1.93531004 1.14593996 -1.93531004 0 P 0 
L 1.12461998 -1.93431004 1.14498996 -1.93431004 0 P 0 
L 1.12338002 -1.93331004 1.14405 -1.93331004 0 P 0 
L 1.12203002 -1.93231004 1.1431 -1.93231004 0 P 0 
L 1.1206 -1.93131004 1.14216004 -1.93131004 0 P 0 
L 1.11916004 -1.93031004 1.14121004 -1.93031004 0 P 0 
L 1.11771998 -1.92931004 1.14026998 -1.92931004 0 P 0 
L 1.11628996 -1.92831004 1.13931998 -1.92831004 0 P 0 
L 1.11483996 -1.92731004 1.13838002 -1.92731004 0 P 0 
L 1.11338996 -1.92631004 1.13743002 -1.92631004 0 P 0 
L 1.11171998 -1.92531004 1.13648996 -1.92531004 0 P 0 
L 1.11005 -1.92431004 1.13538002 -1.92431004 0 P 0 
L 1.10838002 -1.92331004 1.13426998 -1.92331004 0 P 0 
L 1.1067 -1.92231004 1.13315 -1.92231004 0 P 0 
L 1.10503002 -1.92131004 1.13203002 -1.92131004 0 P 0 
L 1.10336004 -1.92031004 1.13091998 -1.92031004 0 P 0 
L 1.1015 -1.91931004 1.1298 -1.91931004 0 P 0 
L 1.09955 -1.91831004 1.12868002 -1.91831004 0 P 0 
L 1.16275 -2.02983002 1.21088996 -2.02983002 0 P 0 
L 1.16278996 -2.02883002 1.21095 -2.02883002 0 P 0 
L 1.16283996 -2.02783002 1.21101004 -2.02783002 0 P 0 
L 1.16226998 -2.02683002 1.21108002 -2.02683002 0 P 0 
L 1.16153996 -2.02583002 1.21113996 -2.02583002 0 P 0 
L 1.15846004 -2.02483002 1.2112 -2.02483002 0 P 0 
L 1.10036004 -2.00383002 1.21255 -2.00383002 0 P 0 
L 1.10226004 -2.00283002 1.2126 -2.00283002 0 P 0 
L 1.10433996 -2.00183002 1.21266998 -2.00183002 0 P 0 
L 1.1065 -2.00083002 1.21273002 -2.00083002 0 P 0 
L 1.10886998 -1.99983002 1.21278996 -1.99983002 0 P 0 
L 1.11138002 -1.99883002 1.21285 -1.99883002 0 P 0 
L 1.11436998 -1.99783002 1.21288002 -1.99783002 0 P 0 
L 1.11748996 -1.99683002 1.21255 -1.99683002 0 P 0 
L 1.12061998 -1.99583002 1.2089 -1.99583002 0 P 0 
L 1.12433996 -1.99483002 1.2036 -1.99483002 0 P 0 
L 1.12863996 -1.99383002 1.19728002 -1.99383002 0 P 0 
L 1.13295 -1.99283002 1.19096998 -1.99283002 0 P 0 
L 1.13985 -1.99183002 1.18111998 -1.99183002 0 P 0 
L 1.14948002 -1.99083002 1.1651 -1.99083002 0 P 0 
L 1.24218002 -2.08316004 1.29143996 -2.08316004 0 P 0 
L 1.24223002 -2.08216004 1.29151004 -2.08216004 0 P 0 
L 1.24228002 -2.08116004 1.29158996 -2.08116004 0 P 0 
L 1.24233996 -2.08016004 1.29166004 -2.08016004 0 P 0 
L 1.24238996 -2.07916004 1.29173002 -2.07916004 0 P 0 
L 1.24245 -2.07816004 1.29181004 -2.07816004 0 P 0 
L 1.2425 -2.07716004 1.29188002 -2.07716004 0 P 0 
L 1.24256004 -2.07616004 1.29195 -2.07616004 0 P 0 
L 1.24261004 -2.07516004 1.29203002 -2.07516004 0 P 0 
L 1.24266998 -2.07416004 1.2921 -2.07416004 0 P 0 
L 1.24271998 -2.07316004 1.29216998 -2.07316004 0 P 0 
L 1.24278002 -2.07216004 1.29223996 -2.07216004 0 P 0 
L 1.24283002 -2.07116004 1.29231998 -2.07116004 0 P 0 
L 1.24288002 -2.07016004 1.29238996 -2.07016004 0 P 0 
L 1.24293002 -2.06916004 1.29246004 -2.06916004 0 P 0 
L 1.24296998 -2.06816004 1.29253002 -2.06816004 0 P 0 
L 1.24301998 -2.06716004 1.29261004 -2.06716004 0 P 0 
L 1.24306004 -2.06616004 1.2927 -2.06616004 0 P 0 
L 1.24311004 -2.06516004 1.29281004 -2.06516004 0 P 0 
L 1.24315 -2.06416004 1.29291998 -2.06416004 0 P 0 
L 1.2432 -2.06316004 1.29303002 -2.06316004 0 P 0 
L 1.24323996 -2.06216004 1.29315 -2.06216004 0 P 0 
L 1.24328996 -2.06116004 1.29331998 -2.06116004 0 P 0 
L 1.24333002 -2.06016004 1.2935 -2.06016004 0 P 0 
L 1.24338002 -2.05916004 1.29366998 -2.05916004 0 P 0 
L 1.24341998 -2.05816004 1.29385 -2.05816004 0 P 0 
L 1.24346998 -2.05716004 1.29408996 -2.05716004 0 P 0 
L 1.24351004 -2.05616004 1.29433996 -2.05616004 0 P 0 
L 1.24355 -2.05516004 1.29458996 -2.05516004 0 P 0 
L 1.2436 -2.05416004 1.29485 -2.05416004 0 P 0 
L 1.24363996 -2.05316004 1.29516998 -2.05316004 0 P 0 
L 1.24368996 -2.05216004 1.29551998 -2.05216004 0 P 0 
L 1.24373002 -2.05116004 1.29586004 -2.05116004 0 P 0 
L 1.24378002 -2.05016004 1.29621004 -2.05016004 0 P 0 
L 1.24383002 -2.04916004 1.29663996 -2.04916004 0 P 0 
L 1.24386998 -2.04816004 1.29708002 -2.04816004 0 P 0 
L 1.24391004 -2.04716004 1.29753002 -2.04716004 0 P 0 
L 1.24396004 -2.04616004 1.29796998 -2.04616004 0 P 0 
L 1.244 -2.04516004 1.29851004 -2.04516004 0 P 0 
L 1.24405 -2.04416004 1.2991 -2.04416004 0 P 0 
L 1.24408996 -2.04316004 1.29975 -2.04316004 0 P 0 
L 1.24413996 -2.04216004 1.3005 -2.04216004 0 P 0 
L 1.24418002 -2.04116004 1.30131998 -2.04116004 0 P 0 
L 1.24423002 -2.04016004 1.30223002 -2.04016004 0 P 0 
L 1.24426998 -2.03916004 1.30326998 -2.03916004 0 P 0 
L 1.24431998 -2.03816004 1.30446004 -2.03816004 0 P 0 
L 1.24436004 -2.03716004 1.30581998 -2.03716004 0 P 0 
L 1.24441004 -2.03616004 1.30738002 -2.03616004 0 P 0 
L 1.24445 -2.03516004 1.30923002 -2.03516004 0 P 0 
L 1.24448996 -2.03416004 1.31156004 -2.03416004 0 P 0 
L 1.24453996 -2.03316004 1.31478996 -2.03316004 0 P 0 
L 1.24458996 -2.03216004 1.32013002 -2.03216004 0 P 0 
L 1.24461998 -2.03116004 1.33481004 -2.03116004 0 P 0 
L 1.24463996 -2.03016004 1.33478002 -2.03016004 0 P 0 
L 1.24466004 -2.02916004 1.33473996 -2.02916004 0 P 0 
L 1.24468002 -2.02816004 1.33471004 -2.02816004 0 P 0 
L 1.2447 -2.02716004 1.33468002 -2.02716004 0 P 0 
L 1.24471998 -2.02616004 1.33463996 -2.02616004 0 P 0 
L 1.24473996 -2.02516004 1.3346 -2.02516004 0 P 0 
L 1.24476004 -2.02416004 1.33456998 -2.02416004 0 P 0 
L 1.24478002 -2.02316004 1.33453002 -2.02316004 0 P 0 
L 1.2448 -2.02216004 1.3345 -2.02216004 0 P 0 
L 1.24481998 -2.02116004 1.33446998 -2.02116004 0 P 0 
L 1.24483996 -2.02016004 1.33443002 -2.02016004 0 P 0 
L 1.24486004 -2.01916004 1.3344 -2.01916004 0 P 0 
L 1.24488002 -2.01816004 1.33436004 -2.01816004 0 P 0 
L 1.2449 -2.01716004 1.33433002 -2.01716004 0 P 0 
L 1.24491998 -2.01616004 1.33428996 -2.01616004 0 P 0 
L 1.24493996 -2.01516004 1.33426004 -2.01516004 0 P 0 
L 1.24496004 -2.01416004 1.33421998 -2.01416004 0 P 0 
L 1.24498002 -2.01316004 1.33418996 -2.01316004 0 P 0 
L 1.245 -2.01216004 1.33415 -2.01216004 0 P 0 
L 1.24501998 -2.01116004 1.33411998 -2.01116004 0 P 0 
L 1.24503996 -2.01016004 1.33408002 -2.01016004 0 P 0 
L 1.24506004 -2.00916004 1.33403996 -2.00916004 0 P 0 
L 1.24508002 -2.00816004 1.334 -2.00816004 0 P 0 
L 1.2451 -2.00716004 1.33396004 -2.00716004 0 P 0 
L 1.24511998 -2.00616004 1.33393002 -2.00616004 0 P 0 
L 1.24513996 -2.00516004 1.29098996 -2.00516004 0 P 0 
L 1.24513996 -2.00416004 1.29033002 -2.00416004 0 P 0 
L 1.24513996 -2.00316004 1.29005 -2.00316004 0 P 0 
L 1.24513996 -2.00216004 1.29005 -2.00216004 0 P 0 
L 1.24513996 -2.00116004 1.29005 -2.00116004 0 P 0 
L 1.24515 -2.00016004 1.29005 -2.00016004 0 P 0 
L 1.24515 -1.99916004 1.29005 -1.99916004 0 P 0 
L 1.24515 -1.99816004 1.29005 -1.99816004 0 P 0 
L 1.24515 -1.99716004 1.29005 -1.99716004 0 P 0 
L 1.24515 -1.99616004 1.29005 -1.99616004 0 P 0 
L 1.24515 -1.99516004 1.29005 -1.99516004 0 P 0 
L 1.16085 -2.02753002 1.1601 -2.04393002 0 P 0 
L 1.1601 -2.04393002 1.15928996 -2.05771998 0 P 0 
L 1.15928996 -2.05771998 1.15883996 -2.06228002 0 P 0 
L 1.15883996 -2.06228002 1.15818002 -2.06681998 0 P 0 
L 1.15818002 -2.06681998 1.15751004 -2.07006998 0 P 0 
L 1.15751004 -2.07006998 1.15661004 -2.07328996 0 P 0 
L 1.15661004 -2.07328996 1.15616004 -2.07453996 0 P 0 
L 1.15616004 -2.07453996 1.15563002 -2.07576998 0 P 0 
L 1.15563002 -2.07576998 1.15501998 -2.07696004 0 P 0 
L 1.15501998 -2.07696004 1.15433002 -2.0781 0 P 0 
L 1.15433002 -2.0781 1.1534 -2.07941998 0 P 0 
L 1.1534 -2.07941998 1.15236004 -2.08066004 0 P 0 
L 1.15236004 -2.08066004 1.15123002 -2.08181998 0 P 0 
L 1.15123002 -2.08181998 1.15001004 -2.08286998 0 P 0 
L 1.15001004 -2.08286998 1.14871004 -2.08383002 0 P 0 
L 1.14871004 -2.08383002 1.14733002 -2.08468002 0 P 0 
L 1.14733002 -2.08468002 1.14591004 -2.0854 0 P 0 
L 1.14591004 -2.0854 1.14443996 -2.086 0 P 0 
L 1.14443996 -2.086 1.14291004 -2.08648002 0 P 0 
L 1.14291004 -2.08648002 1.14136004 -2.08683002 0 P 0 
L 1.14136004 -2.08683002 1.13976998 -2.08703996 0 P 0 
L 1.13976998 -2.08703996 1.13816004 -2.08713002 0 P 0 
L 1.13816004 -2.08713002 1.13656998 -2.08708002 0 P 0 
L 1.13656998 -2.08708002 1.13498996 -2.0869 0 P 0 
L 1.13498996 -2.0869 1.13341998 -2.08658996 0 P 0 
L 1.13341998 -2.08658996 1.13188996 -2.08615 0 P 0 
L 1.13188996 -2.08615 1.1304 -2.08558996 0 P 0 
L 1.1304 -2.08558996 1.12895 -2.08488996 0 P 0 
L 1.12895 -2.08488996 1.12756998 -2.08408002 0 P 0 
L 1.12756998 -2.08408002 1.12625 -2.08315 0 P 0 
L 1.12625 -2.08315 1.12501004 -2.08211998 0 P 0 
L 1.12501004 -2.08211998 1.12386004 -2.081 0 P 0 
L 1.12386004 -2.081 1.12281004 -2.07978002 0 P 0 
L 1.12281004 -2.07978002 1.12183996 -2.07846998 0 P 0 
L 1.12183996 -2.07846998 1.1211 -2.07726004 0 P 0 
L 1.1211 -2.07726004 1.12046998 -2.07598996 0 P 0 
L 1.12046998 -2.07598996 1.11996004 -2.07466998 0 P 0 
L 1.11996004 -2.07466998 1.11955 -2.07331004 0 P 0 
L 1.11955 -2.07331004 1.11926998 -2.07191004 0 P 0 
L 1.11926998 -2.07191004 1.11868002 -2.06693996 0 P 0 
L 1.11868002 -2.06693996 1.11848002 -2.06191004 0 P 0 
L 1.11848002 -2.06191004 1.11871004 -2.05668002 0 P 0 
L 1.11871004 -2.05668002 1.11936004 -2.05148002 0 P 0 
L 1.11936004 -2.05148002 1.11978996 -2.04936998 0 P 0 
L 1.11978996 -2.04936998 1.12036998 -2.0473 0 P 0 
L 1.12036998 -2.0473 1.12108996 -2.04528002 0 P 0 
L 1.12108996 -2.04528002 1.12196004 -2.04331998 0 P 0 
L 1.12196004 -2.04331998 1.1229 -2.04153996 0 P 0 
L 1.1229 -2.04153996 1.12396998 -2.03985 0 P 0 
L 1.12396998 -2.03985 1.12516998 -2.03823002 0 P 0 
L 1.12516998 -2.03823002 1.12735 -2.03573996 0 P 0 
L 1.12735 -2.03573996 1.12973002 -2.03345 0 P 0 
L 1.12973002 -2.03345 1.13223996 -2.03141998 0 P 0 
L 1.13223996 -2.03141998 1.13491998 -2.02961004 0 P 0 
L 1.13491998 -2.02961004 1.13611004 -2.02893002 0 P 0 
L 1.13611004 -2.02893002 1.13735 -2.02833996 0 P 0 
L 1.13735 -2.02833996 1.13861998 -2.02781998 0 P 0 
L 1.13861998 -2.02781998 1.13993996 -2.0274 0 P 0 
L 1.13993996 -2.0274 1.14191004 -2.02693002 0 P 0 
L 1.14191004 -2.02693002 1.14391004 -2.02663002 0 P 0 
L 1.14391004 -2.02663002 1.14935 -2.02626004 0 P 0 
L 1.14935 -2.02626004 1.15471004 -2.0263 0 P 0 
L 1.15471004 -2.0263 1.15591004 -2.02638996 0 P 0 
L 1.15591004 -2.02638996 1.1571 -2.02656998 0 P 0 
L 1.1571 -2.02656998 1.15828002 -2.02683996 0 P 0 
L 1.15828002 -2.02683996 1.16085 -2.02753002 0 P 0 
L 1.13876998 -2.14783002 1.20233002 -2.14783002 0 P 0 
L 1.14236998 -2.14683002 1.20266004 -2.14683002 0 P 0 
L 1.14481004 -2.14583002 1.20296004 -2.14583002 0 P 0 
L 1.1467 -2.14483002 1.20325 -2.14483002 0 P 0 
L 1.14826004 -2.14383002 1.20353002 -2.14383002 0 P 0 
L 1.1496 -2.14283002 1.20373996 -2.14283002 0 P 0 
L 1.15078996 -2.14183002 1.20395 -2.14183002 0 P 0 
L 1.15186004 -2.14083002 1.20415 -2.14083002 0 P 0 
L 1.15278996 -2.13983002 1.20431998 -2.13983002 0 P 0 
L 1.15361998 -2.13883002 1.20446004 -2.13883002 0 P 0 
L 1.15436004 -2.13783002 1.20458002 -2.13783002 0 P 0 
L 1.155 -2.13683002 1.20466998 -2.13683002 0 P 0 
L 1.15556998 -2.13583002 1.20475 -2.13583002 0 P 0 
L 1.15608996 -2.13483002 1.20481998 -2.13483002 0 P 0 
L 1.15653996 -2.13383002 1.20488996 -2.13383002 0 P 0 
L 1.15691004 -2.13283002 1.20496004 -2.13283002 0 P 0 
L 1.15723996 -2.13183002 1.20503002 -2.13183002 0 P 0 
L 1.15751998 -2.13083002 1.2051 -2.13083002 0 P 0 
L 1.15773002 -2.12983002 1.20516004 -2.12983002 0 P 0 
L 1.15793002 -2.12883002 1.20523002 -2.12883002 0 P 0 
L 1.15806004 -2.12783002 1.2053 -2.12783002 0 P 0 
L 1.15816998 -2.12683002 1.20536998 -2.12683002 0 P 0 
L 1.15821004 -2.12583002 1.20543996 -2.12583002 0 P 0 
L 1.11716004 -2.12483002 1.12726004 -2.12483002 0 P 0 
L 1.15823996 -2.12483002 1.20551004 -2.12483002 0 P 0 
L 1.10911998 -2.12383002 1.1352 -2.12383002 0 P 0 
L 1.15821998 -2.12383002 1.20556998 -2.12383002 0 P 0 
L 1.10468996 -2.12283002 1.14018996 -2.12283002 0 P 0 
L 1.1582 -2.12283002 1.20563996 -2.12283002 0 P 0 
L 1.10131004 -2.12183002 1.14366998 -2.12183002 0 P 0 
L 1.15818002 -2.12183002 1.2057 -2.12183002 0 P 0 
L 1.15808996 -2.12083002 1.20576004 -2.12083002 0 P 0 
L 1.15781004 -2.11983002 1.20583002 -2.11983002 0 P 0 
L 1.15721004 -2.11883002 1.20588002 -2.11883002 0 P 0 
L 1.14146004 -2.08883002 1.20758002 -2.08883002 0 P 0 
L 1.14525 -2.08783002 1.20763002 -2.08783002 0 P 0 
L 1.14751004 -2.08683002 1.20768002 -2.08683002 0 P 0 
L 1.14928002 -2.08583002 1.20773002 -2.08583002 0 P 0 
L 1.15073002 -2.08483002 1.20778996 -2.08483002 0 P 0 
L 1.15196004 -2.08383002 1.20783996 -2.08383002 0 P 0 
L 1.13818996 -2.08913002 1.13826998 -2.08913002 0 P 0 
L 1.13826998 -2.08913002 1.13988002 -2.08903996 0 P 0 
L 1.13988002 -2.08903996 1.13996004 -2.08903996 0 P 0 
L 1.13996004 -2.08903996 1.14001004 -2.08903002 0 P 0 
L 1.14001004 -2.08903002 1.14005 -2.08901998 0 P 0 
L 1.14005 -2.08901998 1.14163002 -2.08881004 0 P 0 
L 1.14163002 -2.08881004 1.14166998 -2.0888 0 P 0 
L 1.14166998 -2.0888 1.14171004 -2.0888 0 P 0 
L 1.14171004 -2.0888 1.14178996 -2.08878002 0 P 0 
L 1.14178996 -2.08878002 1.14335 -2.08843002 0 P 0 
L 1.14335 -2.08843002 1.14351004 -2.08838996 0 P 0 
L 1.14351004 -2.08838996 1.14503002 -2.08791004 0 P 0 
L 1.14503002 -2.08791004 1.14511004 -2.08788996 0 P 0 
L 1.14511004 -2.08788996 1.14515 -2.08786998 0 P 0 
L 1.14515 -2.08786998 1.14518996 -2.08786004 0 P 0 
L 1.14518996 -2.08786004 1.14666004 -2.08725 0 P 0 
L 1.14666004 -2.08725 1.14673996 -2.08721998 0 P 0 
L 1.14673996 -2.08721998 1.14678002 -2.0872 0 P 0 
L 1.14678002 -2.0872 1.14681998 -2.08718996 0 P 0 
L 1.14681998 -2.08718996 1.14823996 -2.08646998 0 P 0 
L 1.14823996 -2.08646998 1.14826998 -2.08645 0 P 0 
L 1.14826998 -2.08645 1.14835 -2.08641004 0 P 0 
L 1.14835 -2.08641004 1.14838002 -2.08638002 0 P 0 
L 1.14838002 -2.08638002 1.14976004 -2.08553002 0 P 0 
L 1.14976004 -2.08553002 1.14978996 -2.08551004 0 P 0 
L 1.14978996 -2.08551004 1.14983002 -2.08548996 0 P 0 
L 1.14983002 -2.08548996 1.14988996 -2.08543996 0 P 0 
L 1.14988996 -2.08543996 1.1512 -2.08448996 0 P 0 
L 1.1512 -2.08448996 1.15126004 -2.08443996 0 P 0 
L 1.15126004 -2.08443996 1.15128996 -2.08441004 0 P 0 
L 1.15128996 -2.08441004 1.15131998 -2.08438996 0 P 0 
L 1.15131998 -2.08438996 1.15253996 -2.08333002 0 P 0 
L 1.15253996 -2.08333002 1.15256998 -2.0833 0 P 0 
L 1.15256998 -2.0833 1.1526 -2.08328002 0 P 0 
L 1.1526 -2.08328002 1.15263002 -2.08323996 0 P 0 
L 1.15263002 -2.08323996 1.15266004 -2.08321998 0 P 0 
L 1.15266004 -2.08321998 1.15378996 -2.08206004 0 P 0 
L 1.15378996 -2.08206004 1.15376004 -2.08203996 0 P 0 
L 1.15376004 -2.08203996 1.15381998 -2.08203996 0 P 0 
L 1.15381998 -2.08203996 1.15383996 -2.082 0 P 0 
L 1.15383996 -2.082 1.15386998 -2.08196998 0 P 0 
L 1.15386998 -2.08196998 1.1539 -2.08195 0 P 0 
L 1.1539 -2.08195 1.15493002 -2.08071004 0 P 0 
L 1.15493002 -2.08071004 1.15493002 -2.0807 0 P 0 
L 1.15493002 -2.0807 1.15496004 -2.08066998 0 P 0 
L 1.15496004 -2.08066998 1.15498002 -2.08063996 0 P 0 
L 1.15498002 -2.08063996 1.15501004 -2.08061004 0 P 0 
L 1.15501004 -2.08061004 1.15503002 -2.08058002 0 P 0 
L 1.15503002 -2.08058002 1.15596004 -2.07926004 0 P 0 
L 1.15596004 -2.07926004 1.15603996 -2.07913996 0 P 0 
L 1.15603996 -2.07913996 1.15673002 -2.07798996 0 P 0 
L 1.15673002 -2.07798996 1.15676998 -2.07793002 0 P 0 
L 1.15676998 -2.07793002 1.15678996 -2.07786998 0 P 0 
L 1.15678996 -2.07786998 1.15741004 -2.07668996 0 P 0 
L 1.15741004 -2.07668996 1.15743996 -2.07663002 0 P 0 
L 1.15743996 -2.07663002 1.15746004 -2.07656998 0 P 0 
L 1.15746004 -2.07656998 1.15746998 -2.07656998 0 P 0 
L 1.15746998 -2.07656998 1.158 -2.07533996 0 P 0 
L 1.158 -2.07533996 1.15801004 -2.07531004 0 P 0 
L 1.15801004 -2.07531004 1.15803002 -2.07528002 0 P 0 
L 1.15803002 -2.07528002 1.15805 -2.07521998 0 P 0 
L 1.15805 -2.07521998 1.15848996 -2.07396004 0 P 0 
L 1.15848996 -2.07396004 1.15841004 -2.07393002 0 P 0 
L 1.15841004 -2.07393002 1.15851004 -2.07393002 0 P 0 
L 1.15851004 -2.07393002 1.15851998 -2.0739 0 P 0 
L 1.15851998 -2.0739 1.15853002 -2.07386004 0 P 0 
L 1.15853002 -2.07386004 1.15853996 -2.07383002 0 P 0 
L 1.15853996 -2.07383002 1.15943996 -2.07061004 0 P 0 
L 1.15943996 -2.07061004 1.15945 -2.07058002 0 P 0 
L 1.15945 -2.07058002 1.15946004 -2.07053996 0 P 0 
L 1.15946004 -2.07053996 1.15946998 -2.07051004 0 P 0 
L 1.15946998 -2.07051004 1.15946998 -2.07046998 0 P 0 
L 1.15946998 -2.07046998 1.16013996 -2.06723002 0 P 0 
L 1.16013996 -2.06723002 1.16013996 -2.0672 0 P 0 
L 1.16013996 -2.0672 1.16016004 -2.06713996 0 P 0 
L 1.16016004 -2.06713996 1.16016004 -2.06711004 0 P 0 
L 1.16016004 -2.06711004 1.16081998 -2.06256004 0 P 0 
L 1.16081998 -2.06256004 1.16081998 -2.06253996 0 P 0 
L 1.16081998 -2.06253996 1.16083002 -2.0625 0 P 0 
L 1.16083002 -2.0625 1.16083002 -2.06246998 0 P 0 
L 1.16083002 -2.06246998 1.16126998 -2.05791004 0 P 0 
L 1.16126998 -2.05791004 1.16128002 -2.0579 0 P 0 
L 1.16128002 -2.0579 1.16128002 -2.05783996 0 P 0 
L 1.16128002 -2.05783996 1.1621 -2.04405 0 P 0 
L 1.1621 -2.04405 1.1621 -2.04401998 0 P 0 
L 1.1621 -2.04401998 1.16285 -2.02761998 0 P 0 
L 1.16285 -2.02761998 1.16136998 -2.0256 0 P 0 
L 1.16136998 -2.0256 1.15878996 -2.02491004 0 P 0 
L 1.15878996 -2.02491004 1.15878002 -2.0249 0 P 0 
L 1.15878002 -2.0249 1.15871998 -2.02488996 0 P 0 
L 1.15871998 -2.02488996 1.15755 -2.02461998 0 P 0 
L 1.15755 -2.02461998 1.15746998 -2.0246 0 P 0 
L 1.15746998 -2.0246 1.1574 -2.0246 0 P 0 
L 1.1574 -2.0246 1.15621004 -2.02441004 0 P 0 
L 1.15621004 -2.02441004 1.15616998 -2.02441004 0 P 0 
L 1.15616998 -2.02441004 1.1561 -2.0244 0 P 0 
L 1.1561 -2.0244 1.15606004 -2.02438996 0 P 0 
L 1.15606004 -2.02438996 1.15486004 -2.0243 0 P 0 
L 1.15486004 -2.0243 1.15471998 -2.0243 0 P 0 
L 1.15471998 -2.0243 1.14936004 -2.02426004 0 P 0 
L 1.14936004 -2.02426004 1.14928996 -2.02426004 0 P 0 
L 1.14928996 -2.02426004 1.14925 -2.02426998 0 P 0 
L 1.14925 -2.02426998 1.14921004 -2.02426998 0 P 0 
L 1.14921004 -2.02426998 1.14376998 -2.02463996 0 P 0 
L 1.14376998 -2.02463996 1.1437 -2.02463996 0 P 0 
L 1.1437 -2.02463996 1.14365 -2.02465 0 P 0 
L 1.14365 -2.02465 1.14361004 -2.02465 0 P 0 
L 1.14361004 -2.02465 1.14161998 -2.02495 0 P 0 
L 1.14161998 -2.02495 1.14161004 -2.02495 0 P 0 
L 1.14161004 -2.02495 1.14153002 -2.02496998 0 P 0 
L 1.14153002 -2.02496998 1.14148996 -2.02496998 0 P 0 
L 1.14148996 -2.02496998 1.14143996 -2.02498996 0 P 0 
L 1.14143996 -2.02498996 1.13946998 -2.02545 0 P 0 
L 1.13946998 -2.02545 1.13943996 -2.02546998 0 P 0 
L 1.13943996 -2.02546998 1.1394 -2.02546998 0 P 0 
L 1.1394 -2.02546998 1.13933002 -2.0255 0 P 0 
L 1.13933002 -2.0255 1.13801004 -2.02591998 0 P 0 
L 1.13801004 -2.02591998 1.13798002 -2.02593002 0 P 0 
L 1.13798002 -2.02593002 1.13793996 -2.02593996 0 P 0 
L 1.13793996 -2.02593996 1.13788002 -2.02596998 0 P 0 
L 1.13788002 -2.02596998 1.1366 -2.02648002 0 P 0 
L 1.1366 -2.02648002 1.13653996 -2.0265 0 P 0 
L 1.13653996 -2.0265 1.13648002 -2.02653002 0 P 0 
L 1.13648002 -2.02653002 1.13523996 -2.02713002 0 P 0 
L 1.13523996 -2.02713002 1.13518002 -2.02716004 0 P 0 
L 1.13518002 -2.02716004 1.13515 -2.02716998 0 P 0 
L 1.13515 -2.02716998 1.13511998 -2.02718996 0 P 0 
L 1.13511998 -2.02718996 1.13393002 -2.02786998 0 P 0 
L 1.13393002 -2.02786998 1.13388996 -2.02788996 0 P 0 
L 1.13388996 -2.02788996 1.1338 -2.02795 0 P 0 
L 1.1338 -2.02795 1.13111998 -2.02976004 0 P 0 
L 1.13111998 -2.02976004 1.13105 -2.02981004 0 P 0 
L 1.13105 -2.02981004 1.13101004 -2.02983996 0 P 0 
L 1.13101004 -2.02983996 1.13098002 -2.02986004 0 P 0 
L 1.13098002 -2.02986004 1.12846998 -2.03188996 0 P 0 
L 1.12846998 -2.03188996 1.12838002 -2.03198002 0 P 0 
L 1.12838002 -2.03198002 1.12833996 -2.03201004 0 P 0 
L 1.12833996 -2.03201004 1.12596004 -2.0343 0 P 0 
L 1.12596004 -2.0343 1.12593996 -2.03433002 0 P 0 
L 1.12593996 -2.03433002 1.1259 -2.03436004 0 P 0 
L 1.1259 -2.03436004 1.12588002 -2.03438996 0 P 0 
L 1.12588002 -2.03438996 1.12585 -2.03443002 0 P 0 
L 1.12585 -2.03443002 1.12366998 -2.03691004 0 P 0 
L 1.12366998 -2.03691004 1.12363996 -2.03695 0 P 0 
L 1.12363996 -2.03695 1.12361998 -2.03698002 0 P 0 
L 1.12361998 -2.03698002 1.12358996 -2.03701004 0 P 0 
L 1.12358996 -2.03701004 1.12356998 -2.03703996 0 P 0 
L 1.12356998 -2.03703996 1.12236998 -2.03865 0 P 0 
L 1.12236998 -2.03865 1.12233996 -2.03868996 0 P 0 
L 1.12233996 -2.03868996 1.12233002 -2.03871004 0 P 0 
L 1.12233002 -2.03871004 1.12228996 -2.03878002 0 P 0 
L 1.12228996 -2.03878002 1.12121004 -2.04046998 0 P 0 
L 1.12121004 -2.04046998 1.12118996 -2.0405 0 P 0 
L 1.12118996 -2.0405 1.12116998 -2.04053996 0 P 0 
L 1.12116998 -2.04053996 1.12115 -2.04056998 0 P 0 
L 1.12115 -2.04056998 1.12113996 -2.04061004 0 P 0 
L 1.12113996 -2.04061004 1.12018996 -2.04238002 0 P 0 
L 1.12018996 -2.04238002 1.12016004 -2.04245 0 P 0 
L 1.12016004 -2.04245 1.12013996 -2.04248002 0 P 0 
L 1.12013996 -2.04248002 1.12013002 -2.04251004 0 P 0 
L 1.12013002 -2.04251004 1.11926004 -2.04446998 0 P 0 
L 1.11926004 -2.04446998 1.11925 -2.0445 0 P 0 
L 1.11925 -2.0445 1.11923002 -2.04453996 0 P 0 
L 1.11923002 -2.04453996 1.11921998 -2.04458002 0 P 0 
L 1.11921998 -2.04458002 1.11921004 -2.04461004 0 P 0 
L 1.11921004 -2.04461004 1.11848002 -2.04663002 0 P 0 
L 1.11848002 -2.04663002 1.11846998 -2.04666004 0 P 0 
L 1.11846998 -2.04666004 1.11846004 -2.0467 0 P 0 
L 1.11846004 -2.0467 1.11843996 -2.04676998 0 P 0 
L 1.11843996 -2.04676998 1.11786004 -2.04883996 0 P 0 
L 1.11786004 -2.04883996 1.11785 -2.04886998 0 P 0 
L 1.11785 -2.04886998 1.11783996 -2.04891004 0 P 0 
L 1.11783996 -2.04891004 1.11783996 -2.04893996 0 P 0 
L 1.11783996 -2.04893996 1.11783002 -2.04896998 0 P 0 
L 1.11783002 -2.04896998 1.11783002 -2.04898002 0 P 0 
L 1.11783002 -2.04898002 1.1174 -2.05108002 0 P 0 
L 1.1174 -2.05108002 1.1174 -2.05111998 0 P 0 
L 1.1174 -2.05111998 1.11738996 -2.05116004 0 P 0 
L 1.11738996 -2.05116004 1.11738002 -2.05118996 0 P 0 
L 1.11738002 -2.05118996 1.11738002 -2.05123002 0 P 0 
L 1.11738002 -2.05123002 1.11673002 -2.05643002 0 P 0 
L 1.11673002 -2.05643002 1.11671998 -2.05646998 0 P 0 
L 1.11671998 -2.05646998 1.11671998 -2.05655 0 P 0 
L 1.11671998 -2.05655 1.11671004 -2.05658996 0 P 0 
L 1.11671004 -2.05658996 1.11648996 -2.06181998 0 P 0 
L 1.11648996 -2.06181998 1.11648002 -2.06186998 0 P 0 
L 1.11648002 -2.06186998 1.11648002 -2.06195 0 P 0 
L 1.11648002 -2.06195 1.11648996 -2.06198996 0 P 0 
L 1.11648996 -2.06198996 1.11668002 -2.06696998 0 P 0 
L 1.11668002 -2.06696998 1.11768002 -2.06696998 0 P 0 
L 1.11768002 -2.06696998 1.11668002 -2.06701004 0 P 0 
L 1.11668002 -2.06701004 1.11668002 -2.06713002 0 P 0 
L 1.11668002 -2.06713002 1.11668996 -2.06716998 0 P 0 
L 1.11668996 -2.06716998 1.11728002 -2.07215 0 P 0 
L 1.11728002 -2.07215 1.11728996 -2.07218996 0 P 0 
L 1.11728996 -2.07218996 1.11728996 -2.07223002 0 P 0 
L 1.11728996 -2.07223002 1.11731004 -2.07231004 0 P 0 
L 1.11731004 -2.07231004 1.11758996 -2.07371004 0 P 0 
L 1.11758996 -2.07371004 1.1176 -2.07375 0 P 0 
L 1.1176 -2.07375 1.11761004 -2.0738 0 P 0 
L 1.11761004 -2.0738 1.11761998 -2.07383996 0 P 0 
L 1.11761998 -2.07383996 1.11763996 -2.07388002 0 P 0 
L 1.11763996 -2.07388002 1.11803996 -2.07523996 0 P 0 
L 1.11803996 -2.07523996 1.11806004 -2.07531998 0 P 0 
L 1.11806004 -2.07531998 1.11808002 -2.07536004 0 P 0 
L 1.11808002 -2.07536004 1.11808996 -2.07541004 0 P 0 
L 1.11808996 -2.07541004 1.11861004 -2.07673002 0 P 0 
L 1.11861004 -2.07673002 1.11863996 -2.07681004 0 P 0 
L 1.11863996 -2.07681004 1.11866004 -2.07683996 0 P 0 
L 1.11866004 -2.07683996 1.11868002 -2.07688002 0 P 0 
L 1.11868002 -2.07688002 1.11931004 -2.07815 0 P 0 
L 1.11931004 -2.07815 1.11935 -2.07823002 0 P 0 
L 1.11935 -2.07823002 1.1194 -2.0783 0 P 0 
L 1.1194 -2.0783 1.12013996 -2.07951998 0 P 0 
L 1.12013996 -2.07951998 1.12021004 -2.07961998 0 P 0 
L 1.12021004 -2.07961998 1.12023002 -2.07965 0 P 0 
L 1.12023002 -2.07965 1.12023002 -2.07966004 0 P 0 
L 1.12023002 -2.07966004 1.1212 -2.08096998 0 P 0 
L 1.1212 -2.08096998 1.12123996 -2.08103002 0 P 0 
L 1.12123996 -2.08103002 1.12126998 -2.08106004 0 P 0 
L 1.12126998 -2.08106004 1.12128996 -2.08108996 0 P 0 
L 1.12128996 -2.08108996 1.12235 -2.08231004 0 P 0 
L 1.12235 -2.08231004 1.12238002 -2.08233996 0 P 0 
L 1.12238002 -2.08233996 1.1224 -2.08236998 0 P 0 
L 1.1224 -2.08236998 1.12246004 -2.08243002 0 P 0 
L 1.12246004 -2.08243002 1.12361004 -2.08355 0 P 0 
L 1.12361004 -2.08355 1.12366998 -2.08361004 0 P 0 
L 1.12366998 -2.08361004 1.1237 -2.08363002 0 P 0 
L 1.1237 -2.08363002 1.12373002 -2.08366004 0 P 0 
L 1.12373002 -2.08366004 1.12496998 -2.08468996 0 P 0 
L 1.12496998 -2.08468996 1.125 -2.08471004 0 P 0 
L 1.125 -2.08471004 1.12503002 -2.08473996 0 P 0 
L 1.12503002 -2.08473996 1.12506998 -2.08476004 0 P 0 
L 1.12506998 -2.08476004 1.1251 -2.08478996 0 P 0 
L 1.1251 -2.08478996 1.12641998 -2.08571004 0 P 0 
L 1.12641998 -2.08571004 1.12645 -2.08573002 0 P 0 
L 1.12645 -2.08573002 1.12648002 -2.08576004 0 P 0 
L 1.12648002 -2.08576004 1.12651004 -2.08578002 0 P 0 
L 1.12651004 -2.08578002 1.12655 -2.0858 0 P 0 
L 1.12655 -2.0858 1.12793996 -2.08661004 0 P 0 
L 1.12793996 -2.08661004 1.12801004 -2.08665 0 P 0 
L 1.12801004 -2.08665 1.12805 -2.08666998 0 P 0 
L 1.12805 -2.08666998 1.12808002 -2.08668996 0 P 0 
L 1.12808002 -2.08668996 1.12808996 -2.08668996 0 P 0 
L 1.12808996 -2.08668996 1.12953996 -2.08738996 0 P 0 
L 1.12953996 -2.08738996 1.12961998 -2.08743002 0 P 0 
L 1.12961998 -2.08743002 1.12965 -2.08743996 0 P 0 
L 1.12965 -2.08743996 1.1297 -2.08746004 0 P 0 
L 1.1297 -2.08746004 1.13118002 -2.08801998 0 P 0 
L 1.13118002 -2.08801998 1.13133996 -2.08808002 0 P 0 
L 1.13133996 -2.08808002 1.13286998 -2.08851004 0 P 0 
L 1.13286998 -2.08851004 1.13295 -2.08853996 0 P 0 
L 1.13295 -2.08853996 1.13303996 -2.08855 0 P 0 
L 1.13303996 -2.08855 1.1346 -2.08886004 0 P 0 
L 1.1346 -2.08886004 1.13471998 -2.08888996 0 P 0 
L 1.13471998 -2.08888996 1.13476004 -2.08888996 0 P 0 
L 1.13476004 -2.08888996 1.13633996 -2.08906998 0 P 0 
L 1.13633996 -2.08906998 1.13638996 -2.08908002 0 P 0 
L 1.13638996 -2.08908002 1.13651004 -2.08908002 0 P 0 
L 1.13651004 -2.08908002 1.1381 -2.08913002 0 P 0 
L 1.1381 -2.08913002 1.13818996 -2.08913002 0 P 0 
L 1.31623996 -1.98923996 1.3135 -1.98988002 0 P 0 
L 1.3135 -1.98988002 1.31078996 -1.99071004 0 P 0 
L 1.31078996 -1.99071004 1.30813002 -1.99175 0 P 0 
L 1.30813002 -1.99175 1.30553996 -1.99296998 0 P 0 
L 1.30553996 -1.99296998 1.30308996 -1.99431998 0 P 0 
L 1.30308996 -1.99431998 1.30073996 -1.99585 0 P 0 
L 1.30073996 -1.99585 1.29863996 -1.99746004 0 P 0 
L 1.29863996 -1.99746004 1.29666004 -1.99923996 0 P 0 
L 1.29666004 -1.99923996 1.29205 -2.00375 0 P 0 
L 1.29205 -2.00375 1.29205 -1.99243996 0 P 0 
L 1.29205 -1.99243996 1.24316004 -1.99243996 0 P 0 
L 1.24316004 -1.99243996 1.24313996 -2.00521004 0 P 0 
L 1.24313996 -2.00521004 1.24261004 -2.03151004 0 P 0 
L 1.24261004 -2.03151004 1.24086998 -2.07046004 0 P 0 
L 1.24086998 -2.07046004 1.23873996 -2.10921004 0 P 0 
L 1.23873996 -2.10921004 1.23811998 -2.11641998 0 P 0 
L 1.23811998 -2.11641998 1.23711998 -2.12361998 0 P 0 
L 1.23711998 -2.12361998 1.23655 -2.12716004 0 P 0 
L 1.23655 -2.12716004 1.29205 -2.12716004 0 P 0 
L 1.29205 -2.12716004 1.29206998 -2.11766004 0 P 0 
L 1.29206998 -2.11766004 1.29238996 -2.10283996 0 P 0 
L 1.29238996 -2.10283996 1.29336004 -2.08431004 0 P 0 
L 1.29336004 -2.08431004 1.29463996 -2.06673002 0 P 0 
L 1.29463996 -2.06673002 1.29511004 -2.06253002 0 P 0 
L 1.29511004 -2.06253002 1.29583996 -2.05836004 0 P 0 
L 1.29583996 -2.05836004 1.29683002 -2.05446998 0 P 0 
L 1.29683002 -2.05446998 1.29813996 -2.05068996 0 P 0 
L 1.29813996 -2.05068996 1.29978002 -2.04701998 0 P 0 
L 1.29978002 -2.04701998 1.30056998 -2.04556998 0 P 0 
L 1.30056998 -2.04556998 1.30146998 -2.04418996 0 P 0 
L 1.30146998 -2.04418996 1.30246998 -2.04288002 0 P 0 
L 1.30246998 -2.04288002 1.30356998 -2.04165 0 P 0 
L 1.30356998 -2.04165 1.30475 -2.0405 0 P 0 
L 1.30475 -2.0405 1.30603996 -2.03945 0 P 0 
L 1.30603996 -2.03945 1.30773996 -2.03826004 0 P 0 
L 1.30773996 -2.03826004 1.30953002 -2.03723002 0 P 0 
L 1.30953002 -2.03723002 1.31141004 -2.03635 0 P 0 
L 1.31141004 -2.03635 1.31335 -2.03563002 0 P 0 
L 1.31335 -2.03563002 1.31535 -2.03508002 0 P 0 
L 1.31535 -2.03508002 1.31973996 -2.03423002 0 P 0 
L 1.31973996 -2.03423002 1.32416004 -2.03366998 0 P 0 
L 1.32416004 -2.03366998 1.32863002 -2.0334 0 P 0 
L 1.32863002 -2.0334 1.33688002 -2.03318002 0 P 0 
L 1.33688002 -2.03318002 1.33613002 -2.01151004 0 P 0 
L 1.33613002 -2.01151004 1.33581004 -2.00315 0 P 0 
L 1.33581004 -2.00315 1.33543996 -1.99596004 0 P 0 
L 1.33543996 -1.99596004 1.33508002 -1.98971004 0 P 0 
L 1.33508002 -1.98971004 1.33503996 -1.98945 0 P 0 
L 1.33503996 -1.98945 1.335 -1.98931998 0 P 0 
L 1.335 -1.98931998 1.33496004 -1.9892 0 P 0 
L 1.33496004 -1.9892 1.3349 -1.98908002 0 P 0 
L 1.3349 -1.98908002 1.33483996 -1.98896998 0 P 0 
L 1.33483996 -1.98896998 1.33476998 -1.98886004 0 P 0 
L 1.33476998 -1.98886004 1.33468996 -1.98876004 0 P 0 
L 1.33468996 -1.98876004 1.3346 -1.98866998 0 P 0 
L 1.3346 -1.98866998 1.33451004 -1.98858996 0 P 0 
L 1.33451004 -1.98858996 1.3344 -1.98851998 0 P 0 
L 1.3344 -1.98851998 1.3343 -1.98845 0 P 0 
L 1.3343 -1.98845 1.33418002 -1.98838996 0 P 0 
L 1.33418002 -1.98838996 1.33406998 -1.98833996 0 P 0 
L 1.33406998 -1.98833996 1.33395 -1.9883 0 P 0 
L 1.33395 -1.9883 1.33383002 -1.98828002 0 P 0 
L 1.33383002 -1.98828002 1.3337 -1.98826004 0 P 0 
L 1.3337 -1.98826004 1.33356998 -1.98825 0 P 0 
L 1.33356998 -1.98825 1.32756998 -1.98823002 0 P 0 
L 1.32756998 -1.98823002 1.32135 -1.98853996 0 P 0 
L 1.32135 -1.98853996 1.31878996 -1.98881998 0 P 0 
L 1.31878996 -1.98881998 1.31623996 -1.98923996 0 P 0 
L 1.2389 -2.12516004 1.29006004 -2.12516004 0 P 0 
L 1.23906998 -2.12416004 1.29006004 -2.12416004 0 P 0 
L 1.23921004 -2.12316004 1.29006004 -2.12316004 0 P 0 
L 1.23933996 -2.12216004 1.29006004 -2.12216004 0 P 0 
L 1.23948996 -2.12116004 1.29006004 -2.12116004 0 P 0 
L 1.23961998 -2.12016004 1.29006998 -2.12016004 0 P 0 
L 1.23976004 -2.11916004 1.29006998 -2.11916004 0 P 0 
L 1.2399 -2.11816004 1.29006998 -2.11816004 0 P 0 
L 1.24003996 -2.11716004 1.29008002 -2.11716004 0 P 0 
L 1.24015 -2.11616004 1.2901 -2.11616004 0 P 0 
L 1.24023996 -2.11516004 1.29011998 -2.11516004 0 P 0 
L 1.24033002 -2.11416004 1.29013996 -2.11416004 0 P 0 
L 1.24041004 -2.11316004 1.29016004 -2.11316004 0 P 0 
L 1.24048996 -2.11216004 1.29018996 -2.11216004 0 P 0 
L 1.24058002 -2.11116004 1.29021004 -2.11116004 0 P 0 
L 1.24066998 -2.11016004 1.29023002 -2.11016004 0 P 0 
L 1.24075 -2.10916004 1.29025 -2.10916004 0 P 0 
L 1.2408 -2.10816004 1.29026998 -2.10816004 0 P 0 
L 1.24086004 -2.10716004 1.29028996 -2.10716004 0 P 0 
L 1.24091004 -2.10616004 1.29031998 -2.10616004 0 P 0 
L 1.24096998 -2.10516004 1.29033996 -2.10516004 0 P 0 
L 1.24101998 -2.10416004 1.29036004 -2.10416004 0 P 0 
L 1.24108002 -2.10316004 1.29038002 -2.10316004 0 P 0 
L 1.24113002 -2.10216004 1.29041998 -2.10216004 0 P 0 
L 1.24118002 -2.10116004 1.29046998 -2.10116004 0 P 0 
L 1.24123996 -2.10016004 1.29053002 -2.10016004 0 P 0 
L 1.24128996 -2.09916004 1.29058002 -2.09916004 0 P 0 
L 1.24135 -2.09816004 1.29063002 -2.09816004 0 P 0 
L 1.2414 -2.09716004 1.29068002 -2.09716004 0 P 0 
L 1.24146004 -2.09616004 1.29073996 -2.09616004 0 P 0 
L 1.24151004 -2.09516004 1.29078996 -2.09516004 0 P 0 
L 1.24156998 -2.09416004 1.29083996 -2.09416004 0 P 0 
L 1.24161998 -2.09316004 1.2909 -2.09316004 0 P 0 
L 1.24168002 -2.09216004 1.29095 -2.09216004 0 P 0 
L 1.24173002 -2.09116004 1.291 -2.09116004 0 P 0 
L 1.24178996 -2.09016004 1.29105 -2.09016004 0 P 0 
L 1.24183996 -2.08916004 1.2911 -2.08916004 0 P 0 
L 1.2419 -2.08816004 1.29116004 -2.08816004 0 P 0 
L 1.24196004 -2.08716004 1.29121004 -2.08716004 0 P 0 
L 1.24201004 -2.08616004 1.29126998 -2.08616004 0 P 0 
L 1.24206998 -2.08516004 1.29131998 -2.08516004 0 P 0 
L 1.24211998 -2.08416004 1.29136998 -2.08416004 0 P 0 
L 1.2389 -2.12516004 1.2391 -2.12393002 0 P 0 
L 1.2391 -2.12393002 1.2391 -2.1239 0 P 0 
L 1.2391 -2.1239 1.24011004 -2.11665 0 P 0 
L 1.24011004 -2.11665 1.24073002 -2.10935 0 P 0 
L 1.24073002 -2.10935 1.24073996 -2.10931998 0 P 0 
L 1.24073996 -2.10931998 1.24286004 -2.07056004 0 P 0 
L 1.24286004 -2.07056004 1.24461004 -2.03158002 0 P 0 
L 1.24461004 -2.03158002 1.24513996 -2.00523002 0 P 0 
L 1.24513996 -2.00523002 1.24515 -1.99443996 0 P 0 
L 1.24515 -1.99443996 1.29005 -1.99443996 0 P 0 
L 1.29005 -1.99443996 1.29005 -2.00375 0 P 0 
L 1.29005 -2.00375 1.29128002 -2.0056 0 P 0 
L 1.29128002 -2.0056 1.29345 -2.00518002 0 P 0 
L 1.29345 -2.00518002 1.29803002 -2.0007 0 P 0 
L 1.29803002 -2.0007 1.29991998 -1.999 0 P 0 
L 1.29991998 -1.999 1.30188996 -1.99748996 0 P 0 
L 1.30188996 -1.99748996 1.30411998 -1.99603996 0 P 0 
L 1.30411998 -1.99603996 1.30645 -1.99475 0 P 0 
L 1.30645 -1.99475 1.30891998 -1.99358996 0 P 0 
L 1.30891998 -1.99358996 1.31145 -1.9926 0 P 0 
L 1.31145 -1.9926 1.31401998 -1.99181004 0 P 0 
L 1.31401998 -1.99181004 1.31663996 -1.9912 0 P 0 
L 1.31663996 -1.9912 1.31906004 -1.9908 0 P 0 
L 1.31906004 -1.9908 1.32151004 -1.99053002 0 P 0 
L 1.32151004 -1.99053002 1.32761998 -1.99023002 0 P 0 
L 1.32761998 -1.99023002 1.3331 -1.99025 0 P 0 
L 1.3331 -1.99025 1.33345 -1.99608002 0 P 0 
L 1.33345 -1.99608002 1.33381004 -2.00323002 0 P 0 
L 1.33381004 -2.00323002 1.33413002 -2.01158996 0 P 0 
L 1.33413002 -2.01158996 1.33413002 -2.0116 0 P 0 
L 1.33413002 -2.0116 1.33481998 -2.03123002 0 P 0 
L 1.33481998 -2.03123002 1.32853996 -2.0314 0 P 0 
L 1.32853996 -2.0314 1.32398002 -2.03166998 0 P 0 
L 1.32398002 -2.03166998 1.31941998 -2.03225 0 P 0 
L 1.31941998 -2.03225 1.31488996 -2.03313002 0 P 0 
L 1.31488996 -2.03313002 1.31273996 -2.03373002 0 P 0 
L 1.31273996 -2.03373002 1.31063996 -2.0345 0 P 0 
L 1.31063996 -2.0345 1.3086 -2.03545 0 P 0 
L 1.3086 -2.03545 1.30666004 -2.03656998 0 P 0 
L 1.30666004 -2.03656998 1.30658996 -2.03661998 0 P 0 
L 1.30658996 -2.03661998 1.30483002 -2.03786004 0 P 0 
L 1.30483002 -2.03786004 1.30341998 -2.03901004 0 P 0 
L 1.30341998 -2.03901004 1.30336998 -2.03906004 0 P 0 
L 1.30336998 -2.03906004 1.30211998 -2.04026004 0 P 0 
L 1.30211998 -2.04026004 1.30093002 -2.0416 0 P 0 
L 1.30093002 -2.0416 1.29983002 -2.04303996 0 P 0 
L 1.29983002 -2.04303996 1.29978996 -2.0431 0 P 0 
L 1.29978996 -2.0431 1.29885 -2.04453996 0 P 0 
L 1.29885 -2.04453996 1.29798996 -2.04613002 0 P 0 
L 1.29798996 -2.04613002 1.29631998 -2.04986998 0 P 0 
L 1.29631998 -2.04986998 1.29628002 -2.04995 0 P 0 
L 1.29628002 -2.04995 1.29625 -2.05003002 0 P 0 
L 1.29625 -2.05003002 1.29491998 -2.0539 0 P 0 
L 1.29491998 -2.0539 1.29388996 -2.05793996 0 P 0 
L 1.29388996 -2.05793996 1.29386998 -2.05801998 0 P 0 
L 1.29386998 -2.05801998 1.29313996 -2.06221004 0 P 0 
L 1.29313996 -2.06221004 1.29313002 -2.06223996 0 P 0 
L 1.29313002 -2.06223996 1.29311998 -2.0623 0 P 0 
L 1.29311998 -2.0623 1.29265 -2.06655 0 P 0 
L 1.29265 -2.06655 1.29136998 -2.08418996 0 P 0 
L 1.29136998 -2.08418996 1.29038996 -2.10276998 0 P 0 
L 1.29038996 -2.10276998 1.29006998 -2.11763002 0 P 0 
L 1.29006998 -2.11763002 1.29006004 -2.12516004 0 P 0 
L 1.29006004 -2.12516004 1.2389 -2.12516004 0 P 0 
L 1.09846998 -2.00483002 1.21248002 -2.00483002 0 P 0 
L 1.09838002 -2.12083002 1.14708002 -2.12083002 0 P 0 
L 1.11933002 -2.18283002 1.15161998 -2.18283002 0 P 0 
L 1.11001998 -2.18183002 1.15838002 -2.18183002 0 P 0 
L 1.10246998 -2.18083002 1.16333996 -2.18083002 0 P 0 
L 1.04061004 -1.89731004 1.09978002 -1.89731004 0 P 0 
L 1.03565 -1.89631004 1.09821004 -1.89631004 0 P 0 
L 1.03068996 -1.89531004 1.09661004 -1.89531004 0 P 0 
L 1.02573002 -1.89431004 1.09475 -1.89431004 0 P 0 
L 1.019 -1.89331004 1.09288002 -1.89331004 0 P 0 
L 1.01163996 -1.89231004 1.09101998 -1.89231004 0 P 0 
L 0.99518996 -1.89131004 1.08916004 -1.89131004 0 P 0 
L 0.87011998 -1.88331004 1.07278996 -1.88331004 0 P 0 
L 0.86963996 -1.88231004 1.07053002 -1.88231004 0 P 0 
L 0.86916004 -1.88131004 1.06828002 -1.88131004 0 P 0 
L 0.86863002 -1.88031004 1.06603002 -1.88031004 0 P 0 
L 0.86806998 -1.87931004 1.06351004 -1.87931004 0 P 0 
L 0.8675 -1.87831004 1.06076998 -1.87831004 0 P 0 
L 0.86693002 -1.87731004 1.05803996 -1.87731004 0 P 0 
L 0.86631004 -1.87631004 1.05531004 -1.87631004 0 P 0 
L 0.86563996 -1.87531004 1.05256998 -1.87531004 0 P 0 
L 0.86498002 -1.87431004 1.04983996 -1.87431004 0 P 0 
L 0.86431998 -1.87331004 1.0471 -1.87331004 0 P 0 
L 0.86356004 -1.87231004 1.04376004 -1.87231004 0 P 0 
L 0.86278996 -1.87131004 1.04041998 -1.87131004 0 P 0 
L 0.86203002 -1.87031004 1.03708002 -1.87031004 0 P 0 
L 0.86118996 -1.86931004 1.03373996 -1.86931004 0 P 0 
L 0.8603 -1.86831004 1.0304 -1.86831004 0 P 0 
L 0.85941004 -1.86731004 1.02656998 -1.86731004 0 P 0 
L 0.8585 -1.86631004 1.02231998 -1.86631004 0 P 0 
L 0.85756998 -1.86531004 1.01806998 -1.86531004 0 P 0 
L 0.85663002 -1.86431004 1.01381998 -1.86431004 0 P 0 
L 0.85568996 -1.86331004 1.00931998 -1.86331004 0 P 0 
L 0.85481004 -1.86231004 1.00335 -1.86231004 0 P 0 
L 0.85916998 -1.86131004 0.99738002 -1.86131004 0 P 0 
L 0.86716998 -1.86031004 0.99141998 -1.86031004 0 P 0 
L 0.87476998 -1.89731004 0.89943002 -1.89731004 0 P 0 
L 0.87453996 -1.89631004 0.90426004 -1.89631004 0 P 0 
L 0.87431004 -1.89531004 0.9097 -1.89531004 0 P 0 
L 0.87406998 -1.89431004 0.91608002 -1.89431004 0 P 0 
L 0.87383002 -1.89331004 0.92246004 -1.89331004 0 P 0 
L 0.87355 -1.89231004 0.93086004 -1.89231004 0 P 0 
L 0.87323002 -1.89131004 0.95553002 -1.89131004 0 P 0 
L 0.87291004 -1.89031004 1.08728996 -1.89031004 0 P 0 
L 0.87258996 -1.88931004 1.08543002 -1.88931004 0 P 0 
L 0.87223002 -1.88831004 1.08356998 -1.88831004 0 P 0 
L 0.87183002 -1.88731004 1.0817 -1.88731004 0 P 0 
L 0.87143002 -1.88631004 1.07955 -1.88631004 0 P 0 
L 0.87103002 -1.88531004 1.07728996 -1.88531004 0 P 0 
L 0.8706 -1.88431004 1.07503996 -1.88431004 0 P 0 
L 0.87525 -1.85931004 0.98545 -1.85931004 0 P 0 
L 0.88421004 -1.85831004 0.97621004 -1.85831004 0 P 0 
L 0.89393002 -1.85731004 0.96606998 -1.85731004 0 P 0 
L 0.9106 -1.85631004 0.95203002 -1.85631004 0 P 0 
L 1.08716004 -1.91231004 1.12151004 -1.91231004 0 P 0 
L 1.08486004 -1.91131004 1.12018996 -1.91131004 0 P 0 
L 1.08256004 -1.91031004 1.11886004 -1.91031004 0 P 0 
L 1.08023002 -1.90931004 1.11753996 -1.90931004 0 P 0 
L 1.07738002 -1.90831004 1.11621004 -1.90831004 0 P 0 
L 1.07453002 -1.90731004 1.11488996 -1.90731004 0 P 0 
L 1.07168996 -1.90631004 1.11356998 -1.90631004 0 P 0 
L 1.06883996 -1.90531004 1.11223996 -1.90531004 0 P 0 
L 1.066 -1.90431004 1.11076998 -1.90431004 0 P 0 
L 1.06315 -1.90331004 1.1092 -1.90331004 0 P 0 
L 1.0599 -1.90231004 1.10763002 -1.90231004 0 P 0 
L 1.05611998 -1.90131004 1.10606004 -1.90131004 0 P 0 
L 1.05235 -1.90031004 1.10448996 -1.90031004 0 P 0 
L 1.04856998 -1.89931004 1.10291998 -1.89931004 0 P 0 
L 1.04478996 -1.89831004 1.10135 -1.89831004 0 P 0 
L 0.98815 -2.08316004 1.03726998 -2.08316004 0 P 0 
L 0.98818002 -2.08216004 1.03731004 -2.08216004 0 P 0 
L 0.98821998 -2.08116004 1.03735 -2.08116004 0 P 0 
L 0.98825 -2.08016004 1.03738996 -2.08016004 0 P 0 
L 0.98828002 -2.07916004 1.03743002 -2.07916004 0 P 0 
L 0.98831998 -2.07816004 1.03746998 -2.07816004 0 P 0 
L 0.98835 -2.07716004 1.03751004 -2.07716004 0 P 0 
L 0.98838002 -2.07616004 1.03755 -2.07616004 0 P 0 
L 0.98841998 -2.07516004 1.03758002 -2.07516004 0 P 0 
L 0.98845 -2.07416004 1.03761004 -2.07416004 0 P 0 
L 0.98848002 -2.07316004 1.03763996 -2.07316004 0 P 0 
L 0.98851004 -2.07216004 1.03768002 -2.07216004 0 P 0 
L 0.98855 -2.07116004 1.03771004 -2.07116004 0 P 0 
L 0.98858002 -2.07016004 1.03773996 -2.07016004 0 P 0 
L 0.98858996 -2.06916004 1.03776998 -2.06916004 0 P 0 
L 0.98858996 -2.06816004 1.0378 -2.06816004 0 P 0 
L 0.98858996 -2.06716004 1.03783002 -2.06716004 0 P 0 
L 0.98858002 -2.06616004 1.03786004 -2.06616004 0 P 0 
L 0.98856998 -2.06516004 1.0379 -2.06516004 0 P 0 
L 0.98856998 -2.06416004 1.03793002 -2.06416004 0 P 0 
L 0.98856998 -2.06316004 1.03796004 -2.06316004 0 P 0 
L 0.98856004 -2.06216004 1.03798996 -2.06216004 0 P 0 
L 0.98855 -2.06116004 1.03801998 -2.06116004 0 P 0 
L 0.98855 -2.06016004 1.03805 -2.06016004 0 P 0 
L 0.98853996 -2.05916004 1.03808002 -2.05916004 0 P 0 
L 0.98853996 -2.05816004 1.0381 -2.05816004 0 P 0 
L 0.98853002 -2.05716004 1.03811998 -2.05716004 0 P 0 
L 0.98848002 -2.05616004 1.03815 -2.05616004 0 P 0 
L 0.98841004 -2.05516004 1.03818002 -2.05516004 0 P 0 
L 0.98835 -2.05416004 1.0382 -2.05416004 0 P 0 
L 0.98828002 -2.05316004 1.03821998 -2.05316004 0 P 0 
L 0.98821004 -2.05216004 1.03825 -2.05216004 0 P 0 
L 0.98815 -2.05116004 1.03826998 -2.05116004 0 P 0 
L 0.98808996 -2.05016004 1.03828996 -2.05016004 0 P 0 
L 0.98801998 -2.04916004 1.03831998 -2.04916004 0 P 0 
L 0.98796004 -2.04816004 1.03833996 -2.04816004 0 P 0 
L 0.98788996 -2.04716004 1.03836004 -2.04716004 0 P 0 
L 0.98783002 -2.04616004 1.03838996 -2.04616004 0 P 0 
L 0.98768996 -2.04516004 1.0384 -2.04516004 0 P 0 
L 0.98756004 -2.04416004 1.03841004 -2.04416004 0 P 0 
L 0.98738002 -2.04316004 1.03841998 -2.04316004 0 P 0 
L 0.98716004 -2.04216004 1.03843002 -2.04216004 0 P 0 
L 0.98691998 -2.04116004 1.03843996 -2.04116004 0 P 0 
L 0.98661998 -2.04016004 1.03845 -2.04016004 0 P 0 
L 0.98631998 -2.03916004 1.03846004 -2.03916004 0 P 0 
L 0.98593996 -2.03816004 1.03846998 -2.03816004 0 P 0 
L 0.98546998 -2.03716004 1.03848002 -2.03716004 0 P 0 
L 0.98491004 -2.03616004 1.03846998 -2.03616004 0 P 0 
L 0.98425 -2.03516004 1.03846004 -2.03516004 0 P 0 
L 0.98346004 -2.03416004 1.03846004 -2.03416004 0 P 0 
L 0.98251998 -2.03316004 1.03843996 -2.03316004 0 P 0 
L 0.98138002 -2.03216004 1.03843002 -2.03216004 0 P 0 
L 0.97998996 -2.03116004 1.03841998 -2.03116004 0 P 0 
L 0.97813996 -2.03016004 1.03841004 -2.03016004 0 P 0 
L 0.97491004 -2.02916004 1.0384 -2.02916004 0 P 0 
L 0.94763996 -2.00716004 1.03293996 -2.00716004 0 P 0 
L 0.94978996 -2.00616004 1.03231998 -2.00616004 0 P 0 
L 0.95081004 -2.00516004 1.0317 -2.00516004 0 P 0 
L 0.95183002 -2.00416004 1.03098002 -2.00416004 0 P 0 
L 0.95285 -2.00316004 1.03023002 -2.00316004 0 P 0 
L 0.95388996 -2.00216004 1.02936004 -2.00216004 0 P 0 
L 0.95498002 -2.00116004 1.02841998 -2.00116004 0 P 0 
L 0.95621998 -2.00016004 1.02738996 -2.00016004 0 P 0 
L 0.95761998 -1.99916004 1.0262 -1.99916004 0 P 0 
L 0.9592 -1.99816004 1.02486004 -1.99816004 0 P 0 
L 0.96083996 -1.99716004 1.02335 -1.99716004 0 P 0 
L 0.9627 -1.99616004 1.02161004 -1.99616004 0 P 0 
L 0.96468996 -1.99516004 1.01951998 -1.99516004 0 P 0 
L 0.96685 -1.99416004 1.01683002 -1.99416004 0 P 0 
L 0.96936998 -1.99316004 1.01378002 -1.99316004 0 P 0 
L 0.97236998 -1.99216004 1.00981004 -1.99216004 0 P 0 
L 0.97676004 -1.99116004 1.00456998 -1.99116004 0 P 0 
L 1.06713996 -2.08283002 1.12288002 -2.08283002 0 P 0 
L 1.06698996 -2.08183002 1.12193996 -2.08183002 0 P 0 
L 1.06686004 -2.08083002 1.12108996 -2.08083002 0 P 0 
L 1.06673996 -2.07983002 1.12036004 -2.07983002 0 P 0 
L 1.06661998 -2.07883002 1.11971998 -2.07883002 0 P 0 
L 1.06653002 -2.07783002 1.11916004 -2.07783002 0 P 0 
L 1.06648002 -2.07683002 1.11866004 -2.07683002 0 P 0 
L 1.06641998 -2.07583002 1.11826004 -2.07583002 0 P 0 
L 1.06636998 -2.07483002 1.11791998 -2.07483002 0 P 0 
L 1.06631998 -2.07383002 1.11761998 -2.07383002 0 P 0 
L 1.06626004 -2.07283002 1.11741998 -2.07283002 0 P 0 
L 1.06621004 -2.07183002 1.11723996 -2.07183002 0 P 0 
L 1.06616004 -2.07083002 1.11711998 -2.07083002 0 P 0 
L 1.06616004 -2.06983002 1.11701004 -2.06983002 0 P 0 
L 1.06616004 -2.06883002 1.11688996 -2.06883002 0 P 0 
L 1.06616998 -2.06783002 1.11676998 -2.06783002 0 P 0 
L 1.06618002 -2.06683002 1.11666998 -2.06683002 0 P 0 
L 1.06618996 -2.06583002 1.11663002 -2.06583002 0 P 0 
L 1.0662 -2.06483002 1.11658996 -2.06483002 0 P 0 
L 1.06621004 -2.06383002 1.11656004 -2.06383002 0 P 0 
L 1.06623002 -2.06283002 1.11651998 -2.06283002 0 P 0 
L 1.06631004 -2.06183002 1.11648996 -2.06183002 0 P 0 
L 1.06638002 -2.06083002 1.11653002 -2.06083002 0 P 0 
L 1.06645 -2.05983002 1.11656998 -2.05983002 0 P 0 
L 1.06651998 -2.05883002 1.11661998 -2.05883002 0 P 0 
L 1.06658996 -2.05783002 1.11666004 -2.05783002 0 P 0 
L 1.06666998 -2.05683002 1.11671004 -2.05683002 0 P 0 
L 1.06673996 -2.05583002 1.11681004 -2.05583002 0 P 0 
L 1.06686004 -2.05483002 1.11693002 -2.05483002 0 P 0 
L 1.067 -2.05383002 1.11705 -2.05383002 0 P 0 
L 1.06713996 -2.05283002 1.11718002 -2.05283002 0 P 0 
L 1.06728002 -2.05183002 1.11731004 -2.05183002 0 P 0 
L 1.06741998 -2.05083002 1.11746004 -2.05083002 0 P 0 
L 1.06756004 -2.04983002 1.11766004 -2.04983002 0 P 0 
L 1.0677 -2.04883002 1.11786004 -2.04883002 0 P 0 
L 1.06786004 -2.04783002 1.11813996 -2.04783002 0 P 0 
L 1.06806998 -2.04683002 1.11841998 -2.04683002 0 P 0 
L 1.06828002 -2.04583002 1.11876998 -2.04583002 0 P 0 
L 1.06848996 -2.04483002 1.11913002 -2.04483002 0 P 0 
L 1.06871004 -2.04383002 1.11955 -2.04383002 0 P 0 
L 1.06898996 -2.04283002 1.11998996 -2.04283002 0 P 0 
L 1.06928002 -2.04183002 1.12048002 -2.04183002 0 P 0 
L 1.06956004 -2.04083002 1.12101004 -2.04083002 0 P 0 
L 1.06985 -2.03983002 1.12161998 -2.03983002 0 P 0 
L 1.07021004 -2.03883002 1.12225 -2.03883002 0 P 0 
L 1.07056998 -2.03783002 1.12298002 -2.03783002 0 P 0 
L 1.07093002 -2.03683002 1.12373996 -2.03683002 0 P 0 
L 1.07128996 -2.03583002 1.12461998 -2.03583002 0 P 0 
L 1.07173002 -2.03483002 1.12548996 -2.03483002 0 P 0 
L 1.07216998 -2.03383002 1.12646004 -2.03383002 0 P 0 
L 1.07261998 -2.03283002 1.12748996 -2.03283002 0 P 0 
L 1.07308002 -2.03183002 1.12855 -2.03183002 0 P 0 
L 1.07361998 -2.03083002 1.12978996 -2.03083002 0 P 0 
L 1.09761004 -1.91731004 1.12756998 -1.91731004 0 P 0 
L 1.09566004 -1.91631004 1.12645 -1.91631004 0 P 0 
L 1.09371004 -1.91531004 1.12533002 -1.91531004 0 P 0 
L 1.09176004 -1.91431004 1.12416004 -1.91431004 0 P 0 
L 1.08946004 -1.91331004 1.12283996 -1.91331004 0 P 0 
L 1.07415 -2.02983002 1.13101998 -2.02983002 0 P 0 
L 1.07468996 -2.02883002 1.13248996 -2.02883002 0 P 0 
L 1.07528996 -2.02783002 1.134 -2.02783002 0 P 0 
L 1.07591998 -2.02683002 1.13586004 -2.02683002 0 P 0 
L 1.07656004 -2.02583002 1.13828996 -2.02583002 0 P 0 
L 1.07721004 -2.02483002 1.14243002 -2.02483002 0 P 0 
L 1.07795 -2.02383002 1.21126998 -2.02383002 0 P 0 
L 1.07868002 -2.02283002 1.21133002 -2.02283002 0 P 0 
L 1.07941998 -2.02183002 1.2114 -2.02183002 0 P 0 
L 1.08021004 -2.02083002 1.21146004 -2.02083002 0 P 0 
L 1.08103996 -2.01983002 1.21153002 -2.01983002 0 P 0 
L 1.08186998 -2.01883002 1.2116 -2.01883002 0 P 0 
L 1.08273002 -2.01783002 1.21166004 -2.01783002 0 P 0 
L 1.08366998 -2.01683002 1.21173002 -2.01683002 0 P 0 
L 1.0846 -2.01583002 1.2118 -2.01583002 0 P 0 
L 1.08555 -2.01483002 1.21186004 -2.01483002 0 P 0 
L 1.08661004 -2.01383002 1.21193002 -2.01383002 0 P 0 
L 1.08766998 -2.01283002 1.21198996 -2.01283002 0 P 0 
L 1.08873002 -2.01183002 1.21205 -2.01183002 0 P 0 
L 1.0898 -2.01083002 1.21211998 -2.01083002 0 P 0 
L 1.09098996 -2.00983002 1.21218002 -2.00983002 0 P 0 
L 1.09225 -2.00883002 1.21223996 -2.00883002 0 P 0 
L 1.09358996 -2.00783002 1.2123 -2.00783002 0 P 0 
L 1.09506998 -2.00683002 1.21236004 -2.00683002 0 P 0 
L 1.09668996 -2.00583002 1.21241998 -2.00583002 0 P 0 
L 0.98546998 -2.12516004 1.03548996 -2.12516004 0 P 0 
L 0.98558996 -2.12416004 1.03553996 -2.12416004 0 P 0 
L 0.9857 -2.12316004 1.03558002 -2.12316004 0 P 0 
L 0.98581004 -2.12216004 1.03561998 -2.12216004 0 P 0 
L 0.98591004 -2.12116004 1.03566998 -2.12116004 0 P 0 
L 0.98598996 -2.12016004 1.03571004 -2.12016004 0 P 0 
L 0.98608002 -2.11916004 1.03575 -2.11916004 0 P 0 
L 0.98616998 -2.11816004 1.0358 -2.11816004 0 P 0 
L 0.98625 -2.11716004 1.03583996 -2.11716004 0 P 0 
L 0.98633996 -2.11616004 1.03588002 -2.11616004 0 P 0 
L 0.98641998 -2.11516004 1.03593002 -2.11516004 0 P 0 
L 0.98651004 -2.11416004 1.03596998 -2.11416004 0 P 0 
L 0.9866 -2.11316004 1.03601004 -2.11316004 0 P 0 
L 0.98668002 -2.11216004 1.03605 -2.11216004 0 P 0 
L 0.98676998 -2.11116004 1.0361 -2.11116004 0 P 0 
L 0.98685 -2.11016004 1.03613996 -2.11016004 0 P 0 
L 0.98693996 -2.10916004 1.03618002 -2.10916004 0 P 0 
L 0.987 -2.10816004 1.03623002 -2.10816004 0 P 0 
L 0.98705 -2.10716004 1.03626998 -2.10716004 0 P 0 
L 0.9871 -2.10616004 1.03631004 -2.10616004 0 P 0 
L 0.98716004 -2.10516004 1.03636004 -2.10516004 0 P 0 
L 0.9872 -2.10416004 1.0364 -2.10416004 0 P 0 
L 0.98725 -2.10316004 1.03643996 -2.10316004 0 P 0 
L 0.98731004 -2.10216004 1.03648002 -2.10216004 0 P 0 
L 0.98735 -2.10116004 1.03653002 -2.10116004 0 P 0 
L 0.9874 -2.10016004 1.03656998 -2.10016004 0 P 0 
L 0.98746004 -2.09916004 1.03661004 -2.09916004 0 P 0 
L 0.98751004 -2.09816004 1.03666004 -2.09816004 0 P 0 
L 0.98755 -2.09716004 1.0367 -2.09716004 0 P 0 
L 0.9876 -2.09616004 1.03673996 -2.09616004 0 P 0 
L 0.98766004 -2.09516004 1.03678996 -2.09516004 0 P 0 
L 0.9877 -2.09416004 1.03683002 -2.09416004 0 P 0 
L 0.98775 -2.09316004 1.03686998 -2.09316004 0 P 0 
L 0.98781004 -2.09216004 1.03691998 -2.09216004 0 P 0 
L 0.98785 -2.09116004 1.03696004 -2.09116004 0 P 0 
L 0.9879 -2.09016004 1.037 -2.09016004 0 P 0 
L 0.98796004 -2.08916004 1.03703996 -2.08916004 0 P 0 
L 0.98798996 -2.08816004 1.03706998 -2.08816004 0 P 0 
L 0.98801998 -2.08716004 1.03711004 -2.08716004 0 P 0 
L 0.98805 -2.08616004 1.03715 -2.08616004 0 P 0 
L 0.98808996 -2.08516004 1.03718996 -2.08516004 0 P 0 
L 0.98811998 -2.08416004 1.03723002 -2.08416004 0 P 0 
L 1.08216998 -2.15683002 1.19803996 -2.15683002 0 P 0 
L 1.0821 -2.15583002 1.19861004 -2.15583002 0 P 0 
L 1.08201998 -2.15483002 1.19918002 -2.15483002 0 P 0 
L 1.08195 -2.15383002 1.1997 -2.15383002 0 P 0 
L 1.08188996 -2.15283002 1.20018002 -2.15283002 0 P 0 
L 1.08183002 -2.15183002 1.20066004 -2.15183002 0 P 0 
L 1.08176998 -2.15083002 1.20113996 -2.15083002 0 P 0 
L 1.08171998 -2.14983002 1.20153996 -2.14983002 0 P 0 
L 1.08166004 -2.14883002 1.20193002 -2.14883002 0 P 0 
L 1.0816 -2.14783002 1.11538996 -2.14783002 0 P 0 
L 1.08155 -2.14683002 1.10903002 -2.14683002 0 P 0 
L 1.0815 -2.14583002 1.10415 -2.14583002 0 P 0 
L 1.08146004 -2.14483002 1.09953002 -2.14483002 0 P 0 
L 1.08141004 -2.14383002 1.09563996 -2.14383002 0 P 0 
L 1.08136004 -2.14283002 1.09183996 -2.14283002 0 P 0 
L 1.08131004 -2.14183002 1.08821004 -2.14183002 0 P 0 
L 1.08133002 -2.14083002 1.08471998 -2.14083002 0 P 0 
L 1.09586998 -2.11983002 1.14965 -2.11983002 0 P 0 
L 1.09361998 -2.11883002 1.15221998 -2.11883002 0 P 0 
L 1.09158996 -2.11783002 1.20595 -2.11783002 0 P 0 
L 1.08988002 -2.11683002 1.20601004 -2.11683002 0 P 0 
L 1.08823996 -2.11583002 1.20606998 -2.11583002 0 P 0 
L 1.08678996 -2.11483002 1.20613002 -2.11483002 0 P 0 
L 1.08541004 -2.11383002 1.20618996 -2.11383002 0 P 0 
L 1.08416998 -2.11283002 1.20625 -2.11283002 0 P 0 
L 1.08295 -2.11183002 1.20631004 -2.11183002 0 P 0 
L 1.08188002 -2.11083002 1.20638002 -2.11083002 0 P 0 
L 1.08081998 -2.10983002 1.20643996 -2.10983002 0 P 0 
L 1.07986004 -2.10883002 1.2065 -2.10883002 0 P 0 
L 1.07895 -2.10783002 1.20656004 -2.10783002 0 P 0 
L 1.07803002 -2.10683002 1.20661998 -2.10683002 0 P 0 
L 1.07723996 -2.10583002 1.20666998 -2.10583002 0 P 0 
L 1.07646004 -2.10483002 1.20671998 -2.10483002 0 P 0 
L 1.07568002 -2.10383002 1.20678002 -2.10383002 0 P 0 
L 1.075 -2.10283002 1.20683002 -2.10283002 0 P 0 
L 1.07433002 -2.10183002 1.20688002 -2.10183002 0 P 0 
L 1.07366998 -2.10083002 1.20693996 -2.10083002 0 P 0 
L 1.07308996 -2.09983002 1.20698996 -2.09983002 0 P 0 
L 1.07253002 -2.09883002 1.20705 -2.09883002 0 P 0 
L 1.07198002 -2.09783002 1.2071 -2.09783002 0 P 0 
L 1.07146998 -2.09683002 1.20715 -2.09683002 0 P 0 
L 1.07101998 -2.09583002 1.2072 -2.09583002 0 P 0 
L 1.07056998 -2.09483002 1.20726004 -2.09483002 0 P 0 
L 1.07013002 -2.09383002 1.20731004 -2.09383002 0 P 0 
L 1.06976998 -2.09283002 1.20736004 -2.09283002 0 P 0 
L 1.06941998 -2.09183002 1.20741998 -2.09183002 0 P 0 
L 1.06906004 -2.09083002 1.20746998 -2.09083002 0 P 0 
L 1.06876004 -2.08983002 1.20753002 -2.08983002 0 P 0 
L 1.06848996 -2.08883002 1.13443002 -2.08883002 0 P 0 
L 1.06821998 -2.08783002 1.13068002 -2.08783002 0 P 0 
L 1.06795 -2.08683002 1.12836998 -2.08683002 0 P 0 
L 1.06771998 -2.08583002 1.1266 -2.08583002 0 P 0 
L 1.06753002 -2.08483002 1.12516004 -2.08483002 0 P 0 
L 1.06733002 -2.08383002 1.12393996 -2.08383002 0 P 0 
L 0.90273996 -1.85456998 0.89068996 -1.85558002 0 P 0 
L 0.89068996 -1.85558002 0.87421004 -1.85741998 0 P 0 
L 0.87421004 -1.85741998 0.85783002 -1.85946998 0 P 0 
L 0.85783002 -1.85946998 0.85526998 -1.8599 0 P 0 
L 0.85526998 -1.8599 0.85276004 -1.86055 0 P 0 
L 0.85276004 -1.86055 0.85255 -1.86063996 0 P 0 
L 0.85255 -1.86063996 0.85248996 -1.86068996 0 P 0 
L 0.85248996 -1.86068996 0.85243002 -1.86073002 0 P 0 
L 0.85243002 -1.86073002 0.85238002 -1.86078002 0 P 0 
L 0.85238002 -1.86078002 0.85233002 -1.86083996 0 P 0 
L 0.85233002 -1.86083996 0.85225 -1.86096004 0 P 0 
L 0.85225 -1.86096004 0.85218002 -1.8611 0 P 0 
L 0.85218002 -1.8611 0.85216004 -1.86116998 0 P 0 
L 0.85216004 -1.86116998 0.85215 -1.86123996 0 P 0 
L 0.85215 -1.86123996 0.85213996 -1.86136998 0 P 0 
L 0.85213996 -1.86136998 0.85213002 -1.86148996 0 P 0 
L 0.85213002 -1.86148996 0.85213996 -1.86161998 0 P 0 
L 0.85213996 -1.86161998 0.85215 -1.86173996 0 P 0 
L 0.85215 -1.86173996 0.85218002 -1.86186998 0 P 0 
L 0.85218002 -1.86186998 0.85221004 -1.86198996 0 P 0 
L 0.85221004 -1.86198996 0.85225 -1.8621 0 P 0 
L 0.85225 -1.8621 0.85231004 -1.86221998 0 P 0 
L 0.85231004 -1.86221998 0.85236998 -1.86233002 0 P 0 
L 0.85236998 -1.86233002 0.85281998 -1.863 0 P 0 
L 0.85281998 -1.863 0.8533 -1.86363996 0 P 0 
L 0.8533 -1.86363996 0.85383002 -1.86425 0 P 0 
L 0.85383002 -1.86425 0.85736004 -1.86801998 0 P 0 
L 0.85736004 -1.86801998 0.86013002 -1.87113002 0 P 0 
L 0.86013002 -1.87113002 0.86266004 -1.87443002 0 P 0 
L 0.86266004 -1.87443002 0.86501004 -1.87798996 0 P 0 
L 0.86501004 -1.87798996 0.86711998 -1.88171004 0 P 0 
L 0.86711998 -1.88171004 0.86896998 -1.88553996 0 P 0 
L 0.86896998 -1.88553996 0.87055 -1.8895 0 P 0 
L 0.87055 -1.8895 0.8718 -1.89343002 0 P 0 
L 0.8718 -1.89343002 0.87276004 -1.89745 0 P 0 
L 0.87276004 -1.89745 0.87371004 -1.90195 0 P 0 
L 0.87371004 -1.90195 0.87383002 -1.90236004 0 P 0 
L 0.87383002 -1.90236004 0.87396998 -1.90276004 0 P 0 
L 0.87396998 -1.90276004 0.87416004 -1.90313996 0 P 0 
L 0.87416004 -1.90313996 0.87436998 -1.90351004 0 P 0 
L 0.87436998 -1.90351004 0.87443002 -1.9036 0 P 0 
L 0.87443002 -1.9036 0.87456998 -1.90376004 0 P 0 
L 0.87456998 -1.90376004 0.87465 -1.90381998 0 P 0 
L 0.87465 -1.90381998 0.87473002 -1.90388996 0 P 0 
L 0.87473002 -1.90388996 0.87481998 -1.90393996 0 P 0 
L 0.87481998 -1.90393996 0.87491998 -1.90398996 0 P 0 
L 0.87491998 -1.90398996 0.87501004 -1.90403002 0 P 0 
L 0.87501004 -1.90403002 0.87521004 -1.90408996 0 P 0 
L 0.87521004 -1.90408996 0.87531998 -1.9041 0 P 0 
L 0.87531998 -1.9041 0.87573002 -1.90413002 0 P 0 
L 0.87573002 -1.90413002 0.87613996 -1.90411998 0 P 0 
L 0.87613996 -1.90411998 0.87653996 -1.90408002 0 P 0 
L 0.87653996 -1.90408002 0.87695 -1.90401004 0 P 0 
L 0.87695 -1.90401004 0.90756004 -1.89766998 0 P 0 
L 0.90756004 -1.89766998 0.92603996 -1.89478002 0 P 0 
L 0.92603996 -1.89478002 0.93486004 -1.89393996 0 P 0 
L 0.93486004 -1.89393996 0.94371004 -1.8935 0 P 0 
L 0.94371004 -1.8935 0.97045 -1.89308002 0 P 0 
L 0.97045 -1.89308002 0.99468996 -1.89328996 0 P 0 
L 0.99468996 -1.89328996 1.01021004 -1.89413996 0 P 0 
L 1.01021004 -1.89413996 1.0241 -1.89601998 0 P 0 
L 1.0241 -1.89601998 1.04188002 -1.89961004 0 P 0 
L 1.04188002 -1.89961004 1.06095 -1.90466004 0 P 0 
L 1.06095 -1.90466004 1.07963996 -1.91123002 0 P 0 
L 1.07963996 -1.91123002 1.09093996 -1.91613002 0 P 0 
L 1.09093996 -1.91613002 1.10186998 -1.92175 0 P 0 
L 1.10186998 -1.92175 1.11243996 -1.92806998 0 P 0 
L 1.11243996 -1.92806998 1.12163002 -1.93446998 0 P 0 
L 1.12163002 -1.93446998 1.13033002 -1.94148996 0 P 0 
L 1.13033002 -1.94148996 1.1385 -1.94911004 0 P 0 
L 1.1385 -1.94911004 1.14358996 -1.9546 0 P 0 
L 1.14358996 -1.9546 1.14825 -1.96045 0 P 0 
L 1.14825 -1.96045 1.15246998 -1.96663002 0 P 0 
L 1.15246998 -1.96663002 1.15623002 -1.97316004 0 P 0 
L 1.15623002 -1.97316004 1.15895 -1.97831004 0 P 0 
L 1.15895 -1.97831004 1.17358996 -1.97831004 0 P 0 
L 1.17358996 -1.97831004 1.17135 -1.9726 0 P 0 
L 1.17135 -1.9726 1.16696004 -1.96266998 0 P 0 
L 1.16696004 -1.96266998 1.16171998 -1.95313002 0 P 0 
L 1.16171998 -1.95313002 1.1557 -1.94406998 0 P 0 
L 1.1557 -1.94406998 1.14885 -1.93548002 0 P 0 
L 1.14885 -1.93548002 1.13778996 -1.92378002 0 P 0 
L 1.13778996 -1.92378002 1.12576998 -1.91301998 0 P 0 
L 1.12576998 -1.91301998 1.11283996 -1.90326004 0 P 0 
L 1.11283996 -1.90326004 1.09783002 -1.89368996 0 P 0 
L 1.09783002 -1.89368996 1.08213002 -1.88526998 0 P 0 
L 1.08213002 -1.88526998 1.06576998 -1.87801004 0 P 0 
L 1.06576998 -1.87801004 1.04776004 -1.87141998 0 P 0 
L 1.04776004 -1.87141998 1.02938002 -1.86591998 0 P 0 
L 1.02938002 -1.86591998 1.01058002 -1.8615 0 P 0 
L 1.01058002 -1.8615 0.98441998 -1.85711004 0 P 0 
L 0.98441998 -1.85711004 0.95781004 -1.85448996 0 P 0 
L 0.95781004 -1.85448996 0.93061004 -1.85366004 0 P 0 
L 0.93061004 -1.85366004 0.90273996 -1.85456998 0 P 0 
L 1.16015 -1.97631004 1.15798002 -1.97218996 0 P 0 
L 1.15798002 -1.97218996 1.15796004 -1.97216004 0 P 0 
L 1.15796004 -1.97216004 1.15416004 -1.96556998 0 P 0 
L 1.15416004 -1.96556998 1.15411998 -1.96551004 0 P 0 
L 1.15411998 -1.96551004 1.14986004 -1.95926004 0 P 0 
L 1.14986004 -1.95926004 1.14981998 -1.95921004 0 P 0 
L 1.14981998 -1.95921004 1.14511004 -1.9533 0 P 0 
L 1.14511004 -1.9533 1.13991998 -1.9477 0 P 0 
L 1.13991998 -1.9477 1.13986004 -1.94765 0 P 0 
L 1.13986004 -1.94765 1.13163996 -1.93998002 0 P 0 
L 1.13163996 -1.93998002 1.12283002 -1.93286004 0 P 0 
L 1.12283002 -1.93286004 1.11351998 -1.92638996 0 P 0 
L 1.11351998 -1.92638996 1.10283996 -1.92 0 P 0 
L 1.10283996 -1.92 1.0918 -1.91433002 0 P 0 
L 1.0918 -1.91433002 1.08036998 -1.90936004 0 P 0 
L 1.08036998 -1.90936004 1.06153002 -1.90273996 0 P 0 
L 1.06153002 -1.90273996 1.06146004 -1.90273002 0 P 0 
L 1.06146004 -1.90273002 1.04233002 -1.89766004 0 P 0 
L 1.04233002 -1.89766004 1.02443002 -1.89405 0 P 0 
L 1.02443002 -1.89405 1.0104 -1.89213996 0 P 0 
L 1.0104 -1.89213996 0.99475 -1.89128996 0 P 0 
L 0.99475 -1.89128996 0.97045 -1.89108002 0 P 0 
L 0.97045 -1.89108002 0.94365 -1.8915 0 P 0 
L 0.94365 -1.8915 0.94361998 -1.8915 0 P 0 
L 0.94361998 -1.8915 0.93471998 -1.89195 0 P 0 
L 0.93471998 -1.89195 0.92578996 -1.89278996 0 P 0 
L 0.92578996 -1.89278996 0.9072 -1.89571004 0 P 0 
L 0.9072 -1.89571004 0.87656998 -1.90203996 0 P 0 
L 0.87656998 -1.90203996 0.87626998 -1.9021 0 P 0 
L 0.87626998 -1.9021 0.87601998 -1.90211998 0 P 0 
L 0.87601998 -1.90211998 0.87588996 -1.90213002 0 P 0 
L 0.87588996 -1.90213002 0.87583002 -1.90198996 0 P 0 
L 0.87583002 -1.90198996 0.87573002 -1.90175 0 P 0 
L 0.87573002 -1.90175 0.87566004 -1.90146998 0 P 0 
L 0.87566004 -1.90146998 0.87471004 -1.89701004 0 P 0 
L 0.87471004 -1.89701004 0.8747 -1.89698996 0 P 0 
L 0.8747 -1.89698996 0.87373002 -1.89288996 0 P 0 
L 0.87373002 -1.89288996 0.87243002 -1.88881998 0 P 0 
L 0.87243002 -1.88881998 0.8724 -1.88876004 0 P 0 
L 0.8724 -1.88876004 0.8708 -1.88473996 0 P 0 
L 0.8708 -1.88473996 0.8689 -1.88078002 0 P 0 
L 0.8689 -1.88078002 0.86671998 -1.87693996 0 P 0 
L 0.86671998 -1.87693996 0.86428996 -1.87326004 0 P 0 
L 0.86428996 -1.87326004 0.86166998 -1.86985 0 P 0 
L 0.86166998 -1.86985 0.85883996 -1.86668002 0 P 0 
L 0.85883996 -1.86668002 0.85883002 -1.86666004 0 P 0 
L 0.85883002 -1.86666004 0.85531998 -1.86291004 0 P 0 
L 0.85531998 -1.86291004 0.85486004 -1.86238002 0 P 0 
L 0.85486004 -1.86238002 0.85466004 -1.86211998 0 P 0 
L 0.85466004 -1.86211998 0.8557 -1.86186004 0 P 0 
L 0.8557 -1.86186004 0.85811998 -1.86145 0 P 0 
L 0.85811998 -1.86145 0.87443996 -1.85941004 0 P 0 
L 0.87443996 -1.85941004 0.89088996 -1.85756998 0 P 0 
L 0.89088996 -1.85756998 0.90286004 -1.85656998 0 P 0 
L 0.90286004 -1.85656998 0.93061004 -1.85566004 0 P 0 
L 0.93061004 -1.85566004 0.95768002 -1.85648996 0 P 0 
L 0.95768002 -1.85648996 0.98416004 -1.8591 0 P 0 
L 0.98416004 -1.8591 1.01018996 -1.86346004 0 P 0 
L 1.01018996 -1.86346004 1.02886004 -1.86785 0 P 0 
L 1.02886004 -1.86785 1.04711998 -1.87331998 0 P 0 
L 1.04711998 -1.87331998 1.06501004 -1.87986004 0 P 0 
L 1.06501004 -1.87986004 1.08125 -1.88706998 0 P 0 
L 1.08125 -1.88706998 1.09681004 -1.89541998 0 P 0 
L 1.09681004 -1.89541998 1.1117 -1.9049 0 P 0 
L 1.1117 -1.9049 1.1245 -1.91456998 0 P 0 
L 1.1245 -1.91456998 1.13638996 -1.92521004 0 P 0 
L 1.13638996 -1.92521004 1.14733996 -1.93678996 0 P 0 
L 1.14733996 -1.93678996 1.15408002 -1.94525 0 P 0 
L 1.15408002 -1.94525 1.16001004 -1.95416998 0 P 0 
L 1.16001004 -1.95416998 1.16516004 -1.96355 0 P 0 
L 1.16516004 -1.96355 1.1695 -1.97336998 0 P 0 
L 1.1695 -1.97336998 1.17066004 -1.97631004 0 P 0 
L 1.17066004 -1.97631004 1.16015 -1.97631004 0 P 0 
L 0.87563002 -1.90131004 0.8801 -1.90131004 0 P 0 
L 0.87541004 -1.90031004 0.88493996 -1.90031004 0 P 0 
L 0.8752 -1.89931004 0.88976998 -1.89931004 0 P 0 
L 0.87498996 -1.89831004 0.8946 -1.89831004 0 P 0 
L 0.89423002 -2.08316004 0.94355 -2.08316004 0 P 0 
L 0.89428996 -2.08216004 0.9436 -2.08216004 0 P 0 
L 0.89435 -2.08116004 0.94365 -2.08116004 0 P 0 
L 0.89441004 -2.08016004 0.9437 -2.08016004 0 P 0 
L 0.89446004 -2.07916004 0.94375 -2.07916004 0 P 0 
L 0.89451998 -2.07816004 0.94378996 -2.07816004 0 P 0 
L 0.89458002 -2.07716004 0.94383996 -2.07716004 0 P 0 
L 0.89463996 -2.07616004 0.94388996 -2.07616004 0 P 0 
L 0.8947 -2.07516004 0.94393996 -2.07516004 0 P 0 
L 0.89475 -2.07416004 0.94398002 -2.07416004 0 P 0 
L 0.89481004 -2.07316004 0.94403002 -2.07316004 0 P 0 
L 0.89486998 -2.07216004 0.94408002 -2.07216004 0 P 0 
L 0.89493002 -2.07116004 0.94415 -2.07116004 0 P 0 
L 0.89498996 -2.07016004 0.94426004 -2.07016004 0 P 0 
L 0.89505 -2.06916004 0.94436998 -2.06916004 0 P 0 
L 0.8951 -2.06816004 0.94448002 -2.06816004 0 P 0 
L 0.89516004 -2.06716004 0.94458996 -2.06716004 0 P 0 
L 0.89521998 -2.06616004 0.9447 -2.06616004 0 P 0 
L 0.89526998 -2.06516004 0.94481004 -2.06516004 0 P 0 
L 0.89531004 -2.06416004 0.94491998 -2.06416004 0 P 0 
L 0.89535 -2.06316004 0.94503002 -2.06316004 0 P 0 
L 0.8954 -2.06216004 0.94513996 -2.06216004 0 P 0 
L 0.89543996 -2.06116004 0.94531998 -2.06116004 0 P 0 
L 0.89548996 -2.06016004 0.94551004 -2.06016004 0 P 0 
L 0.89553002 -2.05916004 0.9457 -2.05916004 0 P 0 
L 0.89558002 -2.05816004 0.94588996 -2.05816004 0 P 0 
L 0.89561998 -2.05716004 0.94608002 -2.05716004 0 P 0 
L 0.89566998 -2.05616004 0.94626998 -2.05616004 0 P 0 
L 0.89571004 -2.05516004 0.94646998 -2.05516004 0 P 0 
L 0.89575 -2.05416004 0.94666004 -2.05416004 0 P 0 
L 0.8958 -2.05316004 0.94685 -2.05316004 0 P 0 
L 0.89583996 -2.05216004 0.94708002 -2.05216004 0 P 0 
L 0.89588996 -2.05116004 0.94735 -2.05116004 0 P 0 
L 0.89593996 -2.05016004 0.94761998 -2.05016004 0 P 0 
L 0.89598002 -2.04916004 0.9479 -2.04916004 0 P 0 
L 0.89601998 -2.04816004 0.94825 -2.04816004 0 P 0 
L 0.89606998 -2.04716004 0.94858996 -2.04716004 0 P 0 
L 0.89611004 -2.04616004 0.94893002 -2.04616004 0 P 0 
L 0.89616004 -2.04516004 0.94935 -2.04516004 0 P 0 
L 0.8962 -2.04416004 0.94976998 -2.04416004 0 P 0 
L 0.89625 -2.04316004 0.9502 -2.04316004 0 P 0 
L 0.89628002 -2.04216004 0.95068996 -2.04216004 0 P 0 
L 0.89631004 -2.04116004 0.95118996 -2.04116004 0 P 0 
L 0.89633996 -2.04016004 0.95168996 -2.04016004 0 P 0 
L 0.89638002 -2.03916004 0.95228002 -2.03916004 0 P 0 
L 0.89641004 -2.03816004 0.95291004 -2.03816004 0 P 0 
L 0.89643996 -2.03716004 0.95363002 -2.03716004 0 P 0 
L 0.89646998 -2.03616004 0.95445 -2.03616004 0 P 0 
L 0.89651004 -2.03516004 0.95535 -2.03516004 0 P 0 
L 0.89653996 -2.03416004 0.95636998 -2.03416004 0 P 0 
L 0.89656998 -2.03316004 0.95756998 -2.03316004 0 P 0 
L 0.8966 -2.03216004 0.95893996 -2.03216004 0 P 0 
L 0.89663996 -2.03116004 0.96055 -2.03116004 0 P 0 
L 0.89666998 -2.03016004 0.96278002 -2.03016004 0 P 0 
L 0.8967 -2.02916004 0.96676004 -2.02916004 0 P 0 
L 0.89673996 -2.02816004 1.03838996 -2.02816004 0 P 0 
L 0.89676998 -2.02716004 1.03838002 -2.02716004 0 P 0 
L 0.8968 -2.02616004 1.03833996 -2.02616004 0 P 0 
L 0.89683996 -2.02516004 1.03828996 -2.02516004 0 P 0 
L 0.89686998 -2.02416004 1.03823002 -2.02416004 0 P 0 
L 0.8969 -2.02316004 1.03816004 -2.02316004 0 P 0 
L 0.89693996 -2.02216004 1.0381 -2.02216004 0 P 0 
L 0.89696998 -2.02116004 1.03803996 -2.02116004 0 P 0 
L 0.897 -2.02016004 1.0379 -2.02016004 0 P 0 
L 0.89703002 -2.01916004 1.03773996 -2.01916004 0 P 0 
L 0.89706004 -2.01816004 1.03751998 -2.01816004 0 P 0 
L 0.89708996 -2.01716004 1.03728002 -2.01716004 0 P 0 
L 0.89711998 -2.01616004 1.03698996 -2.01616004 0 P 0 
L 0.89713996 -2.01516004 1.03668002 -2.01516004 0 P 0 
L 0.89716998 -2.01416004 1.03631004 -2.01416004 0 P 0 
L 0.8972 -2.01316004 1.03591998 -2.01316004 0 P 0 
L 0.89721998 -2.01216004 1.03548996 -2.01216004 0 P 0 
L 0.89725 -2.01116004 1.03505 -2.01116004 0 P 0 
L 0.89726998 -2.01016004 1.03458002 -2.01016004 0 P 0 
L 0.8973 -2.00916004 1.03405 -2.00916004 0 P 0 
L 0.89733002 -2.00816004 1.03351998 -2.00816004 0 P 0 
L 0.89736004 -2.00716004 0.94676004 -2.00716004 0 P 0 
L 0.89738002 -2.00616004 0.9461 -2.00616004 0 P 0 
L 0.89741004 -2.00516004 0.94563996 -2.00516004 0 P 0 
L 0.89743996 -2.00416004 0.94563996 -2.00416004 0 P 0 
L 0.89746004 -2.00316004 0.94563996 -2.00316004 0 P 0 
L 0.89748996 -2.00216004 0.94563996 -2.00216004 0 P 0 
L 0.89751004 -2.00116004 0.94563996 -2.00116004 0 P 0 
L 0.89753996 -2.00016004 0.94563996 -2.00016004 0 P 0 
L 0.89756998 -1.99916004 0.94563996 -1.99916004 0 P 0 
L 0.8976 -1.99816004 0.94563996 -1.99816004 0 P 0 
L 0.89761998 -1.99716004 0.94563996 -1.99716004 0 P 0 
L 0.89765 -1.99616004 0.94563996 -1.99616004 0 P 0 
L 0.89768002 -1.99516004 0.94563996 -1.99516004 0 P 0 
L 0.97546998 -1.98933996 0.97236998 -1.99006004 0 P 0 
L 0.97236998 -1.99006004 0.96931998 -1.99103002 0 P 0 
L 0.96931998 -1.99103002 0.96603002 -1.99233002 0 P 0 
L 0.96603002 -1.99233002 0.96281004 -1.99383002 0 P 0 
L 0.96281004 -1.99383002 0.95976004 -1.99546998 0 P 0 
L 0.95976004 -1.99546998 0.95681004 -1.99728996 0 P 0 
L 0.95681004 -1.99728996 0.95521004 -1.99841004 0 P 0 
L 0.95521004 -1.99841004 0.95368996 -1.99963002 0 P 0 
L 0.95368996 -1.99963002 0.95223996 -2.00095 0 P 0 
L 0.95223996 -2.00095 0.94763996 -2.00546998 0 P 0 
L 0.94763996 -2.00546998 0.94763996 -1.99243996 0 P 0 
L 0.94763996 -1.99243996 0.89575 -1.99243996 0 P 0 
L 0.89575 -1.99243996 0.89505 -2.01878002 0 P 0 
L 0.89505 -2.01878002 0.89423996 -2.04316004 0 P 0 
L 0.89423996 -2.04316004 0.89321998 -2.0661 0 P 0 
L 0.89321998 -2.0661 0.89198996 -2.08728996 0 P 0 
L 0.89198996 -2.08728996 0.89055 -2.1063 0 P 0 
L 0.89055 -2.1063 0.88993996 -2.11358002 0 P 0 
L 0.88993996 -2.11358002 0.88943002 -2.11988002 0 P 0 
L 0.88943002 -2.11988002 0.88898996 -2.12533996 0 P 0 
L 0.88898996 -2.12533996 0.88896004 -2.12613002 0 P 0 
L 0.88896004 -2.12613002 0.88896998 -2.12621004 0 P 0 
L 0.88896998 -2.12621004 0.88898002 -2.12625 0 P 0 
L 0.88898002 -2.12625 0.88898996 -2.12628002 0 P 0 
L 0.88898996 -2.12628002 0.88901998 -2.12636004 0 P 0 
L 0.88901998 -2.12636004 0.88903996 -2.12638996 0 P 0 
L 0.88903996 -2.12638996 0.88906998 -2.12641998 0 P 0 
L 0.88906998 -2.12641998 0.88908996 -2.12645 0 P 0 
L 0.88908996 -2.12645 0.88911998 -2.12646998 0 P 0 
L 0.88911998 -2.12646998 0.88915 -2.1265 0 P 0 
L 0.88915 -2.1265 0.88921004 -2.12653996 0 P 0 
L 0.88921004 -2.12653996 0.88925 -2.12655 0 P 0 
L 0.88925 -2.12655 0.88928002 -2.12656004 0 P 0 
L 0.88928002 -2.12656004 0.88931998 -2.12658002 0 P 0 
L 0.88931998 -2.12658002 0.8894 -2.12658002 0 P 0 
L 0.8894 -2.12658002 0.89648002 -2.12686998 0 P 0 
L 0.89648002 -2.12686998 0.90518996 -2.1271 0 P 0 
L 0.90518996 -2.1271 0.9165 -2.12716004 0 P 0 
L 0.9165 -2.12716004 0.94403996 -2.12716004 0 P 0 
L 0.94403996 -2.12716004 0.94468996 -2.10135 0 P 0 
L 0.94468996 -2.10135 0.9461 -2.07171998 0 P 0 
L 0.9461 -2.07171998 0.94713002 -2.06233002 0 P 0 
L 0.94713002 -2.06233002 0.9489 -2.05308002 0 P 0 
L 0.9489 -2.05308002 0.94975 -2.04995 0 P 0 
L 0.94975 -2.04995 0.9508 -2.04688996 0 P 0 
L 0.9508 -2.04688996 0.95205 -2.0439 0 P 0 
L 0.95205 -2.0439 0.95351004 -2.041 0 P 0 
L 0.95351004 -2.041 0.9544 -2.03951004 0 P 0 
L 0.9544 -2.03951004 0.95541998 -2.03811004 0 P 0 
L 0.95541998 -2.03811004 0.95655 -2.03678996 0 P 0 
L 0.95655 -2.03678996 0.95778996 -2.03556998 0 P 0 
L 0.95778996 -2.03556998 0.95911998 -2.03446998 0 P 0 
L 0.95911998 -2.03446998 0.96056998 -2.03346998 0 P 0 
L 0.96056998 -2.03346998 0.96151004 -2.03291004 0 P 0 
L 0.96151004 -2.03291004 0.96248996 -2.03243002 0 P 0 
L 0.96248996 -2.03243002 0.96351004 -2.03201998 0 P 0 
L 0.96351004 -2.03201998 0.96455 -2.03168996 0 P 0 
L 0.96455 -2.03168996 0.96613002 -2.0313 0 P 0 
L 0.96613002 -2.0313 0.96773002 -2.03101998 0 P 0 
L 0.96773002 -2.03101998 0.96935 -2.03086004 0 P 0 
L 0.96935 -2.03086004 0.97095 -2.03081004 0 P 0 
L 0.97095 -2.03081004 0.97255 -2.03086998 0 P 0 
L 0.97255 -2.03086998 0.97413002 -2.03105 0 P 0 
L 0.97413002 -2.03105 0.97513002 -2.03123996 0 P 0 
L 0.97513002 -2.03123996 0.9761 -2.03151004 0 P 0 
L 0.9761 -2.03151004 0.97706004 -2.03186004 0 P 0 
L 0.97706004 -2.03186004 0.97796998 -2.0323 0 P 0 
L 0.97796998 -2.0323 0.97885 -2.0328 0 P 0 
L 0.97885 -2.0328 0.97968002 -2.03336998 0 P 0 
L 0.97968002 -2.03336998 0.98046998 -2.03398996 0 P 0 
L 0.98046998 -2.03398996 0.98121998 -2.03468002 0 P 0 
L 0.98121998 -2.03468002 0.98191004 -2.03541998 0 P 0 
L 0.98191004 -2.03541998 0.98253996 -2.0362 0 P 0 
L 0.98253996 -2.0362 0.9831 -2.03703002 0 P 0 
L 0.9831 -2.03703002 0.9836 -2.03788996 0 P 0 
L 0.9836 -2.03788996 0.98403996 -2.0388 0 P 0 
L 0.98403996 -2.0388 0.9844 -2.03973996 0 P 0 
L 0.9844 -2.03973996 0.98505 -2.04188996 0 P 0 
L 0.98505 -2.04188996 0.98553002 -2.04408002 0 P 0 
L 0.98553002 -2.04408002 0.98583002 -2.0463 0 P 0 
L 0.98583002 -2.0463 0.98653002 -2.05705 0 P 0 
L 0.98653002 -2.05705 0.9866 -2.06961004 0 P 0 
L 0.9866 -2.06961004 0.98596004 -2.08908002 0 P 0 
L 0.98596004 -2.08908002 0.98498002 -2.10858002 0 P 0 
L 0.98498002 -2.10858002 0.98388002 -2.12146998 0 P 0 
L 0.98388002 -2.12146998 0.98323002 -2.12716004 0 P 0 
L 0.98323002 -2.12716004 1.03741004 -2.12716004 0 P 0 
L 1.03741004 -2.12716004 1.03896004 -2.09103002 0 P 0 
L 1.03896004 -2.09103002 1.03956004 -2.0759 0 P 0 
L 1.03956004 -2.0759 1.04005 -2.06025 0 P 0 
L 1.04005 -2.06025 1.04038996 -2.04626004 0 P 0 
L 1.04038996 -2.04626004 1.04048002 -2.03698996 0 P 0 
L 1.04048002 -2.03698996 1.04036998 -2.02651998 0 P 0 
L 1.04036998 -2.02651998 1.04003996 -2.02096998 0 P 0 
L 1.04003996 -2.02096998 1.03975 -2.01895 0 P 0 
L 1.03975 -2.01895 1.0393 -2.01693996 0 P 0 
L 1.0393 -2.01693996 1.03868996 -2.01483996 0 P 0 
L 1.03868996 -2.01483996 1.03793996 -2.01278002 0 P 0 
L 1.03793996 -2.01278002 1.03658996 -2.00968002 0 P 0 
L 1.03658996 -2.00968002 1.03501004 -2.00668996 0 P 0 
L 1.03501004 -2.00668996 1.0332 -2.0038 0 P 0 
L 1.0332 -2.0038 1.03186998 -2.002 0 P 0 
L 1.03186998 -2.002 1.0304 -2.0003 0 P 0 
L 1.0304 -2.0003 1.0288 -1.99873002 0 P 0 
L 1.0288 -1.99873002 1.02708002 -1.99728996 0 P 0 
L 1.02708002 -1.99728996 1.02518002 -1.99593002 0 P 0 
L 1.02518002 -1.99593002 1.02318002 -1.99471998 0 P 0 
L 1.02318002 -1.99471998 1.0211 -1.99365 0 P 0 
L 1.0211 -1.99365 1.01893002 -1.99273996 0 P 0 
L 1.01893002 -1.99273996 1.01358996 -1.99098996 0 P 0 
L 1.01358996 -1.99098996 1.0081 -1.98971004 0 P 0 
L 1.0081 -1.98971004 1.00428996 -1.98908996 0 P 0 
L 1.00428996 -1.98908996 1.00043996 -1.98868002 0 P 0 
L 1.00043996 -1.98868002 0.99138002 -1.98826004 0 P 0 
L 0.99138002 -1.98826004 0.98251998 -1.98846998 0 P 0 
L 0.98251998 -1.98846998 0.97898996 -1.98878996 0 P 0 
L 0.97898996 -1.98878996 0.97546998 -1.98933996 0 P 0 
L 0.91651004 -2.12516004 0.94208996 -2.12516004 0 P 0 
L 0.8911 -2.12416004 0.94211004 -2.12416004 0 P 0 
L 0.89118002 -2.12316004 0.94213996 -2.12316004 0 P 0 
L 0.89125 -2.12216004 0.94216004 -2.12216004 0 P 0 
L 0.89133002 -2.12116004 0.94218996 -2.12116004 0 P 0 
L 0.89141004 -2.12016004 0.94221004 -2.12016004 0 P 0 
L 0.89148996 -2.11916004 0.94223996 -2.11916004 0 P 0 
L 0.89156998 -2.11816004 0.94226998 -2.11816004 0 P 0 
L 0.89166004 -2.11716004 0.94228996 -2.11716004 0 P 0 
L 0.89173996 -2.11616004 0.94231004 -2.11616004 0 P 0 
L 0.89181998 -2.11516004 0.94233996 -2.11516004 0 P 0 
L 0.8919 -2.11416004 0.94236004 -2.11416004 0 P 0 
L 0.89198002 -2.11316004 0.94238996 -2.11316004 0 P 0 
L 0.89206998 -2.11216004 0.94241998 -2.11216004 0 P 0 
L 0.89215 -2.11116004 0.94243996 -2.11116004 0 P 0 
L 0.89223002 -2.11016004 0.94246998 -2.11016004 0 P 0 
L 0.89231998 -2.10916004 0.94248996 -2.10916004 0 P 0 
L 0.8924 -2.10816004 0.94251998 -2.10816004 0 P 0 
L 0.89248002 -2.10716004 0.94255 -2.10716004 0 P 0 
L 0.89256998 -2.10616004 0.94256998 -2.10616004 0 P 0 
L 0.89263996 -2.10516004 0.94258996 -2.10516004 0 P 0 
L 0.89271004 -2.10416004 0.94261998 -2.10416004 0 P 0 
L 0.89278996 -2.10316004 0.94263996 -2.10316004 0 P 0 
L 0.89286998 -2.10216004 0.94266998 -2.10216004 0 P 0 
L 0.89293996 -2.10116004 0.9427 -2.10116004 0 P 0 
L 0.89301998 -2.10016004 0.94275 -2.10016004 0 P 0 
L 0.89308996 -2.09916004 0.94278996 -2.09916004 0 P 0 
L 0.89316998 -2.09816004 0.94283996 -2.09816004 0 P 0 
L 0.89325 -2.09716004 0.94288996 -2.09716004 0 P 0 
L 0.89331998 -2.09616004 0.94293996 -2.09616004 0 P 0 
L 0.8934 -2.09516004 0.94298002 -2.09516004 0 P 0 
L 0.89346998 -2.09416004 0.94303002 -2.09416004 0 P 0 
L 0.89355 -2.09316004 0.94308002 -2.09316004 0 P 0 
L 0.89361998 -2.09216004 0.94313002 -2.09216004 0 P 0 
L 0.8937 -2.09116004 0.94318002 -2.09116004 0 P 0 
L 0.89378002 -2.09016004 0.94321998 -2.09016004 0 P 0 
L 0.89385 -2.08916004 0.94326998 -2.08916004 0 P 0 
L 0.89393002 -2.08816004 0.94331998 -2.08816004 0 P 0 
L 0.894 -2.08716004 0.94336004 -2.08716004 0 P 0 
L 0.89406004 -2.08616004 0.94341004 -2.08616004 0 P 0 
L 0.89411998 -2.08516004 0.94346004 -2.08516004 0 P 0 
L 0.89418002 -2.08416004 0.94351004 -2.08416004 0 P 0 
L 0.91651004 -2.12516004 0.90521998 -2.1251 0 P 0 
L 0.90521998 -2.1251 0.89655 -2.12486998 0 P 0 
L 0.89655 -2.12486998 0.89106004 -2.12465 0 P 0 
L 0.89106004 -2.12465 0.89141998 -2.12003996 0 P 0 
L 0.89141998 -2.12003996 0.89193996 -2.11373996 0 P 0 
L 0.89193996 -2.11373996 0.89253996 -2.10645 0 P 0 
L 0.89253996 -2.10645 0.89398002 -2.08741998 0 P 0 
L 0.89398002 -2.08741998 0.89521998 -2.06621998 0 P 0 
L 0.89521998 -2.06621998 0.89521998 -2.06618996 0 P 0 
L 0.89521998 -2.06618996 0.89623996 -2.04323002 0 P 0 
L 0.89623996 -2.04323002 0.89703996 -2.01883002 0 P 0 
L 0.89703996 -2.01883002 0.8977 -1.99443996 0 P 0 
L 0.8977 -1.99443996 0.94563996 -1.99443996 0 P 0 
L 0.94563996 -1.99443996 0.94563996 -2.00546998 0 P 0 
L 0.94563996 -2.00546998 0.94686004 -2.00731004 0 P 0 
L 0.94686004 -2.00731004 0.94903002 -2.00688996 0 P 0 
L 0.94903002 -2.00688996 0.95361998 -2.00241004 0 P 0 
L 0.95361998 -2.00241004 0.95498996 -2.00115 0 P 0 
L 0.95498996 -2.00115 0.95641998 -2.00001004 0 P 0 
L 0.95641998 -2.00001004 0.9579 -1.99896004 0 P 0 
L 0.9579 -1.99896004 0.96076004 -1.9972 0 P 0 
L 0.96076004 -1.9972 0.9637 -1.99561998 0 P 0 
L 0.9637 -1.99561998 0.96683002 -1.99416998 0 P 0 
L 0.96683002 -1.99416998 0.96998996 -1.99291998 0 P 0 
L 0.96998996 -1.99291998 0.9729 -1.99198996 0 P 0 
L 0.9729 -1.99198996 0.97586004 -1.9913 0 P 0 
L 0.97586004 -1.9913 0.97923002 -1.99076998 0 P 0 
L 0.97923002 -1.99076998 0.98263002 -1.99046998 0 P 0 
L 0.98263002 -1.99046998 0.99136004 -1.99026004 0 P 0 
L 0.99136004 -1.99026004 1.00028996 -1.99066998 0 P 0 
L 1.00028996 -1.99066998 1.00403002 -1.99108002 0 P 0 
L 1.00403002 -1.99108002 1.00771004 -1.99166998 0 P 0 
L 1.00771004 -1.99166998 1.01305 -1.99291998 0 P 0 
L 1.01305 -1.99291998 1.01823002 -1.99461998 0 P 0 
L 1.01823002 -1.99461998 1.02026004 -1.99546998 0 P 0 
L 1.02026004 -1.99546998 1.02221004 -1.99646998 0 P 0 
L 1.02221004 -1.99646998 1.02408002 -1.9976 0 P 0 
L 1.02408002 -1.9976 1.02585 -1.99886998 0 P 0 
L 1.02585 -1.99886998 1.02746004 -2.00021004 0 P 0 
L 1.02746004 -2.00021004 1.02893996 -2.00166998 0 P 0 
L 1.02893996 -2.00166998 1.03031004 -2.00325 0 P 0 
L 1.03031004 -2.00325 1.03155 -2.00493002 0 P 0 
L 1.03155 -2.00493002 1.03326998 -2.00768002 0 P 0 
L 1.03326998 -2.00768002 1.03478002 -2.01055 0 P 0 
L 1.03478002 -2.01055 1.03608002 -2.01351998 0 P 0 
L 1.03608002 -2.01351998 1.03678996 -2.01546998 0 P 0 
L 1.03678996 -2.01546998 1.03736004 -2.01743002 0 P 0 
L 1.03736004 -2.01743002 1.03778002 -2.0193 0 P 0 
L 1.03778002 -2.0193 1.03805 -2.02116998 0 P 0 
L 1.03805 -2.02116998 1.03836998 -2.02658996 0 P 0 
L 1.03836998 -2.02658996 1.03848002 -2.03698996 0 P 0 
L 1.03848002 -2.03698996 1.03838996 -2.04623002 0 P 0 
L 1.03838996 -2.04623002 1.03805 -2.06018996 0 P 0 
L 1.03805 -2.06018996 1.03756004 -2.07583002 0 P 0 
L 1.03756004 -2.07583002 1.03696998 -2.09095 0 P 0 
L 1.03696998 -2.09095 1.03548996 -2.12516004 0 P 0 
L 1.03548996 -2.12516004 0.98546998 -2.12516004 0 P 0 
L 0.98546998 -2.12516004 0.98586998 -2.12166004 0 P 0 
L 0.98586998 -2.12166004 0.98696998 -2.10871998 0 P 0 
L 0.98696998 -2.10871998 0.98796004 -2.08916004 0 P 0 
L 0.98796004 -2.08916004 0.9886 -2.06963002 0 P 0 
L 0.9886 -2.06963002 0.98853002 -2.05698002 0 P 0 
L 0.98853002 -2.05698002 0.98781998 -2.0461 0 P 0 
L 0.98781998 -2.0461 0.9875 -2.04373002 0 P 0 
L 0.9875 -2.04373002 0.98748002 -2.04365 0 P 0 
L 0.98748002 -2.04365 0.98698996 -2.04138996 0 P 0 
L 0.98698996 -2.04138996 0.9863 -2.03908002 0 P 0 
L 0.9863 -2.03908002 0.98588002 -2.038 0 P 0 
L 0.98588002 -2.038 0.98538002 -2.03696004 0 P 0 
L 0.98538002 -2.03696004 0.9848 -2.03596004 0 P 0 
L 0.9848 -2.03596004 0.98413996 -2.03501004 0 P 0 
L 0.98413996 -2.03501004 0.98341998 -2.03411004 0 P 0 
L 0.98341998 -2.03411004 0.98336998 -2.03405 0 P 0 
L 0.98336998 -2.03405 0.98263002 -2.03326004 0 P 0 
L 0.98263002 -2.03326004 0.98176998 -2.03246998 0 P 0 
L 0.98176998 -2.03246998 0.98086998 -2.03175 0 P 0 
L 0.98086998 -2.03175 0.97991004 -2.0311 0 P 0 
L 0.97991004 -2.0311 0.9789 -2.03051998 0 P 0 
L 0.9789 -2.03051998 0.97783002 -2.03001998 0 P 0 
L 0.97783002 -2.03001998 0.97673002 -2.02961004 0 P 0 
L 0.97673002 -2.02961004 0.97663996 -2.02958002 0 P 0 
L 0.97663996 -2.02958002 0.97558996 -2.02928996 0 P 0 
L 0.97558996 -2.02928996 0.97443002 -2.02906998 0 P 0 
L 0.97443002 -2.02906998 0.9727 -2.02888002 0 P 0 
L 0.9727 -2.02888002 0.97261998 -2.02886998 0 P 0 
L 0.97261998 -2.02886998 0.97096004 -2.02881004 0 P 0 
L 0.97096004 -2.02881004 0.96921004 -2.02886004 0 P 0 
L 0.96921004 -2.02886004 0.96745 -2.02903996 0 P 0 
L 0.96745 -2.02903996 0.96571004 -2.02933996 0 P 0 
L 0.96571004 -2.02933996 0.964 -2.02976004 0 P 0 
L 0.964 -2.02976004 0.96283002 -2.03013996 0 P 0 
L 0.96283002 -2.03013996 0.96168002 -2.0306 0 P 0 
L 0.96168002 -2.0306 0.96056998 -2.03115 0 P 0 
L 0.96056998 -2.03115 0.95948996 -2.03178002 0 P 0 
L 0.95948996 -2.03178002 0.95791004 -2.03286998 0 P 0 
L 0.95791004 -2.03286998 0.95645 -2.03408996 0 P 0 
L 0.95645 -2.03408996 0.95508996 -2.03541998 0 P 0 
L 0.95508996 -2.03541998 0.95383996 -2.03686998 0 P 0 
L 0.95383996 -2.03686998 0.9538 -2.03693002 0 P 0 
L 0.9538 -2.03693002 0.95273002 -2.03841004 0 P 0 
L 0.95273002 -2.03841004 0.95175 -2.04003996 0 P 0 
L 0.95175 -2.04003996 0.95023002 -2.04306004 0 P 0 
L 0.95023002 -2.04306004 0.94896004 -2.04611004 0 P 0 
L 0.94896004 -2.04611004 0.94893002 -2.04616998 0 P 0 
L 0.94893002 -2.04616998 0.94783002 -2.04936004 0 P 0 
L 0.94783002 -2.04936004 0.94695 -2.05263002 0 P 0 
L 0.94695 -2.05263002 0.94515 -2.06203002 0 P 0 
L 0.94515 -2.06203002 0.9441 -2.07156004 0 P 0 
L 0.9441 -2.07156004 0.9427 -2.10128002 0 P 0 
L 0.9427 -2.10128002 0.94208996 -2.12516004 0 P 0 
L 0.94208996 -2.12516004 0.91651004 -2.12516004 0 P 0 
L 0.93143002 -2.21261998 1.00578996 -2.21261998 0 P 0 
L 0.94051004 -2.21161998 1.00803002 -2.21161998 0 P 0 
L 0.94941998 -2.21061998 1.01026004 -2.21061998 0 P 0 
L 0.9555 -2.20961998 1.0125 -2.20961998 0 P 0 
L 0.96158002 -2.20861998 1.01473996 -2.20861998 0 P 0 
L 0.96766004 -2.20761998 1.01696998 -2.20761998 0 P 0 
L 0.97373002 -2.20661998 1.01921004 -2.20661998 0 P 0 
L 0.97981004 -2.20561998 1.02145 -2.20561998 0 P 0 
L 0.98498996 -2.20461998 1.02368996 -2.20461998 0 P 0 
L 0.98973996 -2.20361998 1.02591998 -2.20361998 0 P 0 
L 0.99448996 -2.20261998 1.02816004 -2.20261998 0 P 0 
L 0.99923996 -2.20161998 1.0304 -2.20161998 0 P 0 
L 1.00398996 -2.20061998 1.03243996 -2.20061998 0 P 0 
L 1.00875 -2.19961998 1.0344 -2.19961998 0 P 0 
L 1.01348996 -2.19861998 1.03636998 -2.19861998 0 P 0 
L 1.0178 -2.19761998 1.03833996 -2.19761998 0 P 0 
L 1.02168996 -2.19661998 1.04031004 -2.19661998 0 P 0 
L 1.02558002 -2.19561998 1.04228002 -2.19561998 0 P 0 
L 1.02946998 -2.19461998 1.04415 -2.19461998 0 P 0 
L 1.03336004 -2.19361998 1.04596998 -2.19361998 0 P 0 
L 1.03725 -2.19261998 1.04778996 -2.19261998 0 P 0 
L 1.04113996 -2.19161998 1.0496 -2.19161998 0 P 0 
L 1.14356998 -1.98926998 1.13261004 -1.99086004 0 P 0 
L 1.13261004 -1.99086004 1.12165 -1.9934 0 P 0 
L 1.12165 -1.9934 1.11125 -1.99673002 0 P 0 
L 1.11125 -1.99673002 1.10658002 -1.99858996 0 P 0 
L 1.10658002 -1.99858996 1.10198996 -2.00071004 0 P 0 
L 1.10198996 -2.00071004 1.09653002 -2.00358996 0 P 0 
L 1.09653002 -2.00358996 1.09436998 -2.00488996 0 P 0 
L 1.09436998 -2.00488996 1.09226004 -2.00631004 0 P 0 
L 1.09226004 -2.00631004 1.09028002 -2.00781004 0 P 0 
L 1.09028002 -2.00781004 1.08836998 -2.00941998 0 P 0 
L 1.08836998 -2.00941998 1.08405 -2.0135 0 P 0 
L 1.08405 -2.0135 1.08096998 -2.01678996 0 P 0 
L 1.08096998 -2.01678996 1.07808002 -2.02026998 0 P 0 
L 1.07808002 -2.02026998 1.0754 -2.02393002 0 P 0 
L 1.0754 -2.02393002 1.07313996 -2.02748002 0 P 0 
L 1.07313996 -2.02748002 1.07116004 -2.03118996 0 P 0 
L 1.07116004 -2.03118996 1.06943996 -2.03505 0 P 0 
L 1.06943996 -2.03505 1.06795 -2.03918996 0 P 0 
L 1.06795 -2.03918996 1.06673996 -2.04343996 0 P 0 
L 1.06673996 -2.04343996 1.06583002 -2.04778002 0 P 0 
L 1.06583002 -2.04778002 1.06476998 -2.05538996 0 P 0 
L 1.06476998 -2.05538996 1.06421004 -2.06306004 0 P 0 
L 1.06421004 -2.06306004 1.06415 -2.07076004 0 P 0 
L 1.06415 -2.07076004 1.06456998 -2.0785 0 P 0 
L 1.06456998 -2.0785 1.06508996 -2.08276004 0 P 0 
L 1.06508996 -2.08276004 1.06591004 -2.08696004 0 P 0 
L 1.06591004 -2.08696004 1.06703002 -2.09108002 0 P 0 
L 1.06703002 -2.09108002 1.06833002 -2.09473002 0 P 0 
L 1.06833002 -2.09473002 1.06991998 -2.09823996 0 P 0 
L 1.06991998 -2.09823996 1.0718 -2.10161998 0 P 0 
L 1.0718 -2.10161998 1.07398002 -2.10491998 0 P 0 
L 1.07398002 -2.10491998 1.07641998 -2.10803002 0 P 0 
L 1.07641998 -2.10803002 1.07908996 -2.11095 0 P 0 
L 1.07908996 -2.11095 1.08175 -2.11345 0 P 0 
L 1.08175 -2.11345 1.08458996 -2.11573996 0 P 0 
L 1.08458996 -2.11573996 1.08758996 -2.1178 0 P 0 
L 1.08758996 -2.1178 1.09073002 -2.11963996 0 P 0 
L 1.09073002 -2.11963996 1.094 -2.12123996 0 P 0 
L 1.094 -2.12123996 1.0986 -2.12306998 0 P 0 
L 1.0986 -2.12306998 1.10331004 -2.12456004 0 P 0 
L 1.10331004 -2.12456004 1.10811004 -2.12568996 0 P 0 
L 1.10811004 -2.12568996 1.11298002 -2.12646998 0 P 0 
L 1.11298002 -2.12646998 1.1182 -2.12693002 0 P 0 
L 1.1182 -2.12693002 1.12343996 -2.12703002 0 P 0 
L 1.12343996 -2.12703002 1.12866998 -2.12676004 0 P 0 
L 1.12866998 -2.12676004 1.13388002 -2.12613002 0 P 0 
L 1.13388002 -2.12613002 1.14086004 -2.12473996 0 P 0 
L 1.14086004 -2.12473996 1.1477 -2.12273996 0 P 0 
L 1.1477 -2.12273996 1.15433996 -2.12015 0 P 0 
L 1.15433996 -2.12015 1.1545 -2.12008996 0 P 0 
L 1.1545 -2.12008996 1.15466004 -2.12003996 0 P 0 
L 1.15466004 -2.12003996 1.15483002 -2.12001004 0 P 0 
L 1.15483002 -2.12001004 1.15498996 -2.11998996 0 P 0 
L 1.15498996 -2.11998996 1.15533002 -2.11998996 0 P 0 
L 1.15533002 -2.11998996 1.15538996 -2.12 0 P 0 
L 1.15538996 -2.12 1.15545 -2.12001998 0 P 0 
L 1.15545 -2.12001998 1.15551004 -2.12003002 0 P 0 
L 1.15551004 -2.12003002 1.15556004 -2.12006004 0 P 0 
L 1.15556004 -2.12006004 1.15561004 -2.12008002 0 P 0 
L 1.15561004 -2.12008002 1.15566004 -2.12011004 0 P 0 
L 1.15566004 -2.12011004 1.15571004 -2.12015 0 P 0 
L 1.15571004 -2.12015 1.15575 -2.12018996 0 P 0 
L 1.15575 -2.12018996 1.15578996 -2.12023996 0 P 0 
L 1.15578996 -2.12023996 1.15583002 -2.12028002 0 P 0 
L 1.15583002 -2.12028002 1.15586004 -2.12033996 0 P 0 
L 1.15586004 -2.12033996 1.15588002 -2.12038996 0 P 0 
L 1.15588002 -2.12038996 1.15591004 -2.12043996 0 P 0 
L 1.15591004 -2.12043996 1.15601998 -2.12076004 0 P 0 
L 1.15601998 -2.12076004 1.1561 -2.12108002 0 P 0 
L 1.1561 -2.12108002 1.15616004 -2.12141998 0 P 0 
L 1.15616004 -2.12141998 1.15618002 -2.12175 0 P 0 
L 1.15618002 -2.12175 1.15623996 -2.12505 0 P 0 
L 1.15623996 -2.12505 1.15616004 -2.12688002 0 P 0 
L 1.15616004 -2.12688002 1.15593002 -2.12871004 0 P 0 
L 1.15593002 -2.12871004 1.15553996 -2.13051998 0 P 0 
L 1.15553996 -2.13051998 1.15516004 -2.1318 0 P 0 
L 1.15516004 -2.1318 1.1547 -2.13305 0 P 0 
L 1.1547 -2.13305 1.15415 -2.13426004 0 P 0 
L 1.15415 -2.13426004 1.15351004 -2.13545 0 P 0 
L 1.15351004 -2.13545 1.15278996 -2.1366 0 P 0 
L 1.15278996 -2.1366 1.15198002 -2.13768996 0 P 0 
L 1.15198002 -2.13768996 1.15111004 -2.13873002 0 P 0 
L 1.15111004 -2.13873002 1.15016004 -2.13971004 0 P 0 
L 1.15016004 -2.13971004 1.14876004 -2.14096004 0 P 0 
L 1.14876004 -2.14096004 1.14726004 -2.1421 0 P 0 
L 1.14726004 -2.1421 1.14566998 -2.14311004 0 P 0 
L 1.14566998 -2.14311004 1.144 -2.144 0 P 0 
L 1.144 -2.144 1.14226004 -2.14476004 0 P 0 
L 1.14226004 -2.14476004 1.14046004 -2.14536998 0 P 0 
L 1.14046004 -2.14536998 1.13863002 -2.14583002 0 P 0 
L 1.13863002 -2.14583002 1.13676004 -2.14613996 0 P 0 
L 1.13676004 -2.14613996 1.13041998 -2.14663996 0 P 0 
L 1.13041998 -2.14663996 1.12403996 -2.1466 0 P 0 
L 1.12403996 -2.1466 1.11621998 -2.14593996 0 P 0 
L 1.11621998 -2.14593996 1.10843996 -2.14471004 0 P 0 
L 1.10843996 -2.14471004 1.09946998 -2.14276998 0 P 0 
L 1.09946998 -2.14276998 1.0905 -2.14041004 0 P 0 
L 1.0905 -2.14041004 1.07963996 -2.13728996 0 P 0 
L 1.07963996 -2.13728996 1.07936004 -2.1401 0 P 0 
L 1.07936004 -2.1401 1.07931004 -2.14103996 0 P 0 
L 1.07931004 -2.14103996 1.07931998 -2.14198002 0 P 0 
L 1.07931998 -2.14198002 1.07956998 -2.14735 0 P 0 
L 1.07956998 -2.14735 1.07993996 -2.15375 0 P 0 
L 1.07993996 -2.15375 1.08045 -2.16081998 0 P 0 
L 1.08045 -2.16081998 1.08181004 -2.17873002 0 P 0 
L 1.08181004 -2.17873002 1.08996004 -2.18061004 0 P 0 
L 1.08996004 -2.18061004 1.09951004 -2.18246004 0 P 0 
L 1.09951004 -2.18246004 1.11243996 -2.18416998 0 P 0 
L 1.11243996 -2.18416998 1.1254 -2.18543002 0 P 0 
L 1.1254 -2.18543002 1.13508002 -2.18583002 0 P 0 
L 1.13508002 -2.18583002 1.14765 -2.18528996 0 P 0 
L 1.14765 -2.18528996 1.15368002 -2.18461004 0 P 0 
L 1.15368002 -2.18461004 1.15971004 -2.18363996 0 P 0 
L 1.15971004 -2.18363996 1.16521004 -2.18248002 0 P 0 
L 1.16521004 -2.18248002 1.17063996 -2.18103002 0 P 0 
L 1.17063996 -2.18103002 1.17528996 -2.17946998 0 P 0 
L 1.17528996 -2.17946998 1.17978002 -2.17753996 0 P 0 
L 1.17978002 -2.17753996 1.18216998 -2.1763 0 P 0 
L 1.18216998 -2.1763 1.18446004 -2.17488996 0 P 0 
L 1.18446004 -2.17488996 1.18663996 -2.17331004 0 P 0 
L 1.18663996 -2.17331004 1.18871004 -2.17156004 0 P 0 
L 1.18871004 -2.17156004 1.19161004 -2.16871998 0 P 0 
L 1.19161004 -2.16871998 1.19431004 -2.16568996 0 P 0 
L 1.19431004 -2.16568996 1.19678996 -2.16246998 0 P 0 
L 1.19678996 -2.16246998 1.19908996 -2.15901998 0 P 0 
L 1.19908996 -2.15901998 1.20113996 -2.15543996 0 P 0 
L 1.20113996 -2.15543996 1.20295 -2.15171004 0 P 0 
L 1.20295 -2.15171004 1.20435 -2.14815 0 P 0 
L 1.20435 -2.14815 1.20543996 -2.14448996 0 P 0 
L 1.20543996 -2.14448996 1.20621004 -2.14073996 0 P 0 
L 1.20621004 -2.14073996 1.20651998 -2.13855 0 P 0 
L 1.20651998 -2.13855 1.20671998 -2.13633996 0 P 0 
L 1.20671998 -2.13633996 1.20761998 -2.12321004 0 P 0 
L 1.20761998 -2.12321004 1.20858002 -2.10753996 0 P 0 
L 1.20858002 -2.10753996 1.20951004 -2.09021998 0 P 0 
L 1.20951004 -2.09021998 1.21048002 -2.07166004 0 P 0 
L 1.21048002 -2.07166004 1.21156004 -2.05228002 0 P 0 
L 1.21156004 -2.05228002 1.21258002 -2.03478996 0 P 0 
L 1.21258002 -2.03478996 1.21333002 -2.02286004 0 P 0 
L 1.21333002 -2.02286004 1.21393996 -2.01373996 0 P 0 
L 1.21393996 -2.01373996 1.21443996 -2.00568996 0 P 0 
L 1.21443996 -2.00568996 1.21485 -1.99883996 0 P 0 
L 1.21485 -1.99883996 1.2149 -1.99721004 0 P 0 
L 1.2149 -1.99721004 1.21488996 -1.99703996 0 P 0 
L 1.21488996 -1.99703996 1.21486998 -1.99686004 0 P 0 
L 1.21486998 -1.99686004 1.21483996 -1.99668996 0 P 0 
L 1.21483996 -1.99668996 1.21478996 -1.99653002 0 P 0 
L 1.21478996 -1.99653002 1.21473002 -1.99636998 0 P 0 
L 1.21473002 -1.99636998 1.21466004 -1.99621004 0 P 0 
L 1.21466004 -1.99621004 1.21458002 -1.99606004 0 P 0 
L 1.21458002 -1.99606004 1.21448002 -1.99591004 0 P 0 
L 1.21448002 -1.99591004 1.21433002 -1.99571998 0 P 0 
L 1.21433002 -1.99571998 1.21416998 -1.99553996 0 P 0 
L 1.21416998 -1.99553996 1.21398996 -1.99538002 0 P 0 
L 1.21398996 -1.99538002 1.21378996 -1.99523996 0 P 0 
L 1.21378996 -1.99523996 1.21358002 -1.99511004 0 P 0 
L 1.21358002 -1.99511004 1.21336004 -1.995 0 P 0 
L 1.21336004 -1.995 1.21261004 -1.99468996 0 P 0 
L 1.21261004 -1.99468996 1.21183996 -1.99443996 0 P 0 
L 1.21183996 -1.99443996 1.21105 -1.99423002 0 P 0 
L 1.21105 -1.99423002 1.20593996 -1.99318002 0 P 0 
L 1.20593996 -1.99318002 1.18996998 -1.99065 0 P 0 
L 1.18996998 -1.99065 1.17318996 -1.98908002 0 P 0 
L 1.17318996 -1.98908002 1.15718996 -1.98858002 0 P 0 
L 1.15718996 -1.98858002 1.1504 -1.98876004 0 P 0 
L 1.1504 -1.98876004 1.14356998 -1.98926998 0 P 0 
L 1.04503996 -2.19061998 1.05141998 -2.19061998 0 P 0 
L 1.04893002 -2.18961998 1.05323002 -2.18961998 0 P 0 
L 1.05263002 -2.18861998 1.05503996 -2.18861998 0 P 0 
L 1.05628996 -2.18761998 1.05676004 -2.18761998 0 P 0 
L 1.09645 -2.17983002 1.16738002 -2.17983002 0 P 0 
L 1.09126004 -2.17883002 1.17091004 -2.17883002 0 P 0 
L 1.0868 -2.17783002 1.17386998 -2.17783002 0 P 0 
L 1.08368002 -2.17683002 1.17636004 -2.17683002 0 P 0 
L 1.0836 -2.17583002 1.1787 -2.17583002 0 P 0 
L 1.08351998 -2.17483002 1.18066998 -2.17483002 0 P 0 
L 1.08345 -2.17383002 1.18236998 -2.17383002 0 P 0 
L 1.08336998 -2.17283002 1.1839 -2.17283002 0 P 0 
L 1.08328996 -2.17183002 1.18526998 -2.17183002 0 P 0 
L 1.08321998 -2.17083002 1.18646998 -2.17083002 0 P 0 
L 1.08313996 -2.16983002 1.18761998 -2.16983002 0 P 0 
L 1.08306998 -2.16883002 1.18863996 -2.16883002 0 P 0 
L 1.08298996 -2.16783002 1.18966004 -2.16783002 0 P 0 
L 1.08291998 -2.16683002 1.19061004 -2.16683002 0 P 0 
L 1.08283996 -2.16583002 1.1915 -2.16583002 0 P 0 
L 1.08276004 -2.16483002 1.19238996 -2.16483002 0 P 0 
L 1.08268996 -2.16383002 1.19321004 -2.16383002 0 P 0 
L 1.08261004 -2.16283002 1.19398002 -2.16283002 0 P 0 
L 1.08253002 -2.16183002 1.19476004 -2.16183002 0 P 0 
L 1.08246004 -2.16083002 1.19548002 -2.16083002 0 P 0 
L 1.08238002 -2.15983002 1.19613996 -2.15983002 0 P 0 
L 1.08231004 -2.15883002 1.19681004 -2.15883002 0 P 0 
L 1.08223996 -2.15783002 1.19746004 -2.15783002 0 P 0 
L 1.13506998 -2.18383002 1.12553002 -2.18343996 0 P 0 
L 1.12553002 -2.18343996 1.11266004 -2.18218002 0 P 0 
L 1.11266004 -2.18218002 1.09983002 -2.18048002 0 P 0 
L 1.09983002 -2.18048002 1.09036998 -2.17866004 0 P 0 
L 1.09036998 -2.17866004 1.0837 -2.17711004 0 P 0 
L 1.0837 -2.17711004 1.08245 -2.16066998 0 P 0 
L 1.08245 -2.16066998 1.08193996 -2.15361998 0 P 0 
L 1.08193996 -2.15361998 1.08156998 -2.14726004 0 P 0 
L 1.08156998 -2.14726004 1.08131998 -2.14191004 0 P 0 
L 1.08131998 -2.14191004 1.08131004 -2.14108996 0 P 0 
L 1.08131004 -2.14108996 1.08136004 -2.14026004 0 P 0 
L 1.08136004 -2.14026004 1.0814 -2.13986998 0 P 0 
L 1.0814 -2.13986998 1.08996004 -2.14233002 0 P 0 
L 1.08996004 -2.14233002 1.08996998 -2.14233996 0 P 0 
L 1.08996998 -2.14233996 1.08998996 -2.14233996 0 P 0 
L 1.08998996 -2.14233996 1.099 -2.14471998 0 P 0 
L 1.099 -2.14471998 1.10806998 -2.14668002 0 P 0 
L 1.10806998 -2.14668002 1.11598002 -2.14791998 0 P 0 
L 1.11598002 -2.14791998 1.12395 -2.1486 0 P 0 
L 1.12395 -2.1486 1.13048996 -2.14863996 0 P 0 
L 1.13048996 -2.14863996 1.137 -2.14811998 0 P 0 
L 1.137 -2.14811998 1.13903002 -2.14778996 0 P 0 
L 1.13903002 -2.14778996 1.14103002 -2.14728996 0 P 0 
L 1.14103002 -2.14728996 1.14298002 -2.14661998 0 P 0 
L 1.14298002 -2.14661998 1.14486998 -2.14581004 0 P 0 
L 1.14486998 -2.14581004 1.14668002 -2.14483996 0 P 0 
L 1.14668002 -2.14483996 1.1484 -2.14373996 0 P 0 
L 1.1484 -2.14373996 1.15003002 -2.1425 0 P 0 
L 1.15003002 -2.1425 1.15155 -2.14115 0 P 0 
L 1.15155 -2.14115 1.1526 -2.14006998 0 P 0 
L 1.1526 -2.14006998 1.15263996 -2.14001998 0 P 0 
L 1.15263996 -2.14001998 1.15356004 -2.13893002 0 P 0 
L 1.15356004 -2.13893002 1.15443996 -2.13771998 0 P 0 
L 1.15443996 -2.13771998 1.15523002 -2.13646004 0 P 0 
L 1.15523002 -2.13646004 1.15593996 -2.13515 0 P 0 
L 1.15593996 -2.13515 1.15655 -2.13381004 0 P 0 
L 1.15655 -2.13381004 1.15706004 -2.13243002 0 P 0 
L 1.15706004 -2.13243002 1.15748002 -2.13101004 0 P 0 
L 1.15748002 -2.13101004 1.1579 -2.12905 0 P 0 
L 1.1579 -2.12905 1.15816004 -2.12706004 0 P 0 
L 1.15816004 -2.12706004 1.15825 -2.12506998 0 P 0 
L 1.15825 -2.12506998 1.15818002 -2.12165 0 P 0 
L 1.15818002 -2.12165 1.15813996 -2.12118002 0 P 0 
L 1.15813996 -2.12118002 1.15813002 -2.1211 0 P 0 
L 1.15813002 -2.1211 1.15806004 -2.12068002 0 P 0 
L 1.15806004 -2.12068002 1.15793996 -2.12018996 0 P 0 
L 1.15793996 -2.12018996 1.15778002 -2.11973002 0 P 0 
L 1.15778002 -2.11973002 1.1577 -2.11953002 0 P 0 
L 1.1577 -2.11953002 1.15758996 -2.11933002 0 P 0 
L 1.15758996 -2.11933002 1.15746998 -2.11913996 0 P 0 
L 1.15746998 -2.11913996 1.15733002 -2.11895 0 P 0 
L 1.15733002 -2.11895 1.15716998 -2.11878002 0 P 0 
L 1.15716998 -2.11878002 1.157 -2.11863002 0 P 0 
L 1.157 -2.11863002 1.15681998 -2.11848996 0 P 0 
L 1.15681998 -2.11848996 1.15663002 -2.11836004 0 P 0 
L 1.15663002 -2.11836004 1.15641998 -2.11825 0 P 0 
L 1.15641998 -2.11825 1.15621004 -2.11816004 0 P 0 
L 1.15621004 -2.11816004 1.15598996 -2.11808996 0 P 0 
L 1.15598996 -2.11808996 1.15576998 -2.11803996 0 P 0 
L 1.15576998 -2.11803996 1.15553002 -2.118 0 P 0 
L 1.15553002 -2.118 1.15518002 -2.11798002 0 P 0 
L 1.15518002 -2.11798002 1.15483996 -2.11798996 0 P 0 
L 1.15483996 -2.11798996 1.15451004 -2.11803002 0 P 0 
L 1.15451004 -2.11803002 1.15418002 -2.1181 0 P 0 
L 1.15418002 -2.1181 1.15386004 -2.1182 0 P 0 
L 1.15386004 -2.1182 1.15361004 -2.11828996 0 P 0 
L 1.15361004 -2.11828996 1.14705 -2.12083996 0 P 0 
L 1.14705 -2.12083996 1.14038996 -2.12278996 0 P 0 
L 1.14038996 -2.12278996 1.13356004 -2.12416004 0 P 0 
L 1.13356004 -2.12416004 1.1285 -2.12476998 0 P 0 
L 1.1285 -2.12476998 1.12341004 -2.12501998 0 P 0 
L 1.12341004 -2.12501998 1.11831004 -2.12493002 0 P 0 
L 1.11831004 -2.12493002 1.11323002 -2.12448996 0 P 0 
L 1.11323002 -2.12448996 1.10848996 -2.12373002 0 P 0 
L 1.10848996 -2.12373002 1.10383996 -2.12263002 0 P 0 
L 1.10383996 -2.12263002 1.09926998 -2.12118996 0 P 0 
L 1.09926998 -2.12118996 1.09481004 -2.11941004 0 P 0 
L 1.09481004 -2.11941004 1.09168002 -2.11788002 0 P 0 
L 1.09168002 -2.11788002 1.08866004 -2.11611998 0 P 0 
L 1.08866004 -2.11611998 1.08578002 -2.11413002 0 P 0 
L 1.08578002 -2.11413002 1.08306998 -2.11193996 0 P 0 
L 1.08306998 -2.11193996 1.08051998 -2.10955 0 P 0 
L 1.08051998 -2.10955 1.07793996 -2.10673002 0 P 0 
L 1.07793996 -2.10673002 1.07561004 -2.10373996 0 P 0 
L 1.07561004 -2.10373996 1.07351004 -2.10058002 0 P 0 
L 1.07351004 -2.10058002 1.07171004 -2.09733996 0 P 0 
L 1.07171004 -2.09733996 1.07018002 -2.09396998 0 P 0 
L 1.07018002 -2.09396998 1.06893996 -2.09048002 0 P 0 
L 1.06893996 -2.09048002 1.06786004 -2.0865 0 P 0 
L 1.06786004 -2.0865 1.06706004 -2.08243996 0 P 0 
L 1.06706004 -2.08243996 1.06656004 -2.07833002 0 P 0 
L 1.06656004 -2.07833002 1.06615 -2.07071004 0 P 0 
L 1.06615 -2.07071004 1.06621004 -2.06313996 0 P 0 
L 1.06621004 -2.06313996 1.06675 -2.0556 0 P 0 
L 1.06675 -2.0556 1.0678 -2.04813002 0 P 0 
L 1.0678 -2.04813002 1.06868996 -2.04391998 0 P 0 
L 1.06868996 -2.04391998 1.06985 -2.03981004 0 P 0 
L 1.06985 -2.03981004 1.0713 -2.03578996 0 P 0 
L 1.0713 -2.03578996 1.07296004 -2.03206998 0 P 0 
L 1.07296004 -2.03206998 1.07486998 -2.02848996 0 P 0 
L 1.07486998 -2.02848996 1.07705 -2.02506004 0 P 0 
L 1.07705 -2.02506004 1.07966004 -2.0215 0 P 0 
L 1.07966004 -2.0215 1.08246998 -2.01811004 0 P 0 
L 1.08246998 -2.01811004 1.08546998 -2.01491004 0 P 0 
L 1.08546998 -2.01491004 1.0897 -2.01091004 0 P 0 
L 1.0897 -2.01091004 1.09153002 -2.00936998 0 P 0 
L 1.09153002 -2.00936998 1.09341998 -2.00793996 0 P 0 
L 1.09341998 -2.00793996 1.09545 -2.00658002 0 P 0 
L 1.09545 -2.00658002 1.09751004 -2.00533996 0 P 0 
L 1.09751004 -2.00533996 1.10288002 -2.0025 0 P 0 
L 1.10288002 -2.0025 1.10736998 -2.00043002 0 P 0 
L 1.10736998 -2.00043002 1.11193002 -1.99861004 0 P 0 
L 1.11193002 -1.99861004 1.12218002 -1.99533002 0 P 0 
L 1.12218002 -1.99533002 1.13298002 -1.99281998 0 P 0 
L 1.13298002 -1.99281998 1.14378996 -1.99126004 0 P 0 
L 1.14378996 -1.99126004 1.1505 -1.99075 0 P 0 
L 1.1505 -1.99075 1.15718002 -1.99058996 0 P 0 
L 1.15718002 -1.99058996 1.17306998 -1.99108002 0 P 0 
L 1.17306998 -1.99108002 1.18971998 -1.99263002 0 P 0 
L 1.18971998 -1.99263002 1.20558002 -1.99515 0 P 0 
L 1.20558002 -1.99515 1.21058996 -1.99618002 0 P 0 
L 1.21058996 -1.99618002 1.21126998 -1.99636004 0 P 0 
L 1.21126998 -1.99636004 1.21191998 -1.99656998 0 P 0 
L 1.21191998 -1.99656998 1.21253002 -1.99681998 0 P 0 
L 1.21253002 -1.99681998 1.21261004 -1.99686004 0 P 0 
L 1.21261004 -1.99686004 1.21266004 -1.99688996 0 P 0 
L 1.21266004 -1.99688996 1.21271998 -1.99693002 0 P 0 
L 1.21271998 -1.99693002 1.21281998 -1.99703002 0 P 0 
L 1.21281998 -1.99703002 1.21286004 -1.99708996 0 P 0 
L 1.21286004 -1.99708996 1.21288002 -1.99711004 0 P 0 
L 1.21288002 -1.99711004 1.21288002 -1.99711998 0 P 0 
L 1.21288002 -1.99711998 1.21288996 -1.99715 0 P 0 
L 1.21288996 -1.99715 1.2129 -1.99716998 0 P 0 
L 1.2129 -1.99716998 1.2129 -1.99721998 0 P 0 
L 1.2129 -1.99721998 1.21285 -1.99875 0 P 0 
L 1.21285 -1.99875 1.21243996 -2.00556998 0 P 0 
L 1.21243996 -2.00556998 1.21193996 -2.01361004 0 P 0 
L 1.21193996 -2.01361004 1.21133996 -2.02273002 0 P 0 
L 1.21133996 -2.02273002 1.21133996 -2.02273996 0 P 0 
L 1.21133996 -2.02273996 1.21058996 -2.03468002 0 P 0 
L 1.21058996 -2.03468002 1.20956004 -2.05216998 0 P 0 
L 1.20956004 -2.05216998 1.20848996 -2.07156004 0 P 0 
L 1.20848996 -2.07156004 1.20848996 -2.07156998 0 P 0 
L 1.20848996 -2.07156998 1.20751004 -2.09011004 0 P 0 
L 1.20751004 -2.09011004 1.20658996 -2.10743996 0 P 0 
L 1.20658996 -2.10743996 1.20561998 -2.12308996 0 P 0 
L 1.20561998 -2.12308996 1.20473002 -2.13618996 0 P 0 
L 1.20473002 -2.13618996 1.20453002 -2.13831998 0 P 0 
L 1.20453002 -2.13831998 1.20423996 -2.14041004 0 P 0 
L 1.20423996 -2.14041004 1.2035 -2.144 0 P 0 
L 1.2035 -2.144 1.20246004 -2.1475 0 P 0 
L 1.20246004 -2.1475 1.20111998 -2.1509 0 P 0 
L 1.20111998 -2.1509 1.19936998 -2.1545 0 P 0 
L 1.19936998 -2.1545 1.19738002 -2.15796998 0 P 0 
L 1.19738002 -2.15796998 1.19516004 -2.1613 0 P 0 
L 1.19516004 -2.1613 1.19276998 -2.16441004 0 P 0 
L 1.19276998 -2.16441004 1.19016004 -2.16733996 0 P 0 
L 1.19016004 -2.16733996 1.18736004 -2.17008002 0 P 0 
L 1.18736004 -2.17008002 1.1854 -2.17173996 0 P 0 
L 1.1854 -2.17173996 1.18335 -2.17323002 0 P 0 
L 1.18335 -2.17323002 1.18118002 -2.17456004 0 P 0 
L 1.18118002 -2.17456004 1.17893002 -2.17573002 0 P 0 
L 1.17893002 -2.17573002 1.17456998 -2.1776 0 P 0 
L 1.17456998 -2.1776 1.17006998 -2.17911998 0 P 0 
L 1.17006998 -2.17911998 1.16473996 -2.18053002 0 P 0 
L 1.16473996 -2.18053002 1.15935 -2.18166998 0 P 0 
L 1.15935 -2.18166998 1.15341998 -2.18263002 0 P 0 
L 1.15341998 -2.18263002 1.1475 -2.18328996 0 P 0 
L 1.1475 -2.18328996 1.13506998 -2.18383002 0 P 0 
L 0.90491998 -2.21461998 1.00131004 -2.21461998 0 P 0 
L 0.92235 -2.21361998 1.00355 -2.21361998 0 P 0 
L 0.76925 -1.8965 0.85586998 -1.8965 0 P 0 
L 0.76958996 -1.8955 0.85556004 -1.8955 0 P 0 
L 0.76995 -1.8945 0.85521004 -1.8945 0 P 0 
L 0.77031004 -1.8935 0.85486004 -1.8935 0 P 0 
L 0.77071004 -1.8925 0.85443996 -1.8925 0 P 0 
L 0.77115 -1.8915 0.85401004 -1.8915 0 P 0 
L 0.7716 -1.8905 0.85355 -1.8905 0 P 0 
L 0.77206004 -1.8895 0.85303002 -1.8895 0 P 0 
L 0.7726 -1.8885 0.85251004 -1.8885 0 P 0 
L 0.77313996 -1.8875 0.85198996 -1.8875 0 P 0 
L 0.77368996 -1.8865 0.85138002 -1.8865 0 P 0 
L 0.77433002 -1.8855 0.85073996 -1.8855 0 P 0 
L 0.77496004 -1.8845 0.85011004 -1.8845 0 P 0 
L 0.77561998 -1.8835 0.84943002 -1.8835 0 P 0 
L 0.77636004 -1.8825 0.84866998 -1.8825 0 P 0 
L 0.77711004 -1.8815 0.84791004 -1.8815 0 P 0 
L 0.7779 -1.8805 0.84713002 -1.8805 0 P 0 
L 0.77876998 -1.8795 0.84623002 -1.8795 0 P 0 
L 0.77963996 -1.8785 0.84533002 -1.8785 0 P 0 
L 0.7806 -1.8775 0.8444 -1.8775 0 P 0 
L 0.78161004 -1.8765 0.84335 -1.8765 0 P 0 
L 0.78265 -1.8755 0.84228996 -1.8755 0 P 0 
L 0.78381998 -1.8745 0.84108996 -1.8745 0 P 0 
L 0.78498996 -1.8735 0.83986998 -1.8735 0 P 0 
L 0.78635 -1.8725 0.83848002 -1.8725 0 P 0 
L 0.78773002 -1.8715 0.83706004 -1.8715 0 P 0 
L 0.78933002 -1.8705 0.83541998 -1.8705 0 P 0 
L 0.791 -1.8695 0.83366004 -1.8695 0 P 0 
L 0.793 -1.8685 0.83171998 -1.8685 0 P 0 
L 0.79525 -1.8675 0.82941998 -1.8675 0 P 0 
L 0.79791998 -1.8665 0.82671004 -1.8665 0 P 0 
L 0.80143996 -1.8655 0.82328996 -1.8655 0 P 0 
L 0.80705 -1.8645 0.81776004 -1.8645 0 P 0 
L 0.74543002 -1.89661998 0.75033002 -1.89661998 0 P 0 
L 0.74751004 -1.89561998 0.75058996 -1.89561998 0 P 0 
L 0.74958996 -1.89461998 0.75086004 -1.89461998 0 P 0 
L 0.76733996 -1.9125 0.85751998 -1.9125 0 P 0 
L 0.76728996 -1.9115 0.85756004 -1.9115 0 P 0 
L 0.76723996 -1.9105 0.85758996 -1.9105 0 P 0 
L 0.76721998 -1.9095 0.85763002 -1.9095 0 P 0 
L 0.76725 -1.9085 0.85761004 -1.9085 0 P 0 
L 0.76728002 -1.9075 0.85756998 -1.9075 0 P 0 
L 0.76731004 -1.9065 0.85753002 -1.9065 0 P 0 
L 0.76741998 -1.9055 0.85748996 -1.9055 0 P 0 
L 0.76753996 -1.9045 0.85738002 -1.9045 0 P 0 
L 0.76766004 -1.9035 0.85726004 -1.9035 0 P 0 
L 0.76781998 -1.9025 0.85713996 -1.9025 0 P 0 
L 0.76801998 -1.9015 0.85701004 -1.9015 0 P 0 
L 0.76821004 -1.9005 0.85683002 -1.9005 0 P 0 
L 0.76841998 -1.8995 0.85661998 -1.8995 0 P 0 
L 0.7687 -1.8985 0.85641004 -1.8985 0 P 0 
L 0.76896998 -1.8975 0.85613996 -1.8975 0 P 0 
L 0.76751004 -2.08325 0.8416 -2.08325 0 P 0 
L 0.76761998 -2.08225 0.84161998 -2.08225 0 P 0 
L 0.76773996 -2.08125 0.84166998 -2.08125 0 P 0 
L 0.76786004 -2.08025 0.84171998 -2.08025 0 P 0 
L 0.76796998 -2.07925 0.84176998 -2.07925 0 P 0 
L 0.76808002 -2.07825 0.84181004 -2.07825 0 P 0 
L 0.76818002 -2.07725 0.84186004 -2.07725 0 P 0 
L 0.76828996 -2.07625 0.8419 -2.07625 0 P 0 
L 0.76838996 -2.07525 0.84195 -2.07525 0 P 0 
L 0.76848996 -2.07425 0.842 -2.07425 0 P 0 
L 0.7686 -2.07325 0.84205 -2.07325 0 P 0 
L 0.7687 -2.07225 0.84208996 -2.07225 0 P 0 
L 0.7688 -2.07125 0.84213996 -2.07125 0 P 0 
L 0.7689 -2.07025 0.84218002 -2.07025 0 P 0 
L 0.76901004 -2.06925 0.84223002 -2.06925 0 P 0 
L 0.76911004 -2.06825 0.84228002 -2.06825 0 P 0 
L 0.76921004 -2.06725 0.84233002 -2.06725 0 P 0 
L 0.76931998 -2.06625 0.84236998 -2.06625 0 P 0 
L 0.76941998 -2.06525 0.84241998 -2.06525 0 P 0 
L 0.76948996 -2.06425 0.84246004 -2.06425 0 P 0 
L 0.76956004 -2.06325 0.84251004 -2.06325 0 P 0 
L 0.76963002 -2.06225 0.84256004 -2.06225 0 P 0 
L 0.7697 -2.06125 0.8426 -2.06125 0 P 0 
L 0.76976998 -2.06025 0.84265 -2.06025 0 P 0 
L 0.76983996 -2.05925 0.8427 -2.05925 0 P 0 
L 0.76991004 -2.05825 0.84273996 -2.05825 0 P 0 
L 0.76996998 -2.05725 0.84278996 -2.05725 0 P 0 
L 0.77001004 -2.05625 0.84283996 -2.05625 0 P 0 
L 0.77003996 -2.05525 0.84288002 -2.05525 0 P 0 
L 0.77008002 -2.05425 0.84295 -2.05425 0 P 0 
L 0.77011998 -2.05325 0.84303996 -2.05325 0 P 0 
L 0.77016004 -2.05225 0.84311998 -2.05225 0 P 0 
L 0.77018996 -2.05125 0.84321004 -2.05125 0 P 0 
L 0.77023002 -2.05025 0.8433 -2.05025 0 P 0 
L 0.77026998 -2.04925 0.84338002 -2.04925 0 P 0 
L 0.77031004 -2.04825 0.84346998 -2.04825 0 P 0 
L 0.77033996 -2.04725 0.84356004 -2.04725 0 P 0 
L 0.77038002 -2.04625 0.84363996 -2.04625 0 P 0 
L 0.77041004 -2.04525 0.84373002 -2.04525 0 P 0 
L 0.77043996 -2.04425 0.84381004 -2.04425 0 P 0 
L 0.77046004 -2.04325 0.8439 -2.04325 0 P 0 
L 0.77048002 -2.04225 0.84398996 -2.04225 0 P 0 
L 0.77051004 -2.04125 0.84406998 -2.04125 0 P 0 
L 0.77053002 -2.04025 0.84416004 -2.04025 0 P 0 
L 0.77055 -2.03925 0.84425 -2.03925 0 P 0 
L 0.77058002 -2.03825 0.84433002 -2.03825 0 P 0 
L 0.7706 -2.03725 0.84441998 -2.03725 0 P 0 
L 0.77061998 -2.03625 0.84451004 -2.03625 0 P 0 
L 0.77065 -2.03525 0.84458996 -2.03525 0 P 0 
L 0.77066998 -2.03425 0.84468002 -2.03425 0 P 0 
L 0.7707 -2.03325 0.84476998 -2.03325 0 P 0 
L 0.77071998 -2.03225 0.84485 -2.03225 0 P 0 
L 0.77073002 -2.03125 0.84493996 -2.03125 0 P 0 
L 0.77073996 -2.03025 0.84503002 -2.03025 0 P 0 
L 0.79986004 -1.8638 0.79643996 -1.86486998 0 P 0 
L 0.79643996 -1.86486998 0.79311998 -1.86621004 0 P 0 
L 0.79311998 -1.86621004 0.78991004 -1.86781004 0 P 0 
L 0.78991004 -1.86781004 0.78683996 -1.86966998 0 P 0 
L 0.78683996 -1.86966998 0.78391998 -1.87178002 0 P 0 
L 0.78391998 -1.87178002 0.78111998 -1.87416998 0 P 0 
L 0.78111998 -1.87416998 0.7785 -1.87676004 0 P 0 
L 0.7785 -1.87676004 0.77608002 -1.87953996 0 P 0 
L 0.77608002 -1.87953996 0.77386998 -1.8825 0 P 0 
L 0.77386998 -1.8825 0.77188002 -1.88561998 0 P 0 
L 0.77188002 -1.88561998 0.77013996 -1.88886004 0 P 0 
L 0.77013996 -1.88886004 0.76863996 -1.89221004 0 P 0 
L 0.76863996 -1.89221004 0.7674 -1.89566998 0 P 0 
L 0.7674 -1.89566998 0.76643002 -1.89921004 0 P 0 
L 0.76643002 -1.89921004 0.76571004 -1.90283996 0 P 0 
L 0.76571004 -1.90283996 0.76531004 -1.90636004 0 P 0 
L 0.76531004 -1.90636004 0.7652 -1.90991004 0 P 0 
L 0.7652 -1.90991004 0.76538996 -1.91345 0 P 0 
L 0.76538996 -1.91345 0.76586998 -1.91696998 0 P 0 
L 0.76586998 -1.91696998 0.76663996 -1.92046004 0 P 0 
L 0.76663996 -1.92046004 0.76803002 -1.92493996 0 P 0 
L 0.76803002 -1.92493996 0.76978002 -1.9293 0 P 0 
L 0.76978002 -1.9293 0.77106998 -1.93193996 0 P 0 
L 0.77106998 -1.93193996 0.77253002 -1.93448002 0 P 0 
L 0.77253002 -1.93448002 0.77416004 -1.93693996 0 P 0 
L 0.77416004 -1.93693996 0.77593002 -1.93923002 0 P 0 
L 0.77593002 -1.93923002 0.77783996 -1.94141004 0 P 0 
L 0.77783996 -1.94141004 0.77988996 -1.94345 0 P 0 
L 0.77988996 -1.94345 0.78216004 -1.94545 0 P 0 
L 0.78216004 -1.94545 0.78453996 -1.9473 0 P 0 
L 0.78453996 -1.9473 0.78703002 -1.94901998 0 P 0 
L 0.78703002 -1.94901998 0.79016998 -1.95088002 0 P 0 
L 0.79016998 -1.95088002 0.79343996 -1.95248996 0 P 0 
L 0.79343996 -1.95248996 0.79683002 -1.95383996 0 P 0 
L 0.79683002 -1.95383996 0.80031998 -1.95491998 0 P 0 
L 0.80031998 -1.95491998 0.80391004 -1.95573996 0 P 0 
L 0.80391004 -1.95573996 0.80751998 -1.95626004 0 P 0 
L 0.80751998 -1.95626004 0.81116004 -1.9565 0 P 0 
L 0.81116004 -1.9565 0.81481004 -1.95646004 0 P 0 
L 0.81481004 -1.95646004 0.81843996 -1.95613002 0 P 0 
L 0.81843996 -1.95613002 0.82205 -1.95551004 0 P 0 
L 0.82205 -1.95551004 0.82561998 -1.95461004 0 P 0 
L 0.82561998 -1.95461004 0.82911004 -1.95345 0 P 0 
L 0.82911004 -1.95345 0.83248996 -1.95201004 0 P 0 
L 0.83248996 -1.95201004 0.83576004 -1.95031998 0 P 0 
L 0.83576004 -1.95031998 0.83891998 -1.94836004 0 P 0 
L 0.83891998 -1.94836004 0.84191998 -1.94616998 0 P 0 
L 0.84191998 -1.94616998 0.84475 -1.94375 0 P 0 
L 0.84475 -1.94375 0.84738996 -1.94113996 0 P 0 
L 0.84738996 -1.94113996 0.84983002 -1.93833996 0 P 0 
L 0.84983002 -1.93833996 0.85206998 -1.93533996 0 P 0 
L 0.85206998 -1.93533996 0.8536 -1.93291998 0 P 0 
L 0.8536 -1.93291998 0.85496004 -1.93041004 0 P 0 
L 0.85496004 -1.93041004 0.85613996 -1.9278 0 P 0 
L 0.85613996 -1.9278 0.85711998 -1.92511004 0 P 0 
L 0.85711998 -1.92511004 0.85823002 -1.92123002 0 P 0 
L 0.85823002 -1.92123002 0.85901998 -1.91726998 0 P 0 
L 0.85901998 -1.91726998 0.85948996 -1.91323996 0 P 0 
L 0.85948996 -1.91323996 0.85963996 -1.90918002 0 P 0 
L 0.85963996 -1.90918002 0.85946998 -1.90513002 0 P 0 
L 0.85946998 -1.90513002 0.85898002 -1.9011 0 P 0 
L 0.85898002 -1.9011 0.85841998 -1.89826004 0 P 0 
L 0.85841998 -1.89826004 0.85766004 -1.89546004 0 P 0 
L 0.85766004 -1.89546004 0.85671004 -1.89273002 0 P 0 
L 0.85671004 -1.89273002 0.85556998 -1.89006004 0 P 0 
L 0.85556998 -1.89006004 0.85361998 -1.88631004 0 P 0 
L 0.85361998 -1.88631004 0.85136004 -1.88273996 0 P 0 
L 0.85136004 -1.88273996 0.84881004 -1.87938002 0 P 0 
L 0.84881004 -1.87938002 0.84596998 -1.87623002 0 P 0 
L 0.84596998 -1.87623002 0.84355 -1.87393996 0 P 0 
L 0.84355 -1.87393996 0.84096998 -1.87181998 0 P 0 
L 0.84096998 -1.87181998 0.83826004 -1.86988996 0 P 0 
L 0.83826004 -1.86988996 0.83541004 -1.86815 0 P 0 
L 0.83541004 -1.86815 0.83243996 -1.86661004 0 P 0 
L 0.83243996 -1.86661004 0.82938996 -1.86531004 0 P 0 
L 0.82938996 -1.86531004 0.82625 -1.86423002 0 P 0 
L 0.82625 -1.86423002 0.82303996 -1.86336004 0 P 0 
L 0.82303996 -1.86336004 0.81978002 -1.86273002 0 P 0 
L 0.81978002 -1.86273002 0.81646998 -1.86233002 0 P 0 
L 0.81646998 -1.86233002 0.81228996 -1.86215 0 P 0 
L 0.81228996 -1.86215 0.80811004 -1.86233996 0 P 0 
L 0.80811004 -1.86233996 0.80396004 -1.86288996 0 P 0 
L 0.80396004 -1.86288996 0.79986004 -1.8638 0 P 0 
L 0.80308996 -1.9535 0.82186004 -1.9535 0 P 0 
L 0.79926004 -1.9525 0.82563996 -1.9525 0 P 0 
L 0.79636004 -1.9515 0.82856998 -1.9515 0 P 0 
L 0.79393002 -1.9505 0.83093996 -1.9505 0 P 0 
L 0.7919 -1.9495 0.83298996 -1.9495 0 P 0 
L 0.79008002 -1.9485 0.8349 -1.9485 0 P 0 
L 0.78838996 -1.9475 0.83651004 -1.9475 0 P 0 
L 0.7869 -1.9465 0.83806998 -1.9465 0 P 0 
L 0.78548002 -1.9455 0.83943996 -1.9455 0 P 0 
L 0.7842 -1.9445 0.84078996 -1.9445 0 P 0 
L 0.78298002 -1.9435 0.84196998 -1.9435 0 P 0 
L 0.78183996 -1.9425 0.84313996 -1.9425 0 P 0 
L 0.78076998 -1.9415 0.84418996 -1.9415 0 P 0 
L 0.77976004 -1.9405 0.8452 -1.9405 0 P 0 
L 0.77883002 -1.9395 0.84616998 -1.9395 0 P 0 
L 0.77793996 -1.9385 0.84703996 -1.9385 0 P 0 
L 0.77711998 -1.9375 0.84791004 -1.9375 0 P 0 
L 0.77635 -1.9365 0.84871004 -1.9365 0 P 0 
L 0.77561004 -1.9355 0.84945 -1.9355 0 P 0 
L 0.77493996 -1.9345 0.8502 -1.9345 0 P 0 
L 0.77428002 -1.9335 0.85086998 -1.9335 0 P 0 
L 0.7737 -1.9325 0.8515 -1.9325 0 P 0 
L 0.77311998 -1.9315 0.8521 -1.9315 0 P 0 
L 0.77258996 -1.9305 0.85263996 -1.9305 0 P 0 
L 0.7721 -1.9295 0.85318002 -1.9295 0 P 0 
L 0.77161004 -1.9285 0.85363002 -1.9285 0 P 0 
L 0.77121004 -1.9275 0.85408002 -1.9275 0 P 0 
L 0.77081004 -1.9265 0.85448002 -1.9265 0 P 0 
L 0.77041004 -1.9255 0.85485 -1.9255 0 P 0 
L 0.77001004 -1.9245 0.85521998 -1.9245 0 P 0 
L 0.76968002 -1.9235 0.8555 -1.9235 0 P 0 
L 0.76936998 -1.9225 0.85578996 -1.9225 0 P 0 
L 0.76906004 -1.9215 0.85606998 -1.9215 0 P 0 
L 0.76875 -1.9205 0.85633002 -1.9205 0 P 0 
L 0.76848002 -1.9195 0.85653002 -1.9195 0 P 0 
L 0.76826004 -1.9185 0.85673002 -1.9185 0 P 0 
L 0.76803002 -1.9175 0.85693002 -1.9175 0 P 0 
L 0.76783002 -1.9165 0.85708996 -1.9165 0 P 0 
L 0.76768996 -1.9155 0.85721004 -1.9155 0 P 0 
L 0.76755 -1.9145 0.85733002 -1.9145 0 P 0 
L 0.76741998 -1.9135 0.85745 -1.9135 0 P 0 
L 0.81121004 -1.9545 0.80773002 -1.95426998 0 P 0 
L 0.80773002 -1.95426998 0.80426998 -1.95376998 0 P 0 
L 0.80426998 -1.95376998 0.80083996 -1.95298996 0 P 0 
L 0.80083996 -1.95298996 0.7975 -1.95195 0 P 0 
L 0.7975 -1.95195 0.79426004 -1.95066004 0 P 0 
L 0.79426004 -1.95066004 0.79111998 -1.94911998 0 P 0 
L 0.79111998 -1.94911998 0.78811004 -1.94733002 0 P 0 
L 0.78811004 -1.94733002 0.78573002 -1.94568996 0 P 0 
L 0.78573002 -1.94568996 0.78343996 -1.9439 0 P 0 
L 0.78343996 -1.9439 0.78126004 -1.94198996 0 P 0 
L 0.78126004 -1.94198996 0.7793 -1.94003996 0 P 0 
L 0.7793 -1.94003996 0.77746998 -1.93796004 0 P 0 
L 0.77746998 -1.93796004 0.77578996 -1.93576998 0 P 0 
L 0.77578996 -1.93576998 0.77423002 -1.93343002 0 P 0 
L 0.77423002 -1.93343002 0.77283996 -1.931 0 P 0 
L 0.77283996 -1.931 0.77161004 -1.92848996 0 P 0 
L 0.77161004 -1.92848996 0.76991998 -1.92426998 0 P 0 
L 0.76991998 -1.92426998 0.76858002 -1.91993996 0 P 0 
L 0.76858002 -1.91993996 0.76783996 -1.91661998 0 P 0 
L 0.76783996 -1.91661998 0.76738002 -1.91326998 0 P 0 
L 0.76738002 -1.91326998 0.76721004 -1.90988996 0 P 0 
L 0.76721004 -1.90988996 0.76731004 -1.90651004 0 P 0 
L 0.76731004 -1.90651004 0.7677 -1.90315 0 P 0 
L 0.7677 -1.90315 0.76838002 -1.89966998 0 P 0 
L 0.76838002 -1.89966998 0.76931004 -1.89626998 0 P 0 
L 0.76931004 -1.89626998 0.7705 -1.89296004 0 P 0 
L 0.7705 -1.89296004 0.77193996 -1.88973996 0 P 0 
L 0.77193996 -1.88973996 0.7736 -1.88663996 0 P 0 
L 0.7736 -1.88663996 0.77551004 -1.88363996 0 P 0 
L 0.77551004 -1.88363996 0.77763002 -1.8808 0 P 0 
L 0.77763002 -1.8808 0.77996004 -1.87813002 0 P 0 
L 0.77996004 -1.87813002 0.78246998 -1.87565 0 P 0 
L 0.78246998 -1.87565 0.78516004 -1.87336004 0 P 0 
L 0.78516004 -1.87336004 0.78795 -1.87133996 0 P 0 
L 0.78795 -1.87133996 0.79088002 -1.86956004 0 P 0 
L 0.79088002 -1.86956004 0.79393996 -1.86803002 0 P 0 
L 0.79393996 -1.86803002 0.79711004 -1.86675 0 P 0 
L 0.79711004 -1.86675 0.80038002 -1.86573002 0 P 0 
L 0.80038002 -1.86573002 0.80431004 -1.86486004 0 P 0 
L 0.80431004 -1.86486004 0.80828996 -1.86433996 0 P 0 
L 0.80828996 -1.86433996 0.8123 -1.86416004 0 P 0 
L 0.8123 -1.86416004 0.81631004 -1.86431998 0 P 0 
L 0.81631004 -1.86431998 0.81946998 -1.86471004 0 P 0 
L 0.81946998 -1.86471004 0.82258996 -1.86531004 0 P 0 
L 0.82258996 -1.86531004 0.82566004 -1.86613996 0 P 0 
L 0.82566004 -1.86613996 0.82866998 -1.86718002 0 P 0 
L 0.82866998 -1.86718002 0.83158996 -1.86843002 0 P 0 
L 0.83158996 -1.86843002 0.83443002 -1.86988996 0 P 0 
L 0.83443002 -1.86988996 0.83716004 -1.87156004 0 P 0 
L 0.83716004 -1.87156004 0.83976004 -1.87341004 0 P 0 
L 0.83976004 -1.87341004 0.84223002 -1.87543996 0 P 0 
L 0.84223002 -1.87543996 0.84453996 -1.87763002 0 P 0 
L 0.84453996 -1.87763002 0.84726998 -1.88065 0 P 0 
L 0.84726998 -1.88065 0.84971998 -1.88388002 0 P 0 
L 0.84971998 -1.88388002 0.85188996 -1.88731004 0 P 0 
L 0.85188996 -1.88731004 0.85376004 -1.89091004 0 P 0 
L 0.85376004 -1.89091004 0.85483996 -1.89345 0 P 0 
L 0.85483996 -1.89345 0.85575 -1.89605 0 P 0 
L 0.85575 -1.89605 0.85646998 -1.89871004 0 P 0 
L 0.85646998 -1.89871004 0.857 -1.90141004 0 P 0 
L 0.857 -1.90141004 0.85748002 -1.9053 0 P 0 
L 0.85748002 -1.9053 0.85763996 -1.90918996 0 P 0 
L 0.85763996 -1.90918996 0.8575 -1.91308002 0 P 0 
L 0.8575 -1.91308002 0.85703996 -1.91696004 0 P 0 
L 0.85703996 -1.91696004 0.85628002 -1.92076004 0 P 0 
L 0.85628002 -1.92076004 0.85521998 -1.92448996 0 P 0 
L 0.85521998 -1.92448996 0.85428002 -1.92705 0 P 0 
L 0.85428002 -1.92705 0.85316998 -1.92951998 0 P 0 
L 0.85316998 -1.92951998 0.85188002 -1.93191004 0 P 0 
L 0.85188002 -1.93191004 0.85041998 -1.9342 0 P 0 
L 0.85041998 -1.9342 0.84826998 -1.93708002 0 P 0 
L 0.84826998 -1.93708002 0.84593002 -1.93976998 0 P 0 
L 0.84593002 -1.93976998 0.8434 -1.94228002 0 P 0 
L 0.8434 -1.94228002 0.84068002 -1.9446 0 P 0 
L 0.84068002 -1.9446 0.8378 -1.9467 0 P 0 
L 0.8378 -1.9467 0.83476998 -1.94858002 0 P 0 
L 0.83476998 -1.94858002 0.83163996 -1.9502 0 P 0 
L 0.83163996 -1.9502 0.8284 -1.95158002 0 P 0 
L 0.8284 -1.95158002 0.82506004 -1.95268996 0 P 0 
L 0.82506004 -1.95268996 0.82163996 -1.95356004 0 P 0 
L 0.82163996 -1.95356004 0.81818002 -1.95413996 0 P 0 
L 0.81818002 -1.95413996 0.8147 -1.95446004 0 P 0 
L 0.8147 -1.95446004 0.81121004 -1.9545 0 P 0 
L 0.77075 -2.02925 0.84511004 -2.02925 0 P 0 
L 0.77076004 -2.02825 0.8452 -2.02825 0 P 0 
L 0.77076998 -2.02725 0.84528996 -2.02725 0 P 0 
L 0.77078002 -2.02625 0.84536998 -2.02625 0 P 0 
L 0.77078996 -2.02525 0.84548996 -2.02525 0 P 0 
L 0.7708 -2.02425 0.84561998 -2.02425 0 P 0 
L 0.77081004 -2.02325 0.84575 -2.02325 0 P 0 
L 0.77081998 -2.02225 0.84588002 -2.02225 0 P 0 
L 0.77083002 -2.02125 0.84601004 -2.02125 0 P 0 
L 0.77083996 -2.02025 0.84613996 -2.02025 0 P 0 
L 0.77085 -2.01925 0.84626004 -2.01925 0 P 0 
L 0.77085 -2.01825 0.84638996 -2.01825 0 P 0 
L 0.77085 -2.01725 0.84651998 -2.01725 0 P 0 
L 0.77086004 -2.01625 0.84663996 -2.01625 0 P 0 
L 0.77086004 -2.01525 0.84676998 -2.01525 0 P 0 
L 0.77086004 -2.01425 0.8469 -2.01425 0 P 0 
L 0.77086004 -2.01325 0.84703002 -2.01325 0 P 0 
L 0.77086004 -2.01225 0.84716004 -2.01225 0 P 0 
L 0.77086004 -2.01125 0.84728996 -2.01125 0 P 0 
L 0.77086004 -2.01025 0.84741004 -2.01025 0 P 0 
L 0.77086998 -2.00925 0.84753996 -2.00925 0 P 0 
L 0.77086998 -2.00825 0.84766998 -2.00825 0 P 0 
L 0.77086998 -2.00725 0.84778996 -2.00725 0 P 0 
L 0.77086998 -2.00625 0.84791998 -2.00625 0 P 0 
L 0.77086998 -2.00525 0.84805 -2.00525 0 P 0 
L 0.77086998 -2.00425 0.84818002 -2.00425 0 P 0 
L 0.77088002 -2.00325 0.84831004 -2.00325 0 P 0 
L 0.77088002 -2.00225 0.84843996 -2.00225 0 P 0 
L 0.77088002 -2.00125 0.84856004 -2.00125 0 P 0 
L 0.77088002 -2.00025 0.84868996 -2.00025 0 P 0 
L 0.77088002 -1.99925 0.84881998 -1.99925 0 P 0 
L 0.77088002 -1.99825 0.84896004 -1.99825 0 P 0 
L 0.77088002 -1.99725 0.84911004 -1.99725 0 P 0 
L 0.77088996 -1.99625 0.84926998 -1.99625 0 P 0 
L 0.77088996 -1.99525 0.84941998 -1.99525 0 P 0 
L 0.77088996 -1.99425 0.84956998 -1.99425 0 P 0 
L 0.77088996 -1.99325 0.84971998 -1.99325 0 P 0 
L 0.77088996 -1.99225 0.84986998 -1.99225 0 P 0 
L 0.77088996 -1.99125 0.85003002 -1.99125 0 P 0 
L 0.7709 -1.99025 0.85018002 -1.99025 0 P 0 
L 0.7709 -1.98925 0.85033002 -1.98925 0 P 0 
L 0.76885 -2.01878002 0.76871998 -2.03201998 0 P 0 
L 0.76871998 -2.03201998 0.7684 -2.04553996 0 P 0 
L 0.7684 -2.04553996 0.76796004 -2.05751004 0 P 0 
L 0.76796004 -2.05751004 0.76741004 -2.06523002 0 P 0 
L 0.76741004 -2.06523002 0.76596004 -2.07933996 0 P 0 
L 0.76596004 -2.07933996 0.7636 -2.09918002 0 P 0 
L 0.7636 -2.09918002 0.76116004 -2.119 0 P 0 
L 0.76116004 -2.119 0.76011998 -2.12526004 0 P 0 
L 0.76011998 -2.12526004 0.75948996 -2.12825 0 P 0 
L 0.75948996 -2.12825 0.84418002 -2.12825 0 P 0 
L 0.84418002 -2.12825 0.84361998 -2.10788002 0 P 0 
L 0.84361998 -2.10788002 0.8436 -2.08276004 0 P 0 
L 0.8436 -2.08276004 0.8449 -2.05491998 0 P 0 
L 0.8449 -2.05491998 0.84736004 -2.02641004 0 P 0 
L 0.84736004 -2.02641004 0.85083996 -1.99923002 0 P 0 
L 0.85083996 -1.99923002 0.85268996 -1.987 0 P 0 
L 0.85268996 -1.987 0.7689 -1.987 0 P 0 
L 0.7689 -1.987 0.76885 -2.01878002 0 P 0 
L 0.76195 -2.12625 0.84211998 -2.12625 0 P 0 
L 0.76213996 -2.12525 0.8421 -2.12525 0 P 0 
L 0.76231004 -2.12425 0.84206998 -2.12425 0 P 0 
L 0.76248002 -2.12325 0.84203996 -2.12325 0 P 0 
L 0.76263996 -2.12225 0.84201004 -2.12225 0 P 0 
L 0.76281004 -2.12125 0.84198996 -2.12125 0 P 0 
L 0.76296998 -2.12025 0.84196004 -2.12025 0 P 0 
L 0.76313996 -2.11925 0.84193002 -2.11925 0 P 0 
L 0.76326998 -2.11825 0.8419 -2.11825 0 P 0 
L 0.76338996 -2.11725 0.84188002 -2.11725 0 P 0 
L 0.76351004 -2.11625 0.84185 -2.11625 0 P 0 
L 0.76363996 -2.11525 0.84181998 -2.11525 0 P 0 
L 0.76376004 -2.11425 0.84178996 -2.11425 0 P 0 
L 0.76388002 -2.11325 0.84176998 -2.11325 0 P 0 
L 0.76401004 -2.11225 0.84173996 -2.11225 0 P 0 
L 0.76413002 -2.11125 0.84171004 -2.11125 0 P 0 
L 0.76425 -2.11025 0.84168002 -2.11025 0 P 0 
L 0.76438002 -2.10925 0.84166004 -2.10925 0 P 0 
L 0.7645 -2.10825 0.84163002 -2.10825 0 P 0 
L 0.76461998 -2.10725 0.84161998 -2.10725 0 P 0 
L 0.76475 -2.10625 0.84161998 -2.10625 0 P 0 
L 0.76486998 -2.10525 0.84161998 -2.10525 0 P 0 
L 0.76498996 -2.10425 0.84161998 -2.10425 0 P 0 
L 0.76511998 -2.10325 0.84161998 -2.10325 0 P 0 
L 0.76523996 -2.10225 0.84161998 -2.10225 0 P 0 
L 0.76536004 -2.10125 0.84161998 -2.10125 0 P 0 
L 0.76548996 -2.10025 0.84161998 -2.10025 0 P 0 
L 0.76561004 -2.09925 0.84161998 -2.09925 0 P 0 
L 0.76573002 -2.09825 0.84161004 -2.09825 0 P 0 
L 0.76583996 -2.09725 0.84161004 -2.09725 0 P 0 
L 0.76596998 -2.09625 0.84161004 -2.09625 0 P 0 
L 0.76608996 -2.09525 0.84161004 -2.09525 0 P 0 
L 0.7662 -2.09425 0.84161004 -2.09425 0 P 0 
L 0.76631998 -2.09325 0.84161004 -2.09325 0 P 0 
L 0.76643996 -2.09225 0.84161004 -2.09225 0 P 0 
L 0.76656004 -2.09125 0.84161004 -2.09125 0 P 0 
L 0.76668002 -2.09025 0.84161004 -2.09025 0 P 0 
L 0.76678996 -2.08925 0.84161004 -2.08925 0 P 0 
L 0.76691998 -2.08825 0.84161004 -2.08825 0 P 0 
L 0.76703002 -2.08725 0.84161004 -2.08725 0 P 0 
L 0.76715 -2.08625 0.8416 -2.08625 0 P 0 
L 0.76726998 -2.08525 0.8416 -2.08525 0 P 0 
L 0.76738996 -2.08425 0.8416 -2.08425 0 P 0 
L 0.76195 -2.12625 0.76208002 -2.12561998 0 P 0 
L 0.76208002 -2.12561998 0.76313996 -2.11928996 0 P 0 
L 0.76313996 -2.11928996 0.76558996 -2.09941998 0 P 0 
L 0.76558996 -2.09941998 0.76558996 -2.09941004 0 P 0 
L 0.76558996 -2.09941004 0.76793996 -2.07956004 0 P 0 
L 0.76793996 -2.07956004 0.7694 -2.0654 0 P 0 
L 0.7694 -2.0654 0.76941004 -2.06536004 0 P 0 
L 0.76941004 -2.06536004 0.76996004 -2.05761998 0 P 0 
L 0.76996004 -2.05761998 0.76996004 -2.05758996 0 P 0 
L 0.76996004 -2.05758996 0.7704 -2.0456 0 P 0 
L 0.7704 -2.0456 0.77071998 -2.03206004 0 P 0 
L 0.77071998 -2.03206004 0.77085 -2.01878002 0 P 0 
L 0.77085 -2.01878002 0.7709 -1.989 0 P 0 
L 0.7709 -1.989 0.85036004 -1.989 0 P 0 
L 0.85036004 -1.989 0.84886004 -1.99895 0 P 0 
L 0.84886004 -1.99895 0.84538002 -2.02618996 0 P 0 
L 0.84538002 -2.02618996 0.8429 -2.05478996 0 P 0 
L 0.8429 -2.05478996 0.8416 -2.08271004 0 P 0 
L 0.8416 -2.08271004 0.84161998 -2.10791004 0 P 0 
L 0.84161998 -2.10791004 0.84211998 -2.12625 0 P 0 
L 0.84211998 -2.12625 0.76195 -2.12625 0 P 0 
L 0.71628996 -1.91261998 0.74938002 -1.91261998 0 P 0 
L 0.71783002 -1.91161998 0.74933002 -1.91161998 0 P 0 
L 0.71953002 -1.91061998 0.74931004 -1.91061998 0 P 0 
L 0.72133002 -1.90961998 0.74928996 -1.90961998 0 P 0 
L 0.72313996 -1.90861998 0.74926998 -1.90861998 0 P 0 
L 0.72493996 -1.90761998 0.74928996 -1.90761998 0 P 0 
L 0.72673996 -1.90661998 0.74931998 -1.90661998 0 P 0 
L 0.72855 -1.90561998 0.74935 -1.90561998 0 P 0 
L 0.73035 -1.90461998 0.74938996 -1.90461998 0 P 0 
L 0.73215 -1.90361998 0.74946998 -1.90361998 0 P 0 
L 0.73396004 -1.90261998 0.74953996 -1.90261998 0 P 0 
L 0.73576004 -1.90161998 0.74961998 -1.90161998 0 P 0 
L 0.73756998 -1.90061998 0.74973996 -1.90061998 0 P 0 
L 0.73943002 -1.89961998 0.74986004 -1.89961998 0 P 0 
L 0.74141998 -1.89861998 0.74998996 -1.89861998 0 P 0 
L 0.74341004 -1.89761998 0.75015 -1.89761998 0 P 0 
L 0.59843002 -2.08361998 0.6754 -2.08361998 0 P 0 
L 0.59846004 -2.08261998 0.67538996 -2.08261998 0 P 0 
L 0.59848002 -2.08161998 0.67538002 -2.08161998 0 P 0 
L 0.59851004 -2.08061998 0.67538002 -2.08061998 0 P 0 
L 0.59853002 -2.07961998 0.67546004 -2.07961998 0 P 0 
L 0.59856004 -2.07861998 0.67553996 -2.07861998 0 P 0 
L 0.59861998 -2.07761998 0.67561004 -2.07761998 0 P 0 
L 0.5987 -2.07661998 0.67568996 -2.07661998 0 P 0 
L 0.59878002 -2.07561998 0.67576004 -2.07561998 0 P 0 
L 0.59885 -2.07461998 0.67583996 -2.07461998 0 P 0 
L 0.59893002 -2.07361998 0.67591998 -2.07361998 0 P 0 
L 0.59901004 -2.07261998 0.67598996 -2.07261998 0 P 0 
L 0.59908002 -2.07161998 0.67606998 -2.07161998 0 P 0 
L 0.59916004 -2.07061998 0.67613996 -2.07061998 0 P 0 
L 0.59923002 -2.06961998 0.67621004 -2.06961998 0 P 0 
L 0.59936004 -2.06861998 0.6763 -2.06861998 0 P 0 
L 0.59948996 -2.06761998 0.67645 -2.06761998 0 P 0 
L 0.59963002 -2.06661998 0.6766 -2.06661998 0 P 0 
L 0.59976998 -2.06561998 0.67676004 -2.06561998 0 P 0 
L 0.5999 -2.06461998 0.67691998 -2.06461998 0 P 0 
L 0.60003002 -2.06361998 0.67706998 -2.06361998 0 P 0 
L 0.60016998 -2.06261998 0.6773 -2.06261998 0 P 0 
L 0.60031004 -2.06161998 0.67753002 -2.06161998 0 P 0 
L 0.60051004 -2.06061998 0.67776004 -2.06061998 0 P 0 
L 0.60071004 -2.05961998 0.67798996 -2.05961998 0 P 0 
L 0.60091998 -2.05861998 0.67823002 -2.05861998 0 P 0 
L 0.60111998 -2.05761998 0.67853002 -2.05761998 0 P 0 
L 0.60133002 -2.05661998 0.67883996 -2.05661998 0 P 0 
L 0.60153996 -2.05561998 0.67913996 -2.05561998 0 P 0 
L 0.60173996 -2.05461998 0.67945 -2.05461998 0 P 0 
L 0.60195 -2.05361998 0.67975 -2.05361998 0 P 0 
L 0.60223002 -2.05261998 0.68006004 -2.05261998 0 P 0 
L 0.60251004 -2.05161998 0.68036004 -2.05161998 0 P 0 
L 0.60278996 -2.05061998 0.68066998 -2.05061998 0 P 0 
L 0.60306004 -2.04961998 0.68096998 -2.04961998 0 P 0 
L 0.60333996 -2.04861998 0.68135 -2.04861998 0 P 0 
L 0.60361998 -2.04761998 0.68173002 -2.04761998 0 P 0 
L 0.6039 -2.04661998 0.68211004 -2.04661998 0 P 0 
L 0.60418002 -2.04561998 0.68248996 -2.04561998 0 P 0 
L 0.60453002 -2.04461998 0.68288002 -2.04461998 0 P 0 
L 0.60488002 -2.04361998 0.68326004 -2.04361998 0 P 0 
L 0.60523002 -2.04261998 0.68363996 -2.04261998 0 P 0 
L 0.60556998 -2.04161998 0.68401998 -2.04161998 0 P 0 
L 0.60591998 -2.04061998 0.6844 -2.04061998 0 P 0 
L 0.60626998 -2.03961998 0.68486004 -2.03961998 0 P 0 
L 0.60661998 -2.03861998 0.68531998 -2.03861998 0 P 0 
L 0.60698996 -2.03761998 0.68578002 -2.03761998 0 P 0 
L 0.60743002 -2.03661998 0.68623996 -2.03661998 0 P 0 
L 0.60786004 -2.03561998 0.6867 -2.03561998 0 P 0 
L 0.60828996 -2.03461998 0.68716004 -2.03461998 0 P 0 
L 0.60873002 -2.03361998 0.68761998 -2.03361998 0 P 0 
L 0.60916004 -2.03261998 0.68808996 -2.03261998 0 P 0 
L 0.60958996 -2.03161998 0.68856998 -2.03161998 0 P 0 
L 0.61003002 -2.03061998 0.68911004 -2.03061998 0 P 0 
L 0.61046004 -2.02961998 0.68965 -2.02961998 0 P 0 
L 0.61088996 -2.02861998 0.69018996 -2.02861998 0 P 0 
L 0.61133002 -2.02761998 0.69073002 -2.02761998 0 P 0 
L 0.61176004 -2.02661998 0.69126998 -2.02661998 0 P 0 
L 0.6122 -2.02561998 0.69181004 -2.02561998 0 P 0 
L 0.61263002 -2.02461998 0.69235 -2.02461998 0 P 0 
L 0.61306004 -2.02361998 0.69288002 -2.02361998 0 P 0 
L 0.61348996 -2.02261998 0.69346998 -2.02261998 0 P 0 
L 0.61393002 -2.02161998 0.69408996 -2.02161998 0 P 0 
L 0.61436004 -2.02061998 0.6947 -2.02061998 0 P 0 
L 0.61478996 -2.01961998 0.69531998 -2.01961998 0 P 0 
L 0.61531004 -2.01861998 0.69593996 -2.01861998 0 P 0 
L 0.61583996 -2.01761998 0.69656004 -2.01761998 0 P 0 
L 0.61636004 -2.01661998 0.69718002 -2.01661998 0 P 0 
L 0.61688002 -2.01561998 0.69778996 -2.01561998 0 P 0 
L 0.6174 -2.01461998 0.69841998 -2.01461998 0 P 0 
L 0.61791998 -2.01361998 0.69911998 -2.01361998 0 P 0 
L 0.61843996 -2.01261998 0.69981998 -2.01261998 0 P 0 
L 0.61896004 -2.01161998 0.70051998 -2.01161998 0 P 0 
L 0.61948002 -2.01061998 0.70123002 -2.01061998 0 P 0 
L 0.62 -2.00961998 0.70193002 -2.00961998 0 P 0 
L 0.62051998 -2.00861998 0.70263002 -2.00861998 0 P 0 
L 0.62103996 -2.00761998 0.70333002 -2.00761998 0 P 0 
L 0.62163996 -2.00661998 0.70403996 -2.00661998 0 P 0 
L 0.62225 -2.00561998 0.70483002 -2.00561998 0 P 0 
L 0.62285 -2.00461998 0.70565 -2.00461998 0 P 0 
L 0.62346004 -2.00361998 0.70646004 -2.00361998 0 P 0 
L 0.62406004 -2.00261998 0.70726998 -2.00261998 0 P 0 
L 0.62466004 -2.00161998 0.70808996 -2.00161998 0 P 0 
L 0.62526998 -2.00061998 0.7089 -2.00061998 0 P 0 
L 0.62586998 -1.99961998 0.70971004 -1.99961998 0 P 0 
L 0.62648002 -1.99861998 0.71053002 -1.99861998 0 P 0 
L 0.62708002 -1.99761998 0.71133996 -1.99761998 0 P 0 
L 0.62768996 -1.99661998 0.71216004 -1.99661998 0 P 0 
L 0.62831998 -1.99561998 0.71296998 -1.99561998 0 P 0 
L 0.62901004 -1.99461998 0.71378996 -1.99461998 0 P 0 
L 0.62971004 -1.99361998 0.71466004 -1.99361998 0 P 0 
L 0.6304 -1.99261998 0.71561004 -1.99261998 0 P 0 
L 0.6311 -1.99161998 0.71656998 -1.99161998 0 P 0 
L 0.63178996 -1.99061998 0.71753002 -1.99061998 0 P 0 
L 0.63248996 -1.98961998 0.71848996 -1.98961998 0 P 0 
L 0.63318002 -1.98861998 0.71945 -1.98861998 0 P 0 
L 0.63388002 -1.98761998 0.72041004 -1.98761998 0 P 0 
L 0.63456998 -1.98661998 0.72136998 -1.98661998 0 P 0 
L 0.63526998 -1.98561998 0.72233002 -1.98561998 0 P 0 
L 0.63598002 -1.98461998 0.72328996 -1.98461998 0 P 0 
L 0.63678996 -1.98361998 0.72425 -1.98361998 0 P 0 
L 0.6376 -1.98261998 0.72521004 -1.98261998 0 P 0 
L 0.63841004 -1.98161998 0.72628002 -1.98161998 0 P 0 
L 0.63921998 -1.98061998 0.72738996 -1.98061998 0 P 0 
L 0.64003002 -1.97961998 0.7285 -1.97961998 0 P 0 
L 0.64083996 -1.97861998 0.72961004 -1.97861998 0 P 0 
L 0.64165 -1.97761998 0.73071004 -1.97761998 0 P 0 
L 0.64246004 -1.97661998 0.73181998 -1.97661998 0 P 0 
L 0.64326998 -1.97561998 0.73293002 -1.97561998 0 P 0 
L 0.64406998 -1.97461998 0.73403996 -1.97461998 0 P 0 
L 0.64488002 -1.97361998 0.73515 -1.97361998 0 P 0 
L 0.64568996 -1.97261998 0.73625 -1.97261998 0 P 0 
L 0.6465 -1.97161998 0.73736004 -1.97161998 0 P 0 
L 0.64731004 -1.97061998 0.73848002 -1.97061998 0 P 0 
L 0.64811998 -1.96961998 0.73973002 -1.96961998 0 P 0 
L 0.64893002 -1.96861998 0.74098996 -1.96861998 0 P 0 
L 0.64981004 -1.96761998 0.74225 -1.96761998 0 P 0 
L 0.65076004 -1.96661998 0.74351004 -1.96661998 0 P 0 
L 0.65171004 -1.96561998 0.74476998 -1.96561998 0 P 0 
L 0.65266998 -1.96461998 0.74603002 -1.96461998 0 P 0 
L 0.65361998 -1.96361998 0.74728996 -1.96361998 0 P 0 
L 0.65458002 -1.96261998 0.74855 -1.96261998 0 P 0 
L 0.65553002 -1.96161998 0.74981004 -1.96161998 0 P 0 
L 0.65648996 -1.96061998 0.75106004 -1.96061998 0 P 0 
L 0.65743996 -1.95961998 0.75233996 -1.95961998 0 P 0 
L 0.6584 -1.95861998 0.7537 -1.95861998 0 P 0 
L 0.65935 -1.95761998 0.75506004 -1.95761998 0 P 0 
L 0.66031004 -1.95661998 0.75641998 -1.95661998 0 P 0 
L 0.66126004 -1.95561998 0.75778996 -1.95561998 0 P 0 
L 0.66221004 -1.95461998 0.75916004 -1.95461998 0 P 0 
L 0.66316998 -1.95361998 0.76053996 -1.95361998 0 P 0 
L 0.66411998 -1.95261998 0.76193996 -1.95261998 0 P 0 
L 0.66523002 -1.95161998 0.76333996 -1.95161998 0 P 0 
L 0.66636004 -1.95061998 0.76406998 -1.95061998 0 P 0 
L 0.66746998 -1.94961998 0.76355 -1.94961998 0 P 0 
L 0.6686 -1.94861998 0.76291998 -1.94861998 0 P 0 
L 0.66971004 -1.94761998 0.76226998 -1.94761998 0 P 0 
L 0.67083996 -1.94661998 0.76161998 -1.94661998 0 P 0 
L 0.67196004 -1.94561998 0.76096998 -1.94561998 0 P 0 
L 0.67306998 -1.94461998 0.76033002 -1.94461998 0 P 0 
L 0.6742 -1.94361998 0.75968996 -1.94361998 0 P 0 
L 0.67531004 -1.94261998 0.75905 -1.94261998 0 P 0 
L 0.67643996 -1.94161998 0.75846004 -1.94161998 0 P 0 
L 0.67755 -1.94061998 0.75788996 -1.94061998 0 P 0 
L 0.67868002 -1.93961998 0.75731998 -1.93961998 0 P 0 
L 0.67978996 -1.93861998 0.75676998 -1.93861998 0 P 0 
L 0.68091998 -1.93761998 0.75626998 -1.93761998 0 P 0 
L 0.68221004 -1.93661998 0.75576998 -1.93661998 0 P 0 
L 0.68353002 -1.93561998 0.75528002 -1.93561998 0 P 0 
L 0.68483996 -1.93461998 0.75483996 -1.93461998 0 P 0 
L 0.68616004 -1.93361998 0.75441004 -1.93361998 0 P 0 
L 0.68746998 -1.93261998 0.75398002 -1.93261998 0 P 0 
L 0.68878002 -1.93161998 0.7536 -1.93161998 0 P 0 
L 0.6901 -1.93061998 0.75323996 -1.93061998 0 P 0 
L 0.69141004 -1.92961998 0.75286998 -1.92961998 0 P 0 
L 0.69271998 -1.92861998 0.75253996 -1.92861998 0 P 0 
L 0.69403002 -1.92761998 0.75223002 -1.92761998 0 P 0 
L 0.69535 -1.92661998 0.75193002 -1.92661998 0 P 0 
L 0.69666004 -1.92561998 0.75163002 -1.92561998 0 P 0 
L 0.69796998 -1.92461998 0.75138002 -1.92461998 0 P 0 
L 0.69936998 -1.92361998 0.75113996 -1.92361998 0 P 0 
L 0.70091004 -1.92261998 0.75088996 -1.92261998 0 P 0 
L 0.70243996 -1.92161998 0.75066004 -1.92161998 0 P 0 
L 0.70398002 -1.92061998 0.75046004 -1.92061998 0 P 0 
L 0.70551998 -1.91961998 0.75026004 -1.91961998 0 P 0 
L 0.70706004 -1.91861998 0.75006998 -1.91861998 0 P 0 
L 0.7086 -1.91761998 0.7499 -1.91761998 0 P 0 
L 0.71013996 -1.91661998 0.74976998 -1.91661998 0 P 0 
L 0.71166998 -1.91561998 0.74961998 -1.91561998 0 P 0 
L 0.71321004 -1.91461998 0.74951998 -1.91461998 0 P 0 
L 0.71475 -1.91361998 0.74945 -1.91361998 0 P 0 
L 0.61556998 -2.15661998 0.70655 -2.15661998 0 P 0 
L 0.61503002 -2.15561998 0.7056 -2.15561998 0 P 0 
L 0.61448996 -2.15461998 0.70465 -2.15461998 0 P 0 
L 0.61395 -2.15361998 0.7037 -2.15361998 0 P 0 
L 0.61341004 -2.15261998 0.70273996 -2.15261998 0 P 0 
L 0.61286998 -2.15161998 0.70178996 -2.15161998 0 P 0 
L 0.61233002 -2.15061998 0.70095 -2.15061998 0 P 0 
L 0.61188002 -2.14961998 0.70015 -2.14961998 0 P 0 
L 0.61143002 -2.14861998 0.69935 -2.14861998 0 P 0 
L 0.61098002 -2.14761998 0.69855 -2.14761998 0 P 0 
L 0.61053002 -2.14661998 0.69775 -2.14661998 0 P 0 
L 0.61008002 -2.14561998 0.69695 -2.14561998 0 P 0 
L 0.60963002 -2.14461998 0.69615 -2.14461998 0 P 0 
L 0.60918002 -2.14361998 0.69535 -2.14361998 0 P 0 
L 0.60873002 -2.14261998 0.69455 -2.14261998 0 P 0 
L 0.60831004 -2.14161998 0.69381998 -2.14161998 0 P 0 
L 0.60793996 -2.14061998 0.69315 -2.14061998 0 P 0 
L 0.60756998 -2.13961998 0.69248002 -2.13961998 0 P 0 
L 0.60721004 -2.13861998 0.69181004 -2.13861998 0 P 0 
L 0.60683996 -2.13761998 0.69115 -2.13761998 0 P 0 
L 0.60646998 -2.13661998 0.69048002 -2.13661998 0 P 0 
L 0.60611004 -2.13561998 0.68981004 -2.13561998 0 P 0 
L 0.60573996 -2.13461998 0.68918002 -2.13461998 0 P 0 
L 0.60538002 -2.13361998 0.68863002 -2.13361998 0 P 0 
L 0.60503996 -2.13261998 0.68808002 -2.13261998 0 P 0 
L 0.60476004 -2.13161998 0.68753002 -2.13161998 0 P 0 
L 0.60446998 -2.13061998 0.68698002 -2.13061998 0 P 0 
L 0.60418002 -2.12961998 0.68643002 -2.12961998 0 P 0 
L 0.6039 -2.12861998 0.68588002 -2.12861998 0 P 0 
L 0.60361004 -2.12761998 0.68533002 -2.12761998 0 P 0 
L 0.60331998 -2.12661998 0.68486004 -2.12661998 0 P 0 
L 0.60303002 -2.12561998 0.68441998 -2.12561998 0 P 0 
L 0.60275 -2.12461998 0.68396998 -2.12461998 0 P 0 
L 0.60246004 -2.12361998 0.68353002 -2.12361998 0 P 0 
L 0.60218002 -2.12261998 0.68308996 -2.12261998 0 P 0 
L 0.60188996 -2.12161998 0.68263996 -2.12161998 0 P 0 
L 0.60166998 -2.12061998 0.6822 -2.12061998 0 P 0 
L 0.60145 -2.11961998 0.68176004 -2.11961998 0 P 0 
L 0.60123002 -2.11861998 0.68138996 -2.11861998 0 P 0 
L 0.60101004 -2.11761998 0.68105 -2.11761998 0 P 0 
L 0.60078002 -2.11661998 0.68071004 -2.11661998 0 P 0 
L 0.6006 -2.11561998 0.68036004 -2.11561998 0 P 0 
L 0.60043002 -2.11461998 0.68001998 -2.11461998 0 P 0 
L 0.60025 -2.11361998 0.67968002 -2.11361998 0 P 0 
L 0.60008002 -2.11261998 0.67933002 -2.11261998 0 P 0 
L 0.59991004 -2.11161998 0.67898996 -2.11161998 0 P 0 
L 0.59976004 -2.11061998 0.6787 -2.11061998 0 P 0 
L 0.59963996 -2.10961998 0.67845 -2.10961998 0 P 0 
L 0.59951004 -2.10861998 0.6782 -2.10861998 0 P 0 
L 0.59938002 -2.10761998 0.67795 -2.10761998 0 P 0 
L 0.59925 -2.10661998 0.6777 -2.10661998 0 P 0 
L 0.59913002 -2.10561998 0.67746004 -2.10561998 0 P 0 
L 0.59905 -2.10461998 0.67721004 -2.10461998 0 P 0 
L 0.59896998 -2.10361998 0.67696004 -2.10361998 0 P 0 
L 0.59888002 -2.10261998 0.67671004 -2.10261998 0 P 0 
L 0.5988 -2.10161998 0.67653996 -2.10161998 0 P 0 
L 0.59871998 -2.10061998 0.67638002 -2.10061998 0 P 0 
L 0.59866998 -2.09961998 0.67621004 -2.09961998 0 P 0 
L 0.59863996 -2.09861998 0.67605 -2.09861998 0 P 0 
L 0.59861004 -2.09761998 0.67588996 -2.09761998 0 P 0 
L 0.59858996 -2.09661998 0.6758 -2.09661998 0 P 0 
L 0.59856004 -2.09561998 0.67571004 -2.09561998 0 P 0 
L 0.59853002 -2.09461998 0.67563002 -2.09461998 0 P 0 
L 0.5985 -2.09361998 0.67553996 -2.09361998 0 P 0 
L 0.59846998 -2.09261998 0.67546004 -2.09261998 0 P 0 
L 0.59843996 -2.09161998 0.67546004 -2.09161998 0 P 0 
L 0.59841998 -2.09061998 0.67545 -2.09061998 0 P 0 
L 0.59838002 -2.08961998 0.67543996 -2.08961998 0 P 0 
L 0.59836004 -2.08861998 0.67543002 -2.08861998 0 P 0 
L 0.59833002 -2.08761998 0.67543002 -2.08761998 0 P 0 
L 0.59835 -2.08661998 0.67541998 -2.08661998 0 P 0 
L 0.59836998 -2.08561998 0.67541004 -2.08561998 0 P 0 
L 0.5984 -2.08461998 0.67541004 -2.08461998 0 P 0 
L 0.80005 -2.25161998 0.85543996 -2.25161998 0 P 0 
L 0.78651998 -2.25061998 0.86596004 -2.25061998 0 P 0 
L 0.77878996 -2.24961998 0.87636004 -2.24961998 0 P 0 
L 0.77106004 -2.24861998 0.88285 -2.24861998 0 P 0 
L 0.76398996 -2.24761998 0.88933996 -2.24761998 0 P 0 
L 0.75891998 -2.24661998 0.89583996 -2.24661998 0 P 0 
L 0.73781004 -1.8982 0.71738996 -1.90951998 0 P 0 
L 0.71738996 -1.90951998 0.69766998 -1.92233996 0 P 0 
L 0.69766998 -1.92233996 0.67971004 -1.93601998 0 P 0 
L 0.67971004 -1.93601998 0.66278996 -1.95113002 0 P 0 
L 0.66278996 -1.95113002 0.64786998 -1.96675 0 P 0 
L 0.64786998 -1.96675 0.63423996 -1.98358996 0 P 0 
L 0.63423996 -1.98358996 0.62643996 -1.99483002 0 P 0 
L 0.62643996 -1.99483002 0.61933996 -2.00655 0 P 0 
L 0.61933996 -2.00655 0.61298996 -2.01873996 0 P 0 
L 0.61298996 -2.01873996 0.60503002 -2.03713002 0 P 0 
L 0.60503002 -2.03713002 0.60225 -2.04506004 0 P 0 
L 0.60225 -2.04506004 0.59998996 -2.05323002 0 P 0 
L 0.59998996 -2.05323002 0.59833996 -2.0612 0 P 0 
L 0.59833996 -2.0612 0.59725 -2.06928996 0 P 0 
L 0.59725 -2.06928996 0.59656998 -2.07833996 0 P 0 
L 0.59656998 -2.07833996 0.59633002 -2.0875 0 P 0 
L 0.59633002 -2.0875 0.59668996 -2.10036998 0 P 0 
L 0.59668996 -2.10036998 0.59715 -2.10596004 0 P 0 
L 0.59715 -2.10596004 0.59786004 -2.11151004 0 P 0 
L 0.59786004 -2.11151004 0.59878996 -2.11686998 0 P 0 
L 0.59878996 -2.11686998 0.59996998 -2.1222 0 P 0 
L 0.59996998 -2.1222 0.60326998 -2.13368996 0 P 0 
L 0.60326998 -2.13368996 0.60656998 -2.1427 0 P 0 
L 0.60656998 -2.1427 0.6105 -2.15143996 0 P 0 
L 0.6105 -2.15143996 0.61505 -2.15988002 0 P 0 
L 0.61505 -2.15988002 0.62023996 -2.16803996 0 P 0 
L 0.62023996 -2.16803996 0.62828996 -2.17873002 0 P 0 
L 0.62828996 -2.17873002 0.63718996 -2.18871004 0 P 0 
L 0.63718996 -2.18871004 0.64693002 -2.19795 0 P 0 
L 0.64693002 -2.19795 0.6582 -2.20701998 0 P 0 
L 0.6582 -2.20701998 0.67011004 -2.21518996 0 P 0 
L 0.67011004 -2.21518996 0.68261004 -2.22243002 0 P 0 
L 0.68261004 -2.22243002 0.69673996 -2.22936004 0 P 0 
L 0.69673996 -2.22936004 0.71123002 -2.23543996 0 P 0 
L 0.71123002 -2.23543996 0.72611998 -2.24066998 0 P 0 
L 0.72611998 -2.24066998 0.74536004 -2.24598996 0 P 0 
L 0.74536004 -2.24598996 0.76493002 -2.24985 0 P 0 
L 0.76493002 -2.24985 0.78671998 -2.25266998 0 P 0 
L 0.78671998 -2.25266998 0.80863002 -2.25425 0 P 0 
L 0.80863002 -2.25425 0.83146004 -2.25463002 0 P 0 
L 0.83146004 -2.25463002 0.85418002 -2.25375 0 P 0 
L 0.85418002 -2.25375 0.87641004 -2.25163996 0 P 0 
L 0.87641004 -2.25163996 0.89853002 -2.24823002 0 P 0 
L 0.89853002 -2.24823002 0.93045 -2.24101998 0 P 0 
L 0.93045 -2.24101998 0.96466004 -2.23063002 0 P 0 
L 0.96466004 -2.23063002 0.99911004 -2.2178 0 P 0 
L 0.99911004 -2.2178 1.03183002 -2.20318002 0 P 0 
L 1.03183002 -2.20318002 1.04391998 -2.19703002 0 P 0 
L 1.04391998 -2.19703002 1.05581004 -2.19048996 0 P 0 
L 1.05581004 -2.19048996 1.06676004 -2.18411998 0 P 0 
L 1.06676004 -2.18411998 1.06681004 -2.18408996 0 P 0 
L 1.06681004 -2.18408996 1.06685 -2.18405 0 P 0 
L 1.06685 -2.18405 1.0669 -2.18401004 0 P 0 
L 1.0669 -2.18401004 1.06693996 -2.18396998 0 P 0 
L 1.06693996 -2.18396998 1.06696998 -2.18391998 0 P 0 
L 1.06696998 -2.18391998 1.06701004 -2.18386998 0 P 0 
L 1.06701004 -2.18386998 1.06703002 -2.18381998 0 P 0 
L 1.06703002 -2.18381998 1.06706004 -2.18376004 0 P 0 
L 1.06706004 -2.18376004 1.06706998 -2.18371004 0 P 0 
L 1.06706998 -2.18371004 1.06708996 -2.18365 0 P 0 
L 1.06708996 -2.18365 1.06708996 -2.18358996 0 P 0 
L 1.06708996 -2.18358996 1.0671 -2.18353002 0 P 0 
L 1.0671 -2.18353002 1.0671 -2.18346998 0 P 0 
L 1.0671 -2.18346998 1.06708996 -2.18341004 0 P 0 
L 1.06708996 -2.18341004 1.06706998 -2.18336004 0 P 0 
L 1.06706998 -2.18336004 1.06706004 -2.1833 0 P 0 
L 1.06706004 -2.1833 1.06703002 -2.18323996 0 P 0 
L 1.06703002 -2.18323996 1.06701004 -2.18318996 0 P 0 
L 1.06701004 -2.18318996 1.06696998 -2.18313996 0 P 0 
L 1.06696998 -2.18313996 1.06693996 -2.18308996 0 P 0 
L 1.06693996 -2.18308996 1.06688002 -2.18303002 0 P 0 
L 1.06688002 -2.18303002 1.06678996 -2.18296998 0 P 0 
L 1.06678996 -2.18296998 1.06673002 -2.18295 0 P 0 
L 1.06673002 -2.18295 1.0667 -2.18295 0 P 0 
L 1.0667 -2.18295 1.06666004 -2.18293996 0 P 0 
L 1.06666004 -2.18293996 1.0666 -2.18293996 0 P 0 
L 1.0666 -2.18293996 1.06656998 -2.18295 0 P 0 
L 1.06656998 -2.18295 1.06653002 -2.18295 0 P 0 
L 1.06653002 -2.18295 1.06153002 -2.1842 0 P 0 
L 1.06153002 -2.1842 1.05583996 -2.18566998 0 P 0 
L 1.05583996 -2.18566998 1.04916998 -2.1875 0 P 0 
L 1.04916998 -2.1875 1.0153 -2.1962 0 P 0 
L 1.0153 -2.1962 0.9814 -2.20333996 0 P 0 
L 0.9814 -2.20333996 0.94881998 -2.2087 0 P 0 
L 0.94881998 -2.2087 0.9189 -2.21198996 0 P 0 
L 0.9189 -2.21198996 0.90113996 -2.21278996 0 P 0 
L 0.90113996 -2.21278996 0.87738002 -2.21265 0 P 0 
L 0.87738002 -2.21265 0.854 -2.21183002 0 P 0 
L 0.854 -2.21183002 0.83788996 -2.21033996 0 P 0 
L 0.83788996 -2.21033996 0.8174 -2.20693002 0 P 0 
L 0.8174 -2.20693002 0.79708996 -2.2023 0 P 0 
L 0.79708996 -2.2023 0.7769 -2.19641004 0 P 0 
L 0.7769 -2.19641004 0.76433002 -2.19183996 0 P 0 
L 0.76433002 -2.19183996 0.75208996 -2.18638002 0 P 0 
L 0.75208996 -2.18638002 0.74026998 -2.18006998 0 P 0 
L 0.74026998 -2.18006998 0.72886998 -2.17291004 0 P 0 
L 0.72886998 -2.17291004 0.71961998 -2.16603002 0 P 0 
L 0.71961998 -2.16603002 0.71098996 -2.15838996 0 P 0 
L 0.71098996 -2.15838996 0.70303002 -2.15003002 0 P 0 
L 0.70303002 -2.15003002 0.6958 -2.14098996 0 P 0 
L 0.6958 -2.14098996 0.69106998 -2.1339 0 P 0 
L 0.69106998 -2.1339 0.68696004 -2.12643002 0 P 0 
L 0.68696004 -2.12643002 0.68351004 -2.11863002 0 P 0 
L 0.68351004 -2.11863002 0.68073996 -2.11056004 0 P 0 
L 0.68073996 -2.11056004 0.67866004 -2.10218996 0 P 0 
L 0.67866004 -2.10218996 0.67788002 -2.09741998 0 P 0 
L 0.67788002 -2.09741998 0.67746004 -2.0926 0 P 0 
L 0.67746004 -2.0926 0.67738002 -2.08076004 0 P 0 
L 0.67738002 -2.08076004 0.67828002 -2.06891004 0 P 0 
L 0.67828002 -2.06891004 0.67903002 -2.06403996 0 P 0 
L 0.67903002 -2.06403996 0.68013002 -2.05923996 0 P 0 
L 0.68013002 -2.05923996 0.68288002 -2.05021998 0 P 0 
L 0.68288002 -2.05021998 0.68623996 -2.04141004 0 P 0 
L 0.68623996 -2.04141004 0.69018002 -2.03286004 0 P 0 
L 0.69018002 -2.03286004 0.69486004 -2.02418002 0 P 0 
L 0.69486004 -2.02418002 0.70003996 -2.0158 0 P 0 
L 0.70003996 -2.0158 0.70573002 -2.00768996 0 P 0 
L 0.70573002 -2.00768996 0.7158 -1.99531998 0 P 0 
L 0.7158 -1.99531998 0.72681004 -1.98385 0 P 0 
L 0.72681004 -1.98385 0.73971004 -1.9722 0 P 0 
L 0.73971004 -1.9722 0.7533 -1.9614 0 P 0 
L 0.7533 -1.9614 0.75753996 -1.95828002 0 P 0 
L 0.75753996 -1.95828002 0.76138002 -1.95548002 0 P 0 
L 0.76138002 -1.95548002 0.76463002 -1.95316004 0 P 0 
L 0.76463002 -1.95316004 0.76516004 -1.95281004 0 P 0 
L 0.76516004 -1.95281004 0.7657 -1.95248996 0 P 0 
L 0.7657 -1.95248996 0.76578002 -1.95243996 0 P 0 
L 0.76578002 -1.95243996 0.76586004 -1.95238002 0 P 0 
L 0.76586004 -1.95238002 0.76593002 -1.95231998 0 P 0 
L 0.76593002 -1.95231998 0.766 -1.95223996 0 P 0 
L 0.766 -1.95223996 0.76606004 -1.95216998 0 P 0 
L 0.76606004 -1.95216998 0.76616004 -1.95201004 0 P 0 
L 0.76616004 -1.95201004 0.7662 -1.95191998 0 P 0 
L 0.7662 -1.95191998 0.76626004 -1.95173996 0 P 0 
L 0.76626004 -1.95173996 0.76628002 -1.95163996 0 P 0 
L 0.76628002 -1.95163996 0.7663 -1.95143002 0 P 0 
L 0.7663 -1.95143002 0.7663 -1.95121004 0 P 0 
L 0.7663 -1.95121004 0.76628996 -1.951 0 P 0 
L 0.76628996 -1.951 0.76625 -1.95078996 0 P 0 
L 0.76625 -1.95078996 0.7662 -1.95058002 0 P 0 
L 0.7662 -1.95058002 0.76613002 -1.95036998 0 P 0 
L 0.76613002 -1.95036998 0.76583002 -1.94966998 0 P 0 
L 0.76583002 -1.94966998 0.76548996 -1.94896998 0 P 0 
L 0.76548996 -1.94896998 0.76508996 -1.9483 0 P 0 
L 0.76508996 -1.9483 0.76253002 -1.94436004 0 P 0 
L 0.76253002 -1.94436004 0.76056998 -1.94126998 0 P 0 
L 0.76056998 -1.94126998 0.75871998 -1.93806004 0 P 0 
L 0.75871998 -1.93806004 0.75716998 -1.93496998 0 P 0 
L 0.75716998 -1.93496998 0.7558 -1.93178002 0 P 0 
L 0.7558 -1.93178002 0.7546 -1.92853996 0 P 0 
L 0.7546 -1.92853996 0.75358996 -1.92521004 0 P 0 
L 0.75358996 -1.92521004 0.7527 -1.92161998 0 P 0 
L 0.7527 -1.92161998 0.75196998 -1.91796004 0 P 0 
L 0.75196998 -1.91796004 0.75155 -1.91496004 0 P 0 
L 0.75155 -1.91496004 0.75133002 -1.91193002 0 P 0 
L 0.75133002 -1.91193002 0.75126998 -1.9085 0 P 0 
L 0.75126998 -1.9085 0.75136004 -1.90506004 0 P 0 
L 0.75136004 -1.90506004 0.75161004 -1.90181998 0 P 0 
L 0.75161004 -1.90181998 0.752 -1.8986 0 P 0 
L 0.752 -1.8986 0.75228996 -1.89701998 0 P 0 
L 0.75228996 -1.89701998 0.75268996 -1.89546998 0 P 0 
L 0.75268996 -1.89546998 0.7532 -1.89395 0 P 0 
L 0.7532 -1.89395 0.75358996 -1.89281998 0 P 0 
L 0.75358996 -1.89281998 0.75373002 -1.89231998 0 P 0 
L 0.75373002 -1.89231998 0.75383996 -1.8918 0 P 0 
L 0.75383996 -1.8918 0.75391998 -1.89138996 0 P 0 
L 0.75391998 -1.89138996 0.75396998 -1.89098996 0 P 0 
L 0.75396998 -1.89098996 0.75396998 -1.89086004 0 P 0 
L 0.75396998 -1.89086004 0.75393996 -1.89076998 0 P 0 
L 0.75393996 -1.89076998 0.7539 -1.89071004 0 P 0 
L 0.7539 -1.89071004 0.75386004 -1.89066998 0 P 0 
L 0.75386004 -1.89066998 0.75381004 -1.89063002 0 P 0 
L 0.75381004 -1.89063002 0.75378996 -1.89061004 0 P 0 
L 0.75378996 -1.89061004 0.75373002 -1.89058996 0 P 0 
L 0.75373002 -1.89058996 0.75368002 -1.89056998 0 P 0 
L 0.75368002 -1.89056998 0.75356004 -1.89056998 0 P 0 
L 0.75356004 -1.89056998 0.75346998 -1.8906 0 P 0 
L 0.75346998 -1.8906 0.74898002 -1.8927 0 P 0 
L 0.74898002 -1.8927 0.74383002 -1.89518002 0 P 0 
L 0.74383002 -1.89518002 0.73781004 -1.8982 0 P 0 
L 0.69776998 -2.22761998 0.96701004 -2.22761998 0 P 0 
L 0.6957 -2.22661998 0.96968996 -2.22661998 0 P 0 
L 0.69366998 -2.22561998 0.97238002 -2.22561998 0 P 0 
L 0.69163002 -2.22461998 0.97506004 -2.22461998 0 P 0 
L 0.68958996 -2.22361998 0.97775 -2.22361998 0 P 0 
L 0.68756004 -2.22261998 0.98043002 -2.22261998 0 P 0 
L 0.68551998 -2.22161998 0.98311004 -2.22161998 0 P 0 
L 0.68348996 -2.22061998 0.9858 -2.22061998 0 P 0 
L 0.68176998 -2.21961998 0.98848002 -2.21961998 0 P 0 
L 0.68003996 -2.21861998 0.99116998 -2.21861998 0 P 0 
L 0.67831004 -2.21761998 0.99385 -2.21761998 0 P 0 
L 0.67658002 -2.21661998 0.99653996 -2.21661998 0 P 0 
L 0.67485 -2.21561998 0.99908002 -2.21561998 0 P 0 
L 0.67311998 -2.21461998 0.87665 -2.21461998 0 P 0 
L 0.6714 -2.21361998 0.85166004 -2.21361998 0 P 0 
L 0.6699 -2.21261998 0.84083002 -2.21261998 0 P 0 
L 0.66845 -2.21161998 0.8334 -2.21161998 0 P 0 
L 0.66698996 -2.21061998 0.8274 -2.21061998 0 P 0 
L 0.66553002 -2.20961998 0.82138996 -2.20961998 0 P 0 
L 0.66406998 -2.20861998 0.81583002 -2.20861998 0 P 0 
L 0.66261998 -2.20761998 0.81143996 -2.20761998 0 P 0 
L 0.66116004 -2.20661998 0.80706004 -2.20661998 0 P 0 
L 0.6597 -2.20561998 0.80266998 -2.20561998 0 P 0 
L 0.65841004 -2.20461998 0.79828996 -2.20461998 0 P 0 
L 0.65716998 -2.20361998 0.79448996 -2.20361998 0 P 0 
L 0.65593002 -2.20261998 0.79106004 -2.20261998 0 P 0 
L 0.65468996 -2.20161998 0.78763996 -2.20161998 0 P 0 
L 0.83143002 -2.25261998 0.80871998 -2.25225 0 P 0 
L 0.80871998 -2.25225 0.78691998 -2.25066998 0 P 0 
L 0.78691998 -2.25066998 0.76525 -2.24786998 0 P 0 
L 0.76525 -2.24786998 0.74581998 -2.24403996 0 P 0 
L 0.74581998 -2.24403996 0.72671004 -2.23876004 0 P 0 
L 0.72671004 -2.23876004 0.71196004 -2.23356998 0 P 0 
L 0.71196004 -2.23356998 0.69756998 -2.22753996 0 P 0 
L 0.69756998 -2.22753996 0.68355 -2.22066004 0 P 0 
L 0.68355 -2.22066004 0.67118002 -2.2135 0 P 0 
L 0.67118002 -2.2135 0.65938996 -2.20541004 0 P 0 
L 0.65938996 -2.20541004 0.64825 -2.19643996 0 P 0 
L 0.64825 -2.19643996 0.63861998 -2.18731998 0 P 0 
L 0.63861998 -2.18731998 0.62983002 -2.17746998 0 P 0 
L 0.62983002 -2.17746998 0.62188996 -2.1669 0 P 0 
L 0.62188996 -2.1669 0.61678002 -2.15886998 0 P 0 
L 0.61678002 -2.15886998 0.6123 -2.15056004 0 P 0 
L 0.6123 -2.15056004 0.60841998 -2.14193996 0 P 0 
L 0.60841998 -2.14193996 0.60516998 -2.13306998 0 P 0 
L 0.60516998 -2.13306998 0.60191004 -2.12171004 0 P 0 
L 0.60191004 -2.12171004 0.60075 -2.11648002 0 P 0 
L 0.60075 -2.11648002 0.59983996 -2.11121004 0 P 0 
L 0.59983996 -2.11121004 0.59913996 -2.10576004 0 P 0 
L 0.59913996 -2.10576004 0.59868996 -2.10026004 0 P 0 
L 0.59868996 -2.10026004 0.59833002 -2.0875 0 P 0 
L 0.59833002 -2.0875 0.59856998 -2.07843996 0 P 0 
L 0.59856998 -2.07843996 0.59923996 -2.0695 0 P 0 
L 0.59923996 -2.0695 0.60031998 -2.06153996 0 P 0 
L 0.60031998 -2.06153996 0.60193002 -2.05368996 0 P 0 
L 0.60193002 -2.05368996 0.60416004 -2.04566004 0 P 0 
L 0.60416004 -2.04566004 0.60688996 -2.03786004 0 P 0 
L 0.60688996 -2.03786004 0.6148 -2.01961004 0 P 0 
L 0.6148 -2.01961004 0.62108996 -2.00753002 0 P 0 
L 0.62108996 -2.00753002 0.62811998 -1.99591998 0 P 0 
L 0.62811998 -1.99591998 0.63583996 -1.98478996 0 P 0 
L 0.63583996 -1.98478996 0.64936998 -1.96808002 0 P 0 
L 0.64936998 -1.96808002 0.66418002 -1.95256998 0 P 0 
L 0.66418002 -1.95256998 0.68098002 -1.93756004 0 P 0 
L 0.68098002 -1.93756004 0.69881998 -1.92398002 0 P 0 
L 0.69881998 -1.92398002 0.71841998 -1.91123996 0 P 0 
L 0.71841998 -1.91123996 0.73875 -1.89996998 0 P 0 
L 0.73875 -1.89996998 0.74471004 -1.89696998 0 P 0 
L 0.74471004 -1.89696998 0.74983002 -1.89451004 0 P 0 
L 0.74983002 -1.89451004 0.7511 -1.89391004 0 P 0 
L 0.7511 -1.89391004 0.75076998 -1.89488996 0 P 0 
L 0.75076998 -1.89488996 0.75033996 -1.89658996 0 P 0 
L 0.75033996 -1.89658996 0.75003002 -1.8983 0 P 0 
L 0.75003002 -1.8983 0.74961998 -1.90161998 0 P 0 
L 0.74961998 -1.90161998 0.74936004 -1.90496004 0 P 0 
L 0.74936004 -1.90496004 0.74926998 -1.9085 0 P 0 
L 0.74926998 -1.9085 0.74933002 -1.91201998 0 P 0 
L 0.74933002 -1.91201998 0.74956004 -1.91516998 0 P 0 
L 0.74956004 -1.91516998 0.75 -1.91828996 0 P 0 
L 0.75 -1.91828996 0.75075 -1.92205 0 P 0 
L 0.75075 -1.92205 0.75166004 -1.92573996 0 P 0 
L 0.75166004 -1.92573996 0.7527 -1.92916998 0 P 0 
L 0.7527 -1.92916998 0.75393996 -1.93253002 0 P 0 
L 0.75393996 -1.93253002 0.75536004 -1.93581998 0 P 0 
L 0.75536004 -1.93581998 0.75696004 -1.939 0 P 0 
L 0.75696004 -1.939 0.75885 -1.94231004 0 P 0 
L 0.75885 -1.94231004 0.76083996 -1.94543996 0 P 0 
L 0.76083996 -1.94543996 0.76338996 -1.94933996 0 P 0 
L 0.76338996 -1.94933996 0.76371998 -1.94991998 0 P 0 
L 0.76371998 -1.94991998 0.76401004 -1.9505 0 P 0 
L 0.76401004 -1.9505 0.76423996 -1.95103002 0 P 0 
L 0.76423996 -1.95103002 0.76408996 -1.95111004 0 P 0 
L 0.76408996 -1.95111004 0.76348996 -1.95151004 0 P 0 
L 0.76348996 -1.95151004 0.76021004 -1.95386004 0 P 0 
L 0.76021004 -1.95386004 0.7602 -1.95386998 0 P 0 
L 0.7602 -1.95386998 0.75636998 -1.95666004 0 P 0 
L 0.75636998 -1.95666004 0.75636004 -1.95666998 0 P 0 
L 0.75636004 -1.95666998 0.75635 -1.95666998 0 P 0 
L 0.75635 -1.95666998 0.75208996 -1.95981004 0 P 0 
L 0.75208996 -1.95981004 0.73841004 -1.97066998 0 P 0 
L 0.73841004 -1.97066998 0.72541004 -1.98241004 0 P 0 
L 0.72541004 -1.98241004 0.7143 -1.994 0 P 0 
L 0.7143 -1.994 0.71425 -1.99406004 0 P 0 
L 0.71425 -1.99406004 0.70413996 -2.00648002 0 P 0 
L 0.70413996 -2.00648002 0.69836998 -2.01468996 0 P 0 
L 0.69836998 -2.01468996 0.69313002 -2.02318002 0 P 0 
L 0.69313002 -2.02318002 0.68838996 -2.03196004 0 P 0 
L 0.68838996 -2.03196004 0.68438996 -2.04063996 0 P 0 
L 0.68438996 -2.04063996 0.68098996 -2.04958002 0 P 0 
L 0.68098996 -2.04958002 0.6782 -2.05873002 0 P 0 
L 0.6782 -2.05873002 0.67706004 -2.06366004 0 P 0 
L 0.67706004 -2.06366004 0.67628996 -2.06866998 0 P 0 
L 0.67628996 -2.06866998 0.67538002 -2.08068996 0 P 0 
L 0.67538002 -2.08068996 0.67546004 -2.09268996 0 P 0 
L 0.67546004 -2.09268996 0.67588996 -2.09766998 0 P 0 
L 0.67588996 -2.09766998 0.6767 -2.10258996 0 P 0 
L 0.6767 -2.10258996 0.67881998 -2.11111998 0 P 0 
L 0.67881998 -2.11111998 0.68163996 -2.11936004 0 P 0 
L 0.68163996 -2.11936004 0.68516004 -2.12731998 0 P 0 
L 0.68516004 -2.12731998 0.68935 -2.13493996 0 P 0 
L 0.68935 -2.13493996 0.69418002 -2.14216998 0 P 0 
L 0.69418002 -2.14216998 0.70153002 -2.15135 0 P 0 
L 0.70153002 -2.15135 0.7096 -2.15983002 0 P 0 
L 0.7096 -2.15983002 0.71836004 -2.16758996 0 P 0 
L 0.71836004 -2.16758996 0.71843002 -2.16763996 0 P 0 
L 0.71843002 -2.16763996 0.72773996 -2.17456004 0 P 0 
L 0.72773996 -2.17456004 0.73926998 -2.1818 0 P 0 
L 0.73926998 -2.1818 0.75121004 -2.18818002 0 P 0 
L 0.75121004 -2.18818002 0.75128002 -2.18821004 0 P 0 
L 0.75128002 -2.18821004 0.76358002 -2.19368996 0 P 0 
L 0.76358002 -2.19368996 0.77628002 -2.19831004 0 P 0 
L 0.77628002 -2.19831004 0.79658996 -2.20423996 0 P 0 
L 0.79658996 -2.20423996 0.81701004 -2.20888996 0 P 0 
L 0.81701004 -2.20888996 0.83763996 -2.21233002 0 P 0 
L 0.83763996 -2.21233002 0.85388002 -2.21383002 0 P 0 
L 0.85388002 -2.21383002 0.87733996 -2.21465 0 P 0 
L 0.87733996 -2.21465 0.90118002 -2.21478996 0 P 0 
L 0.90118002 -2.21478996 0.91906004 -2.21398996 0 P 0 
L 0.91906004 -2.21398996 0.94908996 -2.21068002 0 P 0 
L 0.94908996 -2.21068002 0.98176998 -2.2053 0 P 0 
L 0.98176998 -2.2053 1.01575 -2.19815 0 P 0 
L 1.01575 -2.19815 1.04968002 -2.18943002 0 P 0 
L 1.04968002 -2.18943002 1.05633996 -2.18761004 0 P 0 
L 1.05633996 -2.18761004 1.05713996 -2.1874 0 P 0 
L 1.05713996 -2.1874 1.05483002 -2.18875 0 P 0 
L 1.05483002 -2.18875 1.04298996 -2.19526004 0 P 0 
L 1.04298996 -2.19526004 1.03096998 -2.20136998 0 P 0 
L 1.03096998 -2.20136998 0.99835 -2.21595 0 P 0 
L 0.99835 -2.21595 0.96401998 -2.22873996 0 P 0 
L 0.96401998 -2.22873996 0.92993996 -2.23908002 0 P 0 
L 0.92993996 -2.23908002 0.89816004 -2.24626004 0 P 0 
L 0.89816004 -2.24626004 0.87616004 -2.24965 0 P 0 
L 0.87616004 -2.24965 0.85405 -2.25176004 0 P 0 
L 0.85405 -2.25176004 0.83143002 -2.25261998 0 P 0 
L 0.65345 -2.20061998 0.78421004 -2.20061998 0 P 0 
L 0.65221004 -2.19961998 0.78078002 -2.19961998 0 P 0 
L 0.65096004 -2.19861998 0.77735 -2.19861998 0 P 0 
L 0.64971998 -2.19761998 0.77438996 -2.19761998 0 P 0 
L 0.64848002 -2.19661998 0.77163996 -2.19661998 0 P 0 
L 0.64738996 -2.19561998 0.76888996 -2.19561998 0 P 0 
L 0.64633996 -2.19461998 0.76613996 -2.19461998 0 P 0 
L 0.64528002 -2.19361998 0.76343002 -2.19361998 0 P 0 
L 0.64421998 -2.19261998 0.76118996 -2.19261998 0 P 0 
L 0.64316998 -2.19161998 0.75893996 -2.19161998 0 P 0 
L 0.64211004 -2.19061998 0.7567 -2.19061998 0 P 0 
L 0.64106004 -2.18961998 0.75446004 -2.18961998 0 P 0 
L 0.64 -2.18861998 0.75221004 -2.18861998 0 P 0 
L 0.63895 -2.18761998 0.75018002 -2.18761998 0 P 0 
L 0.63801004 -2.18661998 0.74831004 -2.18661998 0 P 0 
L 0.63711004 -2.18561998 0.74643002 -2.18561998 0 P 0 
L 0.63621998 -2.18461998 0.74456004 -2.18461998 0 P 0 
L 0.63533002 -2.18361998 0.74268002 -2.18361998 0 P 0 
L 0.63443996 -2.18261998 0.74081004 -2.18261998 0 P 0 
L 0.63353996 -2.18161998 0.73898996 -2.18161998 0 P 0 
L 0.63265 -2.18061998 0.73738996 -2.18061998 0 P 0 
L 0.63176004 -2.17961998 0.7358 -2.17961998 0 P 0 
L 0.63086998 -2.17861998 0.73421004 -2.17861998 0 P 0 
L 0.62996998 -2.17761998 0.73261998 -2.17761998 0 P 0 
L 0.6292 -2.17661998 0.73103002 -2.17661998 0 P 0 
L 0.62845 -2.17561998 0.72943996 -2.17561998 0 P 0 
L 0.6277 -2.17461998 0.72783996 -2.17461998 0 P 0 
L 0.62693996 -2.17361998 0.72648002 -2.17361998 0 P 0 
L 0.62618996 -2.17261998 0.72513996 -2.17261998 0 P 0 
L 0.62543996 -2.17161998 0.72378996 -2.17161998 0 P 0 
L 0.62468996 -2.17061998 0.72245 -2.17061998 0 P 0 
L 0.62393996 -2.16961998 0.7211 -2.16961998 0 P 0 
L 0.62318002 -2.16861998 0.71976004 -2.16861998 0 P 0 
L 0.62243996 -2.16761998 0.71841004 -2.16761998 0 P 0 
L 0.62171004 -2.16661998 0.71726998 -2.16661998 0 P 0 
L 0.62108002 -2.16561998 0.71613996 -2.16561998 0 P 0 
L 0.62043996 -2.16461998 0.71501004 -2.16461998 0 P 0 
L 0.61981004 -2.16361998 0.71388002 -2.16361998 0 P 0 
L 0.61916998 -2.16261998 0.71276004 -2.16261998 0 P 0 
L 0.61853002 -2.16161998 0.71163002 -2.16161998 0 P 0 
L 0.6179 -2.16061998 0.7105 -2.16061998 0 P 0 
L 0.61726004 -2.15961998 0.7094 -2.15961998 0 P 0 
L 0.61665 -2.15861998 0.70845 -2.15861998 0 P 0 
L 0.61611004 -2.15761998 0.7075 -2.15761998 0 P 0 
L 0.75383996 -2.24561998 0.901 -2.24561998 0 P 0 
L 0.74876998 -2.24461998 0.90541998 -2.24461998 0 P 0 
L 0.74431004 -2.24361998 0.90985 -2.24361998 0 P 0 
L 0.7407 -2.24261998 0.91426998 -2.24261998 0 P 0 
L 0.73708002 -2.24161998 0.9187 -2.24161998 0 P 0 
L 0.73346998 -2.24061998 0.92311998 -2.24061998 0 P 0 
L 0.72986004 -2.23961998 0.92753996 -2.23961998 0 P 0 
L 0.72633996 -2.23861998 0.93145 -2.23861998 0 P 0 
L 0.72348996 -2.23761998 0.93473996 -2.23761998 0 P 0 
L 0.72063996 -2.23661998 0.93803996 -2.23661998 0 P 0 
L 0.7178 -2.23561998 0.94133002 -2.23561998 0 P 0 
L 0.71495 -2.23461998 0.94461998 -2.23461998 0 P 0 
L 0.7121 -2.23361998 0.94791998 -2.23361998 0 P 0 
L 0.70968996 -2.23261998 0.95121004 -2.23261998 0 P 0 
L 0.70731004 -2.23161998 0.95451004 -2.23161998 0 P 0 
L 0.70491998 -2.23061998 0.9578 -2.23061998 0 P 0 
L 0.70253996 -2.22961998 0.9611 -2.22961998 0 P 0 
L 0.70015 -2.22861998 0.96431998 -2.22861998 0 P 0 
P 7.17716998 5.7874 21 P 0 0;3=41
P 7.17716998 0.23621998 21 P 0 0;3=41
P 0.22245 0.68898002 20 P 0 0;3=42
P 0.22245 5.11811004 20 P 0 0;3=42
P 12.68701998 5.15748002 20 P 0 0;3=42
P 12.68701998 0.72835 20 P 0 0;3=42
P 6.11811004 1.52756004 20 P 0 0;3=42
P 6.11811004 4.20473002 20 P 0 0;3=42
P 4.83268002 4.22441004 20 P 0 0;3=42
P 2.24606004 4.22441004 20 P 0 0;3=42
P 0.96063002 4.20473002 20 P 0 0;3=42
P 0.96063002 1.52756004 20 P 0 0;3=42
P 2.24606004 1.50786998 20 P 0 0;3=42
P 4.83268002 1.50786998 20 P 0 0;3=42
P 6.04921004 2.58268002 19 P 0 0;3=43
P 1.05905 2.58268002 31 P 0 0;3=44
P 12.12205 1.52756004 20 P 0 0;3=42
P 12.12205 4.20473002 20 P 0 0;3=42
P 10.83661998 4.22441004 20 P 0 0;3=42
P 8.25 4.22441004 20 P 0 0;3=42
P 6.96456998 4.20473002 20 P 0 0;3=42
P 6.96456998 1.52756004 20 P 0 0;3=42
P 8.25 1.50786998 20 P 0 0;3=42
P 10.83661998 1.50786998 20 P 0 0;3=42
P 12.05315 2.58268002 19 P 0 0;3=43
P 7.06298996 2.58268002 31 P 0 0;3=44
P 12.33465 5.69528002 16 P 0 0;3=45
P 3.58311004 4.91851004 11 P 0 0;3=46
P 2.72091004 4.91851004 11 P 0 0;3=46
P 9.58665 4.91851004 11 P 0 0;3=46
P 8.72445 4.91851004 11 P 0 0;3=46
P 2.41851004 4.91851004 11 P 0 0;3=46
P 1.55631004 4.91851004 11 P 0 0;3=46
P 8.42205 4.91851004 11 P 0 0;3=46
P 7.55985 4.91851004 11 P 0 0;3=46
P 6.60051998 4.9574 26 P 0 0;1,3=47
P 6.64186004 4.9574 26 P 0 0;1,3=47
P 6.60051998 4.8767 26 P 0 0;1,3=47
P 6.64186004 4.8767 26 P 0 0;1,3=47
P 6.60051998 4.91705 44 P 0 0;1,3=48
P 6.64186004 4.91705 44 P 0 0;1,3=48
P 0.22243996 1.79331004 14 P 0 0;3=49
P 0.22243996 4.67323002 14 P 0 0;3=49
P 12.687 1.83268002 14 P 0 0;3=49
P 12.687 4.7126 14 P 0 0;3=49
P 0.7687 5.62008002 10 P 0 0;3=50
P 1.47736004 5.62008002 10 P 0 0;3=50
L 0.0349 -2.3038 0.0349 -1.0038 5 P 0 
L 0.0349 -1.0038 4.5349 -1.0038 5 P 0 
L 4.5349 -1.0038 4.5349 -2.3038 5 P 0 
L 4.5349 -2.3038 0.0349 -2.3038 5 P 0 
L 0.0349 -1.6038 4.5349 -1.6038 5 P 0 
L 0.0349 -1.8038 4.5349 -1.8038 5 P 0 
L 2.4349 -2.1038 4.0349 -2.1038 5 P 0 
L 2.4349 -2.3038 2.4349 -1.8038 5 P 0 
L 3.2349 -2.1038 3.2349 -1.8038 5 P 0 
L 4.0349 -2.3038 4.0349 -1.8038 5 P 0 
L 0.0723999 -1.6844687 0.07906663 -1.69030079 2 P 0 ;0,4=51,6=0.000000
L 0.07906663 -1.69030079 0.08656654 -1.6938 2 P 0 ;0,4=51,6=0.000000
L 0.08656654 -1.6938 0.09323337 -1.6938 2 P 0 ;0,4=51,6=0.000000
L 0.09323337 -1.6938 0.0999001 -1.69030079 2 P 0 ;0,4=51,6=0.000000
L 0.0999001 -1.69030079 0.10490059 -1.6844687 2 P 0 ;0,4=51,6=0.000000
L 0.10490059 -1.6844687 0.1074 -1.67629951 2 P 0 ;0,4=51,6=0.000000
L 0.1074 -1.67629951 0.10573376 -1.66813455 2 P 0 ;0,4=51,6=0.000000
L 0.10573376 -1.66813455 0.10156644 -1.66113396 2 P 0 ;0,4=51,6=0.000000
L 0.10156644 -1.66113396 0.09406654 -1.65646614 2 P 0 ;0,4=51,6=0.000000
L 0.09406654 -1.65646614 0.08406713 -1.65413327 2 P 0 ;0,4=51,6=0.000000
L 0.08406713 -1.65413327 0.07823346 -1.64946762 2 P 0 ;0,4=51,6=0.000000
L 0.07823346 -1.64946762 0.07573248 -1.64130059 2 P 0 ;0,4=51,6=0.000000
L 0.07573248 -1.64130059 0.0774003 -1.63313356 2 P 0 ;0,4=51,6=0.000000
L 0.0774003 -1.63313356 0.08156614 -1.62730148 2 P 0 ;0,4=51,6=0.000000
L 0.08156614 -1.62730148 0.0873997 -1.6238 2 P 0 ;0,4=51,6=0.000000
L 0.0873997 -1.6238 0.09323337 -1.6238 2 P 0 ;0,4=51,6=0.000000
L 0.09323337 -1.6238 0.09906693 -1.62613287 2 P 0 ;0,4=51,6=0.000000
L 0.09906693 -1.62613287 0.10406742 -1.63196713 2 P 0 ;0,4=51,6=0.000000
L 0.1383999 -1.6938 0.1383999 -1.6238 2 P 0 ;0,4=51,6=0.000000
L 0.1734 -1.6238 0.1734 -1.6938 2 P 0 ;0,4=51,6=0.000000
L 0.1734 -1.65880108 0.1383999 -1.65880108 2 P 0 ;0,4=51,6=0.000000
L 0.23856683 -1.6938 0.20523307 -1.6938 2 P 0 ;0,4=51,6=0.000000
L 0.20523307 -1.6938 0.20523307 -1.6238 2 P 0 ;0,4=51,6=0.000000
L 0.20523307 -1.6238 0.23856683 -1.6238 2 P 0 ;0,4=51,6=0.000000
L 0.22523337 -1.65763258 0.20523307 -1.65763258 2 P 0 ;0,4=51,6=0.000000
L 0.30456683 -1.6938 0.27123307 -1.6938 2 P 0 ;0,4=51,6=0.000000
L 0.27123307 -1.6938 0.27123307 -1.6238 2 P 0 ;0,4=51,6=0.000000
L 0.27123307 -1.6238 0.30456683 -1.6238 2 P 0 ;0,4=51,6=0.000000
L 0.29123337 -1.65763258 0.27123307 -1.65763258 2 P 0 ;0,4=51,6=0.000000
L 0.35389921 -1.6238 0.35389921 -1.6938 2 P 0 ;0,4=51,6=0.000000
L 0.33473356 -1.6238 0.37306634 -1.6238 2 P 0 ;0,4=51,6=0.000000
L 0.09489921 -1.7188 0.09489921 -1.7888 2 P 0 ;0,4=52,6=0.000000
L 0.07573356 -1.7188 0.11406634 -1.7188 2 P 0 ;0,4=52,6=0.000000
L 0.1508998 -1.7188 0.17089862 -1.7188 2 P 0 ;0,4=52,6=0.000000
L 0.16089921 -1.7188 0.16089921 -1.7888 2 P 0 ;0,4=52,6=0.000000
L 0.1508998 -1.7888 0.17089862 -1.7888 2 P 0 ;0,4=52,6=0.000000
L 0.22689921 -1.7188 0.22689921 -1.7888 2 P 0 ;0,4=52,6=0.000000
L 0.20773356 -1.7188 0.24606634 -1.7188 2 P 0 ;0,4=52,6=0.000000
L 0.27623307 -1.7188 0.27623307 -1.7888 2 P 0 ;0,4=52,6=0.000000
L 0.27623307 -1.7888 0.30956683 -1.7888 2 P 0 ;0,4=52,6=0.000000
L 0.37556683 -1.7888 0.34223307 -1.7888 2 P 0 ;0,4=52,6=0.000000
L 0.34223307 -1.7888 0.34223307 -1.7188 2 P 0 ;0,4=52,6=0.000000
L 0.34223307 -1.7188 0.37556683 -1.7188 2 P 0 ;0,4=52,6=0.000000
L 0.36223337 -1.75263258 0.34223307 -1.75263258 2 P 0 ;0,4=52,6=0.000000
L 2.5438999 -1.96813563 2.5519 -1.97480089 2 P 0 ;0,4=53,6=0.000000
L 2.5519 -1.97480089 2.5608999 -1.9788 2 P 0 ;0,4=53,6=0.000000
L 2.5608999 -1.9788 2.5689 -1.9788 2 P 0 ;0,4=53,6=0.000000
L 2.5689 -1.9788 2.5769001 -1.97480089 2 P 0 ;0,4=53,6=0.000000
L 2.5769001 -1.97480089 2.58290069 -1.96813563 2 P 0 ;0,4=53,6=0.000000
L 2.58290069 -1.96813563 2.5859 -1.95879941 2 P 0 ;0,4=53,6=0.000000
L 2.5859 -1.95879941 2.58390049 -1.94946811 2 P 0 ;0,4=53,6=0.000000
L 2.58390049 -1.94946811 2.5788997 -1.94146732 2 P 0 ;0,4=53,6=0.000000
L 2.5788997 -1.94146732 2.5698998 -1.93613278 2 P 0 ;0,4=53,6=0.000000
L 2.5698998 -1.93613278 2.55790049 -1.93346663 2 P 0 ;0,4=53,6=0.000000
L 2.55790049 -1.93346663 2.5509002 -1.92813445 2 P 0 ;0,4=53,6=0.000000
L 2.5509002 -1.92813445 2.54789902 -1.91880069 2 P 0 ;0,4=53,6=0.000000
L 2.54789902 -1.91880069 2.54990039 -1.90946683 2 P 0 ;0,4=53,6=0.000000
L 2.54990039 -1.90946683 2.55489931 -1.90280167 2 P 0 ;0,4=53,6=0.000000
L 2.55489931 -1.90280167 2.5618997 -1.8988 2 P 0 ;0,4=53,6=0.000000
L 2.5618997 -1.8988 2.5689 -1.8988 2 P 0 ;0,4=53,6=0.000000
L 2.5689 -1.8988 2.57590039 -1.90146614 2 P 0 ;0,4=53,6=0.000000
L 2.57590039 -1.90146614 2.58190089 -1.90813386 2 P 0 ;0,4=53,6=0.000000
L 2.6648998 -1.90546772 2.65889931 -1.90146614 2 P 0 ;0,4=53,6=0.000000
L 2.65889931 -1.90146614 2.65190079 -1.8988 2 P 0 ;0,4=53,6=0.000000
L 2.65190079 -1.8988 2.64390069 -1.8988 2 P 0 ;0,4=53,6=0.000000
L 2.64390069 -1.8988 2.63489892 -1.90280167 2 P 0 ;0,4=53,6=0.000000
L 2.63489892 -1.90280167 2.62790039 -1.90946683 2 P 0 ;0,4=53,6=0.000000
L 2.62790039 -1.90946683 2.62289961 -1.91746762 2 P 0 ;0,4=53,6=0.000000
L 2.62289961 -1.91746762 2.61889862 -1.93080049 2 P 0 ;0,4=53,6=0.000000
L 2.61889862 -1.93080049 2.61789892 -1.94280039 2 P 0 ;0,4=53,6=0.000000
L 2.61789892 -1.94280039 2.6199003 -1.9548003 2 P 0 ;0,4=53,6=0.000000
L 2.6199003 -1.9548003 2.62289961 -1.96280098 2 P 0 ;0,4=53,6=0.000000
L 2.62289961 -1.96280098 2.6289002 -1.97080177 2 P 0 ;0,4=53,6=0.000000
L 2.6289002 -1.97080177 2.63590049 -1.97613396 2 P 0 ;0,4=53,6=0.000000
L 2.63590049 -1.97613396 2.64289902 -1.9788 2 P 0 ;0,4=53,6=0.000000
L 2.64289902 -1.9788 2.64989941 -1.9788 2 P 0 ;0,4=53,6=0.000000
L 2.64989941 -1.9788 2.6568997 -1.97613396 2 P 0 ;0,4=53,6=0.000000
L 2.6568997 -1.97613396 2.6629003 -1.97213484 2 P 0 ;0,4=53,6=0.000000
L 2.6629003 -1.97213484 2.66790098 -1.96680266 2 P 0 ;0,4=53,6=0.000000
L 2.69589892 -1.9788 2.72089902 -1.8988 2 P 0 ;0,4=53,6=0.000000
L 2.72089902 -1.8988 2.74590098 -1.9788 2 P 0 ;0,4=53,6=0.000000
L 2.73689931 -1.95080118 2.70489882 -1.95080118 2 P 0 ;0,4=53,6=0.000000
L 2.77889961 -1.8988 2.77889961 -1.9788 2 P 0 ;0,4=53,6=0.000000
L 2.77889961 -1.9788 2.8189003 -1.9788 2 P 0 ;0,4=53,6=0.000000
L 2.8969003 -1.9788 2.85689961 -1.9788 2 P 0 ;0,4=53,6=0.000000
L 2.85689961 -1.9788 2.85689961 -1.8988 2 P 0 ;0,4=53,6=0.000000
L 2.85689961 -1.8988 2.8969003 -1.8988 2 P 0 ;0,4=53,6=0.000000
L 2.8809 -1.93746575 2.85689961 -1.93746575 2 P 0 ;0,4=53,6=0.000000
L 3.03289902 -1.9788 3.03289902 -1.8988 2 P 0 ;0,4=53,6=0.000000
L 3.03289902 -1.8988 3.0208998 -1.91479911 2 P 0 ;0,4=53,6=0.000000
L 3.0208998 -1.9788 3.04489833 -1.9788 2 P 0 ;0,4=53,6=0.000000
L 3.11089902 -1.98146604 3.10889951 -1.98013297 2 P 0 ;0,4=53,6=0.000000
L 3.10889951 -1.98013297 3.10889951 -1.97746703 2 P 0 ;0,4=53,6=0.000000
L 3.10889951 -1.97746703 3.11089902 -1.97613396 2 P 0 ;0,4=53,6=0.000000
L 3.11089902 -1.97613396 3.11290039 -1.97746703 2 P 0 ;0,4=53,6=0.000000
L 3.11290039 -1.97746703 3.11290039 -1.98013297 2 P 0 ;0,4=53,6=0.000000
L 3.11290039 -1.98013297 3.11089902 -1.98146604 2 P 0 ;0,4=53,6=0.000000
L 3.11089902 -1.945469 3.10889951 -1.94413346 2 P 0 ;0,4=53,6=0.000000
L 3.10889951 -1.94413346 3.10889951 -1.94146732 2 P 0 ;0,4=53,6=0.000000
L 3.10889951 -1.94146732 3.11089902 -1.94013435 2 P 0 ;0,4=53,6=0.000000
L 3.11089902 -1.94013435 3.11290039 -1.94146732 2 P 0 ;0,4=53,6=0.000000
L 3.11290039 -1.94146732 3.11290039 -1.94413346 2 P 0 ;0,4=53,6=0.000000
L 3.11290039 -1.94413346 3.11089902 -1.945469 2 P 0 ;0,4=53,6=0.000000
L 3.18889902 -1.9788 3.18889902 -1.8988 2 P 0 ;0,4=53,6=0.000000
L 3.18889902 -1.8988 3.1768998 -1.91479911 2 P 0 ;0,4=53,6=0.000000
L 3.1768998 -1.9788 3.20089833 -1.9788 2 P 0 ;0,4=53,6=0.000000
L 2.5138999 -2.23313563 2.5219 -2.23980089 2 P 0 ;0,4=51,6=0.000000
L 2.5219 -2.23980089 2.5308999 -2.2438 2 P 0 ;0,4=51,6=0.000000
L 2.5308999 -2.2438 2.5389 -2.2438 2 P 0 ;0,4=51,6=0.000000
L 2.5389 -2.2438 2.5469001 -2.23980089 2 P 0 ;0,4=51,6=0.000000
L 2.5469001 -2.23980089 2.55290069 -2.23313563 2 P 0 ;0,4=51,6=0.000000
L 2.55290069 -2.23313563 2.5559 -2.22379941 2 P 0 ;0,4=51,6=0.000000
L 2.5559 -2.22379941 2.55390049 -2.21446811 2 P 0 ;0,4=51,6=0.000000
L 2.55390049 -2.21446811 2.5488997 -2.20646732 2 P 0 ;0,4=51,6=0.000000
L 2.5488997 -2.20646732 2.5398998 -2.20113278 2 P 0 ;0,4=51,6=0.000000
L 2.5398998 -2.20113278 2.52790049 -2.19846663 2 P 0 ;0,4=51,6=0.000000
L 2.52790049 -2.19846663 2.5209002 -2.19313445 2 P 0 ;0,4=51,6=0.000000
L 2.5209002 -2.19313445 2.51789902 -2.18380069 2 P 0 ;0,4=51,6=0.000000
L 2.51789902 -2.18380069 2.51990039 -2.17446683 2 P 0 ;0,4=51,6=0.000000
L 2.51990039 -2.17446683 2.52489931 -2.16780167 2 P 0 ;0,4=51,6=0.000000
L 2.52489931 -2.16780167 2.5318997 -2.1638 2 P 0 ;0,4=51,6=0.000000
L 2.5318997 -2.1638 2.5389 -2.1638 2 P 0 ;0,4=51,6=0.000000
L 2.5389 -2.1638 2.54590039 -2.16646614 2 P 0 ;0,4=51,6=0.000000
L 2.54590039 -2.16646614 2.55190089 -2.17313386 2 P 0 ;0,4=51,6=0.000000
L 2.5918999 -2.2438 2.5918999 -2.1638 2 P 0 ;0,4=51,6=0.000000
L 2.6339 -2.1638 2.6339 -2.2438 2 P 0 ;0,4=51,6=0.000000
L 2.6339 -2.20380128 2.5918999 -2.20380128 2 P 0 ;0,4=51,6=0.000000
L 2.7109003 -2.2438 2.67089961 -2.2438 2 P 0 ;0,4=51,6=0.000000
L 2.67089961 -2.2438 2.67089961 -2.1638 2 P 0 ;0,4=51,6=0.000000
L 2.67089961 -2.1638 2.7109003 -2.1638 2 P 0 ;0,4=51,6=0.000000
L 2.6949 -2.20246575 2.67089961 -2.20246575 2 P 0 ;0,4=51,6=0.000000
L 2.7889003 -2.2438 2.74889961 -2.2438 2 P 0 ;0,4=51,6=0.000000
L 2.74889961 -2.2438 2.74889961 -2.1638 2 P 0 ;0,4=51,6=0.000000
L 2.74889961 -2.1638 2.7889003 -2.1638 2 P 0 ;0,4=51,6=0.000000
L 2.7729 -2.20246575 2.74889961 -2.20246575 2 P 0 ;0,4=51,6=0.000000
L 2.84689902 -2.1638 2.84689902 -2.2438 2 P 0 ;0,4=51,6=0.000000
L 2.8239003 -2.1638 2.86989961 -2.1638 2 P 0 ;0,4=51,6=0.000000
L 3.29489961 -1.9238 3.29489961 -2.0038 2 P 0 ;0,4=54,6=0.000000
L 3.29489961 -2.0038 3.3349003 -2.0038 2 P 0 ;0,4=54,6=0.000000
L 3.36789892 -2.0038 3.39289902 -1.9238 2 P 0 ;0,4=54,6=0.000000
L 3.39289902 -1.9238 3.41790098 -2.0038 2 P 0 ;0,4=54,6=0.000000
L 3.40889931 -1.97580118 3.37689882 -1.97580118 2 P 0 ;0,4=54,6=0.000000
L 3.47089902 -2.0038 3.47089902 -1.96780039 2 P 0 ;0,4=54,6=0.000000
L 3.47089902 -1.96780039 3.45089961 -1.9238 2 P 0 ;0,4=54,6=0.000000
L 3.4909003 -1.9238 3.47089902 -1.96780039 2 P 0 ;0,4=54,6=0.000000
L 3.5689003 -2.0038 3.52889961 -2.0038 2 P 0 ;0,4=54,6=0.000000
L 3.52889961 -2.0038 3.52889961 -1.9238 2 P 0 ;0,4=54,6=0.000000
L 3.52889961 -1.9238 3.5689003 -1.9238 2 P 0 ;0,4=54,6=0.000000
L 3.5529 -1.96246575 3.52889961 -1.96246575 2 P 0 ;0,4=54,6=0.000000
L 3.60689961 -2.0038 3.60689961 -1.9238 2 P 0 ;0,4=54,6=0.000000
L 3.60689961 -1.9238 3.6318998 -1.9238 2 P 0 ;0,4=54,6=0.000000
L 3.6318998 -1.9238 3.6398999 -1.92780167 2 P 0 ;0,4=54,6=0.000000
L 3.6398999 -1.92780167 3.64490069 -1.93313386 2 P 0 ;0,4=54,6=0.000000
L 3.64490069 -1.93313386 3.6469003 -1.94380069 2 P 0 ;0,4=54,6=0.000000
L 3.6469003 -1.94380069 3.64490069 -1.95446752 2 P 0 ;0,4=54,6=0.000000
L 3.64490069 -1.95446752 3.6389001 -1.96113278 2 P 0 ;0,4=54,6=0.000000
L 3.6389001 -1.96113278 3.6318998 -1.96513435 2 P 0 ;0,4=54,6=0.000000
L 3.6318998 -1.96513435 3.60689961 -1.96513435 2 P 0 ;0,4=54,6=0.000000
L 3.6318998 -1.96513435 3.6469003 -2.0038 2 P 0 ;0,4=54,6=0.000000
L 3.33989902 -2.2538 3.33189892 -2.25246703 2 P 0 ;0,4=55,6=0.000000
L 3.33189892 -2.25246703 3.32490039 -2.24713484 2 P 0 ;0,4=55,6=0.000000
L 3.32490039 -2.24713484 3.3188999 -2.23913406 2 P 0 ;0,4=55,6=0.000000
L 3.3188999 -2.23913406 3.31489892 -2.2298003 2 P 0 ;0,4=55,6=0.000000
L 3.31489892 -2.2298003 3.31289931 -2.21913346 2 P 0 ;0,4=55,6=0.000000
L 3.31289931 -2.21913346 3.31289931 -2.20846663 2 P 0 ;0,4=55,6=0.000000
L 3.31289931 -2.20846663 3.31489892 -2.1977998 2 P 0 ;0,4=55,6=0.000000
L 3.31489892 -2.1977998 3.3188999 -2.18846604 2 P 0 ;0,4=55,6=0.000000
L 3.3188999 -2.18846604 3.32490039 -2.18046772 2 P 0 ;0,4=55,6=0.000000
L 3.32490039 -2.18046772 3.33189892 -2.17513307 2 P 0 ;0,4=55,6=0.000000
L 3.33189892 -2.17513307 3.33989902 -2.1738 2 P 0 ;0,4=55,6=0.000000
L 3.33989902 -2.1738 3.34789911 -2.17513307 2 P 0 ;0,4=55,6=0.000000
L 3.34789911 -2.17513307 3.35489951 -2.18046772 2 P 0 ;0,4=55,6=0.000000
L 3.35489951 -2.18046772 3.3609 -2.18846604 2 P 0 ;0,4=55,6=0.000000
L 3.3609 -2.18846604 3.36490098 -2.1977998 2 P 0 ;0,4=55,6=0.000000
L 3.36490098 -2.1977998 3.36690059 -2.20846663 2 P 0 ;0,4=55,6=0.000000
L 3.36690059 -2.20846663 3.36690059 -2.21913346 2 P 0 ;0,4=55,6=0.000000
L 3.36690059 -2.21913346 3.36490098 -2.2298003 2 P 0 ;0,4=55,6=0.000000
L 3.36490098 -2.2298003 3.3609 -2.23913406 2 P 0 ;0,4=55,6=0.000000
L 3.3609 -2.23913406 3.35489951 -2.24713484 2 P 0 ;0,4=55,6=0.000000
L 3.35489951 -2.24713484 3.34789911 -2.25246703 2 P 0 ;0,4=55,6=0.000000
L 3.34789911 -2.25246703 3.33989902 -2.2538 2 P 0 ;0,4=55,6=0.000000
L 3.39889941 -2.2538 3.39889941 -2.1738 2 P 0 ;0,4=55,6=0.000000
L 3.39889941 -2.1738 3.43690049 -2.1738 2 P 0 ;0,4=55,6=0.000000
L 3.4228998 -2.21246575 3.39889941 -2.21246575 2 P 0 ;0,4=55,6=0.000000
L 0.16489872 -1.0538 0.16489872 -1.1538 2 P 0 ;0,4=52,6=0.000000
L 0.13423376 -1.0538 0.19556614 -1.0538 2 P 0 ;0,4=52,6=0.000000
L 0.2588997 -1.0538 0.29089774 -1.0538 2 P 0 ;0,4=52,6=0.000000
L 0.27489872 -1.0538 0.27489872 -1.1538 2 P 0 ;0,4=52,6=0.000000
L 0.2588997 -1.1538 0.29089774 -1.1538 2 P 0 ;0,4=52,6=0.000000
L 0.38489872 -1.0538 0.38489872 -1.1538 2 P 0 ;0,4=52,6=0.000000
L 0.35423376 -1.0538 0.41556614 -1.0538 2 P 0 ;0,4=52,6=0.000000
L 0.46823287 -1.0538 0.46823287 -1.1538 2 P 0 ;0,4=52,6=0.000000
L 0.46823287 -1.1538 0.52156703 -1.1538 2 P 0 ;0,4=52,6=0.000000
L 0.63156703 -1.1538 0.57823287 -1.1538 2 P 0 ;0,4=52,6=0.000000
L 0.57823287 -1.1538 0.57823287 -1.0538 2 P 0 ;0,4=52,6=0.000000
L 0.57823287 -1.0538 0.63156703 -1.0538 2 P 0 ;0,4=52,6=0.000000
L 0.61023337 -1.10213219 0.57823287 -1.10213219 2 P 0 ;0,4=52,6=0.000000
L 4.18989892 -1.9538 4.21489902 -1.8738 2 P 0 ;0,4=56,6=0.000000
L 4.21489902 -1.8738 4.23990098 -1.9538 2 P 0 ;0,4=56,6=0.000000
L 4.23089931 -1.92580118 4.19889882 -1.92580118 2 P 0 ;0,4=56,6=0.000000
L 4.27289961 -1.9538 4.27289961 -1.8738 2 P 0 ;0,4=56,6=0.000000
L 4.27289961 -1.8738 4.2978998 -1.8738 2 P 0 ;0,4=56,6=0.000000
L 4.2978998 -1.8738 4.3058999 -1.87780167 2 P 0 ;0,4=56,6=0.000000
L 4.3058999 -1.87780167 4.31090069 -1.88313386 2 P 0 ;0,4=56,6=0.000000
L 4.31090069 -1.88313386 4.3129003 -1.89380069 2 P 0 ;0,4=56,6=0.000000
L 4.3129003 -1.89380069 4.31090069 -1.90446752 2 P 0 ;0,4=56,6=0.000000
L 4.31090069 -1.90446752 4.3049001 -1.91113278 2 P 0 ;0,4=56,6=0.000000
L 4.3049001 -1.91113278 4.2978998 -1.91513435 2 P 0 ;0,4=56,6=0.000000
L 4.2978998 -1.91513435 4.27289961 -1.91513435 2 P 0 ;0,4=56,6=0.000000
L 4.2978998 -1.91513435 4.3129003 -1.9538 2 P 0 ;0,4=56,6=0.000000
L 4.37089902 -1.8738 4.37089902 -1.9538 2 P 0 ;0,4=56,6=0.000000
L 4.3479003 -1.8738 4.39389961 -1.8738 2 P 0 ;0,4=56,6=0.000000
L 3.72973337 -1.97380098 3.76006654 -1.97380098 2 P 0 ;0,4=57,6=0.000000
L 3.06989892 -2.2538 3.06989892 -2.1638 2 P 0 ;0,4=58,6=0.000000
L 3.06989892 -2.1638 3.0558997 -2.18179892 2 P 0 ;0,4=58,6=0.000000
L 3.0558997 -2.2538 3.08389803 -2.2538 2 P 0 ;0,4=58,6=0.000000
L 3.64489892 -2.2538 3.64489892 -2.1638 2 P 0 ;0,4=58,6=0.000000
L 3.64489892 -2.1638 3.6308997 -2.18179892 2 P 0 ;0,4=58,6=0.000000
L 3.6308997 -2.2538 3.65889803 -2.2538 2 P 0 ;0,4=58,6=0.000000
L 0.5953998 -1.74180266 0.60473337 -1.74930098 2 P 0 ;0,4=59,6=0.000000
L 0.60473337 -1.74930098 0.61523317 -1.7538 2 P 0 ;0,4=59,6=0.000000
L 0.61523317 -1.7538 0.62456673 -1.7538 2 P 0 ;0,4=59,6=0.000000
L 0.62456673 -1.7538 0.6339002 -1.74930098 2 P 0 ;0,4=59,6=0.000000
L 0.6339002 -1.74930098 0.64090079 -1.74180266 2 P 0 ;0,4=59,6=0.000000
L 0.64090079 -1.74180266 0.6444001 -1.73129941 2 P 0 ;0,4=59,6=0.000000
L 0.6444001 -1.73129941 0.64206722 -1.72080157 2 P 0 ;0,4=59,6=0.000000
L 0.64206722 -1.72080157 0.63623297 -1.71180079 2 P 0 ;0,4=59,6=0.000000
L 0.63623297 -1.71180079 0.62573307 -1.70579931 2 P 0 ;0,4=59,6=0.000000
L 0.62573307 -1.70579931 0.61173396 -1.7028 2 P 0 ;0,4=59,6=0.000000
L 0.61173396 -1.7028 0.60356693 -1.69680128 2 P 0 ;0,4=59,6=0.000000
L 0.60356693 -1.69680128 0.60006555 -1.68630069 2 P 0 ;0,4=59,6=0.000000
L 0.60006555 -1.68630069 0.60240049 -1.6758002 2 P 0 ;0,4=59,6=0.000000
L 0.60240049 -1.6758002 0.60823258 -1.66830187 2 P 0 ;0,4=59,6=0.000000
L 0.60823258 -1.66830187 0.61639961 -1.6638 2 P 0 ;0,4=59,6=0.000000
L 0.61639961 -1.6638 0.62456673 -1.6638 2 P 0 ;0,4=59,6=0.000000
L 0.62456673 -1.6638 0.63273376 -1.66679941 2 P 0 ;0,4=59,6=0.000000
L 0.63273376 -1.66679941 0.63973435 -1.67430059 2 P 0 ;0,4=59,6=0.000000
L 0.70989892 -1.7538 0.70056545 -1.75230039 2 P 0 ;0,4=59,6=0.000000
L 0.70056545 -1.75230039 0.69240049 -1.74630167 2 P 0 ;0,4=59,6=0.000000
L 0.69240049 -1.74630167 0.6853998 -1.73730079 2 P 0 ;0,4=59,6=0.000000
L 0.6853998 -1.73730079 0.68073209 -1.7268003 2 P 0 ;0,4=59,6=0.000000
L 0.68073209 -1.7268003 0.67839921 -1.7148001 2 P 0 ;0,4=59,6=0.000000
L 0.67839921 -1.7148001 0.67839921 -1.7028 2 P 0 ;0,4=59,6=0.000000
L 0.67839921 -1.7028 0.68073209 -1.6907998 2 P 0 ;0,4=59,6=0.000000
L 0.68073209 -1.6907998 0.6853998 -1.68029931 2 P 0 ;0,4=59,6=0.000000
L 0.6853998 -1.68029931 0.69240049 -1.67130118 2 P 0 ;0,4=59,6=0.000000
L 0.69240049 -1.67130118 0.70056545 -1.6652997 2 P 0 ;0,4=59,6=0.000000
L 0.70056545 -1.6652997 0.70989892 -1.6638 2 P 0 ;0,4=59,6=0.000000
L 0.70989892 -1.6638 0.71923238 -1.6652997 2 P 0 ;0,4=59,6=0.000000
L 0.71923238 -1.6652997 0.72739941 -1.67130118 2 P 0 ;0,4=59,6=0.000000
L 0.72739941 -1.67130118 0.7344001 -1.68029931 2 P 0 ;0,4=59,6=0.000000
L 0.7344001 -1.68029931 0.73906782 -1.6907998 2 P 0 ;0,4=59,6=0.000000
L 0.73906782 -1.6907998 0.74140069 -1.7028 2 P 0 ;0,4=59,6=0.000000
L 0.74140069 -1.7028 0.74140069 -1.7148001 2 P 0 ;0,4=59,6=0.000000
L 0.74140069 -1.7148001 0.73906782 -1.7268003 2 P 0 ;0,4=59,6=0.000000
L 0.73906782 -1.7268003 0.7344001 -1.73730079 2 P 0 ;0,4=59,6=0.000000
L 0.7344001 -1.73730079 0.72739941 -1.74630167 2 P 0 ;0,4=59,6=0.000000
L 0.72739941 -1.74630167 0.71923238 -1.75230039 2 P 0 ;0,4=59,6=0.000000
L 0.71923238 -1.75230039 0.70989892 -1.7538 2 P 0 ;0,4=59,6=0.000000
L 0.77656624 -1.6638 0.77656624 -1.7538 2 P 0 ;0,4=59,6=0.000000
L 0.77656624 -1.7538 0.82323366 -1.7538 2 P 0 ;0,4=59,6=0.000000
L 0.86423346 -1.7538 0.86423346 -1.6638 2 P 0 ;0,4=59,6=0.000000
L 0.86423346 -1.6638 0.88756604 -1.6638 2 P 0 ;0,4=59,6=0.000000
L 0.88756604 -1.6638 0.89689951 -1.66830187 2 P 0 ;0,4=59,6=0.000000
L 0.89689951 -1.66830187 0.9039002 -1.67430059 2 P 0 ;0,4=59,6=0.000000
L 0.9039002 -1.67430059 0.90973435 -1.68329862 2 P 0 ;0,4=59,6=0.000000
L 0.90973435 -1.68329862 0.9144001 -1.69380187 2 P 0 ;0,4=59,6=0.000000
L 0.9144001 -1.69380187 0.91556644 -1.70880138 2 P 0 ;0,4=59,6=0.000000
L 0.91556644 -1.70880138 0.9144001 -1.72380098 2 P 0 ;0,4=59,6=0.000000
L 0.9144001 -1.72380098 0.90973435 -1.73430148 2 P 0 ;0,4=59,6=0.000000
L 0.90973435 -1.73430148 0.9039002 -1.74330226 2 P 0 ;0,4=59,6=0.000000
L 0.9039002 -1.74330226 0.89689951 -1.74930098 2 P 0 ;0,4=59,6=0.000000
L 0.89689951 -1.74930098 0.88756604 -1.7538 2 P 0 ;0,4=59,6=0.000000
L 0.88756604 -1.7538 0.86423346 -1.7538 2 P 0 ;0,4=59,6=0.000000
L 1.00323366 -1.7538 0.95656624 -1.7538 2 P 0 ;0,4=59,6=0.000000
L 0.95656624 -1.7538 0.95656624 -1.6638 2 P 0 ;0,4=59,6=0.000000
L 0.95656624 -1.6638 1.00323366 -1.6638 2 P 0 ;0,4=59,6=0.000000
L 0.98456673 -1.70729902 0.95656624 -1.70729902 2 P 0 ;0,4=59,6=0.000000
L 1.04656624 -1.7538 1.04656624 -1.6638 2 P 0 ;0,4=59,6=0.000000
L 1.04656624 -1.6638 1.07573307 -1.6638 2 P 0 ;0,4=59,6=0.000000
L 1.07573307 -1.6638 1.08506654 -1.66830187 2 P 0 ;0,4=59,6=0.000000
L 1.08506654 -1.66830187 1.09090079 -1.67430059 2 P 0 ;0,4=59,6=0.000000
L 1.09090079 -1.67430059 1.09323366 -1.68630069 2 P 0 ;0,4=59,6=0.000000
L 1.09323366 -1.68630069 1.09090079 -1.69830089 2 P 0 ;0,4=59,6=0.000000
L 1.09090079 -1.69830089 1.0839002 -1.70579931 2 P 0 ;0,4=59,6=0.000000
L 1.0839002 -1.70579931 1.07573307 -1.71030108 2 P 0 ;0,4=59,6=0.000000
L 1.07573307 -1.71030108 1.04656624 -1.71030108 2 P 0 ;0,4=59,6=0.000000
L 1.07573307 -1.71030108 1.09323366 -1.7538 2 P 0 ;0,4=59,6=0.000000
L 1.21956565 -1.7538 1.21956565 -1.6638 2 P 0 ;0,4=59,6=0.000000
L 1.21956565 -1.6638 1.24989892 -1.73880049 2 P 0 ;0,4=59,6=0.000000
L 1.24989892 -1.73880049 1.28023425 -1.6638 2 P 0 ;0,4=59,6=0.000000
L 1.28023425 -1.6638 1.28023425 -1.7538 2 P 0 ;0,4=59,6=0.000000
L 1.31073209 -1.7538 1.33989892 -1.6638 2 P 0 ;0,4=59,6=0.000000
L 1.33989892 -1.6638 1.36906782 -1.7538 2 P 0 ;0,4=59,6=0.000000
L 1.35856585 -1.72230128 1.32123189 -1.72230128 2 P 0 ;0,4=59,6=0.000000
L 1.4053998 -1.74180266 1.41473337 -1.74930098 2 P 0 ;0,4=59,6=0.000000
L 1.41473337 -1.74930098 1.42523317 -1.7538 2 P 0 ;0,4=59,6=0.000000
L 1.42523317 -1.7538 1.43456673 -1.7538 2 P 0 ;0,4=59,6=0.000000
L 1.43456673 -1.7538 1.4439002 -1.74930098 2 P 0 ;0,4=59,6=0.000000
L 1.4439002 -1.74930098 1.45090079 -1.74180266 2 P 0 ;0,4=59,6=0.000000
L 1.45090079 -1.74180266 1.4544001 -1.73129941 2 P 0 ;0,4=59,6=0.000000
L 1.4544001 -1.73129941 1.45206722 -1.72080157 2 P 0 ;0,4=59,6=0.000000
L 1.45206722 -1.72080157 1.44623297 -1.71180079 2 P 0 ;0,4=59,6=0.000000
L 1.44623297 -1.71180079 1.43573307 -1.70579931 2 P 0 ;0,4=59,6=0.000000
L 1.43573307 -1.70579931 1.42173396 -1.7028 2 P 0 ;0,4=59,6=0.000000
L 1.42173396 -1.7028 1.41356693 -1.69680128 2 P 0 ;0,4=59,6=0.000000
L 1.41356693 -1.69680128 1.41006555 -1.68630069 2 P 0 ;0,4=59,6=0.000000
L 1.41006555 -1.68630069 1.41240049 -1.6758002 2 P 0 ;0,4=59,6=0.000000
L 1.41240049 -1.6758002 1.41823258 -1.66830187 2 P 0 ;0,4=59,6=0.000000
L 1.41823258 -1.66830187 1.42639961 -1.6638 2 P 0 ;0,4=59,6=0.000000
L 1.42639961 -1.6638 1.43456673 -1.6638 2 P 0 ;0,4=59,6=0.000000
L 1.43456673 -1.6638 1.44273376 -1.66679941 2 P 0 ;0,4=59,6=0.000000
L 1.44273376 -1.66679941 1.44973435 -1.67430059 2 P 0 ;0,4=59,6=0.000000
L 1.49423346 -1.7538 1.49423346 -1.6638 2 P 0 ;0,4=59,6=0.000000
L 1.53856585 -1.6638 1.49423346 -1.71930197 2 P 0 ;0,4=59,6=0.000000
L 1.54556644 -1.7538 1.51406683 -1.69380187 2 P 0 ;0,4=59,6=0.000000
L 1.69406683 -1.78379902 1.68240049 -1.76879951 2 P 0 ;0,4=59,6=0.000000
L 1.68240049 -1.76879951 1.67656624 -1.7538 2 P 0 ;0,4=59,6=0.000000
L 1.67656624 -1.7538 1.67656624 -1.69380187 2 P 0 ;0,4=59,6=0.000000
L 1.67656624 -1.69380187 1.68240049 -1.67879961 2 P 0 ;0,4=59,6=0.000000
L 1.68240049 -1.67879961 1.69406683 -1.6638 2 P 0 ;0,4=59,6=0.000000
L 1.78989892 -1.6638 1.78989892 -1.7538 2 P 0 ;0,4=59,6=0.000000
L 1.76306703 -1.6638 1.81673287 -1.6638 2 P 0 ;0,4=59,6=0.000000
L 1.87989892 -1.7538 1.87056545 -1.75230039 2 P 0 ;0,4=59,6=0.000000
L 1.87056545 -1.75230039 1.86240049 -1.74630167 2 P 0 ;0,4=59,6=0.000000
L 1.86240049 -1.74630167 1.8553998 -1.73730079 2 P 0 ;0,4=59,6=0.000000
L 1.8553998 -1.73730079 1.85073209 -1.7268003 2 P 0 ;0,4=59,6=0.000000
L 1.85073209 -1.7268003 1.84839921 -1.7148001 2 P 0 ;0,4=59,6=0.000000
L 1.84839921 -1.7148001 1.84839921 -1.7028 2 P 0 ;0,4=59,6=0.000000
L 1.84839921 -1.7028 1.85073209 -1.6907998 2 P 0 ;0,4=59,6=0.000000
L 1.85073209 -1.6907998 1.8553998 -1.68029931 2 P 0 ;0,4=59,6=0.000000
L 1.8553998 -1.68029931 1.86240049 -1.67130118 2 P 0 ;0,4=59,6=0.000000
L 1.86240049 -1.67130118 1.87056545 -1.6652997 2 P 0 ;0,4=59,6=0.000000
L 1.87056545 -1.6652997 1.87989892 -1.6638 2 P 0 ;0,4=59,6=0.000000
L 1.87989892 -1.6638 1.88923238 -1.6652997 2 P 0 ;0,4=59,6=0.000000
L 1.88923238 -1.6652997 1.89739941 -1.67130118 2 P 0 ;0,4=59,6=0.000000
L 1.89739941 -1.67130118 1.9044001 -1.68029931 2 P 0 ;0,4=59,6=0.000000
L 1.9044001 -1.68029931 1.90906782 -1.6907998 2 P 0 ;0,4=59,6=0.000000
L 1.90906782 -1.6907998 1.91140069 -1.7028 2 P 0 ;0,4=59,6=0.000000
L 1.91140069 -1.7028 1.91140069 -1.7148001 2 P 0 ;0,4=59,6=0.000000
L 1.91140069 -1.7148001 1.90906782 -1.7268003 2 P 0 ;0,4=59,6=0.000000
L 1.90906782 -1.7268003 1.9044001 -1.73730079 2 P 0 ;0,4=59,6=0.000000
L 1.9044001 -1.73730079 1.89739941 -1.74630167 2 P 0 ;0,4=59,6=0.000000
L 1.89739941 -1.74630167 1.88923238 -1.75230039 2 P 0 ;0,4=59,6=0.000000
L 1.88923238 -1.75230039 1.87989892 -1.7538 2 P 0 ;0,4=59,6=0.000000
L 1.94656624 -1.7538 1.94656624 -1.6638 2 P 0 ;0,4=59,6=0.000000
L 1.94656624 -1.6638 1.97456673 -1.6638 2 P 0 ;0,4=59,6=0.000000
L 1.97456673 -1.6638 1.9839002 -1.66830187 2 P 0 ;0,4=59,6=0.000000
L 1.9839002 -1.66830187 1.99090079 -1.67879961 2 P 0 ;0,4=59,6=0.000000
L 1.99090079 -1.67879961 1.99323366 -1.6907998 2 P 0 ;0,4=59,6=0.000000
L 1.99323366 -1.6907998 1.99090079 -1.7028 2 P 0 ;0,4=59,6=0.000000
L 1.99090079 -1.7028 1.98506654 -1.71180079 2 P 0 ;0,4=59,6=0.000000
L 1.98506654 -1.71180079 1.97456673 -1.71630256 2 P 0 ;0,4=59,6=0.000000
L 1.97456673 -1.71630256 1.94656624 -1.71630256 2 P 0 ;0,4=59,6=0.000000
L 2.06573307 -1.78379902 2.07739941 -1.76879951 2 P 0 ;0,4=59,6=0.000000
L 2.07739941 -1.76879951 2.08323366 -1.7538 2 P 0 ;0,4=59,6=0.000000
L 2.08323366 -1.7538 2.08323366 -1.69380187 2 P 0 ;0,4=59,6=0.000000
L 2.08323366 -1.69380187 2.07739941 -1.67879961 2 P 0 ;0,4=59,6=0.000000
L 2.07739941 -1.67879961 2.06573307 -1.6638 2 P 0 ;0,4=59,6=0.000000
L 0.59099833 -1.36499882 0.5990003 -1.35750039 2 P 0 ;0,4=60,6=0.000000
L 0.5990003 -1.35750039 0.60499902 -1.34500315 2 P 0 ;0,4=60,6=0.000000
L 0.60499902 -1.34500315 0.60900187 -1.32749764 2 P 0 ;0,4=60,6=0.000000
L 0.60900187 -1.32749764 0.60499902 -1.31250089 2 P 0 ;0,4=60,6=0.000000
L 0.60499902 -1.31250089 0.59700079 -1.30250305 2 P 0 ;0,4=60,6=0.000000
L 0.59700079 -1.30250305 0.5830001 -1.295 2 P 0 ;0,4=60,6=0.000000
L 0.5830001 -1.295 0.52900059 -1.295 2 P 0 ;0,4=60,6=0.000000
L 0.52900059 -1.295 0.52900059 -1.445 2 P 0 ;0,4=60,6=0.000000
L 0.52900059 -1.445 0.59500118 -1.445 2 P 0 ;0,4=60,6=0.000000
L 0.59500118 -1.445 0.60900187 -1.43500217 2 P 0 ;0,4=60,6=0.000000
L 0.60900187 -1.43500217 0.6170001 -1.42000079 2 P 0 ;0,4=60,6=0.000000
L 0.6170001 -1.42000079 0.62099931 -1.4025 2 P 0 ;0,4=60,6=0.000000
L 0.62099931 -1.4025 0.6170001 -1.38500374 2 P 0 ;0,4=60,6=0.000000
L 0.6170001 -1.38500374 0.60499902 -1.37000236 2 P 0 ;0,4=60,6=0.000000
L 0.60499902 -1.37000236 0.59099833 -1.36499882 2 P 0 ;0,4=60,6=0.000000
L 0.59099833 -1.36499882 0.52900059 -1.36499882 2 P 0 ;0,4=60,6=0.000000
L 0.77100138 -1.445 0.77100138 -1.34500315 2 P 0 ;0,4=60,6=0.000000
L 0.77100138 -1.36249941 0.76299951 -1.35250148 2 P 0 ;0,4=60,6=0.000000
L 0.76299951 -1.35250148 0.75099833 -1.34750256 2 P 0 ;0,4=60,6=0.000000
L 0.75099833 -1.34750256 0.73700138 -1.34500315 2 P 0 ;0,4=60,6=0.000000
L 0.73700138 -1.34500315 0.72300069 -1.35000207 2 P 0 ;0,4=60,6=0.000000
L 0.72300069 -1.35000207 0.71099961 -1.3599999 2 P 0 ;0,4=60,6=0.000000
L 0.71099961 -1.3599999 0.70299764 -1.37500128 2 P 0 ;0,4=60,6=0.000000
L 0.70299764 -1.37500128 0.69899852 -1.39500157 2 P 0 ;0,4=60,6=0.000000
L 0.69899852 -1.39500157 0.70299764 -1.41500187 2 P 0 ;0,4=60,6=0.000000
L 0.70299764 -1.41500187 0.71099961 -1.43000325 2 P 0 ;0,4=60,6=0.000000
L 0.71099961 -1.43000325 0.72300069 -1.44000108 2 P 0 ;0,4=60,6=0.000000
L 0.72300069 -1.44000108 0.73700138 -1.445 2 P 0 ;0,4=60,6=0.000000
L 0.73700138 -1.445 0.75099833 -1.44250059 2 P 0 ;0,4=60,6=0.000000
L 0.75099833 -1.44250059 0.76299951 -1.43500217 2 P 0 ;0,4=60,6=0.000000
L 0.76299951 -1.43500217 0.77100138 -1.42500433 2 P 0 ;0,4=60,6=0.000000
L 0.86700039 -1.445 0.86700039 -1.34500315 2 P 0 ;0,4=60,6=0.000000
L 0.86700039 -1.36499882 0.87699833 -1.35500098 2 P 0 ;0,4=60,6=0.000000
L 0.87699833 -1.35500098 0.8869998 -1.34750256 2 P 0 ;0,4=60,6=0.000000
L 0.8869998 -1.34750256 0.90100049 -1.34500315 2 P 0 ;0,4=60,6=0.000000
L 0.90100049 -1.34500315 0.91099833 -1.34750256 2 P 0 ;0,4=60,6=0.000000
L 0.91099833 -1.34750256 0.92299951 -1.35500098 2 P 0 ;0,4=60,6=0.000000
L 1.02700039 -1.445 1.02700039 -1.34500315 2 P 0 ;0,4=60,6=0.000000
L 1.02700039 -1.36499882 1.03699833 -1.35500098 2 P 0 ;0,4=60,6=0.000000
L 1.03699833 -1.35500098 1.0469998 -1.34750256 2 P 0 ;0,4=60,6=0.000000
L 1.0469998 -1.34750256 1.06100049 -1.34500315 2 P 0 ;0,4=60,6=0.000000
L 1.06100049 -1.34500315 1.07099833 -1.34750256 2 P 0 ;0,4=60,6=0.000000
L 1.07099833 -1.34750256 1.08299951 -1.35500098 2 P 0 ;0,4=60,6=0.000000
L 1.18500089 -1.37750069 1.24900187 -1.37750069 2 P 0 ;0,4=60,6=0.000000
L 1.24900187 -1.37750069 1.24299951 -1.3599999 2 P 0 ;0,4=60,6=0.000000
L 1.24299951 -1.3599999 1.23300157 -1.35000207 2 P 0 ;0,4=60,6=0.000000
L 1.23300157 -1.35000207 1.21900089 -1.34500315 2 P 0 ;0,4=60,6=0.000000
L 1.21900089 -1.34500315 1.2050003 -1.34750256 2 P 0 ;0,4=60,6=0.000000
L 1.2050003 -1.34750256 1.19299911 -1.35500098 2 P 0 ;0,4=60,6=0.000000
L 1.19299911 -1.35500098 1.18500089 -1.37250177 2 P 0 ;0,4=60,6=0.000000
L 1.18500089 -1.37250177 1.18099803 -1.38750315 2 P 0 ;0,4=60,6=0.000000
L 1.18099803 -1.38750315 1.18099803 -1.4025 2 P 0 ;0,4=60,6=0.000000
L 1.18099803 -1.4025 1.18500089 -1.41750138 2 P 0 ;0,4=60,6=0.000000
L 1.18500089 -1.41750138 1.19499872 -1.43250276 2 P 0 ;0,4=60,6=0.000000
L 1.19499872 -1.43250276 1.2069998 -1.44250059 2 P 0 ;0,4=60,6=0.000000
L 1.2069998 -1.44250059 1.22100049 -1.445 2 P 0 ;0,4=60,6=0.000000
L 1.22100049 -1.445 1.23500118 -1.44000108 2 P 0 ;0,4=60,6=0.000000
L 1.23500118 -1.44000108 1.24900187 -1.42500433 2 P 0 ;0,4=60,6=0.000000
L 1.37499813 -1.445 1.37499813 -1.295 2 P 0 ;0,4=60,6=0.000000
L 1.50500089 -1.37750069 1.56900187 -1.37750069 2 P 0 ;0,4=60,6=0.000000
L 1.56900187 -1.37750069 1.56299951 -1.3599999 2 P 0 ;0,4=60,6=0.000000
L 1.56299951 -1.3599999 1.55300157 -1.35000207 2 P 0 ;0,4=60,6=0.000000
L 1.55300157 -1.35000207 1.53900089 -1.34500315 2 P 0 ;0,4=60,6=0.000000
L 1.53900089 -1.34500315 1.5250003 -1.34750256 2 P 0 ;0,4=60,6=0.000000
L 1.5250003 -1.34750256 1.51299911 -1.35500098 2 P 0 ;0,4=60,6=0.000000
L 1.51299911 -1.35500098 1.50500089 -1.37250177 2 P 0 ;0,4=60,6=0.000000
L 1.50500089 -1.37250177 1.50099803 -1.38750315 2 P 0 ;0,4=60,6=0.000000
L 1.50099803 -1.38750315 1.50099803 -1.4025 2 P 0 ;0,4=60,6=0.000000
L 1.50099803 -1.4025 1.50500089 -1.41750138 2 P 0 ;0,4=60,6=0.000000
L 1.50500089 -1.41750138 1.51499872 -1.43250276 2 P 0 ;0,4=60,6=0.000000
L 1.51499872 -1.43250276 1.5269998 -1.44250059 2 P 0 ;0,4=60,6=0.000000
L 1.5269998 -1.44250059 1.54100049 -1.445 2 P 0 ;0,4=60,6=0.000000
L 1.54100049 -1.445 1.55500118 -1.44000108 2 P 0 ;0,4=60,6=0.000000
L 1.55500118 -1.44000108 1.56900187 -1.42500433 2 P 0 ;0,4=60,6=0.000000
L 1.6529998 -1.48999951 1.66500089 -1.49499843 2 P 0 ;0,4=60,6=0.000000
L 1.66500089 -1.49499843 1.68100108 -1.48999951 2 P 0 ;0,4=60,6=0.000000
L 1.68100108 -1.48999951 1.69099902 -1.48000167 2 P 0 ;0,4=60,6=0.000000
L 1.69099902 -1.48000167 1.69900089 -1.4674997 2 P 0 ;0,4=60,6=0.000000
L 1.69900089 -1.4674997 1.71099833 -1.42750374 2 P 0 ;0,4=60,6=0.000000
L 1.71099833 -1.42750374 1.7370001 -1.34500315 2 P 0 ;0,4=60,6=0.000000
L 1.67299911 -1.34500315 1.71099833 -1.42750374 2 P 0 ;0,4=60,6=0.000000
L 1.82500089 -1.37750069 1.88900187 -1.37750069 2 P 0 ;0,4=60,6=0.000000
L 1.88900187 -1.37750069 1.88299951 -1.3599999 2 P 0 ;0,4=60,6=0.000000
L 1.88299951 -1.3599999 1.87300157 -1.35000207 2 P 0 ;0,4=60,6=0.000000
L 1.87300157 -1.35000207 1.85900089 -1.34500315 2 P 0 ;0,4=60,6=0.000000
L 1.85900089 -1.34500315 1.8450003 -1.34750256 2 P 0 ;0,4=60,6=0.000000
L 1.8450003 -1.34750256 1.83299911 -1.35500098 2 P 0 ;0,4=60,6=0.000000
L 1.83299911 -1.35500098 1.82500089 -1.37250177 2 P 0 ;0,4=60,6=0.000000
L 1.82500089 -1.37250177 1.82099803 -1.38750315 2 P 0 ;0,4=60,6=0.000000
L 1.82099803 -1.38750315 1.82099803 -1.4025 2 P 0 ;0,4=60,6=0.000000
L 1.82099803 -1.4025 1.82500089 -1.41750138 2 P 0 ;0,4=60,6=0.000000
L 1.82500089 -1.41750138 1.83499872 -1.43250276 2 P 0 ;0,4=60,6=0.000000
L 1.83499872 -1.43250276 1.8469998 -1.44250059 2 P 0 ;0,4=60,6=0.000000
L 1.8469998 -1.44250059 1.86100049 -1.445 2 P 0 ;0,4=60,6=0.000000
L 1.86100049 -1.445 1.87500118 -1.44000108 2 P 0 ;0,4=60,6=0.000000
L 1.87500118 -1.44000108 1.88900187 -1.42500433 2 P 0 ;0,4=60,6=0.000000
L 2.18699921 -1.37000236 2.22700167 -1.37000236 2 P 0 ;0,4=60,6=0.000000
L 2.22700167 -1.37000236 2.22700167 -1.41500187 2 P 0 ;0,4=60,6=0.000000
L 2.22700167 -1.41500187 2.21500059 -1.43000325 2 P 0 ;0,4=60,6=0.000000
L 2.21500059 -1.43000325 2.2009999 -1.44000108 2 P 0 ;0,4=60,6=0.000000
L 2.2009999 -1.44000108 2.18100049 -1.445 2 P 0 ;0,4=60,6=0.000000
L 2.18100049 -1.445 2.16100108 -1.44000108 2 P 0 ;0,4=60,6=0.000000
L 2.16100108 -1.44000108 2.14700039 -1.43000325 2 P 0 ;0,4=60,6=0.000000
L 2.14700039 -1.43000325 2.13499931 -1.41500187 2 P 0 ;0,4=60,6=0.000000
L 2.13499931 -1.41500187 2.12699734 -1.39750108 2 P 0 ;0,4=60,6=0.000000
L 2.12699734 -1.39750108 2.12299823 -1.37750069 2 P 0 ;0,4=60,6=0.000000
L 2.12299823 -1.37750069 2.12299823 -1.3599999 2 P 0 ;0,4=60,6=0.000000
L 2.12299823 -1.3599999 2.12699734 -1.34500315 2 P 0 ;0,4=60,6=0.000000
L 2.12699734 -1.34500315 2.13499931 -1.32749764 2 P 0 ;0,4=60,6=0.000000
L 2.13499931 -1.32749764 2.14700039 -1.31250089 2 P 0 ;0,4=60,6=0.000000
L 2.14700039 -1.31250089 2.15899783 -1.30250305 2 P 0 ;0,4=60,6=0.000000
L 2.15899783 -1.30250305 2.17499813 -1.295 2 P 0 ;0,4=60,6=0.000000
L 2.17499813 -1.295 2.18899882 -1.295 2 P 0 ;0,4=60,6=0.000000
L 2.18899882 -1.295 2.20499902 -1.29999902 2 P 0 ;0,4=60,6=0.000000
L 2.20499902 -1.29999902 2.2170001 -1.31000138 2 P 0 ;0,4=60,6=0.000000
L 2.29699892 -1.31999931 2.309 -1.30500246 2 P 0 ;0,4=60,6=0.000000
L 2.309 -1.30500246 2.32300069 -1.29749951 2 P 0 ;0,4=60,6=0.000000
L 2.32300069 -1.29749951 2.33900089 -1.295 2 P 0 ;0,4=60,6=0.000000
L 2.33900089 -1.295 2.3590003 -1.29999902 2 P 0 ;0,4=60,6=0.000000
L 2.3590003 -1.29999902 2.37300098 -1.31250089 2 P 0 ;0,4=60,6=0.000000
L 2.37300098 -1.31250089 2.3770001 -1.32749764 2 P 0 ;0,4=60,6=0.000000
L 2.3770001 -1.32749764 2.37500059 -1.34250364 2 P 0 ;0,4=60,6=0.000000
L 2.37500059 -1.34250364 2.36699862 -1.35500098 2 P 0 ;0,4=60,6=0.000000
L 2.36699862 -1.35500098 2.3269998 -1.3800002 2 P 0 ;0,4=60,6=0.000000
L 2.3269998 -1.3800002 2.309 -1.39750108 2 P 0 ;0,4=60,6=0.000000
L 2.309 -1.39750108 2.29699892 -1.42250482 2 P 0 ;0,4=60,6=0.000000
L 2.29699892 -1.42250482 2.2929998 -1.445 2 P 0 ;0,4=60,6=0.000000
L 2.2929998 -1.445 2.3770001 -1.445 2 P 0 ;0,4=60,6=0.000000
L 2.6129998 -1.42500433 2.629 -1.43750167 2 P 0 ;0,4=60,6=0.000000
L 2.629 -1.43750167 2.6469998 -1.445 2 P 0 ;0,4=60,6=0.000000
L 2.6469998 -1.445 2.6630001 -1.445 2 P 0 ;0,4=60,6=0.000000
L 2.6630001 -1.445 2.6790003 -1.43750167 2 P 0 ;0,4=60,6=0.000000
L 2.6790003 -1.43750167 2.69100138 -1.42500433 2 P 0 ;0,4=60,6=0.000000
L 2.69100138 -1.42500433 2.6970001 -1.40749892 2 P 0 ;0,4=60,6=0.000000
L 2.6970001 -1.40749892 2.69300098 -1.39000266 2 P 0 ;0,4=60,6=0.000000
L 2.69300098 -1.39000266 2.68299951 -1.37500128 2 P 0 ;0,4=60,6=0.000000
L 2.68299951 -1.37500128 2.66499961 -1.36499882 2 P 0 ;0,4=60,6=0.000000
L 2.66499961 -1.36499882 2.64100108 -1.3599999 2 P 0 ;0,4=60,6=0.000000
L 2.64100108 -1.3599999 2.62700039 -1.35000207 2 P 0 ;0,4=60,6=0.000000
L 2.62700039 -1.35000207 2.62099803 -1.33250118 2 P 0 ;0,4=60,6=0.000000
L 2.62099803 -1.33250118 2.62500089 -1.31500039 2 P 0 ;0,4=60,6=0.000000
L 2.62500089 -1.31500039 2.63499872 -1.30250305 2 P 0 ;0,4=60,6=0.000000
L 2.63499872 -1.30250305 2.64899941 -1.295 2 P 0 ;0,4=60,6=0.000000
L 2.64899941 -1.295 2.6630001 -1.295 2 P 0 ;0,4=60,6=0.000000
L 2.6630001 -1.295 2.67700079 -1.29999902 2 P 0 ;0,4=60,6=0.000000
L 2.67700079 -1.29999902 2.68900187 -1.31250089 2 P 0 ;0,4=60,6=0.000000
L 2.7729998 -1.445 2.8570001 -1.295 2 P 0 ;0,4=60,6=0.000000
L 2.7729998 -1.295 2.8570001 -1.445 2 P 0 ;0,4=60,6=0.000000
L 2.92299823 -1.445 2.92299823 -1.295 2 P 0 ;0,4=60,6=0.000000
L 2.92299823 -1.295 2.97499813 -1.42000079 2 P 0 ;0,4=60,6=0.000000
L 2.97499813 -1.42000079 3.02700167 -1.295 2 P 0 ;0,4=60,6=0.000000
L 3.02700167 -1.295 3.02700167 -1.445 2 P 0 ;0,4=60,6=0.000000
L 3.09699892 -1.31999931 3.109 -1.30500246 2 P 0 ;0,4=60,6=0.000000
L 3.109 -1.30500246 3.12300069 -1.29749951 2 P 0 ;0,4=60,6=0.000000
L 3.12300069 -1.29749951 3.13900089 -1.295 2 P 0 ;0,4=60,6=0.000000
L 3.13900089 -1.295 3.1590003 -1.29999902 2 P 0 ;0,4=60,6=0.000000
L 3.1590003 -1.29999902 3.17300098 -1.31250089 2 P 0 ;0,4=60,6=0.000000
L 3.17300098 -1.31250089 3.1770001 -1.32749764 2 P 0 ;0,4=60,6=0.000000
L 3.1770001 -1.32749764 3.17500059 -1.34250364 2 P 0 ;0,4=60,6=0.000000
L 3.17500059 -1.34250364 3.16699862 -1.35500098 2 P 0 ;0,4=60,6=0.000000
L 3.16699862 -1.35500098 3.1269998 -1.3800002 2 P 0 ;0,4=60,6=0.000000
L 3.1269998 -1.3800002 3.109 -1.39750108 2 P 0 ;0,4=60,6=0.000000
L 3.109 -1.39750108 3.09699892 -1.42250482 2 P 0 ;0,4=60,6=0.000000
L 3.09699892 -1.42250482 3.0929998 -1.445 2 P 0 ;0,4=60,6=0.000000
L 3.0929998 -1.445 3.1770001 -1.445 2 P 0 ;0,4=60,6=0.000000
L 3.269 -1.39500157 3.3209999 -1.39500157 2 P 0 ;0,4=60,6=0.000000
L 3.41499931 -1.445 3.41499931 -1.295 2 P 0 ;0,4=60,6=0.000000
L 3.41499931 -1.295 3.46499961 -1.295 2 P 0 ;0,4=60,6=0.000000
L 3.46499961 -1.295 3.4809999 -1.30250305 2 P 0 ;0,4=60,6=0.000000
L 3.4809999 -1.30250305 3.49100138 -1.31250089 2 P 0 ;0,4=60,6=0.000000
L 3.49100138 -1.31250089 3.49500059 -1.33250118 2 P 0 ;0,4=60,6=0.000000
L 3.49500059 -1.33250118 3.49100138 -1.35250148 2 P 0 ;0,4=60,6=0.000000
L 3.49100138 -1.35250148 3.4790003 -1.36499882 2 P 0 ;0,4=60,6=0.000000
L 3.4790003 -1.36499882 3.46499961 -1.37250177 2 P 0 ;0,4=60,6=0.000000
L 3.46499961 -1.37250177 3.41499931 -1.37250177 2 P 0 ;0,4=60,6=0.000000
L 3.46499961 -1.37250177 3.49500059 -1.445 2 P 0 ;0,4=60,6=0.000000
L 3.61499813 -1.34500315 3.61499813 -1.445 2 P 0 ;0,4=60,6=0.000000
L 3.61499813 -1.30500246 3.61099902 -1.30250305 2 P 0 ;0,4=60,6=0.000000
L 3.61099902 -1.30250305 3.61099902 -1.29749951 2 P 0 ;0,4=60,6=0.000000
L 3.61099902 -1.29749951 3.61499813 -1.295 2 P 0 ;0,4=60,6=0.000000
L 3.61499813 -1.295 3.61900089 -1.29749951 2 P 0 ;0,4=60,6=0.000000
L 3.61900089 -1.29749951 3.61900089 -1.30250305 2 P 0 ;0,4=60,6=0.000000
L 3.61900089 -1.30250305 3.61499813 -1.30500246 2 P 0 ;0,4=60,6=0.000000
L 3.74500089 -1.42750374 3.75499872 -1.43750167 2 P 0 ;0,4=60,6=0.000000
L 3.75499872 -1.43750167 3.76899941 -1.445 2 P 0 ;0,4=60,6=0.000000
L 3.76899941 -1.445 3.78100049 -1.445 2 P 0 ;0,4=60,6=0.000000
L 3.78100049 -1.445 3.79300157 -1.44000108 2 P 0 ;0,4=60,6=0.000000
L 3.79300157 -1.44000108 3.8009999 -1.43250276 2 P 0 ;0,4=60,6=0.000000
L 3.8009999 -1.43250276 3.80499902 -1.42250482 2 P 0 ;0,4=60,6=0.000000
L 3.80499902 -1.42250482 3.80299951 -1.40749892 2 P 0 ;0,4=60,6=0.000000
L 3.80299951 -1.40749892 3.79500118 -1.40000049 2 P 0 ;0,4=60,6=0.000000
L 3.79500118 -1.40000049 3.75899783 -1.38500374 2 P 0 ;0,4=60,6=0.000000
L 3.75899783 -1.38500374 3.75099961 -1.36749833 2 P 0 ;0,4=60,6=0.000000
L 3.75099961 -1.36749833 3.75499872 -1.35500098 2 P 0 ;0,4=60,6=0.000000
L 3.75499872 -1.35500098 3.76300069 -1.34750256 2 P 0 ;0,4=60,6=0.000000
L 3.76300069 -1.34750256 3.77499813 -1.34500315 2 P 0 ;0,4=60,6=0.000000
L 3.77499813 -1.34500315 3.78699921 -1.34750256 2 P 0 ;0,4=60,6=0.000000
L 3.78699921 -1.34750256 3.7990003 -1.35500098 2 P 0 ;0,4=60,6=0.000000
L 3.90500089 -1.37750069 3.96900187 -1.37750069 2 P 0 ;0,4=60,6=0.000000
L 3.96900187 -1.37750069 3.96299951 -1.3599999 2 P 0 ;0,4=60,6=0.000000
L 3.96299951 -1.3599999 3.95300157 -1.35000207 2 P 0 ;0,4=60,6=0.000000
L 3.95300157 -1.35000207 3.93900089 -1.34500315 2 P 0 ;0,4=60,6=0.000000
L 3.93900089 -1.34500315 3.9250003 -1.34750256 2 P 0 ;0,4=60,6=0.000000
L 3.9250003 -1.34750256 3.91299911 -1.35500098 2 P 0 ;0,4=60,6=0.000000
L 3.91299911 -1.35500098 3.90500089 -1.37250177 2 P 0 ;0,4=60,6=0.000000
L 3.90500089 -1.37250177 3.90099803 -1.38750315 2 P 0 ;0,4=60,6=0.000000
L 3.90099803 -1.38750315 3.90099803 -1.4025 2 P 0 ;0,4=60,6=0.000000
L 3.90099803 -1.4025 3.90500089 -1.41750138 2 P 0 ;0,4=60,6=0.000000
L 3.90500089 -1.41750138 3.91499872 -1.43250276 2 P 0 ;0,4=60,6=0.000000
L 3.91499872 -1.43250276 3.9269998 -1.44250059 2 P 0 ;0,4=60,6=0.000000
L 3.9269998 -1.44250059 3.94100049 -1.445 2 P 0 ;0,4=60,6=0.000000
L 3.94100049 -1.445 3.95500118 -1.44000108 2 P 0 ;0,4=60,6=0.000000
L 3.95500118 -1.44000108 3.96900187 -1.42500433 2 P 0 ;0,4=60,6=0.000000
L 4.06700039 -1.445 4.06700039 -1.34500315 2 P 0 ;0,4=60,6=0.000000
L 4.06700039 -1.36499882 4.07699833 -1.35500098 2 P 0 ;0,4=60,6=0.000000
L 4.07699833 -1.35500098 4.0869998 -1.34750256 2 P 0 ;0,4=60,6=0.000000
L 4.0869998 -1.34750256 4.10100049 -1.34500315 2 P 0 ;0,4=60,6=0.000000
L 4.10100049 -1.34500315 4.11099833 -1.34750256 2 P 0 ;0,4=60,6=0.000000
L 4.11099833 -1.34750256 4.12299951 -1.35500098 2 P 0 ;0,4=60,6=0.000000
L 4.16964783 -2.2038 4.21839813 -2.0478 2 P 0 ;0,4=61,6=0.000000
L 4.21839813 -2.0478 4.26715207 -2.2038 2 P 0 ;0,4=61,6=0.000000
L 4.24959862 -2.14920217 4.18719774 -2.14920217 2 P 0 ;0,4=61,6=0.000000
L 4.37939813 -2.2038 4.37939813 -2.0478 2 P 0 ;0,4=61,6=0.000000
L 4.37939813 -2.0478 4.35599961 -2.07899813 2 P 0 ;0,4=61,6=0.000000
L 4.35599961 -2.2038 4.40279675 -2.2038 2 P 0 ;0,4=61,6=0.000000
L 2.0009002 -0.9538 2.0009002 -0.8038 2 P 0 ;0,4=62,6=0.000000
L 2.0009002 -0.8038 2.04089902 -0.8038 2 P 0 ;0,4=62,6=0.000000
L 2.04089902 -0.8038 2.05689921 -0.81130305 2 P 0 ;0,4=62,6=0.000000
L 2.05689921 -0.81130305 2.0689003 -0.82130089 2 P 0 ;0,4=62,6=0.000000
L 2.0689003 -0.82130089 2.07890187 -0.83629764 2 P 0 ;0,4=62,6=0.000000
L 2.07890187 -0.83629764 2.0869001 -0.85380315 2 P 0 ;0,4=62,6=0.000000
L 2.0869001 -0.85380315 2.0888997 -0.87880236 2 P 0 ;0,4=62,6=0.000000
L 2.0888997 -0.87880236 2.0869001 -0.90380157 2 P 0 ;0,4=62,6=0.000000
L 2.0869001 -0.90380157 2.07890187 -0.92130246 2 P 0 ;0,4=62,6=0.000000
L 2.07890187 -0.92130246 2.0689003 -0.93630374 2 P 0 ;0,4=62,6=0.000000
L 2.0689003 -0.93630374 2.05689921 -0.94630167 2 P 0 ;0,4=62,6=0.000000
L 2.05689921 -0.94630167 2.04089902 -0.9538 2 P 0 ;0,4=62,6=0.000000
L 2.04089902 -0.9538 2.0009002 -0.9538 2 P 0 ;0,4=62,6=0.000000
L 2.15489783 -0.9538 2.20489813 -0.8038 2 P 0 ;0,4=62,6=0.000000
L 2.20489813 -0.8038 2.25490207 -0.9538 2 P 0 ;0,4=62,6=0.000000
L 2.23689862 -0.90130207 2.17289764 -0.90130207 2 P 0 ;0,4=62,6=0.000000
L 2.36489813 -0.8038 2.36489813 -0.9538 2 P 0 ;0,4=62,6=0.000000
L 2.31890059 -0.8038 2.41089931 -0.8038 2 P 0 ;0,4=62,6=0.000000
L 2.56490059 -0.9538 2.48489931 -0.9538 2 P 0 ;0,4=62,6=0.000000
L 2.48489931 -0.9538 2.48489931 -0.8038 2 P 0 ;0,4=62,6=0.000000
L 2.48489931 -0.8038 2.56490059 -0.8038 2 P 0 ;0,4=62,6=0.000000
L 2.5329001 -0.87629833 2.48489931 -0.87629833 2 P 0 ;0,4=62,6=0.000000
L 2.84489813 -0.9538 2.82889783 -0.95130059 2 P 0 ;0,4=62,6=0.000000
L 2.82889783 -0.95130059 2.81490089 -0.94130276 2 P 0 ;0,4=62,6=0.000000
L 2.81490089 -0.94130276 2.8028998 -0.92630138 2 P 0 ;0,4=62,6=0.000000
L 2.8028998 -0.92630138 2.79489783 -0.90880049 2 P 0 ;0,4=62,6=0.000000
L 2.79489783 -0.90880049 2.79089862 -0.8888002 2 P 0 ;0,4=62,6=0.000000
L 2.79089862 -0.8888002 2.79089862 -0.8687999 2 P 0 ;0,4=62,6=0.000000
L 2.79089862 -0.8687999 2.79489783 -0.84879961 2 P 0 ;0,4=62,6=0.000000
L 2.79489783 -0.84879961 2.8028998 -0.83129872 2 P 0 ;0,4=62,6=0.000000
L 2.8028998 -0.83129872 2.81490089 -0.81630197 2 P 0 ;0,4=62,6=0.000000
L 2.81490089 -0.81630197 2.82889783 -0.80629951 2 P 0 ;0,4=62,6=0.000000
L 2.82889783 -0.80629951 2.84489813 -0.8038 2 P 0 ;0,4=62,6=0.000000
L 2.84489813 -0.8038 2.86089833 -0.80629951 2 P 0 ;0,4=62,6=0.000000
L 2.86089833 -0.80629951 2.87489902 -0.81630197 2 P 0 ;0,4=62,6=0.000000
L 2.87489902 -0.81630197 2.8869001 -0.83129872 2 P 0 ;0,4=62,6=0.000000
L 2.8869001 -0.83129872 2.89490207 -0.84879961 2 P 0 ;0,4=62,6=0.000000
L 2.89490207 -0.84879961 2.89890128 -0.8687999 2 P 0 ;0,4=62,6=0.000000
L 2.89890128 -0.8687999 2.89890128 -0.8888002 2 P 0 ;0,4=62,6=0.000000
L 2.89890128 -0.8888002 2.89490207 -0.90880049 2 P 0 ;0,4=62,6=0.000000
L 2.89490207 -0.90880049 2.8869001 -0.92630138 2 P 0 ;0,4=62,6=0.000000
L 2.8869001 -0.92630138 2.87489902 -0.94130276 2 P 0 ;0,4=62,6=0.000000
L 2.87489902 -0.94130276 2.86089833 -0.95130059 2 P 0 ;0,4=62,6=0.000000
L 2.86089833 -0.95130059 2.84489813 -0.9538 2 P 0 ;0,4=62,6=0.000000
L 3.0488997 -0.81630197 3.03689862 -0.80879902 2 P 0 ;0,4=62,6=0.000000
L 3.03689862 -0.80879902 3.02290157 -0.8038 2 P 0 ;0,4=62,6=0.000000
L 3.02290157 -0.8038 3.00690138 -0.8038 2 P 0 ;0,4=62,6=0.000000
L 3.00690138 -0.8038 2.98889783 -0.81130305 2 P 0 ;0,4=62,6=0.000000
L 2.98889783 -0.81130305 2.97490089 -0.82380039 2 P 0 ;0,4=62,6=0.000000
L 2.97490089 -0.82380039 2.96489931 -0.83880177 2 P 0 ;0,4=62,6=0.000000
L 2.96489931 -0.83880177 2.95689734 -0.86380098 2 P 0 ;0,4=62,6=0.000000
L 2.95689734 -0.86380098 2.95489783 -0.88630069 2 P 0 ;0,4=62,6=0.000000
L 2.95489783 -0.88630069 2.95890059 -0.90880049 2 P 0 ;0,4=62,6=0.000000
L 2.95890059 -0.90880049 2.96489931 -0.92380187 2 P 0 ;0,4=62,6=0.000000
L 2.96489931 -0.92380187 2.97690039 -0.93880325 2 P 0 ;0,4=62,6=0.000000
L 2.97690039 -0.93880325 2.99090108 -0.94880108 2 P 0 ;0,4=62,6=0.000000
L 2.99090108 -0.94880108 3.00489813 -0.9538 2 P 0 ;0,4=62,6=0.000000
L 3.00489813 -0.9538 3.01889882 -0.9538 2 P 0 ;0,4=62,6=0.000000
L 3.01889882 -0.9538 3.03289951 -0.94880108 2 P 0 ;0,4=62,6=0.000000
L 3.03289951 -0.94880108 3.04490059 -0.94130276 2 P 0 ;0,4=62,6=0.000000
L 3.04490059 -0.94130276 3.05490207 -0.93130482 2 P 0 ;0,4=62,6=0.000000
L 3.16489813 -0.8038 3.16489813 -0.9538 2 P 0 ;0,4=62,6=0.000000
L 3.11890059 -0.8038 3.21089931 -0.8038 2 P 0 ;0,4=62,6=0.000000
L 3.28889852 -0.95879892 3.36090138 -0.8038 2 P 0 ;0,4=62,6=0.000000
L 3.44689892 -0.82879931 3.4589 -0.81380246 2 P 0 ;0,4=62,6=0.000000
L 3.4589 -0.81380246 3.47290069 -0.80629951 2 P 0 ;0,4=62,6=0.000000
L 3.47290069 -0.80629951 3.48890089 -0.8038 2 P 0 ;0,4=62,6=0.000000
L 3.48890089 -0.8038 3.5089003 -0.80879902 2 P 0 ;0,4=62,6=0.000000
L 3.5089003 -0.80879902 3.52290098 -0.82130089 2 P 0 ;0,4=62,6=0.000000
L 3.52290098 -0.82130089 3.5269001 -0.83629764 2 P 0 ;0,4=62,6=0.000000
L 3.5269001 -0.83629764 3.52490059 -0.85130364 2 P 0 ;0,4=62,6=0.000000
L 3.52490059 -0.85130364 3.51689862 -0.86380098 2 P 0 ;0,4=62,6=0.000000
L 3.51689862 -0.86380098 3.4768998 -0.8888002 2 P 0 ;0,4=62,6=0.000000
L 3.4768998 -0.8888002 3.4589 -0.90630108 2 P 0 ;0,4=62,6=0.000000
L 3.4589 -0.90630108 3.44689892 -0.93130482 2 P 0 ;0,4=62,6=0.000000
L 3.44689892 -0.93130482 3.4428998 -0.9538 2 P 0 ;0,4=62,6=0.000000
L 3.4428998 -0.9538 3.5269001 -0.9538 2 P 0 ;0,4=62,6=0.000000
L 3.64089902 -0.9538 3.64489813 -0.92130246 2 P 0 ;0,4=62,6=0.000000
L 3.64489813 -0.92130246 3.65090049 -0.89380374 2 P 0 ;0,4=62,6=0.000000
L 3.65090049 -0.89380374 3.65889882 -0.8687999 2 P 0 ;0,4=62,6=0.000000
L 3.65889882 -0.8687999 3.6689003 -0.84130118 2 P 0 ;0,4=62,6=0.000000
L 3.6689003 -0.84130118 3.68490059 -0.8038 2 P 0 ;0,4=62,6=0.000000
L 3.68490059 -0.8038 3.60489931 -0.8038 2 P 0 ;0,4=62,6=0.000000
L 3.76889852 -0.95879892 3.84090138 -0.8038 2 P 0 ;0,4=62,6=0.000000
L 3.92689892 -0.82879931 3.9389 -0.81380246 2 P 0 ;0,4=62,6=0.000000
L 3.9389 -0.81380246 3.95290069 -0.80629951 2 P 0 ;0,4=62,6=0.000000
L 3.95290069 -0.80629951 3.96890089 -0.8038 2 P 0 ;0,4=62,6=0.000000
L 3.96890089 -0.8038 3.9889003 -0.80879902 2 P 0 ;0,4=62,6=0.000000
L 3.9889003 -0.80879902 4.00290098 -0.82130089 2 P 0 ;0,4=62,6=0.000000
L 4.00290098 -0.82130089 4.0069001 -0.83629764 2 P 0 ;0,4=62,6=0.000000
L 4.0069001 -0.83629764 4.00490059 -0.85130364 2 P 0 ;0,4=62,6=0.000000
L 4.00490059 -0.85130364 3.99689862 -0.86380098 2 P 0 ;0,4=62,6=0.000000
L 3.99689862 -0.86380098 3.9568998 -0.8888002 2 P 0 ;0,4=62,6=0.000000
L 3.9568998 -0.8888002 3.9389 -0.90630108 2 P 0 ;0,4=62,6=0.000000
L 3.9389 -0.90630108 3.92689892 -0.93130482 2 P 0 ;0,4=62,6=0.000000
L 3.92689892 -0.93130482 3.9228998 -0.9538 2 P 0 ;0,4=62,6=0.000000
L 3.9228998 -0.9538 4.0069001 -0.9538 2 P 0 ;0,4=62,6=0.000000
L 4.12489813 -0.8038 4.10889783 -0.80879902 2 P 0 ;0,4=62,6=0.000000
L 4.10889783 -0.80879902 4.09690039 -0.82130089 2 P 0 ;0,4=62,6=0.000000
L 4.09690039 -0.82130089 4.08889852 -0.83629764 2 P 0 ;0,4=62,6=0.000000
L 4.08889852 -0.83629764 4.0828998 -0.85630256 2 P 0 ;0,4=62,6=0.000000
L 4.0828998 -0.85630256 4.0809002 -0.87880236 2 P 0 ;0,4=62,6=0.000000
L 4.0809002 -0.87880236 4.0828998 -0.90130207 2 P 0 ;0,4=62,6=0.000000
L 4.0828998 -0.90130207 4.08889852 -0.92130246 2 P 0 ;0,4=62,6=0.000000
L 4.08889852 -0.92130246 4.09690039 -0.93630374 2 P 0 ;0,4=62,6=0.000000
L 4.09690039 -0.93630374 4.10889783 -0.94880108 2 P 0 ;0,4=62,6=0.000000
L 4.10889783 -0.94880108 4.12489813 -0.9538 2 P 0 ;0,4=62,6=0.000000
L 4.12489813 -0.9538 4.14089833 -0.94880108 2 P 0 ;0,4=62,6=0.000000
L 4.14089833 -0.94880108 4.15289951 -0.93630374 2 P 0 ;0,4=62,6=0.000000
L 4.15289951 -0.93630374 4.16090138 -0.92130246 2 P 0 ;0,4=62,6=0.000000
L 4.16090138 -0.92130246 4.1669001 -0.90130207 2 P 0 ;0,4=62,6=0.000000
L 4.1669001 -0.90130207 4.1688997 -0.87880236 2 P 0 ;0,4=62,6=0.000000
L 4.1688997 -0.87880236 4.1669001 -0.85630256 2 P 0 ;0,4=62,6=0.000000
L 4.1669001 -0.85630256 4.16090138 -0.83629764 2 P 0 ;0,4=62,6=0.000000
L 4.16090138 -0.83629764 4.15289951 -0.82130089 2 P 0 ;0,4=62,6=0.000000
L 4.15289951 -0.82130089 4.14089833 -0.80879902 2 P 0 ;0,4=62,6=0.000000
L 4.14089833 -0.80879902 4.12489813 -0.8038 2 P 0 ;0,4=62,6=0.000000
L 4.28489813 -0.9538 4.28489813 -0.8038 2 P 0 ;0,4=62,6=0.000000
L 4.28489813 -0.8038 4.26089961 -0.83379823 2 P 0 ;0,4=62,6=0.000000
L 4.26089961 -0.9538 4.30889665 -0.9538 2 P 0 ;0,4=62,6=0.000000
L 4.44089902 -0.9538 4.44489813 -0.92130246 2 P 0 ;0,4=62,6=0.000000
L 4.44489813 -0.92130246 4.45090049 -0.89380374 2 P 0 ;0,4=62,6=0.000000
L 4.45090049 -0.89380374 4.45889882 -0.8687999 2 P 0 ;0,4=62,6=0.000000
L 4.45889882 -0.8687999 4.4689003 -0.84130118 2 P 0 ;0,4=62,6=0.000000
L 4.4689003 -0.84130118 4.48490059 -0.8038 2 P 0 ;0,4=62,6=0.000000
L 4.48490059 -0.8038 4.40489931 -0.8038 2 P 0 ;0,4=62,6=0.000000

### steps/drc/layers/sms/features
#
#Feature symbol names
#
$0 r2
$1 r5
$2 r6
$3 r11
$4 r14
$5 r15
$6 r34
$7 r48.7
$8 r51.06
$9 r53.37
$10 r65.18
$11 r79.8
$12 r100
$13 r106.52
$14 r112.43
$15 r132.11
$16 r139
$17 r143.92
$18 r151.8
$19 r171.48
$20 r191.17
$21 r319.96
$22 r359.33
$23 r407.7
$24 s25
$25 s48.7
$26 s55
$27 s79.8
$28 oval216.85x157.8
$29 rect40.43x20.75

#
#Feature attribute names
#
@0 .nomenclature
@1 .smd
@2 .test_point
@3 .string_mirrored
@4 .geometry
@5 .string
@6 .pad_usage
@7 .string_angle

#
#Feature attribute text strings
#
&0 S0_508
&1 TPB30V20D10AT28BPM
&2 C1_11P0_7
&3 C1_11P0_7TP
&4 V17D8AT30SM11
&5 ICT-TPB30BPM
&6 V20D10AT28SM14
&7 C2_5N
&8 R0_9X0_4
&9 S1_11P0_7TP
&10 S1_11P0_7
&11 S1_27
&12 V20D10AT28PG
&13 C1_17P0_76TPM
&14 C1_9P1_4
&15 S1_9P1_4
&16 SP-8C5_2P0_254
&17 SP-9C5_7P0_254
&18 C3_175N-A
&19 E-C40SM100PM5-G
&20 C10N
&21 C3_3N
&22 C4_5N-B
&23 C4N-B
&24 C3_5N
&25 O5X3_5N
&26 C3N
&27 C1_3N
&28 C2_35N
&29 C1N
&30 SHEET
&31 TITLE
&32 SCALE 1:1
&33 LAYER
&34 OF
&35 ART
&36 SOLDER MASK (BOT)
&37 1
&38 -
&39 Barreleye G2 SXM2-Riser
&40 A1
&41 DATE OCT/27/2017

#
#Layer features
#
P 7.82853996 4.528 24 P 0 0;1,4=0,6=0
P 7.785 4.45 6 P 0 0;2,4=1,6=1
P 9.11353996 4.542 24 P 0 0;1,4=0,6=0
P 7.88353996 4.528 24 P 0 0;1,4=0,6=0
P 7.835 4.45 6 P 0 0;2,4=1,6=1
P 9.16353996 4.542 24 P 0 0;1,4=0,6=0
P 1.8 4.485 6 P 0 0;2,4=1,6=1
P 1.825 4.528 24 P 0 0;1,4=0,6=0
P 3.11 4.542 24 P 0 0;1,4=0,6=0
P 1.86 4.485 6 P 0 0;2,4=1,6=1
P 1.88 4.528 24 P 0 0;1,4=0,6=0
P 3.16 4.542 24 P 0 0;1,4=0,6=0
P 0.27165 1.72835 7 P 0 0;2,4=2,6=0
P 0.17323002 2.12205 7 P 0 0;2,4=2,6=0
P 12.73621004 1.76771998 7 P 0 0;2,4=2,6=0
P 12.81495 2.59448996 7 P 0 0;2,4=2,6=0
P 12.63778996 2.16141998 7 P 0 0;2,4=2,6=0
P 0.725 -0.25 7 P 0 0;2,4=3,6=0
P 0.875 -0.25 7 P 0 0;2,4=3,6=0
P 1.065 6.26 7 P 0 0;2,4=3,6=0
P 1.065 6.36 7 P 0 0;2,4=3,6=0
P 1.29 6.26 7 P 0 0;2,4=3,6=0
P 1.29 6.36 7 P 0 0;2,4=3,6=0
P 1.515 6.26 7 P 0 0;2,4=3,6=0
P 1.515 6.36 7 P 0 0;2,4=3,6=0
P 0.84 6.26 7 P 0 0;2,4=3,6=0
P 0.84 6.36 7 P 0 0;2,4=3,6=0
P 1.74 6.26 7 P 0 0;2,4=3,6=0
P 1.74 6.36 7 P 0 0;2,4=3,6=0
P 1.857 3.61 24 P 0 0;1,4=0,6=0
P 2.09606004 3.56615 3 P 0 0;4=4,6=1
P 1.9 3.61 6 P 0 0;2,4=5,6=1
P 7.86093996 3.61 24 P 0 0;1,4=0,6=0
P 7.90393996 3.61 6 P 0 0;2,4=5,6=1
P 8.1 3.56615 3 P 0 0;4=4,6=1
P 12.55905 3.38188996 7 P 0 0;2,4=2,6=0
P 12.81495 4.64173996 7 P 0 0;2,4=2,6=0
P 12.81495 1.88583002 7 P 0 0;2,4=2,6=0
P 0.35038996 4.60236998 7 P 0 0;2,4=2,6=0
P 0.35038996 2.55511998 7 P 0 0;2,4=2,6=0
P 0.35038996 1.84646004 7 P 0 0;2,4=2,6=0
P 0.09448996 3.34251998 7 P 0 0;2,4=2,6=0
P 6.38348996 4.99705 24 P 0 0;1,4=0,6=0
P 6.42418996 4.99705 24 P 0 0;1,4=0,6=0
P 6.385 5.03 4 P 0 0;4=6,6=1
P 6.415 4.955 6 P 0 0;2,4=5,6=1
P 12.68701998 0.97243996 14 P 0 0;4=7
P 0.22245 0.93306998 14 P 0 0;4=7
P 12.68701004 4.91338002 14 P 0 0;4=7
P 3.94 4.545 6 P 0 0;2,4=1,6=1
P 4.91 5.375 4 P 0 0;4=6,6=1
P 1.08 5.85 6 P 0 0;2,4=1,6=1
P 3.6817 5.74 4 P 0 0;4=6,6=1
P 10.03813996 2.87558996 29 P 0 0;1,4=8,6=0
P 10.099 2.88 24 P 0 0;1,4=0,6=0
P 10.099 2.928 24 P 0 0;1,4=0,6=0
P 10.07 2.928 4 P 0 0;4=6,6=1
P 4.105 4.985 6 P 0 0;2,4=1,6=1
P 4.05686004 2.65 24 P 0 0;1,4=0,6=0
P 3.99421004 2.64558996 29 P 0 0;1,4=8,6=0
P 4.057 2.7 24 P 0 0;1,4=0,6=0
P 4.125 2.725 4 P 0 0;4=6,6=1
P 4.02 4.355 6 P 0 0;2,4=1,6=1
P 1.16 5.85 6 P 0 0;2,4=1,6=1
P 3.815 5.815 4 P 0 0;4=6,6=1
P 1.19 6.36 25 P 0 0;2,4=9,6=0
P 1.19 6.26 25 P 0 0;4=9,6=0
P 1.415 6.36 25 P 0 0;4=9,6=0
P 1.415 6.26 25 P 0 0;4=9,6=0
P 1.64 6.36 25 P 0 0;4=9,6=0
P 1.64 6.26 25 P 0 0;4=9,6=0
P 0.965 6.26 25 P 0 0;4=9,6=0
P 0.965 6.36 25 P 0 0;4=9,6=0
P 0.74 6.26 25 P 0 0;4=9,6=0
P 0.74 6.36 25 P 0 0;2,4=9,6=0
P 12.33998996 1.3061 24 P 0 0;1,4=0,6=0
P 12.63778996 1.37401998 25 P 0 0;2,4=10,6=0
P 0.17323002 1.33465 25 P 0 0;2,4=10,6=0
P 0.58298996 1.3381 24 P 0 0;1,4=0,6=0
P 6.501 5.017 6 P 0 0;2,4=1,6=1
P 6.45818996 4.99705 24 P 0 0;1,4=0,6=0
P 7.82693996 3.61 24 P 0 0;1,4=0,6=0
P 7.425 3.43 6 P 0 0;2,4=1,6=1
P 7.445 1.705 4 P 0 0;4=6,6=1
P 11.03661004 3.81615 3 P 0 0;4=4,6=1
P 11.135 2.845 4 P 0 0;4=6,6=1
P 11.03661004 2.16615 3 P 0 0;4=4,6=1
P 3.8899 4.765 6 P 0 0;2,4=1,6=1
P 4.93268002 2.41615 3 P 0 0;4=4,6=1
P 5.46358002 2.6305 24 P 0 0;1,4=0,6=0
P 4.93268002 2.46615 3 P 0 0;4=4,6=1
P 5.46358002 2.6755 24 P 0 0;1,4=0,6=0
P 7.2926 5.04351004 6 P 0 0;2,4=1,6=1
P 7.3226 4.97551004 24 P 0 0;1,4=0,6=0
P 7.2426 5.04351004 6 P 0 0;2,4=1,6=1
P 7.2726 4.97551004 24 P 0 0;1,4=0,6=0
P 3.38146004 5.298 24 P 0 0;1,4=0,6=0
P 3.33646004 5.298 24 P 0 0;1,4=0,6=0
P 3.45646004 5.3 6 P 0 0;2,4=1,6=1
P 1.28906004 5.04351004 6 P 0 0;2,4=1,6=1
P 1.31906004 4.97551004 24 P 0 0;1,4=0,6=0
P 1.23906004 5.04351004 6 P 0 0;2,4=1,6=1
P 1.26906004 4.97551004 24 P 0 0;1,4=0,6=0
P 9.385 5.298 24 P 0 0;1,4=0,6=0
P 9.34 5.298 24 P 0 0;1,4=0,6=0
P 9.46 5.3 6 P 0 0;2,4=1,6=1
P 4.68268002 2.36615 3 P 0 0;4=4,6=1
P 0.27165 4.01181004 7 P 0 0;2,4=2,6=0
P 4.58268002 2.36615 3 P 0 0;4=4,6=1
P 0.27165 4.16928996 7 P 0 0;2,4=2,6=0
P 4.63268002 2.41615 3 P 0 0;4=4,6=1
P 0.27165 4.32676998 7 P 0 0;2,4=2,6=0
P 4.73268002 2.26615 3 P 0 0;4=4,6=1
P 0.27165 3.38188996 7 P 0 0;2,4=2,6=0
P 4.73268002 2.41615 3 P 0 0;4=4,6=1
P 0.27165 4.48425 7 P 0 0;2,4=2,6=0
P 4.68268002 2.21615 3 P 0 0;4=4,6=1
P 0.27165 3.53936998 7 P 0 0;2,4=2,6=0
P 4.63268002 2.26615 3 P 0 0;4=4,6=1
P 0.27165 3.85433002 7 P 0 0;2,4=2,6=0
P 4.58268002 2.06615 3 P 0 0;4=4,6=1
P 0.35038996 3.02756004 7 P 0 0;2,4=2,6=0
P 4.58268002 2.11615 3 P 0 0;4=4,6=1
P 0.27165 2.98818996 7 P 0 0;2,4=2,6=0
P 4.63268002 1.86615 3 P 0 0;4=4,6=1
P 0.35038996 2.3189 7 P 0 0;2,4=2,6=0
P 4.58268002 1.96615 3 P 0 0;4=4,6=1
P 0.27165 2.43701004 7 P 0 0;2,4=2,6=0
P 4.68268002 2.06615 3 P 0 0;4=4,6=1
P 0.35038996 3.18503996 7 P 0 0;2,4=2,6=0
P 4.58268002 1.91615 3 P 0 0;4=4,6=1
P 0.35038996 2.47638002 7 P 0 0;2,4=2,6=0
P 0.27165 2.27953002 7 P 0 0;2,4=2,6=0
P 4.63268002 1.91615 3 P 0 0;4=4,6=1
P 5.42048002 1.7396 3 P 0 0;4=4,6=1
P 5.34275 1.7371 24 P 0 0;1,4=0,6=0
P 0.09448996 2.55511998 7 P 0 0;2,4=2,6=0
P 4.68268002 2.11615 3 P 0 0;4=4,6=1
P 0.27165 3.14566998 7 P 0 0;2,4=2,6=0
P 5.42048002 1.7796 3 P 0 0;4=4,6=1
P 5.34275 1.7821 24 P 0 0;1,4=0,6=0
P 0.17323002 2.51575 7 P 0 0;2,4=2,6=0
P 4.68268002 1.91615 3 P 0 0;4=4,6=1
P 0.35038996 2.16141998 7 P 0 0;2,4=2,6=0
P 4.68268002 1.96615 3 P 0 0;4=4,6=1
P 0.27165 2.12205 7 P 0 0;2,4=2,6=0
P 5.49758002 2.0853 24 P 0 0;1,4=0,6=0
P 5.57531004 2.0878 3 P 0 0;4=4,6=1
P 0.09448996 3.1063 7 P 0 0;2,4=2,6=0
P 5.49758002 2.1303 24 P 0 0;1,4=0,6=0
P 5.57531004 2.1278 3 P 0 0;4=4,6=1
P 0.17323002 3.06693002 7 P 0 0;2,4=2,6=0
P 5.49758002 2.2207 24 P 0 0;1,4=0,6=0
P 5.57531004 2.2232 3 P 0 0;4=4,6=1
P 0.17323002 3.46063002 7 P 0 0;2,4=2,6=0
P 5.49758002 2.2657 24 P 0 0;1,4=0,6=0
P 5.57531004 2.2632 3 P 0 0;4=4,6=1
P 0.09448996 3.42126004 7 P 0 0;2,4=2,6=0
P 5.34275 2.4687 24 P 0 0;1,4=0,6=0
P 5.42048002 2.4662 3 P 0 0;4=4,6=1
P 0.09448996 4.05118002 7 P 0 0;2,4=2,6=0
P 5.49758002 2.4011 24 P 0 0;1,4=0,6=0
P 5.57531004 2.3986 3 P 0 0;4=4,6=1
P 0.09448996 3.8937 7 P 0 0;2,4=2,6=0
P 5.49758002 2.6755 24 P 0 0;1,4=0,6=0
P 5.57531004 2.673 3 P 0 0;4=4,6=1
P 0.09448996 4.36613996 7 P 0 0;2,4=2,6=0
P 5.49758002 1.9894 24 P 0 0;1,4=0,6=0
P 5.57531004 1.9869 3 P 0 0;4=4,6=1
P 0.17323002 2.75196998 7 P 0 0;2,4=2,6=0
P 5.49758002 2.4953 24 P 0 0;1,4=0,6=0
P 5.57531004 2.4978 3 P 0 0;4=4,6=1
P 0.17323002 4.24803002 7 P 0 0;2,4=2,6=0
P 5.57531004 1.6718 3 P 0 0;4=4,6=1
P 5.49758002 1.6693 24 P 0 0;1,4=0,6=0
P 0.17323002 2.20078996 7 P 0 0;2,4=2,6=0
P 5.49758002 2.6305 24 P 0 0;1,4=0,6=0
P 5.57531004 2.633 3 P 0 0;4=4,6=1
P 0.17323002 4.40551004 7 P 0 0;2,4=2,6=0
P 5.57531004 1.7118 3 P 0 0;4=4,6=1
P 5.49758002 1.7143 24 P 0 0;1,4=0,6=0
P 0.09448996 2.24016004 7 P 0 0;2,4=2,6=0
P 5.49758002 2.5403 24 P 0 0;1,4=0,6=0
P 5.57531004 2.5378 3 P 0 0;4=4,6=1
P 0.09448996 4.20866004 7 P 0 0;2,4=2,6=0
P 5.42048002 1.6433 3 P 0 0;4=4,6=1
P 5.34275 1.6458 24 P 0 0;1,4=0,6=0
P 0.09448996 2.39763996 7 P 0 0;2,4=2,6=0
P 5.34275 2.6079 24 P 0 0;1,4=0,6=0
P 5.42048002 2.6054 3 P 0 0;4=4,6=1
P 0.09448996 4.52361998 7 P 0 0;2,4=2,6=0
P 5.34275 1.8768 24 P 0 0;1,4=0,6=0
P 5.42048002 1.87835 3 P 0 0;4=4,6=1
P 0.09448996 2.94881998 7 P 0 0;2,4=2,6=0
P 5.49758002 2.3561 24 P 0 0;1,4=0,6=0
P 5.57531004 2.3586 3 P 0 0;4=4,6=1
P 0.17323002 3.93306998 7 P 0 0;2,4=2,6=0
P 5.42048002 1.6033 3 P 0 0;4=4,6=1
P 5.34275 1.6008 24 P 0 0;1,4=0,6=0
P 0.17323002 2.35826998 7 P 0 0;2,4=2,6=0
P 5.34275 2.4237 24 P 0 0;1,4=0,6=0
P 5.42048002 2.4262 3 P 0 0;4=4,6=1
P 0.17323002 4.09055 7 P 0 0;2,4=2,6=0
P 5.34275 1.9218 24 P 0 0;1,4=0,6=0
P 5.42048002 1.91835 3 P 0 0;4=4,6=1
P 0.17323002 2.90945 7 P 0 0;2,4=2,6=0
P 5.34275 2.0572 24 P 0 0;1,4=0,6=0
P 5.42048002 2.0547 3 P 0 0;4=4,6=1
P 0.17323002 3.22441004 7 P 0 0;2,4=2,6=0
P 5.49758002 1.9444 24 P 0 0;1,4=0,6=0
P 5.57531004 1.9469 3 P 0 0;4=4,6=1
P 0.09448996 2.79133996 7 P 0 0;2,4=2,6=0
P 5.34275 2.0122 24 P 0 0;1,4=0,6=0
P 5.42048002 2.0147 3 P 0 0;4=4,6=1
P 0.09448996 3.26378002 7 P 0 0;2,4=2,6=0
P 5.57531004 1.8508 3 P 0 0;4=4,6=1
P 5.49758002 1.8533 24 P 0 0;1,4=0,6=0
P 0.09448996 2.00393996 7 P 0 0;2,4=2,6=0
P 5.57531004 1.8108 3 P 0 0;4=4,6=1
P 5.49758002 1.8083 24 P 0 0;1,4=0,6=0
P 0.17323002 2.04331004 7 P 0 0;2,4=2,6=0
P 0.35038996 3.97243996 7 P 0 0;2,4=2,6=0
P 4.68268002 2.41615 3 P 0 0;4=4,6=1
P 4.73268002 2.46615 3 P 0 0;4=4,6=1
P 0.35038996 4.44488002 7 P 0 0;2,4=2,6=0
P 4.63268002 2.46615 3 P 0 0;4=4,6=1
P 0.35038996 4.2874 7 P 0 0;2,4=2,6=0
P 0.35038996 4.12991998 7 P 0 0;2,4=2,6=0
P 4.58268002 2.41615 3 P 0 0;4=4,6=1
P 4.68268002 2.26615 3 P 0 0;4=4,6=1
P 0.35038996 3.5 7 P 0 0;2,4=2,6=0
P 5.34275 2.1529 24 P 0 0;1,4=0,6=0
P 5.42048002 2.1554 3 P 0 0;4=4,6=1
P 0.17323002 3.77558996 7 P 0 0;2,4=2,6=0
P 4.73268002 2.31615 3 P 0 0;4=4,6=1
P 0.35038996 3.34251998 7 P 0 0;2,4=2,6=0
P 4.63268002 2.31615 3 P 0 0;4=4,6=1
P 0.35038996 3.81496004 7 P 0 0;2,4=2,6=0
P 4.58268002 2.26615 3 P 0 0;4=4,6=1
P 0.35038996 3.65748002 7 P 0 0;2,4=2,6=0
P 5.34275 2.5629 24 P 0 0;1,4=0,6=0
P 5.42048002 2.5654 3 P 0 0;4=4,6=1
P 0.17323002 4.563 7 P 0 0;2,4=2,6=0
P 5.34275 2.1979 24 P 0 0;1,4=0,6=0
P 5.42048002 2.1954 3 P 0 0;4=4,6=1
P 0.09448996 3.73621998 7 P 0 0;2,4=2,6=0
P 0.09448996 3.57873996 7 P 0 0;2,4=2,6=0
P 5.42048002 2.3308 3 P 0 0;4=4,6=1
P 5.34275 2.3333 24 P 0 0;1,4=0,6=0
P 0.17323002 3.61811004 7 P 0 0;2,4=2,6=0
P 5.42048002 2.2908 3 P 0 0;4=4,6=1
P 5.34275 2.2883 24 P 0 0;1,4=0,6=0
P 0.35038996 1.9252 7 P 0 0;2,4=2,6=0
P 4.73268002 1.91615 3 P 0 0;4=4,6=1
P 4.73268002 1.86615 3 P 0 0;4=4,6=1
P 0.27165 1.96456998 7 P 0 0;2,4=2,6=0
P 4.58268002 2.21615 3 P 0 0;4=4,6=1
P 0.27165 3.69685 7 P 0 0;2,4=2,6=0
P 4.73268002 2.06615 3 P 0 0;4=4,6=1
P 0.27165 2.67323002 7 P 0 0;2,4=2,6=0
P 4.73268002 2.01615 3 P 0 0;4=4,6=1
P 0.35038996 2.7126 7 P 0 0;2,4=2,6=0
P 4.63268002 2.01615 3 P 0 0;4=4,6=1
P 0.35038996 2.87008002 7 P 0 0;2,4=2,6=0
P 4.63268002 2.06615 3 P 0 0;4=4,6=1
P 0.27165 2.83071004 7 P 0 0;2,4=2,6=0
P 6.785 4.725 4 P 0 0;4=6,6=1
P 6.785 4.685 4 P 0 0;4=6,6=1
P 6.74018996 4.765 4 P 0 0;4=6,6=1
P 6.74 4.805 6 P 0 0;2,4=1,6=1
P 6.785 4.845 4 P 0 0;4=6,6=1
P 6.785 4.805 4 P 0 0;4=6,6=1
P 6.785 4.765 4 P 0 0;4=6,6=1
P 6.74 4.845 4 P 0 0;4=6,6=1
P 6.83118996 4.73868002 26 P 0 0;1,4=11,6=0
P 6.74208996 4.6252 26 P 0 0;1,4=11,6=0
P 6.74208996 4.7052 26 P 0 0;1,4=11,6=0
P 6.83118996 4.81705 26 P 0 0;1,4=11,6=0
P 6.83318996 4.89705 24 P 0 0;1,4=0,6=0
P 6.65 5.055 6 P 0 0;2,4=1,6=1
P 6.53918996 5.09705 24 P 0 0;1,4=0,6=0
P 6.49205 5.09705 6 P 0 0;2,4=1,6=1
P 6.45818996 5.04705 24 P 0 0;1,4=0,6=0
P 6.495 4.9328 6 P 0 0;2,4=1,6=1
P 6.57418996 4.99705 24 P 0 0;1,4=0,6=0
P 6.55118996 5.04705 6 P 0 0;2,4=1,6=1
P 6.65418996 4.99705 24 P 0 0;1,4=0,6=0
P 6.60818996 4.99705 24 P 0 0;1,4=0,6=0
P 6.78 4.94705 6 P 0 0;2,4=1,6=1
P 6.755 4.89705 6 P 0 0;2,4=1,6=1
P 6.79918996 4.89705 24 P 0 0;1,4=0,6=0
P 6.74 4.987 6 P 0 0;2,4=1,6=1
P 6.68818996 4.99705 24 P 0 0;1,4=0,6=0
P 6.803 5 24 P 0 0;1,4=0,6=0
P 12.33998996 1.3401 24 P 0 0;1,4=0,6=0
P 12.34198002 2.155 24 P 0 0;1,4=0,6=0
P 12.73621004 2.08268002 7 P 0 0;2,4=2,6=0
P 12.73621004 2.63386004 7 P 0 0;4=2,6=0
P 12.81495 3.30315 7 P 0 0;4=2,6=0
P 12.73621004 4.60236998 7 P 0 0;4=2,6=0
P 12.33901004 1.93958996 24 P 0 0;1,4=0,6=0
P 12.55905 1.96456998 7 P 0 0;2,4=2,6=0
P 12.33901004 1.98958996 24 P 0 0;1,4=0,6=0
P 12.63778996 1.9252 7 P 0 0;2,4=2,6=0
P 0.09448996 1.9252 7 P 0 0;2,4=2,6=0
P 0.58298996 1.91181998 24 P 0 0;1,4=0,6=0
P 0.17323002 1.88583002 7 P 0 0;2,4=2,6=0
P 0.58298996 1.86181998 24 P 0 0;1,4=0,6=0
P 0.61698996 1.3381 24 P 0 0;1,4=0,6=0
P 0.58298002 2.045 24 P 0 0;1,4=0,6=0
P 0.27165 2.04331004 7 P 0 0;2,4=2,6=0
P 0.27165 4.563 7 P 0 0;4=2,6=0
P 0.35038996 3.26378002 7 P 0 0;4=2,6=0
P 0.27165 2.59448996 7 P 0 0;4=2,6=0
P 0.58298002 1.655 24 P 0 0;1,4=0,6=0
P 0.17323002 1.72835 7 P 0 0;2,4=2,6=0
P 5.03268002 1.91615 3 P 0 0;4=4,6=1
P 5.46358002 1.6693 24 P 0 0;1,4=0,6=0
P 1.025 -0.25 7 P 0 0;2,4=3,6=0
P 1.175 -0.25 7 P 0 0;2,4=3,6=0
P 1.325 -0.25 7 P 0 0;2,4=3,6=0
P 5.03268002 2.06615 3 P 0 0;4=4,6=1
P 5.46358002 1.9894 24 P 0 0;1,4=0,6=0
P 12.63778996 4.12991998 7 P 0 0;2,4=2,6=0
P 11.53316004 2.372 3 P 0 0;4=4,6=1
P 11.45593002 2.37 24 P 0 0;1,4=0,6=0
P 5.08268002 2.26615 3 P 0 0;4=4,6=1
P 5.46358002 2.2657 24 P 0 0;1,4=0,6=0
P 11.53316004 1.892 3 P 0 0;4=4,6=1
P 11.45593002 1.89 24 P 0 0;1,4=0,6=0
P 12.55905 3.30315 7 P 0 0;2,4=2,6=0
P 12.81495 2.51575 7 P 0 0;2,4=2,6=0
P 10.58661004 1.91615 3 P 0 0;4=4,6=1
P 10.26 1.66445 3 P 0 0;4=4,6=1
P 11.03998996 4.8431 4 P 0 0;4=6,6=1
P 11.08498996 4.8431 4 P 0 0;4=6,6=1
P 11.13498996 4.8431 4 P 0 0;4=6,6=1
P 11.17998996 4.8431 4 P 0 0;4=6,6=1
P 11.17998996 4.8031 4 P 0 0;4=6,6=1
P 11.17998996 4.7581 4 P 0 0;4=6,6=1
P 11.17998996 4.7131 4 P 0 0;4=6,6=1
P 11.17998996 4.6731 4 P 0 0;4=6,6=1
P 11.03998996 4.6731 4 P 0 0;4=6,6=1
P 11.08498996 4.6731 4 P 0 0;4=6,6=1
P 11.13498996 4.6731 4 P 0 0;4=6,6=1
P 11.03998996 4.7131 4 P 0 0;4=6,6=1
P 11.03998996 4.8031 4 P 0 0;4=6,6=1
P 11.03998996 4.7581 4 P 0 0;4=6,6=1
P 10.81998996 4.6631 4 P 0 0;4=6,6=1
P 10.85998996 4.6631 4 P 0 0;4=6,6=1
P 10.65998996 4.6631 4 P 0 0;4=6,6=1
P 10.69998996 4.6631 4 P 0 0;4=6,6=1
P 10.81998996 4.7031 4 P 0 0;4=6,6=1
P 10.81998996 4.8381 4 P 0 0;4=6,6=1
P 10.81998996 4.7931 4 P 0 0;4=6,6=1
P 10.81998996 4.7481 4 P 0 0;4=6,6=1
P 10.85998996 4.7031 4 P 0 0;4=6,6=1
P 10.85998996 4.8381 4 P 0 0;4=6,6=1
P 10.85998996 4.7931 4 P 0 0;4=6,6=1
P 10.85998996 4.7481 4 P 0 0;4=6,6=1
P 10.65998996 4.7031 4 P 0 0;4=6,6=1
P 10.65998996 4.8381 4 P 0 0;4=6,6=1
P 10.65998996 4.7931 4 P 0 0;4=6,6=1
P 10.65998996 4.7481 4 P 0 0;4=6,6=1
P 10.69998996 4.7031 4 P 0 0;4=6,6=1
P 10.69998996 4.8381 4 P 0 0;4=6,6=1
P 10.69998996 4.7931 4 P 0 0;4=6,6=1
P 10.69998996 4.7481 4 P 0 0;4=6,6=1
P 10.77998996 4.6431 4 P 0 0;4=6,6=1
P 10.73498996 4.6431 4 P 0 0;4=6,6=1
P 10.73998996 4.8381 4 P 0 0;4=6,6=1
P 10.77998996 4.8381 4 P 0 0;4=6,6=1
P 10.30998996 4.6631 4 P 0 0;4=6,6=1
P 10.26998996 4.6631 4 P 0 0;4=6,6=1
P 10.34498996 4.6431 4 P 0 0;4=6,6=1
P 10.38998996 4.6431 4 P 0 0;4=6,6=1
P 10.42998996 4.6631 4 P 0 0;4=6,6=1
P 10.46998996 4.6631 4 P 0 0;4=6,6=1
P 10.30998996 4.7481 4 P 0 0;4=6,6=1
P 10.30998996 4.7931 4 P 0 0;4=6,6=1
P 10.30998996 4.7031 4 P 0 0;4=6,6=1
P 10.26998996 4.7481 4 P 0 0;4=6,6=1
P 10.26998996 4.7931 4 P 0 0;4=6,6=1
P 10.26998996 4.7031 4 P 0 0;4=6,6=1
P 10.26998996 4.8381 4 P 0 0;4=6,6=1
P 10.30998996 4.8381 4 P 0 0;4=6,6=1
P 10.38998996 4.8381 4 P 0 0;4=6,6=1
P 10.34998996 4.8381 4 P 0 0;4=6,6=1
P 10.46998996 4.8381 4 P 0 0;4=6,6=1
P 10.42998996 4.8381 4 P 0 0;4=6,6=1
P 10.42998996 4.7031 4 P 0 0;4=6,6=1
P 10.42998996 4.7931 4 P 0 0;4=6,6=1
P 10.42998996 4.7481 4 P 0 0;4=6,6=1
P 10.46998996 4.7031 4 P 0 0;4=6,6=1
P 10.46998996 4.7931 4 P 0 0;4=6,6=1
P 10.46998996 4.7481 4 P 0 0;4=6,6=1
P 10.58661004 3.16615 3 P 0 0;4=4,6=1
P 10.63661004 3.01615 3 P 0 0;4=4,6=1
P 10.58661004 3.11615 3 P 0 0;4=4,6=1
P 10.58661004 3.01615 3 P 0 0;4=4,6=1
P 10.63661004 3.11615 3 P 0 0;4=4,6=1
P 10.63661004 2.96615 3 P 0 0;4=4,6=1
P 10.58661004 2.96615 3 P 0 0;4=4,6=1
P 10.58661004 3.41615 3 P 0 0;4=4,6=1
P 10.63661004 3.16615 3 P 0 0;4=4,6=1
P 10.63661004 3.26615 3 P 0 0;4=4,6=1
P 10.58661004 3.31615 3 P 0 0;4=4,6=1
P 10.58661004 3.26615 3 P 0 0;4=4,6=1
P 10.63661004 3.31615 3 P 0 0;4=4,6=1
P 10.63661004 3.56615 3 P 0 0;4=4,6=1
P 10.63661004 3.61615 3 P 0 0;4=4,6=1
P 10.58661004 3.56615 3 P 0 0;4=4,6=1
P 10.58661004 3.61615 3 P 0 0;4=4,6=1
P 10.63661004 3.46615 3 P 0 0;4=4,6=1
P 10.63661004 3.41615 3 P 0 0;4=4,6=1
P 10.58661004 3.46615 3 P 0 0;4=4,6=1
P 10.63661004 3.86615 3 P 0 0;4=4,6=1
P 10.63661004 3.76615 3 P 0 0;4=4,6=1
P 10.58661004 3.86615 3 P 0 0;4=4,6=1
P 10.58661004 3.76615 3 P 0 0;4=4,6=1
P 10.63661004 3.71615 3 P 0 0;4=4,6=1
P 10.58661004 3.71615 3 P 0 0;4=4,6=1
P 10.88661004 2.96615 3 P 0 0;4=4,6=1
P 10.83661004 2.96615 3 P 0 0;4=4,6=1
P 10.88661004 3.01615 3 P 0 0;4=4,6=1
P 10.83661004 3.01615 3 P 0 0;4=4,6=1
P 10.88661004 3.11615 3 P 0 0;4=4,6=1
P 10.83661004 3.11615 3 P 0 0;4=4,6=1
P 10.83661004 3.16615 3 P 0 0;4=4,6=1
P 10.78661004 3.16615 3 P 0 0;4=4,6=1
P 10.68661004 3.16615 3 P 0 0;4=4,6=1
P 10.73661004 3.16615 3 P 0 0;4=4,6=1
P 10.78661004 3.01615 3 P 0 0;4=4,6=1
P 10.78661004 3.11615 3 P 0 0;4=4,6=1
P 10.73661004 3.01615 3 P 0 0;4=4,6=1
P 10.73661004 3.11615 3 P 0 0;4=4,6=1
P 10.68661004 3.01615 3 P 0 0;4=4,6=1
P 10.68661004 3.11615 3 P 0 0;4=4,6=1
P 10.78661004 2.96615 3 P 0 0;4=4,6=1
P 10.73661004 2.96615 3 P 0 0;4=4,6=1
P 10.68661004 2.96615 3 P 0 0;4=4,6=1
P 10.88661004 3.16615 3 P 0 0;4=4,6=1
P 10.88661004 3.26615 3 P 0 0;4=4,6=1
P 10.83661004 3.26615 3 P 0 0;4=4,6=1
P 10.83661004 3.31615 3 P 0 0;4=4,6=1
P 10.88661004 3.31615 3 P 0 0;4=4,6=1
P 10.83661004 3.41615 3 P 0 0;4=4,6=1
P 10.78661004 3.41615 3 P 0 0;4=4,6=1
P 10.68661004 3.41615 3 P 0 0;4=4,6=1
P 10.73661004 3.41615 3 P 0 0;4=4,6=1
P 10.78661004 3.31615 3 P 0 0;4=4,6=1
P 10.78661004 3.26615 3 P 0 0;4=4,6=1
P 10.68661004 3.31615 3 P 0 0;4=4,6=1
P 10.68661004 3.26615 3 P 0 0;4=4,6=1
P 10.73661004 3.26615 3 P 0 0;4=4,6=1
P 10.73661004 3.31615 3 P 0 0;4=4,6=1
P 10.88661004 3.41615 3 P 0 0;4=4,6=1
P 10.83661004 3.46615 3 P 0 0;4=4,6=1
P 10.88661004 3.46615 3 P 0 0;4=4,6=1
P 10.83661004 3.56615 3 P 0 0;4=4,6=1
P 10.88661004 3.56615 3 P 0 0;4=4,6=1
P 10.83661004 3.61615 3 P 0 0;4=4,6=1
P 10.88661004 3.61615 3 P 0 0;4=4,6=1
P 10.78661004 3.56615 3 P 0 0;4=4,6=1
P 10.78661004 3.61615 3 P 0 0;4=4,6=1
P 10.68661004 3.61615 3 P 0 0;4=4,6=1
P 10.68661004 3.56615 3 P 0 0;4=4,6=1
P 10.73661004 3.61615 3 P 0 0;4=4,6=1
P 10.73661004 3.56615 3 P 0 0;4=4,6=1
P 10.78661004 3.46615 3 P 0 0;4=4,6=1
P 10.73661004 3.46615 3 P 0 0;4=4,6=1
P 10.68661004 3.46615 3 P 0 0;4=4,6=1
P 10.83661004 3.71615 3 P 0 0;4=4,6=1
P 10.88661004 3.71615 3 P 0 0;4=4,6=1
P 10.83661004 3.76615 3 P 0 0;4=4,6=1
P 10.88661004 3.76615 3 P 0 0;4=4,6=1
P 10.83661004 3.86615 3 P 0 0;4=4,6=1
P 10.88661004 3.86615 3 P 0 0;4=4,6=1
P 10.78661004 3.86615 3 P 0 0;4=4,6=1
P 10.78661004 3.76615 3 P 0 0;4=4,6=1
P 10.68661004 3.86615 3 P 0 0;4=4,6=1
P 10.68661004 3.76615 3 P 0 0;4=4,6=1
P 10.73661004 3.86615 3 P 0 0;4=4,6=1
P 10.73661004 3.76615 3 P 0 0;4=4,6=1
P 10.78661004 3.71615 3 P 0 0;4=4,6=1
P 10.68661004 3.71615 3 P 0 0;4=4,6=1
P 10.73661004 3.71615 3 P 0 0;4=4,6=1
P 11.03661004 2.96615 3 P 0 0;4=4,6=1
P 10.93661004 2.96615 3 P 0 0;4=4,6=1
P 10.98661004 2.96615 3 P 0 0;4=4,6=1
P 11.03661004 3.01615 3 P 0 0;4=4,6=1
P 10.93661004 3.01615 3 P 0 0;4=4,6=1
P 10.98661004 3.01615 3 P 0 0;4=4,6=1
P 11.03661004 3.11615 3 P 0 0;4=4,6=1
P 10.93661004 3.11615 3 P 0 0;4=4,6=1
P 10.98661004 3.11615 3 P 0 0;4=4,6=1
P 11.03661004 3.16615 3 P 0 0;4=4,6=1
P 10.93661004 3.16615 3 P 0 0;4=4,6=1
P 10.98661004 3.16615 3 P 0 0;4=4,6=1
P 11.03661004 3.26615 3 P 0 0;4=4,6=1
P 10.93661004 3.26615 3 P 0 0;4=4,6=1
P 10.98661004 3.26615 3 P 0 0;4=4,6=1
P 10.98661004 3.31615 3 P 0 0;4=4,6=1
P 10.93661004 3.31615 3 P 0 0;4=4,6=1
P 11.03661004 3.31615 3 P 0 0;4=4,6=1
P 10.98661004 3.41615 3 P 0 0;4=4,6=1
P 10.93661004 3.41615 3 P 0 0;4=4,6=1
P 11.03661004 3.41615 3 P 0 0;4=4,6=1
P 10.98661004 3.46615 3 P 0 0;4=4,6=1
P 10.93661004 3.46615 3 P 0 0;4=4,6=1
P 11.03661004 3.46615 3 P 0 0;4=4,6=1
P 10.98661004 3.56615 3 P 0 0;4=4,6=1
P 10.93661004 3.56615 3 P 0 0;4=4,6=1
P 11.03661004 3.56615 3 P 0 0;4=4,6=1
P 10.98661004 3.61615 3 P 0 0;4=4,6=1
P 10.93661004 3.61615 3 P 0 0;4=4,6=1
P 11.03661004 3.61615 3 P 0 0;4=4,6=1
P 10.98661004 3.71615 3 P 0 0;4=4,6=1
P 10.93661004 3.71615 3 P 0 0;4=4,6=1
P 11.03661004 3.71615 3 P 0 0;4=4,6=1
P 10.98661004 3.76615 3 P 0 0;4=4,6=1
P 10.93661004 3.76615 3 P 0 0;4=4,6=1
P 11.03661004 3.76615 3 P 0 0;4=4,6=1
P 10.98661004 3.86615 3 P 0 0;4=4,6=1
P 10.93661004 3.86615 3 P 0 0;4=4,6=1
P 11.03661004 3.86615 3 P 0 0;4=4,6=1
P 10.41393996 4.21 6 P 0 0;2,4=5,6=1
P 5.08268002 2.06615 3 P 0 0;4=4,6=1
P 5.30875 2.0122 24 P 0 0;1,4=0,6=0
P 10.58661004 2.36615 3 P 0 0;4=4,6=1
P 9.975 2.4709 3 P 0 0;4=4,6=1
P 12.73621004 4.20866004 7 P 0 0;2,4=2,6=0
P 11.08661004 2.36615 3 P 0 0;4=4,6=1
P 11.42193002 2.37 24 P 0 0;1,4=0,6=0
P 5.08268002 2.11615 3 P 0 0;4=4,6=1
P 5.30875 2.0572 24 P 0 0;1,4=0,6=0
P 11.42193002 2.415 24 P 0 0;1,4=0,6=0
P 11.08661004 2.41615 3 P 0 0;4=4,6=1
P 12.73621004 2.47638002 7 P 0 0;2,4=2,6=0
P 10.58661004 1.96615 3 P 0 0;4=4,6=1
P 10.26 1.70445 3 P 0 0;4=4,6=1
P 11.62193002 2.495 24 P 0 0;1,4=0,6=0
P 10.98661004 2.41615 3 P 0 0;4=4,6=1
P 8.5 3.76615 3 P 0 0;4=4,6=1
P 9.35271004 5.1035 3 P 0 0;4=4,6=1
P 4.98268002 2.06615 3 P 0 0;4=4,6=1
P 5.46358002 2.0853 24 P 0 0;1,4=0,6=0
P 8.5 3.81615 3 P 0 0;4=4,6=1
P 9.31271004 5.1035 3 P 0 0;4=4,6=1
P 12.55905 2.59448996 7 P 0 0;2,4=2,6=0
P 11.53316004 1.572 3 P 0 0;4=4,6=1
P 11.45593002 1.57 24 P 0 0;1,4=0,6=0
P 4.98268002 2.11615 3 P 0 0;4=4,6=1
P 5.46358002 2.1303 24 P 0 0;1,4=0,6=0
P 10.98661004 2.36615 3 P 0 0;4=4,6=1
P 11.62193002 2.45 24 P 0 0;1,4=0,6=0
P 8.5 3.61615 3 P 0 0;4=4,6=1
P 9.56531004 5.14 3 P 0 0;4=4,6=1
P 4.93268002 2.01615 3 P 0 0;4=4,6=1
P 5.30875 1.8768 24 P 0 0;1,4=0,6=0
P 11.45593002 1.41 24 P 0 0;1,4=0,6=0
P 11.53316004 1.412 3 P 0 0;4=4,6=1
P 12.63778996 2.39763996 7 P 0 0;2,4=2,6=0
P 8.5 3.66615 3 P 0 0;4=4,6=1
P 9.52531004 5.14 3 P 0 0;4=4,6=1
P 11.80693002 2.87558996 29 P 0 0;1,4=8,6=0
P 12.308 2.11 24 P 0 0;1,4=0,6=0
P 11.875 2.885 6 P 0 0;2,4=5,6=1
P 12.73621004 2.87008002 7 P 0 0;2,4=2,6=0
P 10.63661004 2.06615 3 P 0 0;4=4,6=1
P 10.225 1.96645 3 P 0 0;4=4,6=1
P 11.53316004 1.452 3 P 0 0;4=4,6=1
P 11.45593002 1.455 24 P 0 0;1,4=0,6=0
P 12.55905 2.43701004 7 P 0 0;2,4=2,6=0
P 8.35 3.66615 3 P 0 0;4=4,6=1
P 9.56531004 4.71973002 3 P 0 0;4=4,6=1
P 4.93268002 2.06615 3 P 0 0;4=4,6=1
P 5.30875 1.9218 24 P 0 0;1,4=0,6=0
P 8.35 3.71615 3 P 0 0;4=4,6=1
P 9.52531004 4.71973002 3 P 0 0;4=4,6=1
P 11.83316004 2.212 3 P 0 0;4=4,6=1
P 11.45593002 2.21 24 P 0 0;1,4=0,6=0
P 12.63778996 3.65748002 7 P 0 0;2,4=2,6=0
P 12.73621004 3.02756004 7 P 0 0;2,4=2,6=0
P 10.58661004 2.11615 3 P 0 0;4=4,6=1
P 10.09 2.05655 3 P 0 0;4=4,6=1
P 11.53316004 1.932 3 P 0 0;4=4,6=1
P 11.45593002 1.935 24 P 0 0;1,4=0,6=0
P 12.63778996 3.26378002 7 P 0 0;2,4=2,6=0
P 8.74578996 5.14 3 P 0 0;4=4,6=1
P 8.05 3.61615 3 P 0 0;4=4,6=1
P 12.81495 4.01181004 7 P 0 0;2,4=2,6=0
P 10.09 2.57845 3 P 0 0;4=4,6=1
P 10.68661004 2.41615 3 P 0 0;4=4,6=1
P 11.73316004 1.492 3 P 0 0;4=4,6=1
P 11.65593002 1.49 24 P 0 0;1,4=0,6=0
P 12.63778996 2.24016004 7 P 0 0;2,4=2,6=0
P 8.78578996 5.14 3 P 0 0;4=4,6=1
P 8.05 3.66615 3 P 0 0;4=4,6=1
P 12.73621004 2.7126 7 P 0 0;2,4=2,6=0
P 10.73661004 2.06615 3 P 0 0;4=4,6=1
P 10.26025 1.86845 3 P 0 0;4=4,6=1
P 11.03661004 2.46615 3 P 0 0;4=4,6=1
P 11.42193002 2.53 24 P 0 0;1,4=0,6=0
P 8.15 3.61615 3 P 0 0;4=4,6=1
P 8.88441004 5.17001998 3 P 0 0;4=4,6=1
P 12.55905 4.09055 7 P 0 0;2,4=2,6=0
P 11.53316004 2.412 3 P 0 0;4=4,6=1
P 11.45593002 2.415 24 P 0 0;1,4=0,6=0
P 11.03661004 2.51615 3 P 0 0;4=4,6=1
P 11.42193002 2.575 24 P 0 0;1,4=0,6=0
P 8.15 3.66615 3 P 0 0;4=4,6=1
P 8.92441004 5.17001998 3 P 0 0;4=4,6=1
P 3.91351004 2.62 29 P 0 0;1,4=8,6=0
P 9.95743996 2.85 29 P 0 0;1,4=8,6=0
P 1.057 5.027 6 P 0 0;2,4=1,6=1
P 12.73621004 3.18503996 7 P 0 0;2,4=2,6=0
P 10.68661004 2.11615 3 P 0 0;4=4,6=1
P 10.09 2.17095 3 P 0 0;4=4,6=1
P 11.78316004 1.692 3 P 0 0;4=4,6=1
P 11.65593002 1.695 24 P 0 0;1,4=0,6=0
P 12.55905 2.04331004 7 P 0 0;2,4=2,6=0
P 12.81495 2.90945 7 P 0 0;2,4=2,6=0
P 10.63661004 2.01615 3 P 0 0;4=4,6=1
P 10.225 1.92645 3 P 0 0;4=4,6=1
P 11.78316004 1.652 3 P 0 0;4=4,6=1
P 11.65593002 1.65 24 P 0 0;1,4=0,6=0
P 12.63778996 2.08268002 7 P 0 0;2,4=2,6=0
P 1.122 5.417 4 P 0 0;4=6,6=1
P 5.6492 3 24 P 0 0;1,4=0,6=0
P 5.72185 3 29 P 0 0;1,4=8,6=0
P 5.855 0.925 4 P 0 0;4=6,6=1
P 3.88 4.545 6 P 0 0;2,4=1,6=1
P 0.96555 5.78055 6 P 0 0;2,4=1,6=1
P 4.07 4.625 4 P 0 0;4=6,6=1
P 10.58661004 2.71615 3 P 0 0;4=4,6=1
P 10.133 2.928 24 P 0 0;1,4=0,6=0
P 9.91 4.433 6 P 0 0;2,4=1,6=1
P 9.995 2.936 4 P 0 0;4=6,6=1
P 11.83316004 2.252 3 P 0 0;4=4,6=1
P 11.45593002 2.255 24 P 0 0;1,4=0,6=0
P 12.55905 3.61811004 7 P 0 0;2,4=2,6=0
P 12.81495 3.06693002 7 P 0 0;2,4=2,6=0
P 10.58661004 2.06615 3 P 0 0;4=4,6=1
P 10.09 2.01655 3 P 0 0;4=4,6=1
P 8.1 3.81615 3 P 0 0;4=4,6=1
P 9.10011004 5.0535 3 P 0 0;4=4,6=1
P 8.1 3.86615 3 P 0 0;4=4,6=1
P 9.14011004 5.0535 3 P 0 0;4=4,6=1
P 3.9599 5.395 6 P 0 0;2,4=1,6=1
P 0.88681004 5.78181004 4 P 0 0;4=6,6=1
P 12.73621004 2.3189 7 P 0 0;2,4=2,6=0
P 10.63661004 1.91615 3 P 0 0;4=4,6=1
P 10.38371998 1.49328002 3 P 0 0;4=4,6=1
P 8.35 3.81615 3 P 0 0;4=4,6=1
P 9.28185 5.22001998 3 P 0 0;4=4,6=1
P 0.72933002 5.463 6 P 0 0;2,4=1,6=1
P 11.53316004 2.572 3 P 0 0;4=4,6=1
P 11.45593002 2.575 24 P 0 0;1,4=0,6=0
P 12.55905 4.56298996 7 P 0 0;2,4=2,6=0
P 8.35 3.86615 3 P 0 0;4=4,6=1
P 9.24185 5.22001998 3 P 0 0;4=4,6=1
P 4.091 2.7 24 P 0 0;1,4=0,6=0
P 4.125 2.682 4 P 0 0;4=6,6=1
P 3.94 4.42 6 P 0 0;2,4=1,6=1
P 5.03 5.4 4 P 0 0;4=6,6=1
P 4.58268002 2.71615 3 P 0 0;4=4,6=1
P 8.45 3.81615 3 P 0 0;4=4,6=1
P 9.21098002 4.78291998 3 P 0 0;4=4,6=1
P 8.45 3.86615 3 P 0 0;4=4,6=1
P 9.17098002 4.78291998 3 P 0 0;4=4,6=1
P 3.75998996 0.24001004 6 P 0 0;2,4=1,6=1
P 9.55795 0.26133996 6 P 0 0;2,4=1,6=1
P 3.71203002 0.77535 4 P 0 0;4=6,6=1
P 3.70998996 0.7 4 P 0 0;4=6,6=1
P 9.50795 0.72133002 4 P 0 0;4=6,6=1
P 9.46795 0.82631998 4 P 0 0;4=6,6=1
P 3.99421004 2.59441004 29 P 0 0;1,4=8,6=0
P 4.09086004 2.65 24 P 0 0;1,4=0,6=0
P 4.05686004 2.59 24 P 0 0;1,4=0,6=0
P 4.02893002 2.59336998 4 P 0 0;4=6,6=1
P 11.35061998 2.73 24 P 0 0;1,4=0,6=0
P 11.395 2.725 6 P 0 0;2,4=1,6=1
P 11.35061998 2.8 24 P 0 0;1,4=0,6=0
P 11.395 2.8 4 P 0 0;4=6,6=1
P 11.61661998 2.905 24 P 0 0;1,4=0,6=0
P 11.58613002 2.905 4 P 0 0;4=6,6=1
P 11.61661998 2.785 24 P 0 0;1,4=0,6=0
P 11.58613002 2.785 4 P 0 0;4=6,6=1
P 1.33906004 4.60351004 6 P 0 0;2,4=1,6=1
P 3.67 4.45 4 P 0 0;4=6,6=1
P 3.72 4.545 4 P 0 0;4=6,6=1
P 5.37968996 2.8 4 P 0 0;4=6,6=1
P 5.34668996 2.8 24 P 0 0;1,4=0,6=0
P 5.387 2.725 6 P 0 0;2,4=1,6=1
P 5.34668996 2.73 24 P 0 0;1,4=0,6=0
P 5.61268996 2.785 24 P 0 0;1,4=0,6=0
P 5.5822 2.785 4 P 0 0;4=6,6=1
P 5.61268996 2.905 24 P 0 0;1,4=0,6=0
P 5.5822 2.905 4 P 0 0;4=6,6=1
P 7.2426 4.69351004 4 P 0 0;4=6,6=1
P 7.2926 4.60351004 4 P 0 0;4=6,6=1
P 9.98 4.51 4 P 0 0;4=6,6=1
P 10.133 2.88 24 P 0 0;1,4=0,6=0
P 10.07286004 2.82336998 4 P 0 0;4=6,6=1
P 10.03813996 2.82441004 29 P 0 0;1,4=8,6=0
P 10.10078996 2.82 24 P 0 0;1,4=0,6=0
P 10.03 4.61 4 P 0 0;4=6,6=1
P 1.23906004 4.69351004 4 P 0 0;4=6,6=1
P 3.89 4.655 4 P 0 0;4=6,6=1
P 3.9899 4.765 4 P 0 0;4=6,6=1
P 4.1049 4.86 4 P 0 0;4=6,6=1
P 4.0599 5.395 4 P 0 0;4=6,6=1
P 3.91 5.51 4 P 0 0;4=6,6=1
P 5.125 5.4 4 P 0 0;4=6,6=1
P 1.37925 5.78 4 P 0 0;4=6,6=1
P 1.45798996 5.78 4 P 0 0;4=6,6=1
P 1.42 5.78 4 P 0 0;4=6,6=1
P 1.335 5.78 4 P 0 0;4=6,6=1
P 12.63778996 2.55511998 7 P 0 0;2,4=2,6=0
P 11.53316004 1.612 3 P 0 0;4=4,6=1
P 11.45593002 1.615 24 P 0 0;1,4=0,6=0
P 8.4 3.76615 3 P 0 0;4=4,6=1
P 9.28185 4.642 3 P 0 0;4=4,6=1
P 12.73621004 4.36613996 7 P 0 0;2,4=2,6=0
P 10.63661004 2.41615 3 P 0 0;4=4,6=1
P 9.975 2.66445 3 P 0 0;4=4,6=1
P 8.4 3.81615 3 P 0 0;4=4,6=1
P 9.24185 4.642 3 P 0 0;4=4,6=1
P 11.53316004 2.532 3 P 0 0;4=4,6=1
P 11.45593002 2.53 24 P 0 0;1,4=0,6=0
P 12.63778996 4.60236998 7 P 0 0;2,4=2,6=0
P 8.45 3.66615 3 P 0 0;4=4,6=1
P 9.42358002 4.78291998 3 P 0 0;4=4,6=1
P 0.95951004 5.4595 6 P 0 0;2,4=1,6=1
P 8.45 3.71615 3 P 0 0;4=4,6=1
P 9.38358002 4.78291998 3 P 0 0;4=4,6=1
P 8.4 3.61615 3 P 0 0;4=4,6=1
P 9.49445 4.587 3 P 0 0;4=4,6=1
P 8.4 3.66615 3 P 0 0;4=4,6=1
P 9.45445 4.587 3 P 0 0;4=4,6=1
P 9.16353996 4.508 24 P 0 0;1,4=0,6=0
P 9.07353996 4.42 4 P 0 0;4=6,6=1
P 7.1926 5.15351004 6 P 0 0;2,4=1,6=1
P 8.1 3.66615 3 P 0 0;4=4,6=1
P 8.74578996 4.667 3 P 0 0;4=4,6=1
P 8.1 3.71615 3 P 0 0;4=4,6=1
P 8.78578996 4.667 3 P 0 0;4=4,6=1
P 8.2 3.66615 3 P 0 0;4=4,6=1
P 8.81665 4.78291998 3 P 0 0;4=4,6=1
P 8.2 3.71615 3 P 0 0;4=4,6=1
P 8.85665 4.78291998 3 P 0 0;4=4,6=1
P 8.05 3.76615 3 P 0 0;4=4,6=1
P 8.89061998 4.667 3 P 0 0;4=4,6=1
P 8.05 3.81615 3 P 0 0;4=4,6=1
P 8.93061998 4.667 3 P 0 0;4=4,6=1
P 9.02925 4.667 3 P 0 0;4=4,6=1
P 8.2 3.81615 3 P 0 0;4=4,6=1
P 9.06925 4.667 3 P 0 0;4=4,6=1
P 8.2 3.86615 3 P 0 0;4=4,6=1
P 5.31268996 2.73 24 P 0 0;1,4=0,6=0
P 5.42768996 2.73 24 P 0 0;1,4=0,6=0
P 4.68268002 2.71615 3 P 0 0;4=4,6=1
P 5.27 2.73 6 P 0 0;2,4=5,6=1
P 4.98268002 2.71615 3 P 0 0;4=4,6=1
P 5.31268996 2.8 24 P 0 0;1,4=0,6=0
P 5.42768996 2.8 24 P 0 0;1,4=0,6=0
P 5.27 2.8 6 P 0 0;2,4=5,6=1
P 1.85421004 2.4781 24 P 0 0;1,4=0,6=0
P 2.14606004 2.51615 3 P 0 0;4=4,6=1
P 1.9 2.48 6 P 0 0;2,4=5,6=1
P 8.45 3.41615 3 P 0 0;4=4,6=1
P 8.18811004 5.0535 3 P 0 0;4=4,6=1
P 1.823 3.61 24 P 0 0;1,4=0,6=0
P 5.03268002 3.81615 3 P 0 0;4=4,6=1
P 4.07408002 4.01978996 6 P 0 0;2,4=1,6=1
P 8.45 3.46615 3 P 0 0;4=4,6=1
P 8.14811004 5.0535 3 P 0 0;4=4,6=1
P 5.03268002 2.16615 3 P 0 0;4=4,6=1
P 3.9099 5.395 6 P 0 0;2,4=1,6=1
P 8.45 3.26615 3 P 0 0;4=4,6=1
P 8.40071004 5.115 3 P 0 0;4=4,6=1
P 8.45 3.31615 3 P 0 0;4=4,6=1
P 8.36071004 5.115 3 P 0 0;4=4,6=1
P 8.35 3.26615 3 P 0 0;4=4,6=1
P 8.40071004 4.742 3 P 0 0;4=4,6=1
P 8.35 3.31615 3 P 0 0;4=4,6=1
P 8.36071004 4.742 3 P 0 0;4=4,6=1
P 8.3 3.56615 3 P 0 0;4=4,6=1
P 7.86093996 3.51 24 P 0 0;1,4=0,6=0
P 7.90393996 3.51 6 P 0 0;2,4=5,6=1
P 8.05 3.31615 3 P 0 0;4=4,6=1
P 7.58118996 5.169 3 P 0 0;4=4,6=1
P 8.25 3.56615 3 P 0 0;4=4,6=1
P 7.90393996 3.56 6 P 0 0;2,4=5,6=1
P 7.86093996 3.56 24 P 0 0;1,4=0,6=0
P 8.05 3.36615 3 P 0 0;4=4,6=1
P 7.62118996 5.169 3 P 0 0;4=4,6=1
P 2.24606004 2.86615 3 P 0 0;4=4,6=1
P 2.63685 2.82 24 P 0 0;1,4=0,6=0
P 5.59 4.475 6 P 0 0;2,4=5,6=1
P 8.05 2.61615 3 P 0 0;4=4,6=1
P 8.05 2.66615 3 P 0 0;4=4,6=1
P 8.1 2.46615 3 P 0 0;4=4,6=1
P 8.1 2.41615 3 P 0 0;4=4,6=1
P 8.2 2.46615 3 P 0 0;4=4,6=1
P 8.2 2.41615 3 P 0 0;4=4,6=1
P 8.15 2.41615 3 P 0 0;4=4,6=1
P 8.15 2.36615 3 P 0 0;4=4,6=1
P 8.05 2.41615 3 P 0 0;4=4,6=1
P 8.05 2.36615 3 P 0 0;4=4,6=1
P 8.2 2.31615 3 P 0 0;4=4,6=1
P 8.2 2.26615 3 P 0 0;4=4,6=1
P 8.15 2.26615 3 P 0 0;4=4,6=1
P 8.15 2.21615 3 P 0 0;4=4,6=1
P 8.1 2.31615 3 P 0 0;4=4,6=1
P 8.1 2.26615 3 P 0 0;4=4,6=1
P 8.05 2.26615 3 P 0 0;4=4,6=1
P 8.05 2.21615 3 P 0 0;4=4,6=1
P 8.1 2.11615 3 P 0 0;4=4,6=1
P 8.1 2.06615 3 P 0 0;4=4,6=1
P 8.2 2.11615 3 P 0 0;4=4,6=1
P 8.2 2.06615 3 P 0 0;4=4,6=1
P 8.15 2.06615 3 P 0 0;4=4,6=1
P 8.15 2.01615 3 P 0 0;4=4,6=1
P 8.05 2.06615 3 P 0 0;4=4,6=1
P 8.05 2.01615 3 P 0 0;4=4,6=1
P 8.2 1.96615 3 P 0 0;4=4,6=1
P 8.2 1.91615 3 P 0 0;4=4,6=1
P 8.15 1.91615 3 P 0 0;4=4,6=1
P 8.15 1.86615 3 P 0 0;4=4,6=1
P 8.1 1.96615 3 P 0 0;4=4,6=1
P 8.1 1.91615 3 P 0 0;4=4,6=1
P 8.05 1.91615 3 P 0 0;4=4,6=1
P 8.05 1.86615 3 P 0 0;4=4,6=1
P 8.1 3.16615 3 P 0 0;4=4,6=1
P 8.1 3.11615 3 P 0 0;4=4,6=1
P 8.2 3.16615 3 P 0 0;4=4,6=1
P 8.2 3.11615 3 P 0 0;4=4,6=1
P 8.15 3.11615 3 P 0 0;4=4,6=1
P 8.15 3.06615 3 P 0 0;4=4,6=1
P 8.05 3.11615 3 P 0 0;4=4,6=1
P 8.05 3.06615 3 P 0 0;4=4,6=1
P 8.2 3.01615 3 P 0 0;4=4,6=1
P 8.2 2.96615 3 P 0 0;4=4,6=1
P 8.15 2.96615 3 P 0 0;4=4,6=1
P 8.15 2.91615 3 P 0 0;4=4,6=1
P 8.1 3.01615 3 P 0 0;4=4,6=1
P 8.1 2.96615 3 P 0 0;4=4,6=1
P 8.05 2.96615 3 P 0 0;4=4,6=1
P 8.05 2.91615 3 P 0 0;4=4,6=1
P 8 2.81615 3 P 0 0;4=4,6=1
P 8 2.76615 3 P 0 0;4=4,6=1
P 8.15 2.81615 3 P 0 0;4=4,6=1
P 8.15 2.76615 3 P 0 0;4=4,6=1
P 8.2 2.76615 3 P 0 0;4=4,6=1
P 8.2 2.71615 3 P 0 0;4=4,6=1
P 8.1 2.76615 3 P 0 0;4=4,6=1
P 8.1 2.71615 3 P 0 0;4=4,6=1
P 8.15 2.66615 3 P 0 0;4=4,6=1
P 8.15 2.61615 3 P 0 0;4=4,6=1
P 8.2 2.61615 3 P 0 0;4=4,6=1
P 8.2 2.56615 3 P 0 0;4=4,6=1
P 8.1 2.61615 3 P 0 0;4=4,6=1
P 8.1 2.56615 3 P 0 0;4=4,6=1
P 8.35 2.56615 3 P 0 0;4=4,6=1
P 8.35 2.61615 3 P 0 0;4=4,6=1
P 8.35 2.46615 3 P 0 0;4=4,6=1
P 8.35 2.41615 3 P 0 0;4=4,6=1
P 8.45 2.46615 3 P 0 0;4=4,6=1
P 8.45 2.41615 3 P 0 0;4=4,6=1
P 8.5 2.41615 3 P 0 0;4=4,6=1
P 8.5 2.36615 3 P 0 0;4=4,6=1
P 8.4 2.41615 3 P 0 0;4=4,6=1
P 8.4 2.36615 3 P 0 0;4=4,6=1
P 8.45 2.31615 3 P 0 0;4=4,6=1
P 8.45 2.26615 3 P 0 0;4=4,6=1
P 8.5 2.26615 3 P 0 0;4=4,6=1
P 8.5 2.21615 3 P 0 0;4=4,6=1
P 8.4 2.26615 3 P 0 0;4=4,6=1
P 8.4 2.21615 3 P 0 0;4=4,6=1
P 8.35 2.31615 3 P 0 0;4=4,6=1
P 8.35 2.26615 3 P 0 0;4=4,6=1
P 8.35 2.11615 3 P 0 0;4=4,6=1
P 8.35 2.06615 3 P 0 0;4=4,6=1
P 8.45 2.11615 3 P 0 0;4=4,6=1
P 8.45 2.06615 3 P 0 0;4=4,6=1
P 8.5 2.06615 3 P 0 0;4=4,6=1
P 8.5 2.01615 3 P 0 0;4=4,6=1
P 8.4 2.06615 3 P 0 0;4=4,6=1
P 8.4 2.01615 3 P 0 0;4=4,6=1
P 8.45 1.96615 3 P 0 0;4=4,6=1
P 8.45 1.91615 3 P 0 0;4=4,6=1
P 8.5 1.91615 3 P 0 0;4=4,6=1
P 8.5 1.86615 3 P 0 0;4=4,6=1
P 8.4 1.91615 3 P 0 0;4=4,6=1
P 8.4 1.86615 3 P 0 0;4=4,6=1
P 8.35 1.96615 3 P 0 0;4=4,6=1
P 8.35 1.91615 3 P 0 0;4=4,6=1
P 8.35 3.16615 3 P 0 0;4=4,6=1
P 8.35 3.11615 3 P 0 0;4=4,6=1
P 8.45 3.16615 3 P 0 0;4=4,6=1
P 8.45 3.11615 3 P 0 0;4=4,6=1
P 8.5 3.11615 3 P 0 0;4=4,6=1
P 8.5 3.06615 3 P 0 0;4=4,6=1
P 8.4 3.11615 3 P 0 0;4=4,6=1
P 8.4 3.06615 3 P 0 0;4=4,6=1
P 8.45 3.01615 3 P 0 0;4=4,6=1
P 8.45 2.96615 3 P 0 0;4=4,6=1
P 8.5 2.96615 3 P 0 0;4=4,6=1
P 8.5 2.91615 3 P 0 0;4=4,6=1
P 8.4 2.96615 3 P 0 0;4=4,6=1
P 8.4 2.91615 3 P 0 0;4=4,6=1
P 8.35 3.01615 3 P 0 0;4=4,6=1
P 8.35 2.96615 3 P 0 0;4=4,6=1
P 8.4 2.81615 3 P 0 0;4=4,6=1
P 8.4 2.76615 3 P 0 0;4=4,6=1
P 8.5 2.81615 3 P 0 0;4=4,6=1
P 8.5 2.76615 3 P 0 0;4=4,6=1
P 8.45 2.76615 3 P 0 0;4=4,6=1
P 8.45 2.71615 3 P 0 0;4=4,6=1
P 8.35 2.76615 3 P 0 0;4=4,6=1
P 8.35 2.71615 3 P 0 0;4=4,6=1
P 8.5 2.66615 3 P 0 0;4=4,6=1
P 8.5 2.61615 3 P 0 0;4=4,6=1
P 8.45 2.61615 3 P 0 0;4=4,6=1
P 8.45 2.56615 3 P 0 0;4=4,6=1
P 8.4 2.66615 3 P 0 0;4=4,6=1
P 8.4 2.61615 3 P 0 0;4=4,6=1
P 2.04606004 2.61615 3 P 0 0;4=4,6=1
P 2.04606004 2.66615 3 P 0 0;4=4,6=1
P 2.09606004 2.46615 3 P 0 0;4=4,6=1
P 2.09606004 2.41615 3 P 0 0;4=4,6=1
P 2.19606004 2.46615 3 P 0 0;4=4,6=1
P 2.19606004 2.41615 3 P 0 0;4=4,6=1
P 2.14606004 2.41615 3 P 0 0;4=4,6=1
P 2.14606004 2.36615 3 P 0 0;4=4,6=1
P 2.04606004 2.41615 3 P 0 0;4=4,6=1
P 2.04606004 2.36615 3 P 0 0;4=4,6=1
P 2.19606004 2.31615 3 P 0 0;4=4,6=1
P 2.19606004 2.26615 3 P 0 0;4=4,6=1
P 2.14606004 2.26615 3 P 0 0;4=4,6=1
P 2.14606004 2.21615 3 P 0 0;4=4,6=1
P 2.09606004 2.31615 3 P 0 0;4=4,6=1
P 2.09606004 2.26615 3 P 0 0;4=4,6=1
P 2.04606004 2.26615 3 P 0 0;4=4,6=1
P 2.04606004 2.21615 3 P 0 0;4=4,6=1
P 2.09606004 2.11615 3 P 0 0;4=4,6=1
P 2.09606004 2.06615 3 P 0 0;4=4,6=1
P 2.19606004 2.11615 3 P 0 0;4=4,6=1
P 2.19606004 2.06615 3 P 0 0;4=4,6=1
P 2.14606004 2.06615 3 P 0 0;4=4,6=1
P 2.14606004 2.01615 3 P 0 0;4=4,6=1
P 2.04606004 2.06615 3 P 0 0;4=4,6=1
P 2.04606004 2.01615 3 P 0 0;4=4,6=1
P 2.19606004 1.96615 3 P 0 0;4=4,6=1
P 2.19606004 1.91615 3 P 0 0;4=4,6=1
P 2.14606004 1.91615 3 P 0 0;4=4,6=1
P 2.14606004 1.86615 3 P 0 0;4=4,6=1
P 2.09606004 1.96615 3 P 0 0;4=4,6=1
P 2.09606004 1.91615 3 P 0 0;4=4,6=1
P 2.04606004 1.91615 3 P 0 0;4=4,6=1
P 2.04606004 1.86615 3 P 0 0;4=4,6=1
P 2.09606004 3.16615 3 P 0 0;4=4,6=1
P 2.09606004 3.11615 3 P 0 0;4=4,6=1
P 2.19606004 3.16615 3 P 0 0;4=4,6=1
P 2.19606004 3.11615 3 P 0 0;4=4,6=1
P 2.14606004 3.11615 3 P 0 0;4=4,6=1
P 2.14606004 3.06615 3 P 0 0;4=4,6=1
P 2.04606004 3.11615 3 P 0 0;4=4,6=1
P 2.04606004 3.06615 3 P 0 0;4=4,6=1
P 2.19606004 3.01615 3 P 0 0;4=4,6=1
P 2.19606004 2.96615 3 P 0 0;4=4,6=1
P 2.14606004 2.96615 3 P 0 0;4=4,6=1
P 2.14606004 2.91615 3 P 0 0;4=4,6=1
P 2.09606004 3.01615 3 P 0 0;4=4,6=1
P 2.09606004 2.96615 3 P 0 0;4=4,6=1
P 2.04606004 2.96615 3 P 0 0;4=4,6=1
P 2.04606004 2.91615 3 P 0 0;4=4,6=1
P 1.99606004 2.81615 3 P 0 0;4=4,6=1
P 1.99606004 2.76615 3 P 0 0;4=4,6=1
P 2.14606004 2.81615 3 P 0 0;4=4,6=1
P 2.14606004 2.76615 3 P 0 0;4=4,6=1
P 2.19606004 2.76615 3 P 0 0;4=4,6=1
P 2.19606004 2.71615 3 P 0 0;4=4,6=1
P 2.09606004 2.76615 3 P 0 0;4=4,6=1
P 2.09606004 2.71615 3 P 0 0;4=4,6=1
P 2.14606004 2.66615 3 P 0 0;4=4,6=1
P 2.14606004 2.61615 3 P 0 0;4=4,6=1
P 2.19606004 2.61615 3 P 0 0;4=4,6=1
P 2.19606004 2.56615 3 P 0 0;4=4,6=1
P 2.09606004 2.61615 3 P 0 0;4=4,6=1
P 2.09606004 2.56615 3 P 0 0;4=4,6=1
P 2.34606004 2.56615 3 P 0 0;4=4,6=1
P 2.34606004 2.61615 3 P 0 0;4=4,6=1
P 2.34606004 2.46615 3 P 0 0;4=4,6=1
P 2.34606004 2.41615 3 P 0 0;4=4,6=1
P 2.44606004 2.46615 3 P 0 0;4=4,6=1
P 2.44606004 2.41615 3 P 0 0;4=4,6=1
P 2.49606004 2.41615 3 P 0 0;4=4,6=1
P 2.49606004 2.36615 3 P 0 0;4=4,6=1
P 2.39606004 2.41615 3 P 0 0;4=4,6=1
P 2.39606004 2.36615 3 P 0 0;4=4,6=1
P 2.44606004 2.31615 3 P 0 0;4=4,6=1
P 2.44606004 2.26615 3 P 0 0;4=4,6=1
P 2.49606004 2.26615 3 P 0 0;4=4,6=1
P 2.49606004 2.21615 3 P 0 0;4=4,6=1
P 2.39606004 2.26615 3 P 0 0;4=4,6=1
P 2.39606004 2.21615 3 P 0 0;4=4,6=1
P 2.34606004 2.31615 3 P 0 0;4=4,6=1
P 2.34606004 2.26615 3 P 0 0;4=4,6=1
P 2.34606004 2.11615 3 P 0 0;4=4,6=1
P 2.34606004 2.06615 3 P 0 0;4=4,6=1
P 2.44606004 2.11615 3 P 0 0;4=4,6=1
P 2.44606004 2.06615 3 P 0 0;4=4,6=1
P 2.49606004 2.06615 3 P 0 0;4=4,6=1
P 2.49606004 2.01615 3 P 0 0;4=4,6=1
P 2.39606004 2.06615 3 P 0 0;4=4,6=1
P 2.39606004 2.01615 3 P 0 0;4=4,6=1
P 2.44606004 1.96615 3 P 0 0;4=4,6=1
P 2.44606004 1.91615 3 P 0 0;4=4,6=1
P 2.49606004 1.91615 3 P 0 0;4=4,6=1
P 2.49606004 1.86615 3 P 0 0;4=4,6=1
P 2.39606004 1.91615 3 P 0 0;4=4,6=1
P 2.39606004 1.86615 3 P 0 0;4=4,6=1
P 2.34606004 1.96615 3 P 0 0;4=4,6=1
P 2.34606004 1.91615 3 P 0 0;4=4,6=1
P 2.34606004 3.16615 3 P 0 0;4=4,6=1
P 2.34606004 3.11615 3 P 0 0;4=4,6=1
P 2.44606004 3.16615 3 P 0 0;4=4,6=1
P 2.44606004 3.11615 3 P 0 0;4=4,6=1
P 2.49606004 3.11615 3 P 0 0;4=4,6=1
P 2.49606004 3.06615 3 P 0 0;4=4,6=1
P 2.39606004 3.11615 3 P 0 0;4=4,6=1
P 2.39606004 3.06615 3 P 0 0;4=4,6=1
P 2.44606004 3.01615 3 P 0 0;4=4,6=1
P 2.44606004 2.96615 3 P 0 0;4=4,6=1
P 2.49606004 2.96615 3 P 0 0;4=4,6=1
P 2.49606004 2.91615 3 P 0 0;4=4,6=1
P 2.39606004 2.96615 3 P 0 0;4=4,6=1
P 2.39606004 2.91615 3 P 0 0;4=4,6=1
P 2.34606004 3.01615 3 P 0 0;4=4,6=1
P 2.34606004 2.96615 3 P 0 0;4=4,6=1
P 2.39606004 2.81615 3 P 0 0;4=4,6=1
P 2.39606004 2.76615 3 P 0 0;4=4,6=1
P 2.49606004 2.81615 3 P 0 0;4=4,6=1
P 2.49606004 2.76615 3 P 0 0;4=4,6=1
P 2.44606004 2.76615 3 P 0 0;4=4,6=1
P 2.44606004 2.71615 3 P 0 0;4=4,6=1
P 2.34606004 2.76615 3 P 0 0;4=4,6=1
P 2.34606004 2.71615 3 P 0 0;4=4,6=1
P 2.49606004 2.66615 3 P 0 0;4=4,6=1
P 2.49606004 2.61615 3 P 0 0;4=4,6=1
P 2.44606004 2.61615 3 P 0 0;4=4,6=1
P 2.44606004 2.56615 3 P 0 0;4=4,6=1
P 2.39606004 2.66615 3 P 0 0;4=4,6=1
P 2.39606004 2.61615 3 P 0 0;4=4,6=1
P 8.94061998 4.70573996 4 P 0 0;4=6,6=1
P 9.01925 4.70573996 4 P 0 0;4=6,6=1
P 9.07925 4.70573996 4 P 0 0;4=6,6=1
P 8.73578996 4.70573996 4 P 0 0;4=6,6=1
P 8.79578996 4.70573996 4 P 0 0;4=6,6=1
P 8.86665 4.74418002 4 P 0 0;4=6,6=1
P 8.80665 4.74418002 4 P 0 0;4=6,6=1
P 9.43358002 4.74418002 4 P 0 0;4=6,6=1
P 9.51531004 4.68098996 4 P 0 0;4=6,6=1
P 9.57531004 4.68098996 4 P 0 0;4=6,6=1
P 9.44445 4.62573996 4 P 0 0;4=6,6=1
P 9.50445 4.62573996 4 P 0 0;4=6,6=1
P 9.23185 4.68073996 4 P 0 0;4=6,6=1
P 9.29185 4.68073996 4 P 0 0;4=6,6=1
P 9.16098002 4.74418002 4 P 0 0;4=6,6=1
P 9.37358002 4.74418002 4 P 0 0;4=6,6=1
P 9.22098002 4.74418002 4 P 0 0;4=6,6=1
P 9.51531004 5.17873996 4 P 0 0;4=6,6=1
P 9.57531004 5.17873996 4 P 0 0;4=6,6=1
P 9.43358002 5.18128002 4 P 0 0;4=6,6=1
P 9.23185 5.18128002 4 P 0 0;4=6,6=1
P 9.29185 5.18128002 4 P 0 0;4=6,6=1
P 9.37358002 5.18128002 4 P 0 0;4=6,6=1
P 9.36271004 5.14223996 4 P 0 0;4=6,6=1
P 9.30271004 5.14223996 4 P 0 0;4=6,6=1
P 9.15011004 5.09223996 4 P 0 0;4=6,6=1
P 9.09011004 5.09223996 4 P 0 0;4=6,6=1
P 9.07925 5.20373996 4 P 0 0;4=6,6=1
P 9.01925 5.20373996 4 P 0 0;4=6,6=1
P 8.93441004 5.20876004 4 P 0 0;4=6,6=1
P 8.73578996 5.17873996 4 P 0 0;4=6,6=1
P 8.79578996 5.17873996 4 P 0 0;4=6,6=1
P 8.87441004 5.20876004 4 P 0 0;4=6,6=1
P 7.64205 4.74418002 4 P 0 0;4=6,6=1
P 7.70205 4.74418002 4 P 0 0;4=6,6=1
P 7.63118996 4.66826004 4 P 0 0;4=6,6=1
P 7.57118996 4.66826004 4 P 0 0;4=6,6=1
P 7.91465 4.61826004 4 P 0 0;4=6,6=1
P 7.78378996 4.74418002 4 P 0 0;4=6,6=1
P 7.84378996 4.74418002 4 P 0 0;4=6,6=1
P 7.85465 4.61826004 4 P 0 0;4=6,6=1
P 8.06725 4.74418002 4 P 0 0;4=6,6=1
P 8.12725 4.74418002 4 P 0 0;4=6,6=1
P 8.02206998 4.62815 4 P 0 0;4=6,6=1
P 8.08206998 4.62815 4 P 0 0;4=6,6=1
P 8.41071004 4.70326004 4 P 0 0;4=6,6=1
P 8.35071004 4.70326004 4 P 0 0;4=6,6=1
P 8.20898002 4.74418002 4 P 0 0;4=6,6=1
P 8.26898002 4.74418002 4 P 0 0;4=6,6=1
P 8.21208996 4.62826004 4 P 0 0;4=6,6=1
P 8.27208996 4.62826004 4 P 0 0;4=6,6=1
P 8.19811004 5.09223996 4 P 0 0;4=6,6=1
P 8.12725 5.13026004 4 P 0 0;4=6,6=1
P 8.06725 5.13026004 4 P 0 0;4=6,6=1
P 7.91465 5.13026004 4 P 0 0;4=6,6=1
P 7.92551004 5.09223996 4 P 0 0;4=6,6=1
P 7.98551004 5.09223996 4 P 0 0;4=6,6=1
P 7.85465 5.13026004 4 P 0 0;4=6,6=1
P 7.64203996 5.09223996 4 P 0 0;4=6,6=1
P 7.70203996 5.09223996 4 P 0 0;4=6,6=1
P 7.57118996 5.13026004 4 P 0 0;4=6,6=1
P 7.63118996 5.13026004 4 P 0 0;4=6,6=1
P 2.73225 4.70573996 4 P 0 0;4=6,6=1
P 2.79225 4.70573996 4 P 0 0;4=6,6=1
P 3.22831004 5.18128002 4 P 0 0;4=6,6=1
P 3.28831004 5.18128002 4 P 0 0;4=6,6=1
P 3.01571004 5.20373996 4 P 0 0;4=6,6=1
P 3.07571004 5.20373996 4 P 0 0;4=6,6=1
P 2.73225 5.17873996 4 P 0 0;4=6,6=1
P 2.79225 5.17873996 4 P 0 0;4=6,6=1
P 1.56765 4.66826004 4 P 0 0;4=6,6=1
P 1.62765 4.66826004 4 P 0 0;4=6,6=1
P 1.56765 5.13026004 4 P 0 0;4=6,6=1
P 1.62765 5.13026004 4 P 0 0;4=6,6=1
P 1.91111004 5.13026004 4 P 0 0;4=6,6=1
P 1.85111004 5.13026004 4 P 0 0;4=6,6=1
P 5.08268002 2.76615 3 P 0 0;4=4,6=1
P 5.03268002 2.76615 3 P 0 0;4=4,6=1
P 5.03268002 2.71615 3 P 0 0;4=4,6=1
P 4.93268002 2.76615 3 P 0 0;4=4,6=1
P 4.98268002 2.76615 3 P 0 0;4=4,6=1
P 4.93268002 2.71615 3 P 0 0;4=4,6=1
P 5.08268002 2.66615 3 P 0 0;4=4,6=1
P 4.98268002 2.66615 3 P 0 0;4=4,6=1
P 5.03268002 2.56615 3 P 0 0;4=4,6=1
P 4.93268002 2.56615 3 P 0 0;4=4,6=1
P 4.98268002 2.46615 3 P 0 0;4=4,6=1
P 4.98268002 2.51615 3 P 0 0;4=4,6=1
P 4.93268002 2.51615 3 P 0 0;4=4,6=1
P 5.08268002 2.51615 3 P 0 0;4=4,6=1
P 5.08268002 2.46615 3 P 0 0;4=4,6=1
P 5.03268002 2.21615 3 P 0 0;4=4,6=1
P 4.93268002 2.21615 3 P 0 0;4=4,6=1
P 4.98268002 2.31615 3 P 0 0;4=4,6=1
P 4.93268002 2.36615 3 P 0 0;4=4,6=1
P 5.08268002 2.31615 3 P 0 0;4=4,6=1
P 5.08268002 2.16615 3 P 0 0;4=4,6=1
P 4.93268002 2.16615 3 P 0 0;4=4,6=1
P 4.98268002 2.16615 3 P 0 0;4=4,6=1
P 4.93268002 1.96615 3 P 0 0;4=4,6=1
P 5.03268002 1.96615 3 P 0 0;4=4,6=1
P 5.03268002 2.11615 3 P 0 0;4=4,6=1
P 4.93268002 2.11615 3 P 0 0;4=4,6=1
P 4.98268002 2.01615 3 P 0 0;4=4,6=1
P 5.08268002 2.01615 3 P 0 0;4=4,6=1
P 4.98268002 1.86615 3 P 0 0;4=4,6=1
P 5.08268002 1.86615 3 P 0 0;4=4,6=1
P 4.78268002 3.81615 3 P 0 0;4=4,6=1
P 4.78268002 3.66615 3 P 0 0;4=4,6=1
P 4.73268002 3.81615 3 P 0 0;4=4,6=1
P 4.73268002 3.66615 3 P 0 0;4=4,6=1
P 4.68268002 3.81615 3 P 0 0;4=4,6=1
P 4.68268002 3.66615 3 P 0 0;4=4,6=1
P 4.78268002 3.51615 3 P 0 0;4=4,6=1
P 4.73268002 3.51615 3 P 0 0;4=4,6=1
P 4.68268002 3.51615 3 P 0 0;4=4,6=1
P 4.78268002 3.36615 3 P 0 0;4=4,6=1
P 4.73268002 3.36615 3 P 0 0;4=4,6=1
P 4.78268002 3.21615 3 P 0 0;4=4,6=1
P 4.73268002 3.21615 3 P 0 0;4=4,6=1
P 4.68268002 3.36615 3 P 0 0;4=4,6=1
P 4.68268002 3.21615 3 P 0 0;4=4,6=1
P 4.78268002 3.06615 3 P 0 0;4=4,6=1
P 4.73268002 3.06615 3 P 0 0;4=4,6=1
P 4.68268002 3.06615 3 P 0 0;4=4,6=1
P 4.78268002 2.91615 3 P 0 0;4=4,6=1
P 4.73268002 2.91615 3 P 0 0;4=4,6=1
P 4.68268002 2.91615 3 P 0 0;4=4,6=1
P 4.88268002 2.76615 3 P 0 0;4=4,6=1
P 4.88268002 2.66615 3 P 0 0;4=4,6=1
P 4.78268002 2.46615 3 P 0 0;4=4,6=1
P 4.88268002 2.56615 3 P 0 0;4=4,6=1
P 4.88268002 2.61615 3 P 0 0;4=4,6=1
P 4.68268002 2.46615 3 P 0 0;4=4,6=1
P 4.88268002 2.46615 3 P 0 0;4=4,6=1
P 4.88268002 2.51615 3 P 0 0;4=4,6=1
P 4.78268002 2.41615 3 P 0 0;4=4,6=1
P 4.88268002 2.41615 3 P 0 0;4=4,6=1
P 4.78268002 2.36615 3 P 0 0;4=4,6=1
P 4.78268002 2.31615 3 P 0 0;4=4,6=1
P 4.78268002 2.26615 3 P 0 0;4=4,6=1
P 4.78268002 2.21615 3 P 0 0;4=4,6=1
P 4.73268002 2.36615 3 P 0 0;4=4,6=1
P 4.68268002 2.31615 3 P 0 0;4=4,6=1
P 4.73268002 2.21615 3 P 0 0;4=4,6=1
P 4.88268002 2.21615 3 P 0 0;4=4,6=1
P 4.88268002 2.26615 3 P 0 0;4=4,6=1
P 4.88268002 2.31615 3 P 0 0;4=4,6=1
P 4.88268002 2.36615 3 P 0 0;4=4,6=1
P 4.73268002 2.16615 3 P 0 0;4=4,6=1
P 4.68268002 2.16615 3 P 0 0;4=4,6=1
P 4.78268002 1.96615 3 P 0 0;4=4,6=1
P 4.78268002 2.06615 3 P 0 0;4=4,6=1
P 4.78268002 2.01615 3 P 0 0;4=4,6=1
P 4.88268002 1.96615 3 P 0 0;4=4,6=1
P 4.88268002 2.06615 3 P 0 0;4=4,6=1
P 4.88268002 2.01615 3 P 0 0;4=4,6=1
P 4.78268002 2.11615 3 P 0 0;4=4,6=1
P 4.88268002 2.11615 3 P 0 0;4=4,6=1
P 4.73268002 2.11615 3 P 0 0;4=4,6=1
P 4.68268002 2.01615 3 P 0 0;4=4,6=1
P 4.73268002 1.96615 3 P 0 0;4=4,6=1
P 4.78268002 1.86615 3 P 0 0;4=4,6=1
P 4.88268002 1.86615 3 P 0 0;4=4,6=1
P 4.68268002 1.86615 3 P 0 0;4=4,6=1
P 4.63268002 3.81615 3 P 0 0;4=4,6=1
P 4.63268002 3.66615 3 P 0 0;4=4,6=1
P 4.58268002 3.81615 3 P 0 0;4=4,6=1
P 4.58268002 3.66615 3 P 0 0;4=4,6=1
P 4.63268002 3.51615 3 P 0 0;4=4,6=1
P 4.58268002 3.51615 3 P 0 0;4=4,6=1
P 4.63268002 3.36615 3 P 0 0;4=4,6=1
P 4.58268002 3.36615 3 P 0 0;4=4,6=1
P 4.63268002 3.21615 3 P 0 0;4=4,6=1
P 4.58268002 3.21615 3 P 0 0;4=4,6=1
P 4.63268002 3.06615 3 P 0 0;4=4,6=1
P 4.58268002 3.06615 3 P 0 0;4=4,6=1
P 4.63268002 2.91615 3 P 0 0;4=4,6=1
P 4.58268002 2.91615 3 P 0 0;4=4,6=1
P 4.58268002 2.46615 3 P 0 0;4=4,6=1
P 4.63268002 2.21615 3 P 0 0;4=4,6=1
P 4.58268002 2.31615 3 P 0 0;4=4,6=1
P 4.63268002 2.36615 3 P 0 0;4=4,6=1
P 4.58268002 2.01615 3 P 0 0;4=4,6=1
P 4.63268002 2.11615 3 P 0 0;4=4,6=1
P 4.63268002 1.96615 3 P 0 0;4=4,6=1
P 4.58268002 1.86615 3 P 0 0;4=4,6=1
P 2.04606004 3.41615 3 P 0 0;4=4,6=1
P 2.09606004 3.51615 3 P 0 0;4=4,6=1
P 7.82415 2.4781 24 P 0 0;1,4=0,6=0
P 3.37003996 5.18128002 4 P 0 0;4=6,6=1
P 3.43003996 5.18128002 4 P 0 0;4=6,6=1
P 3.29916998 5.14223996 4 P 0 0;4=6,6=1
P 3.35916998 5.14223996 4 P 0 0;4=6,6=1
P 2.93708002 4.70573996 4 P 0 0;4=6,6=1
P 3.07571004 4.70573996 4 P 0 0;4=6,6=1
P 3.01571004 4.70573996 4 P 0 0;4=6,6=1
P 2.87708002 4.70573996 4 P 0 0;4=6,6=1
P 2.93086998 5.20876004 4 P 0 0;4=6,6=1
P 2.87086998 5.20876004 4 P 0 0;4=6,6=1
P 2.80311004 4.74418002 4 P 0 0;4=6,6=1
P 2.86311004 4.74418002 4 P 0 0;4=6,6=1
P 3.08656998 5.09223996 4 P 0 0;4=6,6=1
P 3.14656998 5.09223996 4 P 0 0;4=6,6=1
P 2.26855 4.62826004 4 P 0 0;4=6,6=1
P 2.20855 4.62826004 4 P 0 0;4=6,6=1
P 2.26543996 4.74418002 4 P 0 0;4=6,6=1
P 2.20543996 4.74418002 4 P 0 0;4=6,6=1
P 2.34716998 4.70326004 4 P 0 0;4=6,6=1
P 2.07853002 4.62815 4 P 0 0;4=6,6=1
P 2.01853002 4.62815 4 P 0 0;4=6,6=1
P 2.12371004 4.74418002 4 P 0 0;4=6,6=1
P 2.06371004 4.74418002 4 P 0 0;4=6,6=1
P 2.19456998 5.09223996 4 P 0 0;4=6,6=1
P 2.13456998 5.09223996 4 P 0 0;4=6,6=1
P 2.12371004 5.13026004 4 P 0 0;4=6,6=1
P 2.06371004 5.13026004 4 P 0 0;4=6,6=1
P 1.6985 5.09223996 4 P 0 0;4=6,6=1
P 1.6385 5.09223996 4 P 0 0;4=6,6=1
P 1.85111004 4.61826004 4 P 0 0;4=6,6=1
P 1.63851004 4.74418002 4 P 0 0;4=6,6=1
P 1.69851004 4.74418002 4 P 0 0;4=6,6=1
P 1.98196998 5.09223996 4 P 0 0;4=6,6=1
P 1.92196998 5.09223996 4 P 0 0;4=6,6=1
P 1.84025 4.74418002 4 P 0 0;4=6,6=1
P 1.78025 4.74418002 4 P 0 0;4=6,6=1
P 11.03661004 2.71615 3 P 0 0;4=4,6=1
P 10.93661004 2.71615 3 P 0 0;4=4,6=1
P 11.03661004 2.76615 3 P 0 0;4=4,6=1
P 10.98661004 2.76615 3 P 0 0;4=4,6=1
P 10.93661004 2.76615 3 P 0 0;4=4,6=1
P 11.08661004 2.76615 3 P 0 0;4=4,6=1
P 11.03661004 2.56615 3 P 0 0;4=4,6=1
P 10.93661004 2.56615 3 P 0 0;4=4,6=1
P 10.98661004 2.66615 3 P 0 0;4=4,6=1
P 10.98661004 2.51615 3 P 0 0;4=4,6=1
P 10.93661004 2.51615 3 P 0 0;4=4,6=1
P 11.08661004 2.66615 3 P 0 0;4=4,6=1
P 11.08661004 2.51615 3 P 0 0;4=4,6=1
P 11.08661004 2.46615 3 P 0 0;4=4,6=1
P 10.98661004 2.46615 3 P 0 0;4=4,6=1
P 11.08661004 2.31615 3 P 0 0;4=4,6=1
P 10.93661004 2.36615 3 P 0 0;4=4,6=1
P 10.98661004 2.31615 3 P 0 0;4=4,6=1
P 10.93661004 2.21615 3 P 0 0;4=4,6=1
P 11.03661004 2.21615 3 P 0 0;4=4,6=1
P 11.03661004 2.11615 3 P 0 0;4=4,6=1
P 10.93661004 2.11615 3 P 0 0;4=4,6=1
P 10.98661004 2.01615 3 P 0 0;4=4,6=1
P 10.93661004 1.96615 3 P 0 0;4=4,6=1
P 11.03661004 1.96615 3 P 0 0;4=4,6=1
P 11.08661004 2.01615 3 P 0 0;4=4,6=1
P 10.98661004 2.16615 3 P 0 0;4=4,6=1
P 10.93661004 2.16615 3 P 0 0;4=4,6=1
P 11.08661004 2.16615 3 P 0 0;4=4,6=1
P 10.98661004 1.86615 3 P 0 0;4=4,6=1
P 11.08661004 1.86615 3 P 0 0;4=4,6=1
P 10.73661004 2.71615 3 P 0 0;4=4,6=1
P 10.73661004 2.76615 3 P 0 0;4=4,6=1
P 10.88661004 2.76615 3 P 0 0;4=4,6=1
P 10.78661004 2.76615 3 P 0 0;4=4,6=1
P 10.73661004 2.56615 3 P 0 0;4=4,6=1
P 10.68661004 2.66615 3 P 0 0;4=4,6=1
P 10.73661004 2.51615 3 P 0 0;4=4,6=1
P 10.68661004 2.51615 3 P 0 0;4=4,6=1
P 10.88661004 2.61615 3 P 0 0;4=4,6=1
P 10.88661004 2.56615 3 P 0 0;4=4,6=1
P 10.88661004 2.51615 3 P 0 0;4=4,6=1
P 10.78661004 2.56615 3 P 0 0;4=4,6=1
P 10.78661004 2.61615 3 P 0 0;4=4,6=1
P 10.78661004 2.66615 3 P 0 0;4=4,6=1
P 10.78661004 2.51615 3 P 0 0;4=4,6=1
P 10.78661004 2.46615 3 P 0 0;4=4,6=1
P 10.68661004 2.46615 3 P 0 0;4=4,6=1
P 10.88661004 2.46615 3 P 0 0;4=4,6=1
P 10.78661004 2.21615 3 P 0 0;4=4,6=1
P 10.78661004 2.26615 3 P 0 0;4=4,6=1
P 10.78661004 2.31615 3 P 0 0;4=4,6=1
P 10.78661004 2.36615 3 P 0 0;4=4,6=1
P 10.68661004 2.31615 3 P 0 0;4=4,6=1
P 10.73661004 2.36615 3 P 0 0;4=4,6=1
P 10.73661004 2.21615 3 P 0 0;4=4,6=1
P 10.78661004 2.41615 3 P 0 0;4=4,6=1
P 10.88661004 2.36615 3 P 0 0;4=4,6=1
P 10.88661004 2.31615 3 P 0 0;4=4,6=1
P 10.88661004 2.26615 3 P 0 0;4=4,6=1
P 10.88661004 2.21615 3 P 0 0;4=4,6=1
P 10.73661004 1.96615 3 P 0 0;4=4,6=1
P 10.68661004 2.01615 3 P 0 0;4=4,6=1
P 10.73661004 2.11615 3 P 0 0;4=4,6=1
P 10.78661004 2.11615 3 P 0 0;4=4,6=1
P 10.78661004 2.01615 3 P 0 0;4=4,6=1
P 10.78661004 1.96615 3 P 0 0;4=4,6=1
P 10.78661004 2.06615 3 P 0 0;4=4,6=1
P 10.68661004 2.16615 3 P 0 0;4=4,6=1
P 10.73661004 2.16615 3 P 0 0;4=4,6=1
P 10.88661004 2.01615 3 P 0 0;4=4,6=1
P 10.88661004 2.06615 3 P 0 0;4=4,6=1
P 10.88661004 2.11615 3 P 0 0;4=4,6=1
P 10.88661004 1.96615 3 P 0 0;4=4,6=1
P 10.78661004 1.91615 3 P 0 0;4=4,6=1
P 10.68661004 1.86615 3 P 0 0;4=4,6=1
P 10.78661004 1.86615 3 P 0 0;4=4,6=1
P 10.88661004 1.86615 3 P 0 0;4=4,6=1
P 10.63661004 2.71615 3 P 0 0;4=4,6=1
P 10.63661004 2.76615 3 P 0 0;4=4,6=1
P 10.63661004 2.56615 3 P 0 0;4=4,6=1
P 10.58661004 2.66615 3 P 0 0;4=4,6=1
P 10.63661004 2.51615 3 P 0 0;4=4,6=1
P 10.58661004 2.51615 3 P 0 0;4=4,6=1
P 10.58661004 2.46615 3 P 0 0;4=4,6=1
P 10.63661004 2.36615 3 P 0 0;4=4,6=1
P 10.58661004 2.31615 3 P 0 0;4=4,6=1
P 10.58661004 2.01615 3 P 0 0;4=4,6=1
P 10.63661004 1.96615 3 P 0 0;4=4,6=1
P 10.63661004 2.11615 3 P 0 0;4=4,6=1
P 10.58661004 1.86615 3 P 0 0;4=4,6=1
P 1.92346004 5.377 4 P 0 0;4=6,6=1
P 2.14346004 5.377 4 P 0 0;4=6,6=1
P 7.927 5.377 4 P 0 0;4=6,6=1
P 8.147 5.377 4 P 0 0;4=6,6=1
P 3.43003996 4.74418002 4 P 0 0;4=6,6=1
P 3.51176998 4.68098996 4 P 0 0;4=6,6=1
P 3.57176998 4.68098996 4 P 0 0;4=6,6=1
P 3.21743996 4.74418002 4 P 0 0;4=6,6=1
P 3.37003996 4.74418002 4 P 0 0;4=6,6=1
P 3.09646004 5.332 24 P 0 0;1,4=0,6=0
P 3.23146004 5.332 24 P 0 0;1,4=0,6=0
P 3.38146004 5.332 24 P 0 0;1,4=0,6=0
P 3.41 5.332 4 P 0 0;4=6,6=1
P 5.38048002 1.5957 4 P 0 0;4=6,6=1
P 5.38048002 1.7891 4 P 0 0;4=6,6=1
P 5.38048002 1.732 4 P 0 0;4=6,6=1
P 5.38048002 1.6528 4 P 0 0;4=6,6=1
P 5.53531004 1.8603 4 P 0 0;4=6,6=1
P 5.53531004 1.8032 4 P 0 0;4=6,6=1
P 5.53531004 2.2727 4 P 0 0;4=6,6=1
P 5.53531004 2.1373 4 P 0 0;4=6,6=1
P 5.53531004 1.9964 4 P 0 0;4=6,6=1
P 5.38048002 2.3403 4 P 0 0;4=6,6=1
P 5.38048002 2.2832 4 P 0 0;4=6,6=1
P 5.38048002 2.2049 4 P 0 0;4=6,6=1
P 5.38048002 2.1478 4 P 0 0;4=6,6=1
P 5.38048002 2.0642 4 P 0 0;4=6,6=1
P 5.38048002 2.0071 4 P 0 0;4=6,6=1
P 5.38048002 1.9288 4 P 0 0;4=6,6=1
P 5.38048002 1.8717 4 P 0 0;4=6,6=1
P 5.53531004 2.351 4 P 0 0;4=6,6=1
P 5.38048002 2.4757 4 P 0 0;4=6,6=1
P 5.38048002 2.4186 4 P 0 0;4=6,6=1
P 5.53531004 2.4902 4 P 0 0;4=6,6=1
P 5.53531004 2.6825 4 P 0 0;4=6,6=1
P 5.53531004 2.6254 4 P 0 0;4=6,6=1
P 5.38048002 2.5578 4 P 0 0;4=6,6=1
P 5.38048002 2.6149 4 P 0 0;4=6,6=1
P 10.43 1.3341 4 P 0 0;4=6,6=1
P 10.43 1.277 4 P 0 0;4=6,6=1
P 10.4159 1.43 4 P 0 0;4=6,6=1
P 10.473 1.43 4 P 0 0;4=6,6=1
P 10.37313996 1.55336004 4 P 0 0;4=6,6=1
P 10.41451004 1.51198002 4 P 0 0;4=6,6=1
P 10.295 1.713 4 P 0 0;4=6,6=1
P 10.295 1.6559 4 P 0 0;4=6,6=1
P 10.26 1.9179 4 P 0 0;4=6,6=1
P 10.29525 1.877 4 P 0 0;4=6,6=1
P 10.29525 1.8199 4 P 0 0;4=6,6=1
P 10.26 1.975 4 P 0 0;4=6,6=1
P 10.125 2.0651 4 P 0 0;4=6,6=1
P 10.125 2.1224 4 P 0 0;4=6,6=1
P 10.125 2.1795 4 P 0 0;4=6,6=1
P 10.01 2.2481 4 P 0 0;4=6,6=1
P 10.01 2.191 4 P 0 0;4=6,6=1
P 10.01 2.38435 4 P 0 0;4=6,6=1
P 10.01 2.32725 4 P 0 0;4=6,6=1
P 10.125 2.3168 4 P 0 0;4=6,6=1
P 10.125 2.2597 4 P 0 0;4=6,6=1
P 10.125 2.4519 4 P 0 0;4=6,6=1
P 10.125 2.3948 4 P 0 0;4=6,6=1
P 10.01 2.51945 4 P 0 0;4=6,6=1
P 10.01 2.46235 4 P 0 0;4=6,6=1
P 10.125 2.587 4 P 0 0;4=6,6=1
P 10.125 2.5299 4 P 0 0;4=6,6=1
P 10.01 2.673 4 P 0 0;4=6,6=1
P 10.01 2.6159 4 P 0 0;4=6,6=1
P 11.74316004 1.7035 4 P 0 0;4=6,6=1
P 11.74316004 1.6405 4 P 0 0;4=6,6=1
P 11.69316004 1.4805 4 P 0 0;4=6,6=1
P 11.69316004 1.5435 4 P 0 0;4=6,6=1
P 11.49316004 1.5605 4 P 0 0;4=6,6=1
P 11.49316004 1.6235 4 P 0 0;4=6,6=1
P 11.49316004 1.4635 4 P 0 0;4=6,6=1
P 11.49366004 1.401 4 P 0 0;4=6,6=1
P 11.69316004 2.6005 4 P 0 0;4=6,6=1
P 11.69316004 2.5035 4 P 0 0;4=6,6=1
P 11.69316004 2.4405 4 P 0 0;4=6,6=1
P 11.69316004 2.3435 4 P 0 0;4=6,6=1
P 11.69316004 2.2805 4 P 0 0;4=6,6=1
P 11.69316004 2.1835 4 P 0 0;4=6,6=1
P 11.69316004 1.9605 4 P 0 0;4=6,6=1
P 11.69316004 2.0235 4 P 0 0;4=6,6=1
P 11.69316004 2.1205 4 P 0 0;4=6,6=1
P 11.69316004 1.8005 4 P 0 0;4=6,6=1
P 11.69316004 1.8635 4 P 0 0;4=6,6=1
P 11.49316004 2.5205 4 P 0 0;4=6,6=1
P 11.49316004 2.5835 4 P 0 0;4=6,6=1
P 11.49316004 2.4235 4 P 0 0;4=6,6=1
P 11.49316004 2.3605 4 P 0 0;4=6,6=1
P 11.79316004 2.2635 4 P 0 0;4=6,6=1
P 11.79316004 2.2005 4 P 0 0;4=6,6=1
P 11.49316004 1.9435 4 P 0 0;4=6,6=1
P 11.49316004 2.1035 4 P 0 0;4=6,6=1
P 11.49316004 2.0405 4 P 0 0;4=6,6=1
P 11.49316004 1.8805 4 P 0 0;4=6,6=1
P 11.49366004 1.721 4 P 0 0;4=6,6=1
P 11.49316004 1.7835 4 P 0 0;4=6,6=1
P 10.125 2.7451 4 P 0 0;4=6,6=1
P 10.125 2.688 4 P 0 0;4=6,6=1
P 12.30798002 2.155 24 P 0 0;1,4=0,6=0
P 12.34 2.19 4 P 0 0;4=6,6=1
P 9.415 5.332 4 P 0 0;4=6,6=1
P 9.265 5.332 4 P 0 0;4=6,6=1
P 9.07 5.332 4 P 0 0;4=6,6=1
P 4.7 5.54928996 4 P 0 0;4=6,6=1
P 4.81 5.375 4 P 0 0;4=6,6=1
P 4.96 5.375 4 P 0 0;4=6,6=1
P 5.16 5.645 4 P 0 0;4=6,6=1
P 5.04441004 5.605 4 P 0 0;4=6,6=1
P 4.92 5.7 4 P 0 0;4=6,6=1
P 9.91 4.7 4 P 0 0;4=6,6=1
P 3.57 4.45 4 P 0 0;4=6,6=1
P 10.465 5.195 4 P 0 0;4=6,6=1
P 10.515 5.32 4 P 0 0;4=6,6=1
P 10.465 5.275 4 P 0 0;4=6,6=1
P 12.025 4.915 4 P 0 0;4=6,6=1
P 12.12 4.965 4 P 0 0;4=6,6=1
P 12.185 4.915 4 P 0 0;4=6,6=1
P 3.72 4.45 4 P 0 0;4=6,6=1
P 3.66 4.63 4 P 0 0;4=6,6=1
P 3.77 4.86 4 P 0 0;4=6,6=1
P 9.96 4.69 4 P 0 0;4=6,6=1
P 10.03 4.51 4 P 0 0;4=6,6=1
P 3.835 4.6 4 P 0 0;4=6,6=1
P 3.9865 4.635 4 P 0 0;4=6,6=1
P 4.14 4.655 4 P 0 0;4=6,6=1
P 4.1049 4.7649 4 P 0 0;4=6,6=1
P 1.28051004 5.78 4 P 0 0;4=6,6=1
P 3.87 5.125 4 P 0 0;4=6,6=1
P 0.4826 5.8976 4 P 0 0;4=6,6=1
P 0.84953002 5.17 4 P 0 0;4=6,6=1
P 0.955 5.325 4 P 0 0;4=6,6=1
P 1.31 5.355 4 P 0 0;4=6,6=1
P 1.20176998 5.78 4 P 0 0;4=6,6=1
P 6.34948996 4.99705 24 P 0 0;1,4=0,6=0
P 6.31295 4.99705 4 P 0 0;4=6,6=1
P 6.837 5 24 P 0 0;1,4=0,6=0
P 6.87 5 4 P 0 0;4=6,6=1
P 6.27208996 4.7202 26 P 0 0;1,4=11,6=0
P 6.27208996 4.6402 26 P 0 0;1,4=11,6=0
P 6.27208996 4.8802 26 P 0 0;1,4=11,6=0
P 6.27208996 4.8002 26 P 0 0;1,4=11,6=0
P 9.64796004 0.79643002 4 P 0 0;4=6,6=1
P 9.40795 0.26133002 4 P 0 0;4=6,6=1
P 3.60998996 0.24 4 P 0 0;4=6,6=1
P 3.65998996 0.345 4 P 0 0;4=6,6=1
P 3.86 0.7751 6 P 0 0;2,4=1,6=1
P 6.905 4.94705 4 P 0 0;4=6,6=1
P 6.905 4.88705 4 P 0 0;4=6,6=1
P 6.91118996 4.81705 26 P 0 0;1,4=11,6=0
P 6.955 4.8 4 P 0 0;4=6,6=1
P 6.955 4.84 4 P 0 0;4=6,6=1
P 6.91118996 4.73868002 26 P 0 0;1,4=11,6=0
P 6.955 4.72 4 P 0 0;4=6,6=1
P 6.955 4.76 4 P 0 0;4=6,6=1
P 6.59708996 5.0502 4 P 0 0;4=6,6=1
P 6.65218996 4.77 4 P 0 0;4=6,6=1
P 6.62118996 4.95641998 1 P 0 0;4=12,6=1
P 6.6015 4.93673996 1 P 0 0;4=12,6=1
P 6.64088002 4.93673996 1 P 0 0;4=12,6=1
P 6.62118996 4.91705 1 P 0 0;4=12,6=1
P 6.62118996 4.87768002 1 P 0 0;4=12,6=1
P 6.6015 4.89736004 1 P 0 0;4=12,6=1
P 6.64088002 4.89736004 1 P 0 0;4=12,6=1
P 6.66208996 4.6252 26 P 0 0;1,4=11,6=0
P 6.66208996 4.7052 26 P 0 0;1,4=11,6=0
P 6.62 4.69 4 P 0 0;4=6,6=1
P 6.62 4.725 4 P 0 0;4=6,6=1
P 6.385 5.07 4 P 0 0;4=6,6=1
P 5.53593996 4.55505 4 P 0 0;4=6,6=1
P 5.99708996 4.5552 26 P 0 0;1,4=11,6=0
P 5.91708996 4.5552 26 P 0 0;1,4=11,6=0
P 6.07708996 4.5552 26 P 0 0;1,4=11,6=0
P 6.05708996 4.5102 4 P 0 0;4=6,6=1
P 6.01708996 4.5102 4 P 0 0;4=6,6=1
P 5.97708996 4.5102 4 P 0 0;4=6,6=1
P 5.93708996 4.5102 4 P 0 0;4=6,6=1
P 5.89708996 4.5102 4 P 0 0;4=6,6=1
P 6.09708996 4.5102 4 P 0 0;4=6,6=1
P 5.83708996 4.5552 26 P 0 0;1,4=11,6=0
P 5.75708996 4.5552 26 P 0 0;1,4=11,6=0
P 5.67708996 4.5552 26 P 0 0;1,4=11,6=0
P 5.61708996 4.5102 4 P 0 0;4=6,6=1
P 5.65708996 4.5102 4 P 0 0;4=6,6=1
P 5.85708996 4.5102 4 P 0 0;4=6,6=1
P 5.81708996 4.5102 4 P 0 0;4=6,6=1
P 5.77708996 4.5102 4 P 0 0;4=6,6=1
P 5.73708996 4.5102 4 P 0 0;4=6,6=1
P 5.69708996 4.5102 4 P 0 0;4=6,6=1
P 5.59778996 4.5552 26 P 0 0;1,4=11,6=0
P 5.57708996 4.5102 4 P 0 0;4=6,6=1
P 0.036 0.10868002 4 P 0 0;4=6,6=1
P 0.036 0.15868002 4 P 0 0;4=6,6=1
P 0.036 0.20868002 4 P 0 0;4=6,6=1
P 0.22873996 0.036 4 P 0 0;4=6,6=1
P 0.17873996 0.036 4 P 0 0;4=6,6=1
P 0.12873996 0.036 4 P 0 0;4=6,6=1
P 0.07873996 0.036 4 P 0 0;4=6,6=1
P 0.47873996 0.036 4 P 0 0;4=6,6=1
P 0.42873996 0.036 4 P 0 0;4=6,6=1
P 0.37873996 0.036 4 P 0 0;4=6,6=1
P 0.32873996 0.036 4 P 0 0;4=6,6=1
P 0.27873996 0.036 4 P 0 0;4=6,6=1
P 0.77873996 0.036 4 P 0 0;4=6,6=1
P 0.72873996 0.036 4 P 0 0;4=6,6=1
P 0.67873996 0.036 4 P 0 0;4=6,6=1
P 0.62873996 0.036 4 P 0 0;4=6,6=1
P 0.57873996 0.036 4 P 0 0;4=6,6=1
P 0.52873996 0.036 4 P 0 0;4=6,6=1
P 1.02873996 0.036 4 P 0 0;4=6,6=1
P 0.97873996 0.036 4 P 0 0;4=6,6=1
P 0.92873996 0.036 4 P 0 0;4=6,6=1
P 0.87873996 0.036 4 P 0 0;4=6,6=1
P 0.82873996 0.036 4 P 0 0;4=6,6=1
P 1.27873996 0.036 4 P 0 0;4=6,6=1
P 1.22873996 0.036 4 P 0 0;4=6,6=1
P 1.17873996 0.036 4 P 0 0;4=6,6=1
P 1.12873996 0.036 4 P 0 0;4=6,6=1
P 1.07873996 0.036 4 P 0 0;4=6,6=1
P 1.52873996 0.036 4 P 0 0;4=6,6=1
P 1.47873996 0.036 4 P 0 0;4=6,6=1
P 1.42873996 0.036 4 P 0 0;4=6,6=1
P 1.37873996 0.036 4 P 0 0;4=6,6=1
P 1.32873996 0.036 4 P 0 0;4=6,6=1
P 1.82873996 0.036 4 P 0 0;4=6,6=1
P 1.77873996 0.036 4 P 0 0;4=6,6=1
P 1.72873996 0.036 4 P 0 0;4=6,6=1
P 1.67873996 0.036 4 P 0 0;4=6,6=1
P 1.62873996 0.036 4 P 0 0;4=6,6=1
P 1.57873996 0.036 4 P 0 0;4=6,6=1
P 2.07873996 0.036 4 P 0 0;4=6,6=1
P 2.02873996 0.036 4 P 0 0;4=6,6=1
P 1.97873996 0.036 4 P 0 0;4=6,6=1
P 1.92873996 0.036 4 P 0 0;4=6,6=1
P 1.87873996 0.036 4 P 0 0;4=6,6=1
P 2.32873996 0.036 4 P 0 0;4=6,6=1
P 2.27873996 0.036 4 P 0 0;4=6,6=1
P 2.22873996 0.036 4 P 0 0;4=6,6=1
P 2.17873996 0.036 4 P 0 0;4=6,6=1
P 2.12873996 0.036 4 P 0 0;4=6,6=1
P 2.62873996 0.036 4 P 0 0;4=6,6=1
P 2.57873996 0.036 4 P 0 0;4=6,6=1
P 2.52873996 0.036 4 P 0 0;4=6,6=1
P 2.47873996 0.036 4 P 0 0;4=6,6=1
P 2.42873996 0.036 4 P 0 0;4=6,6=1
P 2.37873996 0.036 4 P 0 0;4=6,6=1
P 2.87873996 0.036 4 P 0 0;4=6,6=1
P 2.82873996 0.036 4 P 0 0;4=6,6=1
P 2.77873996 0.036 4 P 0 0;4=6,6=1
P 2.72873996 0.036 4 P 0 0;4=6,6=1
P 2.67873996 0.036 4 P 0 0;4=6,6=1
P 3.12873996 0.036 4 P 0 0;4=6,6=1
P 3.07873996 0.036 4 P 0 0;4=6,6=1
P 3.02873996 0.036 4 P 0 0;4=6,6=1
P 2.97873996 0.036 4 P 0 0;4=6,6=1
P 2.92873996 0.036 4 P 0 0;4=6,6=1
P 3.37873996 0.036 4 P 0 0;4=6,6=1
P 3.32873996 0.036 4 P 0 0;4=6,6=1
P 3.27873996 0.036 4 P 0 0;4=6,6=1
P 3.22873996 0.036 4 P 0 0;4=6,6=1
P 3.17873996 0.036 4 P 0 0;4=6,6=1
P 3.67873996 0.036 4 P 0 0;4=6,6=1
P 3.62873996 0.036 4 P 0 0;4=6,6=1
P 3.57873996 0.036 4 P 0 0;4=6,6=1
P 3.52873996 0.036 4 P 0 0;4=6,6=1
P 3.47873996 0.036 4 P 0 0;4=6,6=1
P 3.42873996 0.036 4 P 0 0;4=6,6=1
P 3.92873996 0.036 4 P 0 0;4=6,6=1
P 3.87873996 0.036 4 P 0 0;4=6,6=1
P 3.82873996 0.036 4 P 0 0;4=6,6=1
P 3.77873996 0.036 4 P 0 0;4=6,6=1
P 3.72873996 0.036 4 P 0 0;4=6,6=1
P 4.17873996 0.036 4 P 0 0;4=6,6=1
P 4.12873996 0.036 4 P 0 0;4=6,6=1
P 4.07873996 0.036 4 P 0 0;4=6,6=1
P 4.02873996 0.036 4 P 0 0;4=6,6=1
P 3.97873996 0.036 4 P 0 0;4=6,6=1
P 4.42873996 0.036 4 P 0 0;4=6,6=1
P 4.37873996 0.036 4 P 0 0;4=6,6=1
P 4.32873996 0.036 4 P 0 0;4=6,6=1
P 4.27873996 0.036 4 P 0 0;4=6,6=1
P 4.22873996 0.036 4 P 0 0;4=6,6=1
P 4.72873996 0.036 4 P 0 0;4=6,6=1
P 4.67873996 0.036 4 P 0 0;4=6,6=1
P 4.62873996 0.036 4 P 0 0;4=6,6=1
P 4.57873996 0.036 4 P 0 0;4=6,6=1
P 4.52873996 0.036 4 P 0 0;4=6,6=1
P 4.47873996 0.036 4 P 0 0;4=6,6=1
P 4.81833996 0.21825 4 P 0 0;4=6,6=1
P 4.81833996 0.16825 4 P 0 0;4=6,6=1
P 4.81833996 0.11825 4 P 0 0;4=6,6=1
P 4.81703996 0.06826004 4 P 0 0;4=6,6=1
P 4.77873996 0.03611998 4 P 0 0;4=6,6=1
P 6.80731004 0.036 4 P 0 0;4=6,6=1
P 6.75731004 0.036 4 P 0 0;4=6,6=1
P 6.70731004 0.036 4 P 0 0;4=6,6=1
P 6.65731004 0.03676004 4 P 0 0;4=6,6=1
P 6.62298996 0.07311998 4 P 0 0;4=6,6=1
P 6.62261998 0.12311998 4 P 0 0;4=6,6=1
P 6.62261998 0.17311998 4 P 0 0;4=6,6=1
P 6.62261998 0.22311998 4 P 0 0;4=6,6=1
P 7.00731004 0.036 4 P 0 0;4=6,6=1
P 6.95731004 0.036 4 P 0 0;4=6,6=1
P 6.90731004 0.036 4 P 0 0;4=6,6=1
P 6.85731004 0.036 4 P 0 0;4=6,6=1
P 0.036 0.25868002 4 P 0 0;4=6,6=1
P 0.036 0.30868002 4 P 0 0;4=6,6=1
P 0.036 0.35868002 4 P 0 0;4=6,6=1
P 0.036 0.40868002 4 P 0 0;4=6,6=1
P 0.036 0.45868002 4 P 0 0;4=6,6=1
P 4.96803996 0.46906998 4 P 0 0;4=6,6=1
P 4.91805 0.46808002 4 P 0 0;4=6,6=1
P 4.87108996 0.45088996 4 P 0 0;4=6,6=1
P 4.83591004 0.41536004 4 P 0 0;4=6,6=1
P 4.81918996 0.36823996 4 P 0 0;4=6,6=1
P 4.81833996 0.31825 4 P 0 0;4=6,6=1
P 4.81833996 0.26825 4 P 0 0;4=6,6=1
P 5.21803996 0.46906998 4 P 0 0;4=6,6=1
P 5.16803996 0.46906998 4 P 0 0;4=6,6=1
P 5.11803996 0.46906998 4 P 0 0;4=6,6=1
P 5.06803996 0.46906998 4 P 0 0;4=6,6=1
P 5.01803996 0.46906998 4 P 0 0;4=6,6=1
P 5.51803996 0.46906998 4 P 0 0;4=6,6=1
P 5.46803996 0.46906998 4 P 0 0;4=6,6=1
P 5.41803996 0.46906998 4 P 0 0;4=6,6=1
P 5.36803996 0.46906998 4 P 0 0;4=6,6=1
P 5.31803996 0.46906998 4 P 0 0;4=6,6=1
P 5.26803996 0.46906998 4 P 0 0;4=6,6=1
P 5.76803996 0.46906998 4 P 0 0;4=6,6=1
P 5.71803996 0.46906998 4 P 0 0;4=6,6=1
P 5.66803996 0.46906998 4 P 0 0;4=6,6=1
P 5.61803996 0.46906998 4 P 0 0;4=6,6=1
P 5.56803996 0.46906998 4 P 0 0;4=6,6=1
P 6.01803996 0.46906998 4 P 0 0;4=6,6=1
P 5.96803996 0.46906998 4 P 0 0;4=6,6=1
P 5.91803996 0.46906998 4 P 0 0;4=6,6=1
P 5.86803996 0.46906998 4 P 0 0;4=6,6=1
P 5.81803996 0.46906998 4 P 0 0;4=6,6=1
P 6.31803996 0.46906998 4 P 0 0;4=6,6=1
P 6.26803996 0.46906998 4 P 0 0;4=6,6=1
P 6.21803996 0.46906998 4 P 0 0;4=6,6=1
P 6.16803996 0.46906998 4 P 0 0;4=6,6=1
P 6.11803996 0.46906998 4 P 0 0;4=6,6=1
P 6.06803996 0.46906998 4 P 0 0;4=6,6=1
P 6.56568002 0.45345 4 P 0 0;4=6,6=1
P 6.51803002 0.46861998 4 P 0 0;4=6,6=1
P 6.46803996 0.46906998 4 P 0 0;4=6,6=1
P 6.41803996 0.46906998 4 P 0 0;4=6,6=1
P 6.36803996 0.46906998 4 P 0 0;4=6,6=1
P 6.62261998 0.27311998 4 P 0 0;4=6,6=1
P 6.62261998 0.32311998 4 P 0 0;4=6,6=1
P 6.62106998 0.3731 4 P 0 0;4=6,6=1
P 6.60233996 0.41946004 4 P 0 0;4=6,6=1
P 0.036 0.50868002 4 P 0 0;4=6,6=1
P 0.036 0.55868002 4 P 0 0;4=6,6=1
P 5.40386004 2.96 26 P 0 0;1,4=11,6=0
P 5.40386004 3.04 26 P 0 0;1,4=11,6=0
P 5.40386004 3.12 26 P 0 0;1,4=11,6=0
P 11.40778996 3.04 26 P 0 0;1,4=11,6=0
P 11.40778996 3.12 26 P 0 0;1,4=11,6=0
P 11.40778996 2.96 26 P 0 0;1,4=11,6=0
P 11.80693002 2.85 29 P 0 0;1,4=8,6=0
P 11.845 2.85 4 P 0 0;4=6,6=1
P 8.98115 2.7861 4 P 0 0;4=6,6=1
P 8.98115 2.8989 4 P 0 0;4=6,6=1
P 11.58613002 2.855 4 P 0 0;4=6,6=1
P 11.50361998 2.8 4 P 0 0;4=6,6=1
P 11.50361998 2.73 4 P 0 0;4=6,6=1
P 5.6152 3 24 P 0 0;1,4=0,6=0
P 5.5722 3 4 P 0 0;4=6,6=1
P 5.72185 3.02558996 29 P 0 0;1,4=8,6=0
P 5.75778996 3.02558996 4 P 0 0;4=6,6=1
P 5.9192 2.943 4 P 0 0;4=6,6=1
P 4.07386004 2.55 4 P 0 0;4=6,6=1
P 3.86826998 2.64558996 4 P 0 0;4=6,6=1
P 9.95743996 2.87558996 29 P 0 0;1,4=8,6=0
P 9.995 2.87558996 4 P 0 0;4=6,6=1
P 10.11778996 2.78 4 P 0 0;4=6,6=1
P 7.2426 4.60351004 4 P 0 0;4=6,6=1
P 7.3401 4.85601004 4 P 0 0;4=6,6=1
P 7.1926 5.04351004 4 P 0 0;4=6,6=1
P 0.66 2.045 6 P 0 0;2,4=1,6=1
P 1.792 2.4781 4 P 0 0;4=6,6=1
P 2.97721004 2.8989 4 P 0 0;4=6,6=1
P 2.97721004 2.7861 4 P 0 0;4=6,6=1
P 2.9422 2.925 4 P 0 0;4=6,6=1
P 8.94278996 2.925 4 P 0 0;4=6,6=1
P 5.5822 2.855 4 P 0 0;4=6,6=1
P 5.84968996 2.85 4 P 0 0;4=6,6=1
P 0.65348996 1.85608996 4 P 0 0;4=6,6=1
P 0.65348996 1.91628996 4 P 0 0;4=6,6=1
P 0.09448996 4.60236998 7 P 0 0;2,4=2,6=0
P 0.35038996 4.20866004 7 P 0 0;4=2,6=0
P 0.09448996 4.2874 7 P 0 0;4=2,6=0
P 0.09448996 4.12991998 7 P 0 0;4=2,6=0
P 0.17323002 4.16928996 7 P 0 0;4=2,6=0
P 0.27165 4.09055 7 P 0 0;4=2,6=0
P 0.27165 3.93306998 7 P 0 0;4=2,6=0
P 0.35038996 4.05118002 7 P 0 0;4=2,6=0
P 0.35038996 3.8937 7 P 0 0;4=2,6=0
P 0.09448996 3.97243996 7 P 0 0;4=2,6=0
P 0.09448996 3.81496004 7 P 0 0;4=2,6=0
P 0.17323002 4.01181004 7 P 0 0;4=2,6=0
P 0.17323002 3.85433002 7 P 0 0;4=2,6=0
P 0.27165 3.77558996 7 P 0 0;4=2,6=0
P 0.27165 3.61811004 7 P 0 0;4=2,6=0
P 0.35038996 3.73621998 7 P 0 0;4=2,6=0
P 0.35038996 3.57873996 7 P 0 0;4=2,6=0
P 0.09448996 3.65748002 7 P 0 0;4=2,6=0
P 0.09448996 3.5 7 P 0 0;4=2,6=0
P 0.17323002 3.69685 7 P 0 0;4=2,6=0
P 0.17323002 3.53936998 7 P 0 0;4=2,6=0
P 0.27165 3.46063002 7 P 0 0;4=2,6=0
P 0.35038996 3.42126004 7 P 0 0;4=2,6=0
P 0.27165 3.30315 7 P 0 0;4=2,6=0
P 0.27165 3.22441004 7 P 0 0;4=2,6=0
P 0.17323002 3.38188996 7 P 0 0;4=2,6=0
P 0.17323002 3.30315 7 P 0 0;4=2,6=0
P 0.35038996 3.1063 7 P 0 0;4=2,6=0
P 0.35038996 2.94881998 7 P 0 0;4=2,6=0
P 0.27165 3.06693002 7 P 0 0;4=2,6=0
P 0.27165 2.90945 7 P 0 0;4=2,6=0
P 0.17323002 3.14566998 7 P 0 0;4=2,6=0
P 0.17323002 2.98818996 7 P 0 0;4=2,6=0
P 0.09448996 3.18503996 7 P 0 0;4=2,6=0
P 0.09448996 3.02756004 7 P 0 0;4=2,6=0
P 0.35038996 2.79133996 7 P 0 0;4=2,6=0
P 0.27165 2.75196998 7 P 0 0;4=2,6=0
P 0.35038996 2.63386004 7 P 0 0;4=2,6=0
P 0.17323002 2.83071004 7 P 0 0;4=2,6=0
P 0.09448996 2.87008002 7 P 0 0;4=2,6=0
P 0.09448996 2.7126 7 P 0 0;4=2,6=0
P 0.35038996 2.39763996 7 P 0 0;4=2,6=0
P 0.27165 2.51575 7 P 0 0;4=2,6=0
P 0.27165 2.35826998 7 P 0 0;4=2,6=0
P 0.17323002 2.59448996 7 P 0 0;4=2,6=0
P 0.17323002 2.43701004 7 P 0 0;4=2,6=0
P 0.09448996 2.47638002 7 P 0 0;4=2,6=0
P 0.09448996 2.3189 7 P 0 0;4=2,6=0
P 0.35038996 2.24016004 7 P 0 0;4=2,6=0
P 0.35038996 2.08268002 7 P 0 0;4=2,6=0
P 0.35038996 2.00393996 7 P 0 0;4=2,6=0
P 0.27165 2.20078996 7 P 0 0;4=2,6=0
P 0.17323002 2.27953002 7 P 0 0;4=2,6=0
P 0.09448996 2.16141998 7 P 0 0;4=2,6=0
P 0.09448996 2.08268002 7 P 0 0;4=2,6=0
P 0.17323002 1.96456998 7 P 0 0;4=2,6=0
P 0.09448996 1.84646004 7 P 0 0;4=2,6=0
P 0.09448996 4.44488002 7 P 0 0;4=2,6=0
P 12.63778996 2.00393996 7 P 0 0;4=2,6=0
P 12.55905 2.12205 7 P 0 0;4=2,6=0
P 12.55905 1.88583002 7 P 0 0;4=2,6=0
P 12.81495 2.12205 7 P 0 0;4=2,6=0
P 12.81495 2.04331004 7 P 0 0;4=2,6=0
P 12.73621004 2.39763996 7 P 0 0;4=2,6=0
P 12.73621004 2.24016004 7 P 0 0;4=2,6=0
P 12.63778996 2.3189 7 P 0 0;4=2,6=0
P 12.55905 2.35826998 7 P 0 0;4=2,6=0
P 12.55905 2.20078996 7 P 0 0;4=2,6=0
P 12.81495 2.43701004 7 P 0 0;4=2,6=0
P 12.81495 2.27953002 7 P 0 0;4=2,6=0
P 12.73621004 2.55511998 7 P 0 0;4=2,6=0
P 12.63778996 2.63386004 7 P 0 0;4=2,6=0
P 12.63778996 2.47638002 7 P 0 0;4=2,6=0
P 12.55905 2.51575 7 P 0 0;4=2,6=0
P 12.81495 2.67323002 7 P 0 0;4=2,6=0
P 12.73621004 2.94881998 7 P 0 0;4=2,6=0
P 12.73621004 2.79133996 7 P 0 0;4=2,6=0
P 12.63778996 3.02756004 7 P 0 0;4=2,6=0
P 12.63778996 2.87008002 7 P 0 0;4=2,6=0
P 12.55905 2.90945 7 P 0 0;4=2,6=0
P 12.55905 2.75196998 7 P 0 0;4=2,6=0
P 12.81495 2.98818996 7 P 0 0;4=2,6=0
P 12.81495 2.83071004 7 P 0 0;4=2,6=0
P 12.73621004 3.26378002 7 P 0 0;4=2,6=0
P 12.73621004 3.1063 7 P 0 0;4=2,6=0
P 12.63778996 3.18503996 7 P 0 0;4=2,6=0
P 12.55905 3.22441004 7 P 0 0;4=2,6=0
P 12.55905 3.06693002 7 P 0 0;4=2,6=0
P 12.81495 3.14566998 7 P 0 0;4=2,6=0
P 12.55905 3.53936998 7 P 0 0;4=2,6=0
P 12.63778996 3.57873996 7 P 0 0;4=2,6=0
P 12.63778996 3.42126004 7 P 0 0;4=2,6=0
P 12.73621004 3.5 7 P 0 0;4=2,6=0
P 12.73621004 3.34251998 7 P 0 0;4=2,6=0
P 12.63778996 3.34251998 7 P 0 0;4=2,6=0
P 12.81495 3.61811004 7 P 0 0;4=2,6=0
P 12.81495 3.46063002 7 P 0 0;4=2,6=0
P 12.55905 3.85433002 7 P 0 0;4=2,6=0
P 12.55905 3.69685 7 P 0 0;4=2,6=0
P 12.63778996 3.8937 7 P 0 0;4=2,6=0
P 12.63778996 3.73621998 7 P 0 0;4=2,6=0
P 12.73621004 3.81496004 7 P 0 0;4=2,6=0
P 12.73621004 3.65748002 7 P 0 0;4=2,6=0
P 12.81495 3.93306998 7 P 0 0;4=2,6=0
P 12.81495 3.77558996 7 P 0 0;4=2,6=0
P 12.55905 4.16928996 7 P 0 0;4=2,6=0
P 12.55905 4.01181004 7 P 0 0;4=2,6=0
P 12.63778996 4.20866004 7 P 0 0;4=2,6=0
P 12.63778996 4.05118002 7 P 0 0;4=2,6=0
P 12.73621004 4.12991998 7 P 0 0;4=2,6=0
P 12.73621004 3.97243996 7 P 0 0;4=2,6=0
P 12.81495 4.09055 7 P 0 0;4=2,6=0
P 12.55905 4.48425 7 P 0 0;4=2,6=0
P 12.55905 4.32676998 7 P 0 0;4=2,6=0
P 12.63778996 4.52361998 7 P 0 0;4=2,6=0
P 12.63778996 4.36613996 7 P 0 0;4=2,6=0
P 12.73621004 4.44488002 7 P 0 0;4=2,6=0
P 12.73621004 4.2874 7 P 0 0;4=2,6=0
P 12.81495 4.40551004 7 P 0 0;4=2,6=0
P 12.81495 4.24803002 7 P 0 0;4=2,6=0
P 12.55905 4.64173996 7 P 0 0;4=2,6=0
P 12.81495 4.56298996 7 P 0 0;4=2,6=0
P 0.27165 4.40551004 7 P 0 0;4=2,6=0
P 0.35038996 4.52361998 7 P 0 0;4=2,6=0
P 0.17323002 4.48425 7 P 0 0;4=2,6=0
P 0.27165 4.24803002 7 P 0 0;4=2,6=0
P 0.35038996 4.36613996 7 P 0 0;4=2,6=0
P 0.17323002 4.32676998 7 P 0 0;4=2,6=0
P 5.49221004 2.73 4 P 0 0;4=6,6=1
P 5.803 2.85 29 P 0 0;1,4=8,6=0
P 5.61268996 2.855 24 P 0 0;1,4=0,6=0
P 5.44886004 2.9414 4 P 0 0;4=6,6=1
P 5.44886004 3.0214 4 P 0 0;4=6,6=1
P 5.44886004 3.0564 4 P 0 0;4=6,6=1
P 5.44886004 3.1014 4 P 0 0;4=6,6=1
P 5.44886004 3.1364 4 P 0 0;4=6,6=1
P 5.44886004 3.2164 4 P 0 0;4=6,6=1
P 5.44886004 3.1814 4 P 0 0;4=6,6=1
P 5.44886004 2.9764 4 P 0 0;4=6,6=1
P 5.44886004 3.2614 4 P 0 0;4=6,6=1
P 5.44886004 3.2964 4 P 0 0;4=6,6=1
P 10.33998996 4.9231 4 P 0 0;4=6,6=1
P 10.38498996 4.9231 6 P 0 0;2,4=1,6=1
P 10.77498996 4.9231 4 P 0 0;4=6,6=1
P 10.72998996 4.9231 4 P 0 0;4=6,6=1
P 10.30498996 4.9431 4 P 0 0;4=6,6=1
P 10.26498996 4.9431 4 P 0 0;4=6,6=1
P 10.30498996 5.0281 4 P 0 0;4=6,6=1
P 10.30498996 5.0731 4 P 0 0;4=6,6=1
P 10.30498996 4.9831 4 P 0 0;4=6,6=1
P 10.26498996 5.0281 4 P 0 0;4=6,6=1
P 10.26498996 5.0731 4 P 0 0;4=6,6=1
P 10.26498996 4.9831 4 P 0 0;4=6,6=1
P 10.26498996 5.1181 4 P 0 0;4=6,6=1
P 10.30498996 5.1181 4 P 0 0;4=6,6=1
P 10.34498996 5.1181 4 P 0 0;4=6,6=1
P 10.42498996 4.9431 4 P 0 0;4=6,6=1
P 10.46498996 4.9431 4 P 0 0;4=6,6=1
P 10.38498996 5.1181 4 P 0 0;4=6,6=1
P 10.46498996 5.1181 4 P 0 0;4=6,6=1
P 10.42498996 5.1181 4 P 0 0;4=6,6=1
P 10.42498996 4.9831 4 P 0 0;4=6,6=1
P 10.42498996 5.0731 4 P 0 0;4=6,6=1
P 10.42498996 5.0281 4 P 0 0;4=6,6=1
P 10.46498996 4.9831 4 P 0 0;4=6,6=1
P 10.46498996 5.0731 4 P 0 0;4=6,6=1
P 10.46498996 5.0281 4 P 0 0;4=6,6=1
P 10.85498996 4.9431 4 P 0 0;4=6,6=1
P 10.81498996 4.9431 4 P 0 0;4=6,6=1
P 10.65498996 4.9431 4 P 0 0;4=6,6=1
P 10.69498996 4.9431 4 P 0 0;4=6,6=1
P 10.85498996 5.0281 4 P 0 0;4=6,6=1
P 10.85498996 5.0731 4 P 0 0;4=6,6=1
P 10.85498996 4.9831 4 P 0 0;4=6,6=1
P 10.81498996 5.0281 4 P 0 0;4=6,6=1
P 10.81498996 5.0731 4 P 0 0;4=6,6=1
P 10.81498996 4.9831 4 P 0 0;4=6,6=1
P 10.81498996 5.1181 4 P 0 0;4=6,6=1
P 10.85498996 5.1181 4 P 0 0;4=6,6=1
P 10.73498996 5.1181 4 P 0 0;4=6,6=1
P 10.69498996 5.1181 4 P 0 0;4=6,6=1
P 10.65498996 5.1181 4 P 0 0;4=6,6=1
P 10.77498996 5.1181 4 P 0 0;4=6,6=1
P 10.65498996 4.9831 4 P 0 0;4=6,6=1
P 10.65498996 5.0731 4 P 0 0;4=6,6=1
P 10.65498996 5.0281 4 P 0 0;4=6,6=1
P 10.69498996 4.9831 4 P 0 0;4=6,6=1
P 10.69498996 5.0731 4 P 0 0;4=6,6=1
P 10.69498996 5.0281 4 P 0 0;4=6,6=1
P 1.23906004 4.60351004 4 P 0 0;4=6,6=1
P 1.18906004 5.04351004 4 P 0 0;4=6,6=1
P 1.33656004 4.85601004 4 P 0 0;4=6,6=1
P 10.16606998 2.81 4 P 0 0;4=6,6=1
P 3.91351004 2.64558996 29 P 0 0;1,4=8,6=0
P 4.15221004 2.9281 4 P 0 0;4=6,6=1
P 4.09086004 2.59 24 P 0 0;1,4=0,6=0
P 10.13478996 2.82 24 P 0 0;1,4=0,6=0
P 11.45278996 2.9414 4 P 0 0;4=6,6=1
P 11.45278996 3.0214 4 P 0 0;4=6,6=1
P 11.45278996 3.0564 4 P 0 0;4=6,6=1
P 11.45278996 3.1014 4 P 0 0;4=6,6=1
P 11.45278996 3.1364 4 P 0 0;4=6,6=1
P 11.45278996 3.2164 4 P 0 0;4=6,6=1
P 11.45278996 3.1814 4 P 0 0;4=6,6=1
P 11.45278996 2.9764 4 P 0 0;4=6,6=1
P 11.45278996 3.2614 4 P 0 0;4=6,6=1
P 11.45278996 3.2964 4 P 0 0;4=6,6=1
P 11.47061998 2.73 24 P 0 0;1,4=0,6=0
P 11.47061998 2.8 24 P 0 0;1,4=0,6=0
P 11.61661998 2.855 24 P 0 0;1,4=0,6=0
P 0.09448996 1.45276004 7 P 0 0;4=2,6=0
P 0.27165 1.57086998 7 P 0 0;4=2,6=0
P 0.35038996 1.45276004 7 P 0 0;4=2,6=0
P 12.81495 1.49213002 7 P 0 0;4=2,6=0
P 12.73621004 1.61023996 7 P 0 0;4=2,6=0
P 12.55905 1.49213002 7 P 0 0;4=2,6=0
P 0.27165 1.88583002 7 P 0 0;4=2,6=0
P 12.73621004 1.9252 7 P 0 0;4=2,6=0
P 5.46168996 2.73 24 P 0 0;1,4=0,6=0
P 5.46168996 2.8 24 P 0 0;1,4=0,6=0
P 11.40778996 3.28 26 P 0 0;1,4=11,6=0
P 11.40778996 3.2 26 P 0 0;1,4=11,6=0
P 5.40386004 3.2 26 P 0 0;1,4=11,6=0
P 5.40386004 3.28 26 P 0 0;1,4=11,6=0
P 7.35731004 0.036 4 P 0 0;4=6,6=1
P 7.60731004 0.036 4 P 0 0;4=6,6=1
P 7.55731004 0.036 4 P 0 0;4=6,6=1
P 7.50731004 0.036 4 P 0 0;4=6,6=1
P 7.45731004 0.036 4 P 0 0;4=6,6=1
P 7.40731004 0.036 4 P 0 0;4=6,6=1
P 7.85731004 0.036 4 P 0 0;4=6,6=1
P 7.80731004 0.036 4 P 0 0;4=6,6=1
P 7.75731004 0.036 4 P 0 0;4=6,6=1
P 7.70731004 0.036 4 P 0 0;4=6,6=1
P 7.65731004 0.036 4 P 0 0;4=6,6=1
P 8.15731004 0.036 4 P 0 0;4=6,6=1
P 8.10731004 0.036 4 P 0 0;4=6,6=1
P 8.05731004 0.036 4 P 0 0;4=6,6=1
P 8.00731004 0.036 4 P 0 0;4=6,6=1
P 7.95731004 0.036 4 P 0 0;4=6,6=1
P 7.90731004 0.036 4 P 0 0;4=6,6=1
P 8.40731004 0.036 4 P 0 0;4=6,6=1
P 8.35731004 0.036 4 P 0 0;4=6,6=1
P 8.30731004 0.036 4 P 0 0;4=6,6=1
P 8.25731004 0.036 4 P 0 0;4=6,6=1
P 8.20731004 0.036 4 P 0 0;4=6,6=1
P 8.65731004 0.036 4 P 0 0;4=6,6=1
P 8.60731004 0.036 4 P 0 0;4=6,6=1
P 8.55731004 0.036 4 P 0 0;4=6,6=1
P 8.50731004 0.036 4 P 0 0;4=6,6=1
P 8.45731004 0.036 4 P 0 0;4=6,6=1
P 8.90731004 0.036 4 P 0 0;4=6,6=1
P 8.85731004 0.036 4 P 0 0;4=6,6=1
P 8.80731004 0.036 4 P 0 0;4=6,6=1
P 8.75731004 0.036 4 P 0 0;4=6,6=1
P 8.70731004 0.036 4 P 0 0;4=6,6=1
P 9.20731004 0.036 4 P 0 0;4=6,6=1
P 9.15731004 0.036 4 P 0 0;4=6,6=1
P 9.10731004 0.036 4 P 0 0;4=6,6=1
P 9.05731004 0.036 4 P 0 0;4=6,6=1
P 9.00731004 0.036 4 P 0 0;4=6,6=1
P 8.95731004 0.036 4 P 0 0;4=6,6=1
P 9.45731004 0.036 4 P 0 0;4=6,6=1
P 9.40731004 0.036 4 P 0 0;4=6,6=1
P 9.35731004 0.036 4 P 0 0;4=6,6=1
P 9.30731004 0.036 4 P 0 0;4=6,6=1
P 9.25731004 0.036 4 P 0 0;4=6,6=1
P 9.70731004 0.036 4 P 0 0;4=6,6=1
P 9.65731004 0.036 4 P 0 0;4=6,6=1
P 9.60731004 0.036 4 P 0 0;4=6,6=1
P 9.55731004 0.036 4 P 0 0;4=6,6=1
P 9.50731004 0.036 4 P 0 0;4=6,6=1
P 10.00731004 0.036 4 P 0 0;4=6,6=1
P 9.95731004 0.036 4 P 0 0;4=6,6=1
P 9.90731004 0.036 4 P 0 0;4=6,6=1
P 9.85731004 0.036 4 P 0 0;4=6,6=1
P 9.80731004 0.036 4 P 0 0;4=6,6=1
P 9.75731004 0.036 4 P 0 0;4=6,6=1
P 10.25731004 0.036 4 P 0 0;4=6,6=1
P 10.20731004 0.036 4 P 0 0;4=6,6=1
P 10.15731004 0.036 4 P 0 0;4=6,6=1
P 10.10731004 0.036 4 P 0 0;4=6,6=1
P 10.05731004 0.036 4 P 0 0;4=6,6=1
P 10.50731004 0.036 4 P 0 0;4=6,6=1
P 10.45731004 0.036 4 P 0 0;4=6,6=1
P 10.40731004 0.036 4 P 0 0;4=6,6=1
P 10.35731004 0.036 4 P 0 0;4=6,6=1
P 10.30731004 0.036 4 P 0 0;4=6,6=1
P 10.75731004 0.036 4 P 0 0;4=6,6=1
P 10.70731004 0.036 4 P 0 0;4=6,6=1
P 10.65731004 0.036 4 P 0 0;4=6,6=1
P 10.60731004 0.036 4 P 0 0;4=6,6=1
P 10.55731004 0.036 4 P 0 0;4=6,6=1
P 11.05731004 0.036 4 P 0 0;4=6,6=1
P 11.00731004 0.036 4 P 0 0;4=6,6=1
P 10.95731004 0.036 4 P 0 0;4=6,6=1
P 10.90731004 0.036 4 P 0 0;4=6,6=1
P 10.85731004 0.036 4 P 0 0;4=6,6=1
P 10.80731004 0.036 4 P 0 0;4=6,6=1
P 11.30731004 0.036 4 P 0 0;4=6,6=1
P 11.25731004 0.036 4 P 0 0;4=6,6=1
P 11.20731004 0.036 4 P 0 0;4=6,6=1
P 11.15731004 0.036 4 P 0 0;4=6,6=1
P 11.10731004 0.036 4 P 0 0;4=6,6=1
P 11.55731004 0.036 4 P 0 0;4=6,6=1
P 11.50731004 0.036 4 P 0 0;4=6,6=1
P 11.45731004 0.036 4 P 0 0;4=6,6=1
P 11.40731004 0.036 4 P 0 0;4=6,6=1
P 11.35731004 0.036 4 P 0 0;4=6,6=1
P 11.80731004 0.036 4 P 0 0;4=6,6=1
P 11.75731004 0.036 4 P 0 0;4=6,6=1
P 11.70731004 0.036 4 P 0 0;4=6,6=1
P 11.65731004 0.036 4 P 0 0;4=6,6=1
P 11.60731004 0.036 4 P 0 0;4=6,6=1
P 12.10731004 0.036 4 P 0 0;4=6,6=1
P 12.05731004 0.036 4 P 0 0;4=6,6=1
P 12.00731004 0.036 4 P 0 0;4=6,6=1
P 11.95731004 0.036 4 P 0 0;4=6,6=1
P 11.90731004 0.036 4 P 0 0;4=6,6=1
P 11.85731004 0.036 4 P 0 0;4=6,6=1
P 12.35731004 0.036 4 P 0 0;4=6,6=1
P 12.30731004 0.036 4 P 0 0;4=6,6=1
P 12.25731004 0.036 4 P 0 0;4=6,6=1
P 12.20731004 0.036 4 P 0 0;4=6,6=1
P 12.15731004 0.036 4 P 0 0;4=6,6=1
P 12.60731004 0.036 4 P 0 0;4=6,6=1
P 12.55731004 0.036 4 P 0 0;4=6,6=1
P 12.50731004 0.036 4 P 0 0;4=6,6=1
P 12.45731004 0.036 4 P 0 0;4=6,6=1
P 12.40731004 0.036 4 P 0 0;4=6,6=1
P 12.8892 0.22596004 4 P 0 0;4=6,6=1
P 12.8892 0.17596004 4 P 0 0;4=6,6=1
P 12.8892 0.12596004 4 P 0 0;4=6,6=1
P 12.88911004 0.07596004 4 P 0 0;4=6,6=1
P 12.85728996 0.03738996 4 P 0 0;4=6,6=1
P 12.80731004 0.036 4 P 0 0;4=6,6=1
P 12.75731004 0.036 4 P 0 0;4=6,6=1
P 12.70731004 0.036 4 P 0 0;4=6,6=1
P 12.65731004 0.036 4 P 0 0;4=6,6=1
P 12.8892 0.47596004 4 P 0 0;4=6,6=1
P 12.8892 0.42596004 4 P 0 0;4=6,6=1
P 12.8892 0.37596004 4 P 0 0;4=6,6=1
P 12.8892 0.32596004 4 P 0 0;4=6,6=1
P 12.8892 0.27596004 4 P 0 0;4=6,6=1
P 12.8892 0.62596004 4 P 0 0;4=6,6=1
P 12.8892 0.57596004 4 P 0 0;4=6,6=1
P 12.8892 0.52596004 4 P 0 0;4=6,6=1
P 0.036 1.00868002 4 P 0 0;4=6,6=1
P 0.036 1.05868002 4 P 0 0;4=6,6=1
P 0.036 1.10868002 4 P 0 0;4=6,6=1
P 0.036 1.15868002 4 P 0 0;4=6,6=1
P 0.036 1.20868002 4 P 0 0;4=6,6=1
P 0.036 1.25868002 4 P 0 0;4=6,6=1
P 0.036 1.30868002 4 P 0 0;4=6,6=1
P 0.036 1.35868002 4 P 0 0;4=6,6=1
P 0.036 1.40868002 4 P 0 0;4=6,6=1
P 0.036 1.45868002 4 P 0 0;4=6,6=1
P 0.036 1.50868002 4 P 0 0;4=6,6=1
P 0.036 1.55868002 4 P 0 0;4=6,6=1
P 0.036 1.60868002 4 P 0 0;4=6,6=1
P 0.036 1.65868002 4 P 0 0;4=6,6=1
P 0.036 1.70868002 4 P 0 0;4=6,6=1
P 0.036 1.75868002 4 P 0 0;4=6,6=1
P 0.036 1.80868002 4 P 0 0;4=6,6=1
P 0.036 1.85868002 4 P 0 0;4=6,6=1
P 0.036 1.90868002 4 P 0 0;4=6,6=1
P 0.036 1.95868002 4 P 0 0;4=6,6=1
P 0.036 2.00868002 4 P 0 0;4=6,6=1
P 0.036 2.05868002 4 P 0 0;4=6,6=1
P 0.036 2.10868002 4 P 0 0;4=6,6=1
P 0.036 2.15868002 4 P 0 0;4=6,6=1
P 0.036 2.20868002 4 P 0 0;4=6,6=1
P 0.036 2.25868002 4 P 0 0;4=6,6=1
P 0.036 2.30868002 4 P 0 0;4=6,6=1
P 0.036 2.35868002 4 P 0 0;4=6,6=1
P 0.036 2.40868002 4 P 0 0;4=6,6=1
P 0.036 2.45868002 4 P 0 0;4=6,6=1
P 0.036 2.50868002 4 P 0 0;4=6,6=1
P 0.036 2.55868002 4 P 0 0;4=6,6=1
P 0.036 2.60868002 4 P 0 0;4=6,6=1
P 0.036 2.65868002 4 P 0 0;4=6,6=1
P 0.036 2.70868002 4 P 0 0;4=6,6=1
P 0.036 2.75868002 4 P 0 0;4=6,6=1
P 0.036 2.80868002 4 P 0 0;4=6,6=1
P 0.036 2.85868002 4 P 0 0;4=6,6=1
P 0.036 2.90868002 4 P 0 0;4=6,6=1
P 0.036 2.95868002 4 P 0 0;4=6,6=1
P 0.036 3.00868002 4 P 0 0;4=6,6=1
P 0.036 3.05868002 4 P 0 0;4=6,6=1
P 0.036 3.10868002 4 P 0 0;4=6,6=1
P 0.036 3.15868002 4 P 0 0;4=6,6=1
P 0.036 3.20868002 4 P 0 0;4=6,6=1
P 0.036 3.25868002 4 P 0 0;4=6,6=1
P 0.036 3.30868002 4 P 0 0;4=6,6=1
P 0.036 3.35868002 4 P 0 0;4=6,6=1
P 0.036 3.40868002 4 P 0 0;4=6,6=1
P 0.036 3.45868002 4 P 0 0;4=6,6=1
P 0.036 3.50868002 4 P 0 0;4=6,6=1
P 0.036 3.55868002 4 P 0 0;4=6,6=1
P 0.036 3.60868002 4 P 0 0;4=6,6=1
P 0.036 3.65868002 4 P 0 0;4=6,6=1
P 0.036 3.70868002 4 P 0 0;4=6,6=1
P 0.036 3.75868002 4 P 0 0;4=6,6=1
P 0.036 3.80868002 4 P 0 0;4=6,6=1
P 0.036 3.85868002 4 P 0 0;4=6,6=1
P 0.036 3.90868002 4 P 0 0;4=6,6=1
P 0.036 3.95868002 4 P 0 0;4=6,6=1
P 0.036 4.00868002 4 P 0 0;4=6,6=1
P 0.036 4.05868002 4 P 0 0;4=6,6=1
P 0.036 4.10868002 4 P 0 0;4=6,6=1
P 0.036 4.15868002 4 P 0 0;4=6,6=1
P 0.036 4.20868002 4 P 0 0;4=6,6=1
P 0.036 4.25868002 4 P 0 0;4=6,6=1
P 0.036 4.30868002 4 P 0 0;4=6,6=1
P 0.036 4.35868002 4 P 0 0;4=6,6=1
P 0.036 4.40868002 4 P 0 0;4=6,6=1
P 0.036 4.45868002 4 P 0 0;4=6,6=1
P 0.036 4.50868002 4 P 0 0;4=6,6=1
P 0.036 4.55868002 4 P 0 0;4=6,6=1
P 0.036 4.60868002 4 P 0 0;4=6,6=1
P 0.036 4.65868002 4 P 0 0;4=6,6=1
P 0.036 4.70868002 4 P 0 0;4=6,6=1
P 0.036 4.75868002 4 P 0 0;4=6,6=1
P 12.8892 1.02596004 4 P 0 0;4=6,6=1
P 12.8892 1.27596004 4 P 0 0;4=6,6=1
P 12.8892 1.22596004 4 P 0 0;4=6,6=1
P 12.8892 1.17596004 4 P 0 0;4=6,6=1
P 12.8892 1.12596004 4 P 0 0;4=6,6=1
P 12.8892 1.07596004 4 P 0 0;4=6,6=1
P 12.8892 1.52596004 4 P 0 0;4=6,6=1
P 12.8892 1.47596004 4 P 0 0;4=6,6=1
P 12.8892 1.42596004 4 P 0 0;4=6,6=1
P 12.8892 1.37596004 4 P 0 0;4=6,6=1
P 12.8892 1.32596004 4 P 0 0;4=6,6=1
P 12.8892 1.77596004 4 P 0 0;4=6,6=1
P 12.8892 1.72596004 4 P 0 0;4=6,6=1
P 12.8892 1.67596004 4 P 0 0;4=6,6=1
P 12.8892 1.62596004 4 P 0 0;4=6,6=1
P 12.8892 1.57596004 4 P 0 0;4=6,6=1
P 12.8892 2.07596004 4 P 0 0;4=6,6=1
P 12.8892 2.02596004 4 P 0 0;4=6,6=1
P 12.8892 1.97596004 4 P 0 0;4=6,6=1
P 12.8892 1.92596004 4 P 0 0;4=6,6=1
P 12.8892 1.87596004 4 P 0 0;4=6,6=1
P 12.8892 1.82596004 4 P 0 0;4=6,6=1
P 12.8892 2.32596004 4 P 0 0;4=6,6=1
P 12.8892 2.27596004 4 P 0 0;4=6,6=1
P 12.8892 2.22596004 4 P 0 0;4=6,6=1
P 12.8892 2.17596004 4 P 0 0;4=6,6=1
P 12.8892 2.57596004 4 P 0 0;4=6,6=1
P 12.8892 2.52596004 4 P 0 0;4=6,6=1
P 12.8892 2.47596004 4 P 0 0;4=6,6=1
P 12.8892 2.42596004 4 P 0 0;4=6,6=1
P 12.8892 2.37596004 4 P 0 0;4=6,6=1
P 12.8892 2.82596004 4 P 0 0;4=6,6=1
P 12.8892 2.77596004 4 P 0 0;4=6,6=1
P 12.8892 2.72596004 4 P 0 0;4=6,6=1
P 12.8892 2.67596004 4 P 0 0;4=6,6=1
P 12.8892 2.62596004 4 P 0 0;4=6,6=1
P 12.8892 3.12596004 4 P 0 0;4=6,6=1
P 12.8892 3.07596004 4 P 0 0;4=6,6=1
P 12.8892 3.02596004 4 P 0 0;4=6,6=1
P 12.8892 2.97596004 4 P 0 0;4=6,6=1
P 12.8892 2.92596004 4 P 0 0;4=6,6=1
P 12.8892 2.87596004 4 P 0 0;4=6,6=1
P 12.8892 3.37596004 4 P 0 0;4=6,6=1
P 12.8892 3.32596004 4 P 0 0;4=6,6=1
P 12.8892 3.27596004 4 P 0 0;4=6,6=1
P 12.8892 3.22596004 4 P 0 0;4=6,6=1
P 12.8892 3.17596004 4 P 0 0;4=6,6=1
P 12.8892 3.62596004 4 P 0 0;4=6,6=1
P 12.8892 3.57596004 4 P 0 0;4=6,6=1
P 12.8892 3.52596004 4 P 0 0;4=6,6=1
P 12.8892 3.47596004 4 P 0 0;4=6,6=1
P 12.8892 3.42596004 4 P 0 0;4=6,6=1
P 12.8892 3.92596004 4 P 0 0;4=6,6=1
P 12.8892 3.87596004 4 P 0 0;4=6,6=1
P 12.8892 3.82596004 4 P 0 0;4=6,6=1
P 12.8892 3.77596004 4 P 0 0;4=6,6=1
P 12.8892 3.72596004 4 P 0 0;4=6,6=1
P 12.8892 3.67596004 4 P 0 0;4=6,6=1
P 12.8892 4.17596004 4 P 0 0;4=6,6=1
P 12.8892 4.12596004 4 P 0 0;4=6,6=1
P 12.8892 4.07596004 4 P 0 0;4=6,6=1
P 12.8892 4.02596004 4 P 0 0;4=6,6=1
P 12.8892 3.97596004 4 P 0 0;4=6,6=1
P 12.8892 4.42596004 4 P 0 0;4=6,6=1
P 12.8892 4.37596004 4 P 0 0;4=6,6=1
P 12.8892 4.32596004 4 P 0 0;4=6,6=1
P 12.8892 4.27596004 4 P 0 0;4=6,6=1
P 12.8892 4.22596004 4 P 0 0;4=6,6=1
P 12.8892 4.67596004 4 P 0 0;4=6,6=1
P 12.8892 4.62596004 4 P 0 0;4=6,6=1
P 12.8892 4.57596004 4 P 0 0;4=6,6=1
P 12.8892 4.52596004 4 P 0 0;4=6,6=1
P 12.8892 4.47596004 4 P 0 0;4=6,6=1
P 12.8892 4.82596004 4 P 0 0;4=6,6=1
P 12.8892 4.77596004 4 P 0 0;4=6,6=1
P 12.8892 4.72596004 4 P 0 0;4=6,6=1
P 0.036 5.25868002 4 P 0 0;4=6,6=1
P 0.036 5.30868002 4 P 0 0;4=6,6=1
P 0.036 5.35868002 4 P 0 0;4=6,6=1
P 0.036 5.40868002 4 P 0 0;4=6,6=1
P 0.036 5.45868002 4 P 0 0;4=6,6=1
P 0.036 5.50868002 4 P 0 0;4=6,6=1
P 0.036 5.55868002 4 P 0 0;4=6,6=1
P 0.036 5.60868002 4 P 0 0;4=6,6=1
P 0.036 5.65868002 4 P 0 0;4=6,6=1
P 0.036 5.70868002 4 P 0 0;4=6,6=1
P 0.036 5.75868002 4 P 0 0;4=6,6=1
P 0.036 5.80868002 4 P 0 0;4=6,6=1
P 0.036 5.85868002 4 P 0 0;4=6,6=1
P 0.036 5.90868002 4 P 0 0;4=6,6=1
P 0.03826998 5.95863002 4 P 0 0;4=6,6=1
P 0.07901004 5.98761998 4 P 0 0;4=6,6=1
P 0.12901004 5.98761998 4 P 0 0;4=6,6=1
P 0.17901004 5.98761998 4 P 0 0;4=6,6=1
P 0.22901004 5.98761998 4 P 0 0;4=6,6=1
P 0.27901004 5.98761998 4 P 0 0;4=6,6=1
P 0.32901004 5.98761998 4 P 0 0;4=6,6=1
P 0.37901004 5.98761998 4 P 0 0;4=6,6=1
P 0.42901004 5.98761998 4 P 0 0;4=6,6=1
P 0.47901004 5.98761998 4 P 0 0;4=6,6=1
P 0.52901004 5.98761998 4 P 0 0;4=6,6=1
P 0.57901004 5.98761998 4 P 0 0;4=6,6=1
P 0.62901004 5.98761998 4 P 0 0;4=6,6=1
P 0.67901004 5.98761998 4 P 0 0;4=6,6=1
P 0.72901004 5.98761998 4 P 0 0;4=6,6=1
P 0.77901004 5.98761998 4 P 0 0;4=6,6=1
P 0.82901004 5.98761998 4 P 0 0;4=6,6=1
P 0.87901004 5.98761998 4 P 0 0;4=6,6=1
P 0.92901004 5.98761998 4 P 0 0;4=6,6=1
P 0.97901004 5.98761998 4 P 0 0;4=6,6=1
P 1.02901004 5.98761998 4 P 0 0;4=6,6=1
P 1.07901004 5.98761998 4 P 0 0;4=6,6=1
P 1.12901004 5.98761998 4 P 0 0;4=6,6=1
P 1.17901004 5.98761998 4 P 0 0;4=6,6=1
P 1.22901004 5.98761998 4 P 0 0;4=6,6=1
P 1.27901004 5.98761998 4 P 0 0;4=6,6=1
P 1.32901004 5.98761998 4 P 0 0;4=6,6=1
P 1.37901004 5.98761998 4 P 0 0;4=6,6=1
P 1.42901004 5.98761998 4 P 0 0;4=6,6=1
P 1.47901004 5.98761998 4 P 0 0;4=6,6=1
P 1.52901004 5.98761998 4 P 0 0;4=6,6=1
P 1.57901004 5.98761998 4 P 0 0;4=6,6=1
P 1.62901004 5.98761998 4 P 0 0;4=6,6=1
P 1.67901004 5.98761998 4 P 0 0;4=6,6=1
P 1.72901004 5.98761998 4 P 0 0;4=6,6=1
P 1.77901004 5.98761998 4 P 0 0;4=6,6=1
P 1.82901004 5.98761998 4 P 0 0;4=6,6=1
P 1.87901004 5.98761998 4 P 0 0;4=6,6=1
P 1.92901004 5.98761998 4 P 0 0;4=6,6=1
P 1.97901004 5.98761998 4 P 0 0;4=6,6=1
P 2.02901004 5.98761998 4 P 0 0;4=6,6=1
P 2.07901004 5.98761998 4 P 0 0;4=6,6=1
P 2.12901004 5.98761998 4 P 0 0;4=6,6=1
P 2.17901004 5.98761998 4 P 0 0;4=6,6=1
P 2.22901004 5.98761998 4 P 0 0;4=6,6=1
P 2.27901004 5.98761998 4 P 0 0;4=6,6=1
P 2.32901004 5.98761998 4 P 0 0;4=6,6=1
P 2.37901004 5.98761998 4 P 0 0;4=6,6=1
P 2.42901004 5.98761998 4 P 0 0;4=6,6=1
P 2.47901004 5.98761998 4 P 0 0;4=6,6=1
P 2.52901004 5.98761998 4 P 0 0;4=6,6=1
P 2.57901004 5.98761998 4 P 0 0;4=6,6=1
P 2.62901004 5.98761998 4 P 0 0;4=6,6=1
P 2.67901004 5.98761998 4 P 0 0;4=6,6=1
P 2.72901004 5.98761998 4 P 0 0;4=6,6=1
P 2.77901004 5.98761998 4 P 0 0;4=6,6=1
P 2.82901004 5.98761998 4 P 0 0;4=6,6=1
P 2.87901004 5.98761998 4 P 0 0;4=6,6=1
P 2.92901004 5.98761998 4 P 0 0;4=6,6=1
P 2.97901004 5.98761998 4 P 0 0;4=6,6=1
P 3.02901004 5.98761998 4 P 0 0;4=6,6=1
P 3.07901004 5.98761998 4 P 0 0;4=6,6=1
P 3.12901004 5.98761998 4 P 0 0;4=6,6=1
P 3.17901004 5.98761998 4 P 0 0;4=6,6=1
P 3.22901004 5.98761998 4 P 0 0;4=6,6=1
P 3.27901004 5.98761998 4 P 0 0;4=6,6=1
P 3.32901004 5.98761998 4 P 0 0;4=6,6=1
P 3.37901004 5.98761998 4 P 0 0;4=6,6=1
P 3.42901004 5.98761998 4 P 0 0;4=6,6=1
P 3.47901004 5.98761998 4 P 0 0;4=6,6=1
P 3.52901004 5.98761998 4 P 0 0;4=6,6=1
P 3.57901004 5.98761998 4 P 0 0;4=6,6=1
P 3.62901004 5.98761998 4 P 0 0;4=6,6=1
P 3.67901004 5.98761998 4 P 0 0;4=6,6=1
P 3.72901004 5.98761998 4 P 0 0;4=6,6=1
P 3.77901004 5.98761998 4 P 0 0;4=6,6=1
P 3.82901004 5.98761998 4 P 0 0;4=6,6=1
P 3.87901004 5.98761998 4 P 0 0;4=6,6=1
P 3.92901004 5.98761998 4 P 0 0;4=6,6=1
P 3.97901004 5.98761998 4 P 0 0;4=6,6=1
P 4.02901004 5.98761998 4 P 0 0;4=6,6=1
P 4.07901004 5.98761998 4 P 0 0;4=6,6=1
P 4.12901004 5.98761998 4 P 0 0;4=6,6=1
P 4.17901004 5.98761998 4 P 0 0;4=6,6=1
P 4.22901004 5.98761998 4 P 0 0;4=6,6=1
P 4.27901004 5.98761998 4 P 0 0;4=6,6=1
P 4.32901004 5.98761998 4 P 0 0;4=6,6=1
P 4.37901004 5.98761998 4 P 0 0;4=6,6=1
P 4.42901004 5.98761998 4 P 0 0;4=6,6=1
P 4.47901004 5.98761998 4 P 0 0;4=6,6=1
P 4.52901004 5.98761998 4 P 0 0;4=6,6=1
P 4.57901004 5.98761998 4 P 0 0;4=6,6=1
P 4.62901004 5.98761998 4 P 0 0;4=6,6=1
P 4.67901004 5.98761998 4 P 0 0;4=6,6=1
P 4.72901004 5.98761998 4 P 0 0;4=6,6=1
P 4.77901004 5.98761998 4 P 0 0;4=6,6=1
P 4.82901004 5.98761998 4 P 0 0;4=6,6=1
P 4.87901004 5.98761998 4 P 0 0;4=6,6=1
P 4.92901004 5.98761998 4 P 0 0;4=6,6=1
P 4.97901004 5.98761998 4 P 0 0;4=6,6=1
P 5.02901004 5.98761998 4 P 0 0;4=6,6=1
P 5.07901004 5.98761998 4 P 0 0;4=6,6=1
P 5.12901004 5.98761998 4 P 0 0;4=6,6=1
P 5.17901004 5.98761998 4 P 0 0;4=6,6=1
P 5.22901004 5.98761998 4 P 0 0;4=6,6=1
P 5.27901004 5.98761998 4 P 0 0;4=6,6=1
P 5.32901004 5.98761998 4 P 0 0;4=6,6=1
P 5.37901004 5.98761998 4 P 0 0;4=6,6=1
P 5.42901004 5.98761998 4 P 0 0;4=6,6=1
P 5.47901004 5.98761998 4 P 0 0;4=6,6=1
P 5.52901004 5.98761998 4 P 0 0;4=6,6=1
P 5.57901004 5.98761998 4 P 0 0;4=6,6=1
P 5.62901004 5.98761998 4 P 0 0;4=6,6=1
P 5.67901004 5.98761998 4 P 0 0;4=6,6=1
P 5.72901004 5.98761998 4 P 0 0;4=6,6=1
P 5.77901004 5.98761998 4 P 0 0;4=6,6=1
P 5.82901004 5.98761998 4 P 0 0;4=6,6=1
P 5.87901004 5.98761998 4 P 0 0;4=6,6=1
P 5.92901004 5.98761998 4 P 0 0;4=6,6=1
P 5.97901004 5.98761998 4 P 0 0;4=6,6=1
P 6.02901004 5.98761998 4 P 0 0;4=6,6=1
P 6.07901004 5.98761998 4 P 0 0;4=6,6=1
P 6.12901004 5.98761998 4 P 0 0;4=6,6=1
P 6.17901004 5.98761998 4 P 0 0;4=6,6=1
P 6.22901004 5.98761998 4 P 0 0;4=6,6=1
P 6.27901004 5.98761998 4 P 0 0;4=6,6=1
P 6.32901004 5.98761998 4 P 0 0;4=6,6=1
P 6.37901004 5.98761998 4 P 0 0;4=6,6=1
P 6.42901004 5.98761998 4 P 0 0;4=6,6=1
P 6.47901004 5.98761998 4 P 0 0;4=6,6=1
P 6.52901004 5.98761998 4 P 0 0;4=6,6=1
P 6.57901004 5.98761998 4 P 0 0;4=6,6=1
P 6.62901004 5.98761998 4 P 0 0;4=6,6=1
P 6.67901004 5.98761998 4 P 0 0;4=6,6=1
P 6.72901004 5.98761998 4 P 0 0;4=6,6=1
P 6.77901004 5.98761998 4 P 0 0;4=6,6=1
P 6.82901004 5.98761998 4 P 0 0;4=6,6=1
P 6.87901004 5.98761998 4 P 0 0;4=6,6=1
P 6.92901004 5.98761998 4 P 0 0;4=6,6=1
P 6.97901004 5.98761998 4 P 0 0;4=6,6=1
P 12.8892 5.47596004 4 P 0 0;4=6,6=1
P 12.8892 5.42596004 4 P 0 0;4=6,6=1
P 12.8892 5.37596004 4 P 0 0;4=6,6=1
P 12.8892 5.32596004 4 P 0 0;4=6,6=1
P 12.8892 5.27596004 4 P 0 0;4=6,6=1
P 12.8892 5.72596004 4 P 0 0;4=6,6=1
P 12.8892 5.67596004 4 P 0 0;4=6,6=1
P 12.8892 5.62596004 4 P 0 0;4=6,6=1
P 12.8892 5.57596004 4 P 0 0;4=6,6=1
P 12.8892 5.52596004 4 P 0 0;4=6,6=1
P 7.37901004 5.98761998 4 P 0 0;4=6,6=1
P 7.42901004 5.98761998 4 P 0 0;4=6,6=1
P 7.47901004 5.98761998 4 P 0 0;4=6,6=1
P 7.52901004 5.98761998 4 P 0 0;4=6,6=1
P 7.57901004 5.98761998 4 P 0 0;4=6,6=1
P 7.62901004 5.98761998 4 P 0 0;4=6,6=1
P 7.67901004 5.98761998 4 P 0 0;4=6,6=1
P 7.72901004 5.98761998 4 P 0 0;4=6,6=1
P 7.77901004 5.98761998 4 P 0 0;4=6,6=1
P 7.82901004 5.98761998 4 P 0 0;4=6,6=1
P 7.87901004 5.98761998 4 P 0 0;4=6,6=1
P 7.92901004 5.98761998 4 P 0 0;4=6,6=1
P 7.97901004 5.98761998 4 P 0 0;4=6,6=1
P 8.02901004 5.98761998 4 P 0 0;4=6,6=1
P 8.07901004 5.98761998 4 P 0 0;4=6,6=1
P 8.12901004 5.98761998 4 P 0 0;4=6,6=1
P 8.17901004 5.98761998 4 P 0 0;4=6,6=1
P 8.22901004 5.98761998 4 P 0 0;4=6,6=1
P 8.27901004 5.98761998 4 P 0 0;4=6,6=1
P 8.32901004 5.98761998 4 P 0 0;4=6,6=1
P 8.37901004 5.98761998 4 P 0 0;4=6,6=1
P 8.42901004 5.98761998 4 P 0 0;4=6,6=1
P 8.47901004 5.98761998 4 P 0 0;4=6,6=1
P 8.52901004 5.98761998 4 P 0 0;4=6,6=1
P 8.57901004 5.98761998 4 P 0 0;4=6,6=1
P 8.62901004 5.98761998 4 P 0 0;4=6,6=1
P 8.67901004 5.98761998 4 P 0 0;4=6,6=1
P 8.72901004 5.98761998 4 P 0 0;4=6,6=1
P 8.77901004 5.98761998 4 P 0 0;4=6,6=1
P 8.82901004 5.98761998 4 P 0 0;4=6,6=1
P 8.87901004 5.98761998 4 P 0 0;4=6,6=1
P 8.92901004 5.98761998 4 P 0 0;4=6,6=1
P 8.97901004 5.98761998 4 P 0 0;4=6,6=1
P 9.02901004 5.98761998 4 P 0 0;4=6,6=1
P 9.07901004 5.98761998 4 P 0 0;4=6,6=1
P 9.12901004 5.98761998 4 P 0 0;4=6,6=1
P 9.17901004 5.98761998 4 P 0 0;4=6,6=1
P 9.22901004 5.98761998 4 P 0 0;4=6,6=1
P 9.27901004 5.98761998 4 P 0 0;4=6,6=1
P 9.32901004 5.98761998 4 P 0 0;4=6,6=1
P 9.37901004 5.98761998 4 P 0 0;4=6,6=1
P 9.42901004 5.98761998 4 P 0 0;4=6,6=1
P 9.47901004 5.98761998 4 P 0 0;4=6,6=1
P 9.52901004 5.98761998 4 P 0 0;4=6,6=1
P 9.57901004 5.98761998 4 P 0 0;4=6,6=1
P 9.62901004 5.98761998 4 P 0 0;4=6,6=1
P 9.67901004 5.98761998 4 P 0 0;4=6,6=1
P 9.72901004 5.98761998 4 P 0 0;4=6,6=1
P 9.77901004 5.98761998 4 P 0 0;4=6,6=1
P 9.82901004 5.98761998 4 P 0 0;4=6,6=1
P 9.87901004 5.98761998 4 P 0 0;4=6,6=1
P 9.92901004 5.98761998 4 P 0 0;4=6,6=1
P 9.97901004 5.98761998 4 P 0 0;4=6,6=1
P 10.02901004 5.98761998 4 P 0 0;4=6,6=1
P 10.07901004 5.98761998 4 P 0 0;4=6,6=1
P 10.12901004 5.98761998 4 P 0 0;4=6,6=1
P 10.17901004 5.98761998 4 P 0 0;4=6,6=1
P 10.22901004 5.98761998 4 P 0 0;4=6,6=1
P 10.27901004 5.98761998 4 P 0 0;4=6,6=1
P 10.32901004 5.98761998 4 P 0 0;4=6,6=1
P 10.37901004 5.98761998 4 P 0 0;4=6,6=1
P 10.42901004 5.98761998 4 P 0 0;4=6,6=1
P 10.47901004 5.98761998 4 P 0 0;4=6,6=1
P 10.52901004 5.98761998 4 P 0 0;4=6,6=1
P 10.57901004 5.98761998 4 P 0 0;4=6,6=1
P 10.62901004 5.98761998 4 P 0 0;4=6,6=1
P 10.67901004 5.98761998 4 P 0 0;4=6,6=1
P 10.72901004 5.98761998 4 P 0 0;4=6,6=1
P 10.77901004 5.98761998 4 P 0 0;4=6,6=1
P 10.82901004 5.98761998 4 P 0 0;4=6,6=1
P 10.87901004 5.98761998 4 P 0 0;4=6,6=1
P 10.92901004 5.98761998 4 P 0 0;4=6,6=1
P 10.97901004 5.98761998 4 P 0 0;4=6,6=1
P 11.02901004 5.98761998 4 P 0 0;4=6,6=1
P 11.07901004 5.98761998 4 P 0 0;4=6,6=1
P 11.12901004 5.98761998 4 P 0 0;4=6,6=1
P 11.17901004 5.98761998 4 P 0 0;4=6,6=1
P 11.22901004 5.98761998 4 P 0 0;4=6,6=1
P 11.27901004 5.98761998 4 P 0 0;4=6,6=1
P 11.32901004 5.98761998 4 P 0 0;4=6,6=1
P 11.37901004 5.98761998 4 P 0 0;4=6,6=1
P 11.42901004 5.98761998 4 P 0 0;4=6,6=1
P 11.47901004 5.98761998 4 P 0 0;4=6,6=1
P 11.52901004 5.98761998 4 P 0 0;4=6,6=1
P 11.57901004 5.98761998 4 P 0 0;4=6,6=1
P 11.62901004 5.98761998 4 P 0 0;4=6,6=1
P 11.67901004 5.98761998 4 P 0 0;4=6,6=1
P 11.72901004 5.98761998 4 P 0 0;4=6,6=1
P 11.77901004 5.98761998 4 P 0 0;4=6,6=1
P 11.82901004 5.98761998 4 P 0 0;4=6,6=1
P 11.87901004 5.98761998 4 P 0 0;4=6,6=1
P 11.92901004 5.98761998 4 P 0 0;4=6,6=1
P 11.97901004 5.98761998 4 P 0 0;4=6,6=1
P 12.02901004 5.98761998 4 P 0 0;4=6,6=1
P 12.07901004 5.98761998 4 P 0 0;4=6,6=1
P 12.12901004 5.98761998 4 P 0 0;4=6,6=1
P 12.17901004 5.98761998 4 P 0 0;4=6,6=1
P 12.22901004 5.98761998 4 P 0 0;4=6,6=1
P 12.27901004 5.98761998 4 P 0 0;4=6,6=1
P 12.32901004 5.98761998 4 P 0 0;4=6,6=1
P 12.37901004 5.98761998 4 P 0 0;4=6,6=1
P 12.42901004 5.98761998 4 P 0 0;4=6,6=1
P 12.47901004 5.98761998 4 P 0 0;4=6,6=1
P 12.52901004 5.98761998 4 P 0 0;4=6,6=1
P 12.57901004 5.98761998 4 P 0 0;4=6,6=1
P 12.62901004 5.98761998 4 P 0 0;4=6,6=1
P 12.67901004 5.98761998 4 P 0 0;4=6,6=1
P 12.72901004 5.98761998 4 P 0 0;4=6,6=1
P 12.77901004 5.98761998 4 P 0 0;4=6,6=1
P 12.82901004 5.98761998 4 P 0 0;4=6,6=1
P 12.87726004 5.97451004 4 P 0 0;4=6,6=1
P 12.8892 5.92596004 4 P 0 0;4=6,6=1
P 12.8892 5.87596004 4 P 0 0;4=6,6=1
P 12.8892 5.82596004 4 P 0 0;4=6,6=1
P 12.8892 5.77596004 4 P 0 0;4=6,6=1
P 4.33605 4.9231 4 P 0 0;4=6,6=1
P 4.38105 4.9231 4 P 0 0;4=6,6=1
P 4.30105 4.9431 4 P 0 0;4=6,6=1
P 4.42105 4.9431 4 P 0 0;4=6,6=1
P 4.46105 4.9431 4 P 0 0;4=6,6=1
P 4.26105 4.9431 4 P 0 0;4=6,6=1
P 4.72605 4.9231 4 P 0 0;4=6,6=1
P 4.65105 4.9431 4 P 0 0;4=6,6=1
P 4.69105 4.9431 4 P 0 0;4=6,6=1
P 4.85105 4.9431 4 P 0 0;4=6,6=1
P 4.81105 4.9431 4 P 0 0;4=6,6=1
P 4.77105 4.9231 4 P 0 0;4=6,6=1
P 4.30105 5.0281 4 P 0 0;4=6,6=1
P 4.30105 5.0731 4 P 0 0;4=6,6=1
P 4.30105 4.9831 4 P 0 0;4=6,6=1
P 4.34105 5.1181 4 P 0 0;4=6,6=1
P 4.38105 5.1181 4 P 0 0;4=6,6=1
P 4.46105 5.1181 4 P 0 0;4=6,6=1
P 4.42105 5.1181 4 P 0 0;4=6,6=1
P 4.42105 4.9831 4 P 0 0;4=6,6=1
P 4.42105 5.0731 4 P 0 0;4=6,6=1
P 4.42105 5.0281 4 P 0 0;4=6,6=1
P 4.46105 4.9831 4 P 0 0;4=6,6=1
P 4.46105 5.0731 4 P 0 0;4=6,6=1
P 4.46105 5.0281 4 P 0 0;4=6,6=1
P 4.26105 5.0281 4 P 0 0;4=6,6=1
P 4.26105 5.0731 4 P 0 0;4=6,6=1
P 4.26105 4.9831 4 P 0 0;4=6,6=1
P 4.73105 5.1181 4 P 0 0;4=6,6=1
P 4.69105 5.1181 4 P 0 0;4=6,6=1
P 4.65105 5.1181 4 P 0 0;4=6,6=1
P 4.65105 4.9831 4 P 0 0;4=6,6=1
P 4.65105 5.0731 4 P 0 0;4=6,6=1
P 4.65105 5.0281 4 P 0 0;4=6,6=1
P 4.69105 4.9831 4 P 0 0;4=6,6=1
P 4.69105 5.0731 4 P 0 0;4=6,6=1
P 4.69105 5.0281 4 P 0 0;4=6,6=1
P 4.85105 5.0281 4 P 0 0;4=6,6=1
P 4.85105 5.0731 4 P 0 0;4=6,6=1
P 4.85105 4.9831 4 P 0 0;4=6,6=1
P 4.81105 5.0281 4 P 0 0;4=6,6=1
P 4.81105 5.0731 4 P 0 0;4=6,6=1
P 4.81105 4.9831 4 P 0 0;4=6,6=1
P 4.81105 5.1181 4 P 0 0;4=6,6=1
P 4.85105 5.1181 4 P 0 0;4=6,6=1
P 4.77105 5.1181 4 P 0 0;4=6,6=1
P 4.30105 5.1181 4 P 0 0;4=6,6=1
P 4.26105 5.1181 4 P 0 0;4=6,6=1
P 9.45795 0.36633002 4 P 0 0;4=6,6=1
P 6.62 4.645 4 P 0 0;4=6,6=1
P 6.62 4.61 4 P 0 0;4=6,6=1
P 6.605 4.77 4 P 0 0;4=6,6=1
P 6.315 4.9 4 P 0 0;4=6,6=1
P 6.315 4.865 4 P 0 0;4=6,6=1
P 6.315 4.82 4 P 0 0;4=6,6=1
P 6.315 4.785 4 P 0 0;4=6,6=1
P 6.315 4.705 4 P 0 0;4=6,6=1
P 6.315 4.74 4 P 0 0;4=6,6=1
P 6.315 4.66 4 P 0 0;4=6,6=1
P 6.315 4.625 4 P 0 0;4=6,6=1
P 1.51673002 5.78 4 P 0 0;4=6,6=1
P 1.12303002 5.46016004 4 P 0 0;4=6,6=1
P 1.20176998 5.46016004 4 P 0 0;4=6,6=1
P 1.51673002 5.46016004 4 P 0 0;4=6,6=1
P 1.36 5.355 4 P 0 0;4=6,6=1
P 1.41 5.355 4 P 0 0;4=6,6=1
P 1.46 5.355 4 P 0 0;4=6,6=1
P 1.305 5.885 4 P 0 0;4=6,6=1
P 1.355 5.885 4 P 0 0;4=6,6=1
P 1.405 5.885 4 P 0 0;4=6,6=1
P 1.455 5.885 4 P 0 0;4=6,6=1
P 0.705 5.355 4 P 0 0;4=6,6=1
P 0.7 5.267 6 P 0 0;2,4=1,6=1
P 0.73 5.175 4 P 0 0;4=6,6=1
P 1.03 5.065 4 P 0 0;4=6,6=1
P 1.28051004 5.46016004 4 P 0 0;4=6,6=1
P 5.917 2.97 24 P 0 0;1,4=0,6=0
P 12.215 4.915 4 P 0 0;4=6,6=1
P 12.055 4.915 4 P 0 0;4=6,6=1
P 10.465 5.245 4 P 0 0;4=6,6=1
P 10.465 5.165 4 P 0 0;4=6,6=1
P 11.7719 4.80998996 4 P 0 0;4=6,6=1
P 11.7719 4.85498996 4 P 0 0;4=6,6=1
P 11.7719 4.90498996 4 P 0 0;4=6,6=1
P 11.7719 4.94998996 4 P 0 0;4=6,6=1
P 11.9719 4.94998996 4 P 0 0;4=6,6=1
P 11.9719 4.80998996 4 P 0 0;4=6,6=1
P 11.9719 4.85498996 4 P 0 0;4=6,6=1
P 11.9719 4.90498996 4 P 0 0;4=6,6=1
P 11.9219 4.94998996 4 P 0 0;4=6,6=1
P 11.9219 4.80998996 4 P 0 0;4=6,6=1
P 11.8719 4.94998996 4 P 0 0;4=6,6=1
P 11.8719 4.80998996 4 P 0 0;4=6,6=1
P 11.8219 4.80998996 4 P 0 0;4=6,6=1
P 11.8219 4.94998996 4 P 0 0;4=6,6=1
P 0.61698002 2.045 24 P 0 0;1,4=0,6=0
P 1.82021004 2.4781 24 P 0 0;1,4=0,6=0
P 11.69316004 2.6635 4 P 0 0;4=6,6=1
P 10.125 2.008 4 P 0 0;4=6,6=1
P 6.42418996 5.04705 24 P 0 0;1,4=0,6=0
P 5.53531004 1.6642 4 P 0 0;4=6,6=1
P 5.53531004 1.7213 4 P 0 0;4=6,6=1
P 5.53531004 2.0802 4 P 0 0;4=6,6=1
P 5.53531004 1.9393 4 P 0 0;4=6,6=1
P 5.53531004 2.2156 4 P 0 0;4=6,6=1
P 5.53531004 2.4081 4 P 0 0;4=6,6=1
P 5.53531004 2.5473 4 P 0 0;4=6,6=1
P 9.1 5.332 24 P 0 0;1,4=0,6=0
P 9.235 5.332 24 P 0 0;1,4=0,6=0
P 9.385 5.332 24 P 0 0;1,4=0,6=0
P 2.86855 4.92 4 P 0 0;4=6,6=1
P 2.79768002 4.92 4 P 0 0;4=6,6=1
P 3.08113996 4.92 4 P 0 0;4=6,6=1
P 3.36461004 4.926 4 P 0 0;4=6,6=1
P 3.22288002 4.92 4 P 0 0;4=6,6=1
P 3.50633996 4.92 4 P 0 0;4=6,6=1
P 3.43546998 4.928 4 P 0 0;4=6,6=1
P 3.15398002 4.81401998 4 P 0 0;4=6,6=1
P 3.22288002 4.81401998 4 P 0 0;4=6,6=1
P 3.36461004 4.81401998 4 P 0 0;4=6,6=1
P 3.43546998 4.81401998 4 P 0 0;4=6,6=1
P 3.50633996 4.81401998 4 P 0 0;4=6,6=1
P 3.22288002 5.023 4 P 0 0;4=6,6=1
P 3.50633996 5.023 4 P 0 0;4=6,6=1
P 3.43546998 5.023 4 P 0 0;4=6,6=1
P 3.14 4.92 4 P 0 0;4=6,6=1
P 3.275 4.92 4 P 0 0;4=6,6=1
P 3.26 5.332 4 P 0 0;4=6,6=1
P 3.06791998 5.332 4 P 0 0;4=6,6=1
P 3.51176998 5.17873996 4 P 0 0;4=6,6=1
P 3.57176998 5.17873996 4 P 0 0;4=6,6=1
P 3.15743996 4.74418002 4 P 0 0;4=6,6=1
P 1.63308002 4.92 4 P 0 0;4=6,6=1
P 1.84568002 4.92 4 P 0 0;4=6,6=1
P 1.77481004 4.92 4 P 0 0;4=6,6=1
P 1.70395 4.92 4 P 0 0;4=6,6=1
P 2.12913996 4.92 4 P 0 0;4=6,6=1
P 2.05828002 4.92 4 P 0 0;4=6,6=1
P 1.98741004 4.92 4 P 0 0;4=6,6=1
P 1.91653996 4.92 4 P 0 0;4=6,6=1
P 2.34173996 4.92 4 P 0 0;4=6,6=1
P 2.27086998 4.92 4 P 0 0;4=6,6=1
P 2.20001004 4.926 4 P 0 0;4=6,6=1
P 2.34173996 4.81 4 P 0 0;4=6,6=1
P 2.27086998 4.81 4 P 0 0;4=6,6=1
P 2.20001004 4.81 4 P 0 0;4=6,6=1
P 1.63173002 4.81526998 4 P 0 0;4=6,6=1
P 1.7 4.812 4 P 0 0;4=6,6=1
P 1.84568002 4.81 4 P 0 0;4=6,6=1
P 1.776 4.812 4 P 0 0;4=6,6=1
P 2.12913996 4.81 4 P 0 0;4=6,6=1
P 1.99 4.81 4 P 0 0;4=6,6=1
P 1.92 4.81 4 P 0 0;4=6,6=1
P 2.40716998 5.15373996 4 P 0 0;4=6,6=1
P 2.34716998 5.15373996 4 P 0 0;4=6,6=1
P 2.11646004 5.377 24 P 0 0;1,4=0,6=0
P 1.95146004 5.377 24 P 0 0;1,4=0,6=0
P 10.58661004 2.16615 3 P 0 0;4=4,6=1
P 10.63661004 2.16615 3 P 0 0;4=4,6=1
P 10.63661004 2.21615 3 P 0 0;4=4,6=1
P 10.88661004 1.91615 3 P 0 0;4=4,6=1
P 10.88661004 2.41615 3 P 0 0;4=4,6=1
P 10.88661004 2.66615 3 P 0 0;4=4,6=1
P 11.03661004 2.41615 3 P 0 0;4=4,6=1
P 11.03661004 2.36615 3 P 0 0;4=4,6=1
P 1.91111004 4.61826004 4 P 0 0;4=6,6=1
P 2.40716998 4.70326004 4 P 0 0;4=6,6=1
P 2.945 4.92 4 P 0 0;4=6,6=1
P 3.01028002 4.92 4 P 0 0;4=6,6=1
P 7.78 2.4781 6 P 0 0;2,4=1,6=1
P 2.24606004 3.86615 3 P 0 0;4=4,6=1
P 2.49606004 3.86615 3 P 0 0;4=4,6=1
P 2.24606004 3.81615 3 P 0 0;4=4,6=1
P 2.19606004 3.76615 3 P 0 0;4=4,6=1
P 2.24606004 3.76615 3 P 0 0;4=4,6=1
P 2.29606004 3.76615 3 P 0 0;4=4,6=1
P 2.49606004 3.71615 3 P 0 0;4=4,6=1
P 2.49606004 3.56615 3 P 0 0;4=4,6=1
P 2.44606004 3.56615 3 P 0 0;4=4,6=1
P 2.39606004 3.56615 3 P 0 0;4=4,6=1
P 2.29606004 3.61615 3 P 0 0;4=4,6=1
P 2.24606004 3.71615 3 P 0 0;4=4,6=1
P 2.24606004 3.66615 3 P 0 0;4=4,6=1
P 2.24606004 3.61615 3 P 0 0;4=4,6=1
P 2.19606004 3.61615 3 P 0 0;4=4,6=1
P 2.19606004 3.56615 3 P 0 0;4=4,6=1
P 2.14606004 3.56615 3 P 0 0;4=4,6=1
P 2.04606004 3.56615 3 P 0 0;4=4,6=1
P 1.99606004 3.56615 3 P 0 0;4=4,6=1
P 2.04606004 3.51615 3 P 0 0;4=4,6=1
P 2.04606004 3.46615 3 P 0 0;4=4,6=1
P 2.19606004 3.51615 3 P 0 0;4=4,6=1
P 2.24606004 3.51615 3 P 0 0;4=4,6=1
P 2.29606004 3.51615 3 P 0 0;4=4,6=1
P 2.49606004 3.41615 3 P 0 0;4=4,6=1
P 2.44606004 3.36615 3 P 0 0;4=4,6=1
P 2.24606004 3.46615 3 P 0 0;4=4,6=1
P 2.24606004 3.41615 3 P 0 0;4=4,6=1
P 2.29606004 3.36615 3 P 0 0;4=4,6=1
P 2.24606004 3.36615 3 P 0 0;4=4,6=1
P 2.19606004 3.36615 3 P 0 0;4=4,6=1
P 1.99606004 3.41615 3 P 0 0;4=4,6=1
P 2.09606004 3.36615 3 P 0 0;4=4,6=1
P 2.24606004 3.31615 3 P 0 0;4=4,6=1
P 2.24606004 3.26615 3 P 0 0;4=4,6=1
P 2.29606004 3.21615 3 P 0 0;4=4,6=1
P 2.24606004 3.21615 3 P 0 0;4=4,6=1
P 2.19606004 3.21615 3 P 0 0;4=4,6=1
P 2.09606004 3.21615 3 P 0 0;4=4,6=1
P 2.14606004 3.16615 3 P 0 0;4=4,6=1
P 2.04606004 3.16615 3 P 0 0;4=4,6=1
P 2.24606004 3.16615 3 P 0 0;4=4,6=1
P 2.29606004 3.16615 3 P 0 0;4=4,6=1
P 2.34606004 3.21615 3 P 0 0;4=4,6=1
P 2.44606004 3.21615 3 P 0 0;4=4,6=1
P 2.49606004 3.21615 3 P 0 0;4=4,6=1
P 2.49606004 3.26615 3 P 0 0;4=4,6=1
P 2.49606004 3.16615 3 P 0 0;4=4,6=1
P 2.39606004 3.16615 3 P 0 0;4=4,6=1
P 2.29606004 3.06615 3 P 0 0;4=4,6=1
P 2.29606004 3.11615 3 P 0 0;4=4,6=1
P 2.29606004 2.96615 3 P 0 0;4=4,6=1
P 2.29606004 3.01615 3 P 0 0;4=4,6=1
P 2.24606004 3.06615 3 P 0 0;4=4,6=1
P 2.24606004 3.11615 3 P 0 0;4=4,6=1
P 2.24606004 2.96615 3 P 0 0;4=4,6=1
P 2.24606004 3.01615 3 P 0 0;4=4,6=1
P 2.34606004 2.86615 3 P 0 0;4=4,6=1
P 2.34606004 2.91615 3 P 0 0;4=4,6=1
P 2.29606004 2.76615 3 P 0 0;4=4,6=1
P 2.29606004 2.81615 3 P 0 0;4=4,6=1
P 2.24606004 2.76615 3 P 0 0;4=4,6=1
P 2.24606004 2.81615 3 P 0 0;4=4,6=1
P 2.19606004 2.81615 3 P 0 0;4=4,6=1
P 2.09606004 2.81615 3 P 0 0;4=4,6=1
P 2.09606004 2.86615 3 P 0 0;4=4,6=1
P 2.19606004 3.06615 3 P 0 0;4=4,6=1
P 2.14606004 3.01615 3 P 0 0;4=4,6=1
P 2.09606004 3.06615 3 P 0 0;4=4,6=1
P 2.04606004 3.01615 3 P 0 0;4=4,6=1
P 2.09606004 2.91615 3 P 0 0;4=4,6=1
P 2.14606004 2.86615 3 P 0 0;4=4,6=1
P 2.04606004 2.86615 3 P 0 0;4=4,6=1
P 2.19606004 2.91615 3 P 0 0;4=4,6=1
P 2.24606004 2.91615 3 P 0 0;4=4,6=1
P 2.29606004 2.91615 3 P 0 0;4=4,6=1
P 2.39606004 3.01615 3 P 0 0;4=4,6=1
P 2.34606004 3.06615 3 P 0 0;4=4,6=1
P 2.44606004 3.06615 3 P 0 0;4=4,6=1
P 2.49606004 3.01615 3 P 0 0;4=4,6=1
P 2.44606004 2.91615 3 P 0 0;4=4,6=1
P 2.44606004 2.86615 3 P 0 0;4=4,6=1
P 2.39606004 2.86615 3 P 0 0;4=4,6=1
P 2.34606004 2.81615 3 P 0 0;4=4,6=1
P 2.44606004 2.81615 3 P 0 0;4=4,6=1
P 2.49606004 2.86615 3 P 0 0;4=4,6=1
P 2.49606004 2.71615 3 P 0 0;4=4,6=1
P 2.44606004 2.66615 3 P 0 0;4=4,6=1
P 2.39606004 2.71615 3 P 0 0;4=4,6=1
P 2.34606004 2.66615 3 P 0 0;4=4,6=1
P 2.29606004 2.71615 3 P 0 0;4=4,6=1
P 2.29606004 2.66615 3 P 0 0;4=4,6=1
P 2.24606004 2.71615 3 P 0 0;4=4,6=1
P 2.24606004 2.66615 3 P 0 0;4=4,6=1
P 2.19606004 2.66615 3 P 0 0;4=4,6=1
P 2.14606004 2.71615 3 P 0 0;4=4,6=1
P 2.09606004 2.66615 3 P 0 0;4=4,6=1
P 2.04606004 2.71615 3 P 0 0;4=4,6=1
P 2.04606004 2.56615 3 P 0 0;4=4,6=1
P 2.04606004 2.51615 3 P 0 0;4=4,6=1
P 2.04606004 2.46615 3 P 0 0;4=4,6=1
P 2.09606004 2.51615 3 P 0 0;4=4,6=1
P 2.14606004 2.56615 3 P 0 0;4=4,6=1
P 2.24606004 2.61615 3 P 0 0;4=4,6=1
P 2.24606004 2.56615 3 P 0 0;4=4,6=1
P 2.29606004 2.61615 3 P 0 0;4=4,6=1
P 2.29606004 2.56615 3 P 0 0;4=4,6=1
P 2.34606004 2.51615 3 P 0 0;4=4,6=1
P 2.29606004 2.51615 3 P 0 0;4=4,6=1
P 2.24606004 2.51615 3 P 0 0;4=4,6=1
P 2.19606004 2.51615 3 P 0 0;4=4,6=1
P 2.14606004 2.46615 3 P 0 0;4=4,6=1
P 2.24606004 2.46615 3 P 0 0;4=4,6=1
P 2.29606004 2.46615 3 P 0 0;4=4,6=1
P 2.29606004 2.41615 3 P 0 0;4=4,6=1
P 2.24606004 2.41615 3 P 0 0;4=4,6=1
P 2.24606004 2.36615 3 P 0 0;4=4,6=1
P 2.19606004 2.36615 3 P 0 0;4=4,6=1
P 2.29606004 2.36615 3 P 0 0;4=4,6=1
P 2.39606004 2.46615 3 P 0 0;4=4,6=1
P 2.39606004 2.51615 3 P 0 0;4=4,6=1
P 2.39606004 2.56615 3 P 0 0;4=4,6=1
P 2.44606004 2.51615 3 P 0 0;4=4,6=1
P 2.49606004 2.56615 3 P 0 0;4=4,6=1
P 2.49606004 2.51615 3 P 0 0;4=4,6=1
P 2.49606004 2.46615 3 P 0 0;4=4,6=1
P 2.44606004 2.36615 3 P 0 0;4=4,6=1
P 2.49606004 2.31615 3 P 0 0;4=4,6=1
P 2.39606004 2.31615 3 P 0 0;4=4,6=1
P 2.34606004 2.36615 3 P 0 0;4=4,6=1
P 2.29606004 2.31615 3 P 0 0;4=4,6=1
P 2.24606004 2.31615 3 P 0 0;4=4,6=1
P 2.04606004 2.31615 3 P 0 0;4=4,6=1
P 2.04606004 2.16615 3 P 0 0;4=4,6=1
P 2.04606004 2.11615 3 P 0 0;4=4,6=1
P 2.04606004 1.96615 3 P 0 0;4=4,6=1
P 2.09606004 2.01615 3 P 0 0;4=4,6=1
P 2.14606004 1.96615 3 P 0 0;4=4,6=1
P 2.09606004 1.86615 3 P 0 0;4=4,6=1
P 2.19606004 1.86615 3 P 0 0;4=4,6=1
P 2.24606004 1.86615 3 P 0 0;4=4,6=1
P 2.29606004 1.86615 3 P 0 0;4=4,6=1
P 2.34606004 1.86615 3 P 0 0;4=4,6=1
P 2.24606004 1.91615 3 P 0 0;4=4,6=1
P 2.29606004 1.91615 3 P 0 0;4=4,6=1
P 2.24606004 1.96615 3 P 0 0;4=4,6=1
P 2.29606004 1.96615 3 P 0 0;4=4,6=1
P 2.19606004 2.01615 3 P 0 0;4=4,6=1
P 2.24606004 2.01615 3 P 0 0;4=4,6=1
P 2.29606004 2.01615 3 P 0 0;4=4,6=1
P 2.34606004 2.01615 3 P 0 0;4=4,6=1
P 2.39606004 1.96615 3 P 0 0;4=4,6=1
P 2.44606004 2.01615 3 P 0 0;4=4,6=1
P 2.49606004 1.96615 3 P 0 0;4=4,6=1
P 2.44606004 1.86615 3 P 0 0;4=4,6=1
P 2.49606004 2.11615 3 P 0 0;4=4,6=1
P 2.44606004 2.16615 3 P 0 0;4=4,6=1
P 2.49606004 2.16615 3 P 0 0;4=4,6=1
P 2.44606004 2.21615 3 P 0 0;4=4,6=1
P 2.39606004 2.16615 3 P 0 0;4=4,6=1
P 2.39606004 2.11615 3 P 0 0;4=4,6=1
P 2.34606004 2.16615 3 P 0 0;4=4,6=1
P 2.34606004 2.21615 3 P 0 0;4=4,6=1
P 2.29606004 2.21615 3 P 0 0;4=4,6=1
P 2.29606004 2.16615 3 P 0 0;4=4,6=1
P 2.29606004 2.06615 3 P 0 0;4=4,6=1
P 2.29606004 2.11615 3 P 0 0;4=4,6=1
P 2.24606004 2.11615 3 P 0 0;4=4,6=1
P 2.24606004 2.16615 3 P 0 0;4=4,6=1
P 2.24606004 2.06615 3 P 0 0;4=4,6=1
P 2.24606004 2.21615 3 P 0 0;4=4,6=1
P 2.29606004 2.26615 3 P 0 0;4=4,6=1
P 2.24606004 2.26615 3 P 0 0;4=4,6=1
P 2.19606004 2.21615 3 P 0 0;4=4,6=1
P 2.19606004 2.16615 3 P 0 0;4=4,6=1
P 2.14606004 2.11615 3 P 0 0;4=4,6=1
P 2.14606004 2.16615 3 P 0 0;4=4,6=1
P 2.09606004 2.21615 3 P 0 0;4=4,6=1
P 2.09606004 2.16615 3 P 0 0;4=4,6=1
P 2.09606004 2.36615 3 P 0 0;4=4,6=1
P 2.14606004 2.31615 3 P 0 0;4=4,6=1
P 1.99606004 2.71615 3 P 0 0;4=4,6=1
P 1.99606004 2.86615 3 P 0 0;4=4,6=1
P 2.04606004 2.81615 3 P 0 0;4=4,6=1
P 2.04606004 2.76615 3 P 0 0;4=4,6=1
P 3.29373996 5.023 4 P 0 0;4=6,6=1
P 2.14606004 3.26615 3 P 0 0;4=4,6=1
P 2.04606004 3.26615 3 P 0 0;4=4,6=1
P 2.04606004 3.21615 3 P 0 0;4=4,6=1
P 2.14606004 3.21615 3 P 0 0;4=4,6=1
P 2.39606004 3.21615 3 P 0 0;4=4,6=1
P 2.39606004 3.26615 3 P 0 0;4=4,6=1
P 2.29606004 3.26615 3 P 0 0;4=4,6=1
P 2.29606004 3.31615 3 P 0 0;4=4,6=1
P 2.34606004 3.36615 3 P 0 0;4=4,6=1
P 2.14606004 3.41615 3 P 0 0;4=4,6=1
P 2.09606004 3.61615 3 P 0 0;4=4,6=1
P 2.29606004 3.46615 3 P 0 0;4=4,6=1
P 2.29606004 3.41615 3 P 0 0;4=4,6=1
P 2.39606004 3.41615 3 P 0 0;4=4,6=1
P 2.34606004 3.51615 3 P 0 0;4=4,6=1
P 2.34606004 3.61615 3 P 0 0;4=4,6=1
P 2.34606004 3.56615 3 P 0 0;4=4,6=1
P 2.44606004 3.51615 3 P 0 0;4=4,6=1
P 2.44606004 3.61615 3 P 0 0;4=4,6=1
P 2.14606004 3.71615 3 P 0 0;4=4,6=1
P 2.04606004 3.71615 3 P 0 0;4=4,6=1
P 2.09606004 3.76615 3 P 0 0;4=4,6=1
P 2.14606004 3.86615 3 P 0 0;4=4,6=1
P 2.04606004 3.86615 3 P 0 0;4=4,6=1
P 2.29606004 3.71615 3 P 0 0;4=4,6=1
P 2.29606004 3.66615 3 P 0 0;4=4,6=1
P 2.39606004 3.71615 3 P 0 0;4=4,6=1
P 2.34606004 3.76615 3 P 0 0;4=4,6=1
P 2.29606004 3.81615 3 P 0 0;4=4,6=1
P 2.39606004 3.86615 3 P 0 0;4=4,6=1
P 2.29606004 3.86615 3 P 0 0;4=4,6=1
P 2.44606004 3.76615 3 P 0 0;4=4,6=1
P 2.19606004 2.86615 3 P 0 0;4=4,6=1
P 3.36461004 5.023 4 P 0 0;4=6,6=1
P 3.29373996 4.81401998 4 P 0 0;4=6,6=1
P 3.01028002 4.81401998 4 P 0 0;4=6,6=1
P 2.94141004 4.81401998 4 P 0 0;4=6,6=1
P 2.86555 4.81401998 4 P 0 0;4=6,6=1
P 2.79768002 4.81401998 4 P 0 0;4=6,6=1
P 3.15201004 5.023 4 P 0 0;4=6,6=1
P 3.08113996 5.023 4 P 0 0;4=6,6=1
P 3.01028002 5.023 4 P 0 0;4=6,6=1
P 2.93941004 5.023 4 P 0 0;4=6,6=1
P 2.86855 5.023 4 P 0 0;4=6,6=1
P 2.79768002 5.023 4 P 0 0;4=6,6=1
P 1.70395 5.023 4 P 0 0;4=6,6=1
P 1.63308002 5.023 4 P 0 0;4=6,6=1
P 1.77481004 5.023 4 P 0 0;4=6,6=1
P 1.91653996 5.023 4 P 0 0;4=6,6=1
P 1.84568002 5.023 4 P 0 0;4=6,6=1
P 1.98741004 5.023 4 P 0 0;4=6,6=1
P 2.05828002 5.023 4 P 0 0;4=6,6=1
P 2.12913996 5.023 4 P 0 0;4=6,6=1
P 2.20001004 5.023 4 P 0 0;4=6,6=1
P 2.27086998 5.023 4 P 0 0;4=6,6=1
P 2.34173996 5.023 4 P 0 0;4=6,6=1
P 1.56221004 5.023 4 P 0 0;4=6,6=1
P 1.56221004 4.81401998 4 P 0 0;4=6,6=1
P 2.06086998 4.81 4 P 0 0;4=6,6=1
P 2.41261004 5.023 4 P 0 0;4=6,6=1
P 2.41261004 4.81401998 4 P 0 0;4=6,6=1
P 2.72681004 5.023 4 P 0 0;4=6,6=1
P 2.72681004 4.81401998 4 P 0 0;4=6,6=1
P 3.57721004 4.81401998 4 P 0 0;4=6,6=1
P 3.57721004 5.023 4 P 0 0;4=6,6=1
P 4.88268002 1.91615 3 P 0 0;4=4,6=1
P 4.78268002 1.91615 3 P 0 0;4=4,6=1
P 5.03268002 2.36615 3 P 0 0;4=4,6=1
P 5.03268002 2.41615 3 P 0 0;4=4,6=1
P 4.88268002 3.66615 3 P 0 0;4=4,6=1
P 4.83268002 3.66615 3 P 0 0;4=4,6=1
P 5.03268002 3.66615 3 P 0 0;4=4,6=1
P 4.93268002 3.66615 3 P 0 0;4=4,6=1
P 4.98268002 3.66615 3 P 0 0;4=4,6=1
P 4.88268002 3.51615 3 P 0 0;4=4,6=1
P 4.83268002 3.51615 3 P 0 0;4=4,6=1
P 5.03268002 3.51615 3 P 0 0;4=4,6=1
P 4.93268002 3.51615 3 P 0 0;4=4,6=1
P 4.98268002 3.51615 3 P 0 0;4=4,6=1
P 4.88268002 3.81615 3 P 0 0;4=4,6=1
P 4.83268002 3.81615 3 P 0 0;4=4,6=1
P 4.93268002 3.81615 3 P 0 0;4=4,6=1
P 4.98268002 3.81615 3 P 0 0;4=4,6=1
P 4.88268002 3.36615 3 P 0 0;4=4,6=1
P 4.83268002 3.36615 3 P 0 0;4=4,6=1
P 5.03268002 3.36615 3 P 0 0;4=4,6=1
P 4.93268002 3.36615 3 P 0 0;4=4,6=1
P 4.98268002 3.36615 3 P 0 0;4=4,6=1
P 4.83268002 3.21615 3 P 0 0;4=4,6=1
P 4.88268002 3.21615 3 P 0 0;4=4,6=1
P 4.98268002 3.21615 3 P 0 0;4=4,6=1
P 4.93268002 3.21615 3 P 0 0;4=4,6=1
P 5.03268002 3.21615 3 P 0 0;4=4,6=1
P 4.83268002 3.06615 3 P 0 0;4=4,6=1
P 4.88268002 3.06615 3 P 0 0;4=4,6=1
P 4.98268002 3.06615 3 P 0 0;4=4,6=1
P 4.93268002 3.06615 3 P 0 0;4=4,6=1
P 5.03268002 3.06615 3 P 0 0;4=4,6=1
P 4.83268002 2.91615 3 P 0 0;4=4,6=1
P 4.88268002 2.91615 3 P 0 0;4=4,6=1
P 4.98268002 2.91615 3 P 0 0;4=4,6=1
P 4.93268002 2.91615 3 P 0 0;4=4,6=1
P 5.03268002 2.91615 3 P 0 0;4=4,6=1
P 4.78268002 2.51615 3 P 0 0;4=4,6=1
P 4.73268002 2.51615 3 P 0 0;4=4,6=1
P 4.68268002 2.51615 3 P 0 0;4=4,6=1
P 4.63268002 2.51615 3 P 0 0;4=4,6=1
P 4.58268002 2.51615 3 P 0 0;4=4,6=1
P 4.63268002 2.56615 3 P 0 0;4=4,6=1
P 4.73268002 2.56615 3 P 0 0;4=4,6=1
P 4.78268002 2.56615 3 P 0 0;4=4,6=1
P 4.78268002 2.61615 3 P 0 0;4=4,6=1
P 4.78268002 2.66615 3 P 0 0;4=4,6=1
P 4.68268002 2.66615 3 P 0 0;4=4,6=1
P 4.58268002 2.66615 3 P 0 0;4=4,6=1
P 4.73268002 2.71615 3 P 0 0;4=4,6=1
P 4.63268002 2.71615 3 P 0 0;4=4,6=1
P 4.63268002 2.76615 3 P 0 0;4=4,6=1
P 4.73268002 2.76615 3 P 0 0;4=4,6=1
P 4.78268002 2.76615 3 P 0 0;4=4,6=1
P 4.63268002 2.16615 3 P 0 0;4=4,6=1
P 4.78268002 2.16615 3 P 0 0;4=4,6=1
P 10.63661004 2.91615 3 P 0 0;4=4,6=1
P 10.58661004 2.91615 3 P 0 0;4=4,6=1
P 10.63661004 3.06615 3 P 0 0;4=4,6=1
P 10.58661004 3.06615 3 P 0 0;4=4,6=1
P 10.63661004 3.36615 3 P 0 0;4=4,6=1
P 10.58661004 3.36615 3 P 0 0;4=4,6=1
P 10.63661004 3.21615 3 P 0 0;4=4,6=1
P 10.58661004 3.21615 3 P 0 0;4=4,6=1
P 10.58661004 3.66615 3 P 0 0;4=4,6=1
P 10.63661004 3.51615 3 P 0 0;4=4,6=1
P 10.58661004 3.51615 3 P 0 0;4=4,6=1
P 10.63661004 3.81615 3 P 0 0;4=4,6=1
P 10.63661004 3.66615 3 P 0 0;4=4,6=1
P 10.58661004 3.81615 3 P 0 0;4=4,6=1
P 10.83661004 2.91615 3 P 0 0;4=4,6=1
P 10.78661004 2.91615 3 P 0 0;4=4,6=1
P 10.73661004 2.91615 3 P 0 0;4=4,6=1
P 10.68661004 2.91615 3 P 0 0;4=4,6=1
P 10.88661004 2.91615 3 P 0 0;4=4,6=1
P 10.88661004 3.06615 3 P 0 0;4=4,6=1
P 10.83661004 3.06615 3 P 0 0;4=4,6=1
P 10.78661004 3.06615 3 P 0 0;4=4,6=1
P 10.73661004 3.06615 3 P 0 0;4=4,6=1
P 10.68661004 3.06615 3 P 0 0;4=4,6=1
P 10.88661004 3.21615 3 P 0 0;4=4,6=1
P 10.83661004 3.21615 3 P 0 0;4=4,6=1
P 10.83661004 3.36615 3 P 0 0;4=4,6=1
P 10.88661004 3.36615 3 P 0 0;4=4,6=1
P 10.78661004 3.36615 3 P 0 0;4=4,6=1
P 10.73661004 3.36615 3 P 0 0;4=4,6=1
P 10.78661004 3.21615 3 P 0 0;4=4,6=1
P 10.73661004 3.21615 3 P 0 0;4=4,6=1
P 10.68661004 3.36615 3 P 0 0;4=4,6=1
P 10.68661004 3.21615 3 P 0 0;4=4,6=1
P 10.83661004 3.51615 3 P 0 0;4=4,6=1
P 10.88661004 3.51615 3 P 0 0;4=4,6=1
P 10.83661004 3.66615 3 P 0 0;4=4,6=1
P 10.78661004 3.66615 3 P 0 0;4=4,6=1
P 10.73661004 3.66615 3 P 0 0;4=4,6=1
P 10.68661004 3.66615 3 P 0 0;4=4,6=1
P 10.78661004 3.51615 3 P 0 0;4=4,6=1
P 10.73661004 3.51615 3 P 0 0;4=4,6=1
P 10.68661004 3.51615 3 P 0 0;4=4,6=1
P 10.83661004 3.81615 3 P 0 0;4=4,6=1
P 10.88661004 3.81615 3 P 0 0;4=4,6=1
P 10.88661004 3.66615 3 P 0 0;4=4,6=1
P 10.78661004 3.81615 3 P 0 0;4=4,6=1
P 10.73661004 3.81615 3 P 0 0;4=4,6=1
P 10.68661004 3.81615 3 P 0 0;4=4,6=1
P 11.03661004 2.91615 3 P 0 0;4=4,6=1
P 10.93661004 2.91615 3 P 0 0;4=4,6=1
P 10.98661004 2.91615 3 P 0 0;4=4,6=1
P 11.03661004 3.06615 3 P 0 0;4=4,6=1
P 10.93661004 3.06615 3 P 0 0;4=4,6=1
P 10.98661004 3.06615 3 P 0 0;4=4,6=1
P 11.03661004 3.21615 3 P 0 0;4=4,6=1
P 10.93661004 3.21615 3 P 0 0;4=4,6=1
P 10.98661004 3.21615 3 P 0 0;4=4,6=1
P 10.98661004 3.36615 3 P 0 0;4=4,6=1
P 10.93661004 3.36615 3 P 0 0;4=4,6=1
P 11.03661004 3.36615 3 P 0 0;4=4,6=1
P 10.98661004 3.51615 3 P 0 0;4=4,6=1
P 10.93661004 3.51615 3 P 0 0;4=4,6=1
P 11.03661004 3.51615 3 P 0 0;4=4,6=1
P 10.98661004 3.66615 3 P 0 0;4=4,6=1
P 10.93661004 3.66615 3 P 0 0;4=4,6=1
P 11.03661004 3.66615 3 P 0 0;4=4,6=1
P 10.98661004 3.81615 3 P 0 0;4=4,6=1
P 10.93661004 3.81615 3 P 0 0;4=4,6=1
P 3.07691004 4.81401998 4 P 0 0;4=6,6=1
P 8.1 1.86615 3 P 0 0;4=4,6=1
P 8.15 2.16615 3 P 0 0;4=4,6=1
P 8.15 2.11615 3 P 0 0;4=4,6=1
P 8.15 1.96615 3 P 0 0;4=4,6=1
P 8.1 2.01615 3 P 0 0;4=4,6=1
P 8.05 1.96615 3 P 0 0;4=4,6=1
P 8.05 2.11615 3 P 0 0;4=4,6=1
P 8.05 2.16615 3 P 0 0;4=4,6=1
P 8.15 2.31615 3 P 0 0;4=4,6=1
P 8.1 2.36615 3 P 0 0;4=4,6=1
P 8.1 2.16615 3 P 0 0;4=4,6=1
P 8.1 2.21615 3 P 0 0;4=4,6=1
P 8.05 2.31615 3 P 0 0;4=4,6=1
P 8.15 2.46615 3 P 0 0;4=4,6=1
P 8.15 2.56615 3 P 0 0;4=4,6=1
P 8.1 2.51615 3 P 0 0;4=4,6=1
P 8.05 2.46615 3 P 0 0;4=4,6=1
P 8.05 2.51615 3 P 0 0;4=4,6=1
P 8.05 2.56615 3 P 0 0;4=4,6=1
P 8.1 2.66615 3 P 0 0;4=4,6=1
P 8.05 2.76615 3 P 0 0;4=4,6=1
P 8.05 2.81615 3 P 0 0;4=4,6=1
P 8 2.86615 3 P 0 0;4=4,6=1
P 8 2.71615 3 P 0 0;4=4,6=1
P 8.05 2.71615 3 P 0 0;4=4,6=1
P 8.15 2.71615 3 P 0 0;4=4,6=1
P 8.05 2.86615 3 P 0 0;4=4,6=1
P 8.15 2.86615 3 P 0 0;4=4,6=1
P 8.1 2.91615 3 P 0 0;4=4,6=1
P 8.1 2.86615 3 P 0 0;4=4,6=1
P 8.1 2.81615 3 P 0 0;4=4,6=1
P 8.05 3.01615 3 P 0 0;4=4,6=1
P 8.1 3.06615 3 P 0 0;4=4,6=1
P 8.15 3.01615 3 P 0 0;4=4,6=1
P 8.15 3.16615 3 P 0 0;4=4,6=1
P 8.05 3.16615 3 P 0 0;4=4,6=1
P 8 3.41615 3 P 0 0;4=4,6=1
P 8.05 3.41615 3 P 0 0;4=4,6=1
P 8.1 3.36615 3 P 0 0;4=4,6=1
P 8.1 3.21615 3 P 0 0;4=4,6=1
P 8.15 3.56615 3 P 0 0;4=4,6=1
P 8.05 3.56615 3 P 0 0;4=4,6=1
P 8 3.56615 3 P 0 0;4=4,6=1
P 8.05 3.51615 3 P 0 0;4=4,6=1
P 8.05 3.46615 3 P 0 0;4=4,6=1
P 8.1 3.51615 3 P 0 0;4=4,6=1
P 8.35 1.86615 3 P 0 0;4=4,6=1
P 8.3 1.86615 3 P 0 0;4=4,6=1
P 8.25 1.86615 3 P 0 0;4=4,6=1
P 8.2 1.86615 3 P 0 0;4=4,6=1
P 8.25 2.06615 3 P 0 0;4=4,6=1
P 8.25 2.16615 3 P 0 0;4=4,6=1
P 8.25 2.11615 3 P 0 0;4=4,6=1
P 8.3 2.11615 3 P 0 0;4=4,6=1
P 8.3 2.06615 3 P 0 0;4=4,6=1
P 8.4 2.11615 3 P 0 0;4=4,6=1
P 8.4 2.16615 3 P 0 0;4=4,6=1
P 8.4 1.96615 3 P 0 0;4=4,6=1
P 8.35 2.01615 3 P 0 0;4=4,6=1
P 8.3 2.01615 3 P 0 0;4=4,6=1
P 8.25 2.01615 3 P 0 0;4=4,6=1
P 8.2 2.01615 3 P 0 0;4=4,6=1
P 8.3 1.96615 3 P 0 0;4=4,6=1
P 8.25 1.96615 3 P 0 0;4=4,6=1
P 8.3 1.91615 3 P 0 0;4=4,6=1
P 8.25 1.91615 3 P 0 0;4=4,6=1
P 8.2 2.16615 3 P 0 0;4=4,6=1
P 8.2 2.21615 3 P 0 0;4=4,6=1
P 8.25 2.26615 3 P 0 0;4=4,6=1
P 8.3 2.26615 3 P 0 0;4=4,6=1
P 8.25 2.21615 3 P 0 0;4=4,6=1
P 8.3 2.16615 3 P 0 0;4=4,6=1
P 8.3 2.21615 3 P 0 0;4=4,6=1
P 8.35 2.21615 3 P 0 0;4=4,6=1
P 8.35 2.16615 3 P 0 0;4=4,6=1
P 8.25 2.31615 3 P 0 0;4=4,6=1
P 8.3 2.31615 3 P 0 0;4=4,6=1
P 8.35 2.36615 3 P 0 0;4=4,6=1
P 8.4 2.31615 3 P 0 0;4=4,6=1
P 8.3 2.36615 3 P 0 0;4=4,6=1
P 8.2 2.36615 3 P 0 0;4=4,6=1
P 8.25 2.36615 3 P 0 0;4=4,6=1
P 8.25 2.41615 3 P 0 0;4=4,6=1
P 8.3 2.41615 3 P 0 0;4=4,6=1
P 8.4 2.56615 3 P 0 0;4=4,6=1
P 8.4 2.51615 3 P 0 0;4=4,6=1
P 8.4 2.46615 3 P 0 0;4=4,6=1
P 8.3 2.46615 3 P 0 0;4=4,6=1
P 8.25 2.46615 3 P 0 0;4=4,6=1
P 8.2 2.51615 3 P 0 0;4=4,6=1
P 8.25 2.51615 3 P 0 0;4=4,6=1
P 8.3 2.51615 3 P 0 0;4=4,6=1
P 8.35 2.51615 3 P 0 0;4=4,6=1
P 8.3 2.56615 3 P 0 0;4=4,6=1
P 8.3 2.61615 3 P 0 0;4=4,6=1
P 8.25 2.56615 3 P 0 0;4=4,6=1
P 8.25 2.61615 3 P 0 0;4=4,6=1
P 8.2 2.66615 3 P 0 0;4=4,6=1
P 8.25 2.66615 3 P 0 0;4=4,6=1
P 8.3 2.66615 3 P 0 0;4=4,6=1
P 8.35 2.66615 3 P 0 0;4=4,6=1
P 8.25 2.71615 3 P 0 0;4=4,6=1
P 8.3 2.71615 3 P 0 0;4=4,6=1
P 8.4 2.71615 3 P 0 0;4=4,6=1
P 8.35 2.81615 3 P 0 0;4=4,6=1
P 8.4 2.86615 3 P 0 0;4=4,6=1
P 8.3 2.91615 3 P 0 0;4=4,6=1
P 8.25 2.91615 3 P 0 0;4=4,6=1
P 8.2 2.91615 3 P 0 0;4=4,6=1
P 8.2 2.81615 3 P 0 0;4=4,6=1
P 8.25 2.81615 3 P 0 0;4=4,6=1
P 8.25 2.76615 3 P 0 0;4=4,6=1
P 8.3 2.81615 3 P 0 0;4=4,6=1
P 8.3 2.76615 3 P 0 0;4=4,6=1
P 8.35 2.91615 3 P 0 0;4=4,6=1
P 8.35 2.86615 3 P 0 0;4=4,6=1
P 8.35 3.06615 3 P 0 0;4=4,6=1
P 8.4 3.01615 3 P 0 0;4=4,6=1
P 8.2 3.06615 3 P 0 0;4=4,6=1
P 8.25 3.01615 3 P 0 0;4=4,6=1
P 8.25 2.96615 3 P 0 0;4=4,6=1
P 8.25 3.11615 3 P 0 0;4=4,6=1
P 8.25 3.06615 3 P 0 0;4=4,6=1
P 8.3 3.01615 3 P 0 0;4=4,6=1
P 8.3 2.96615 3 P 0 0;4=4,6=1
P 8.3 3.11615 3 P 0 0;4=4,6=1
P 8.3 3.06615 3 P 0 0;4=4,6=1
P 8.25 3.16615 3 P 0 0;4=4,6=1
P 8.3 3.16615 3 P 0 0;4=4,6=1
P 8.4 3.16615 3 P 0 0;4=4,6=1
P 8.25 3.41615 3 P 0 0;4=4,6=1
P 8.3 3.36615 3 P 0 0;4=4,6=1
P 8.25 3.36615 3 P 0 0;4=4,6=1
P 8.2 3.36615 3 P 0 0;4=4,6=1
P 8.25 3.31615 3 P 0 0;4=4,6=1
P 8.25 3.26615 3 P 0 0;4=4,6=1
P 8.3 3.21615 3 P 0 0;4=4,6=1
P 8.25 3.21615 3 P 0 0;4=4,6=1
P 8.2 3.21615 3 P 0 0;4=4,6=1
P 8.35 3.21615 3 P 0 0;4=4,6=1
P 8.4 3.56615 3 P 0 0;4=4,6=1
P 8.3 3.61615 3 P 0 0;4=4,6=1
P 8.25 3.66615 3 P 0 0;4=4,6=1
P 8.25 3.61615 3 P 0 0;4=4,6=1
P 8.2 3.61615 3 P 0 0;4=4,6=1
P 8.2 3.56615 3 P 0 0;4=4,6=1
P 8.2 3.51615 3 P 0 0;4=4,6=1
P 8.25 3.51615 3 P 0 0;4=4,6=1
P 8.3 3.51615 3 P 0 0;4=4,6=1
P 8.25 3.46615 3 P 0 0;4=4,6=1
P 8.25 3.86615 3 P 0 0;4=4,6=1
P 8.25 3.81615 3 P 0 0;4=4,6=1
P 8.2 3.76615 3 P 0 0;4=4,6=1
P 8.25 3.76615 3 P 0 0;4=4,6=1
P 8.3 3.76615 3 P 0 0;4=4,6=1
P 8.25 3.71615 3 P 0 0;4=4,6=1
P 8.45 1.86615 3 P 0 0;4=4,6=1
P 8.5 2.16615 3 P 0 0;4=4,6=1
P 8.5 2.11615 3 P 0 0;4=4,6=1
P 8.5 1.96615 3 P 0 0;4=4,6=1
P 8.45 2.01615 3 P 0 0;4=4,6=1
P 8.45 2.21615 3 P 0 0;4=4,6=1
P 8.45 2.16615 3 P 0 0;4=4,6=1
P 8.5 2.31615 3 P 0 0;4=4,6=1
P 8.45 2.36615 3 P 0 0;4=4,6=1
P 8.5 2.46615 3 P 0 0;4=4,6=1
P 8.5 2.51615 3 P 0 0;4=4,6=1
P 8.5 2.56615 3 P 0 0;4=4,6=1
P 8.45 2.51615 3 P 0 0;4=4,6=1
P 8.45 2.66615 3 P 0 0;4=4,6=1
P 8.5 2.71615 3 P 0 0;4=4,6=1
P 8.5 2.86615 3 P 0 0;4=4,6=1
P 8.45 2.81615 3 P 0 0;4=4,6=1
P 8.45 2.86615 3 P 0 0;4=4,6=1
P 8.45 2.91615 3 P 0 0;4=4,6=1
P 8.5 3.01615 3 P 0 0;4=4,6=1
P 8.45 3.06615 3 P 0 0;4=4,6=1
P 8.5 3.16615 3 P 0 0;4=4,6=1
P 8.5 3.41615 3 P 0 0;4=4,6=1
P 8.45 3.36615 3 P 0 0;4=4,6=1
P 8.45 3.21615 3 P 0 0;4=4,6=1
P 8.5 3.21615 3 P 0 0;4=4,6=1
P 8.5 3.26615 3 P 0 0;4=4,6=1
P 8.5 3.56615 3 P 0 0;4=4,6=1
P 8.45 3.56615 3 P 0 0;4=4,6=1
P 8.5 3.86615 3 P 0 0;4=4,6=1
P 8.5 3.71615 3 P 0 0;4=4,6=1
P 8.2 2.86615 3 P 0 0;4=4,6=1
P 8.05 3.26615 3 P 0 0;4=4,6=1
P 8.05 3.21615 3 P 0 0;4=4,6=1
P 8.3 3.26615 3 P 0 0;4=4,6=1
P 8.3 3.31615 3 P 0 0;4=4,6=1
P 8.35 3.36615 3 P 0 0;4=4,6=1
P 8.15 3.26615 3 P 0 0;4=4,6=1
P 8.15 3.21615 3 P 0 0;4=4,6=1
P 8.4 3.21615 3 P 0 0;4=4,6=1
P 8.4 3.26615 3 P 0 0;4=4,6=1
P 8.1 3.61615 3 P 0 0;4=4,6=1
P 8.3 3.46615 3 P 0 0;4=4,6=1
P 8.3 3.41615 3 P 0 0;4=4,6=1
P 8.35 3.51615 3 P 0 0;4=4,6=1
P 8.35 3.61615 3 P 0 0;4=4,6=1
P 8.35 3.56615 3 P 0 0;4=4,6=1
P 8.15 3.41615 3 P 0 0;4=4,6=1
P 8.45 3.51615 3 P 0 0;4=4,6=1
P 8.45 3.61615 3 P 0 0;4=4,6=1
P 8.4 3.41615 3 P 0 0;4=4,6=1
P 8.05 3.71615 3 P 0 0;4=4,6=1
P 8.1 3.76615 3 P 0 0;4=4,6=1
P 8.05 3.86615 3 P 0 0;4=4,6=1
P 8.3 3.71615 3 P 0 0;4=4,6=1
P 8.3 3.66615 3 P 0 0;4=4,6=1
P 8.35 3.76615 3 P 0 0;4=4,6=1
P 8.3 3.81615 3 P 0 0;4=4,6=1
P 8.3 3.86615 3 P 0 0;4=4,6=1
P 8.15 3.71615 3 P 0 0;4=4,6=1
P 8.15 3.86615 3 P 0 0;4=4,6=1
P 8.45 3.76615 3 P 0 0;4=4,6=1
P 8.4 3.71615 3 P 0 0;4=4,6=1
P 8.4 3.86615 3 P 0 0;4=4,6=1
P 7.955 5.377 24 P 0 0;1,4=0,6=0
P 8.12 5.377 24 P 0 0;1,4=0,6=0
P 3.28831004 4.68073996 4 P 0 0;4=6,6=1
P 3.22831004 4.68073996 4 P 0 0;4=6,6=1
P 3.50091004 4.62573996 4 P 0 0;4=6,6=1
P 3.44091004 4.62573996 4 P 0 0;4=6,6=1
P 7.56575 5.023 4 P 0 0;4=6,6=1
P 7.63661998 5.023 4 P 0 0;4=6,6=1
P 7.84921998 5.023 4 P 0 0;4=6,6=1
P 7.77835 5.023 4 P 0 0;4=6,6=1
P 7.70748996 5.023 4 P 0 0;4=6,6=1
P 7.92008002 5.023 4 P 0 0;4=6,6=1
P 8.06181998 5.023 4 P 0 0;4=6,6=1
P 8.13268002 5.023 4 P 0 0;4=6,6=1
P 7.99095 5.023 4 P 0 0;4=6,6=1
P 8.34528002 5.023 4 P 0 0;4=6,6=1
P 8.27441004 5.023 4 P 0 0;4=6,6=1
P 8.20355 5.023 4 P 0 0;4=6,6=1
P 8.41615 5.023 4 P 0 0;4=6,6=1
P 7.63661998 4.92 4 P 0 0;4=6,6=1
P 7.84921998 4.9207 4 P 0 0;4=6,6=1
P 7.70748996 4.9207 4 P 0 0;4=6,6=1
P 7.77835 4.9207 4 P 0 0;4=6,6=1
P 7.99095 4.9207 4 P 0 0;4=6,6=1
P 7.92008002 4.9207 4 P 0 0;4=6,6=1
P 8.06181998 4.9207 4 P 0 0;4=6,6=1
P 8.13268002 4.9207 4 P 0 0;4=6,6=1
P 8.27441004 4.9207 4 P 0 0;4=6,6=1
P 8.20355 4.9267 4 P 0 0;4=6,6=1
P 8.34528002 4.9207 4 P 0 0;4=6,6=1
P 7.63526998 4.81526998 4 P 0 0;4=6,6=1
P 7.84921998 4.81 4 P 0 0;4=6,6=1
P 7.77953996 4.812 4 P 0 0;4=6,6=1
P 7.70353996 4.812 4 P 0 0;4=6,6=1
P 8.13268002 4.81 4 P 0 0;4=6,6=1
P 8.06441004 4.81 4 P 0 0;4=6,6=1
P 7.99353996 4.81 4 P 0 0;4=6,6=1
P 7.92353996 4.81 4 P 0 0;4=6,6=1
P 8.27441004 4.81 4 P 0 0;4=6,6=1
P 8.34528002 4.81 4 P 0 0;4=6,6=1
P 8.20355 4.81 4 P 0 0;4=6,6=1
P 8.41615 4.81401998 4 P 0 0;4=6,6=1
P 8.86908996 4.81401998 4 P 0 0;4=6,6=1
P 8.73035 4.81401998 4 P 0 0;4=6,6=1
P 8.80121998 4.81401998 4 P 0 0;4=6,6=1
P 8.94495 4.81401998 4 P 0 0;4=6,6=1
P 9.08045 4.81401998 4 P 0 0;4=6,6=1
P 9.01381998 4.81401998 4 P 0 0;4=6,6=1
P 9.36815 4.81401998 4 P 0 0;4=6,6=1
P 9.29728002 4.81401998 4 P 0 0;4=6,6=1
P 9.22641998 4.81401998 4 P 0 0;4=6,6=1
P 9.15751998 4.81401998 4 P 0 0;4=6,6=1
P 9.43901004 4.81401998 4 P 0 0;4=6,6=1
P 9.50988002 4.81401998 4 P 0 0;4=6,6=1
P 9.58075 4.81401998 4 P 0 0;4=6,6=1
P 8.80121998 5.023 4 P 0 0;4=6,6=1
P 8.73035 5.023 4 P 0 0;4=6,6=1
P 8.87208996 5.023 4 P 0 0;4=6,6=1
P 9.08468002 5.023 4 P 0 0;4=6,6=1
P 9.01381998 5.023 4 P 0 0;4=6,6=1
P 8.94295 5.023 4 P 0 0;4=6,6=1
P 8.87208996 4.92 4 P 0 0;4=6,6=1
P 8.80121998 4.92 4 P 0 0;4=6,6=1
P 9.01381998 4.92 4 P 0 0;4=6,6=1
P 9.08468002 4.92 4 P 0 0;4=6,6=1
P 9.22641998 4.92 4 P 0 0;4=6,6=1
P 9.36815 4.926 4 P 0 0;4=6,6=1
P 9.50988002 4.92 4 P 0 0;4=6,6=1
P 9.43901004 4.928 4 P 0 0;4=6,6=1
P 9.36815 5.023 4 P 0 0;4=6,6=1
P 9.29728002 5.023 4 P 0 0;4=6,6=1
P 9.22641998 5.023 4 P 0 0;4=6,6=1
P 9.15555 5.023 4 P 0 0;4=6,6=1
P 9.50988002 5.023 4 P 0 0;4=6,6=1
P 9.43901004 5.023 4 P 0 0;4=6,6=1
P 9.58075 5.023 4 P 0 0;4=6,6=1
P 8.94853996 4.92 4 P 0 0;4=6,6=1
P 9.27853996 4.92 4 P 0 0;4=6,6=1
P 9.14353996 4.92 4 P 0 0;4=6,6=1
P 8.13811004 5.09223996 4 P 0 0;4=6,6=1
P 8.35071004 5.15373996 4 P 0 0;4=6,6=1
P 8.41071004 5.15373996 4 P 0 0;4=6,6=1
P 7.56575 4.81401998 4 P 0 0;4=6,6=1
P 8.88061998 4.70573996 4 P 0 0;4=6,6=1
P 2.45985 4.77875 8 P 0 0;4=13,6=0
P 1.51496998 4.77875 8 P 0 0;4=13,6=0
P 2.44016998 5.05826998 8 P 0 0;4=13,6=0
P 1.53465 5.05826998 8 P 0 0;4=13,6=0
P 3.60476998 4.77875 8 P 0 0;4=13,6=0
P 2.67956998 4.77875 8 P 0 0;4=13,6=0
P 3.60476998 5.05826998 8 P 0 0;4=13,6=0
P 2.69925 5.05826998 8 P 0 0;4=13,6=0
P 8.46338996 4.77875 8 P 0 0;4=13,6=0
P 7.51851004 4.77875 8 P 0 0;4=13,6=0
P 8.44371004 5.05826998 8 P 0 0;4=13,6=0
P 7.53818996 5.05826998 8 P 0 0;4=13,6=0
P 9.60831004 4.77875 8 P 0 0;4=13,6=0
P 8.68311004 4.77875 8 P 0 0;4=13,6=0
P 9.60831004 5.05826998 8 P 0 0;4=13,6=0
P 8.70278996 5.05826998 8 P 0 0;4=13,6=0
P 10.82676998 5.49685 11 P 0 0;4=14,6=0
P 10.99213002 5.49685 11 P 0 0;4=14,6=0
P 11.15748002 5.49685 11 P 0 0;4=14,6=0
P 11.32283996 5.49685 11 P 0 0;4=14,6=0
P 11.48818996 5.49685 11 P 0 0;4=14,6=0
P 11.65353996 5.49685 11 P 0 0;4=14,6=0
P 11.8189 5.49685 11 P 0 0;4=14,6=0
P 11.98425 5.49685 11 P 0 0;4=14,6=0
P 12.14961004 5.49685 27 P 0 0;2,4=15,6=0
P 10.83661998 1.50786998 21 P 0 0;4=16,6=0
P 10.83661998 1.50788002 21 P 0 0;4=16,6=0
P 8.25 1.50788002 21 P 0 0;4=16,6=0
P 8.25 1.50786998 21 P 0 0;4=16,6=0
P 6.96456998 1.52756004 21 P 0 0;4=16,6=0
P 6.96456998 1.52756004 21 P 0 0;4=16,6=0
P 6.96456998 4.20471998 21 P 0 0;4=16,6=0
P 6.96456998 4.20473002 21 P 0 0;4=16,6=0
P 8.25 4.22441004 21 P 0 0;4=16,6=0
P 8.25 4.22441004 21 P 0 0;4=16,6=0
P 10.83661998 4.22441004 21 P 0 0;4=16,6=0
P 10.83661998 4.22441004 21 P 0 0;4=16,6=0
P 12.12205 4.20471998 21 P 0 0;4=16,6=0
P 12.12205 4.20473002 21 P 0 0;4=16,6=0
P 12.12205 1.52756004 21 P 0 0;4=16,6=0
P 12.12205 1.52756004 21 P 0 0;4=16,6=0
P 11.99213002 4.20473002 4 P 0 0;4=6,6=0
P 12.03018002 4.11286004 4 P 0 0;4=6,6=0
P 12.03018002 4.2966 4 P 0 0;4=6,6=0
P 12.21391998 4.11286004 4 P 0 0;4=6,6=0
P 12.25196998 4.20473002 4 P 0 0;4=6,6=0
P 12.21391998 4.2966 4 P 0 0;4=6,6=0
P 10.7067 4.22441004 4 P 0 0;4=6,6=0
P 10.74475 4.13253996 4 P 0 0;4=6,6=0
P 10.74475 4.31628002 4 P 0 0;4=6,6=0
P 10.92848996 4.13253996 4 P 0 0;4=6,6=0
P 10.96653996 4.22441004 4 P 0 0;4=6,6=0
P 10.92848996 4.31628002 4 P 0 0;4=6,6=0
P 8.12008002 4.22441004 4 P 0 0;4=6,6=0
P 8.15813002 4.13253996 4 P 0 0;4=6,6=0
P 8.15813002 4.31628002 4 P 0 0;4=6,6=0
P 8.34186998 4.13253996 4 P 0 0;4=6,6=0
P 8.37991998 4.22441004 4 P 0 0;4=6,6=0
P 8.34186998 4.31628002 4 P 0 0;4=6,6=0
P 6.83465 4.20473002 4 P 0 0;4=6,6=0
P 6.8727 4.11286004 4 P 0 0;4=6,6=0
P 6.8727 4.2966 4 P 0 0;4=6,6=0
P 7.05643996 4.11286004 4 P 0 0;4=6,6=0
P 7.09448996 4.20473002 4 P 0 0;4=6,6=0
P 7.05643996 4.2966 4 P 0 0;4=6,6=0
P 6.83465 1.52756004 4 P 0 0;4=6,6=0
P 6.8727 1.43568996 4 P 0 0;4=6,6=0
P 6.8727 1.61943002 4 P 0 0;4=6,6=0
P 7.05643996 1.43568996 4 P 0 0;4=6,6=0
P 7.09448996 1.52756004 4 P 0 0;4=6,6=0
P 7.05643996 1.61943002 4 P 0 0;4=6,6=0
P 8.15813002 1.416 4 P 0 0;4=6,6=0
P 8.12008002 1.50786998 4 P 0 0;4=6,6=0
P 8.15813002 1.59975 4 P 0 0;4=6,6=0
P 8.34186998 1.416 4 P 0 0;4=6,6=0
P 8.34186998 1.59975 4 P 0 0;4=6,6=0
P 8.37991998 1.50786998 4 P 0 0;4=6,6=0
P 10.74475 1.59975 4 P 0 0;4=6,6=0
P 10.92848996 1.59975 4 P 0 0;4=6,6=0
P 10.96653996 1.50786998 4 P 0 0;4=6,6=0
P 10.92848996 1.416 4 P 0 0;4=6,6=0
P 10.74475 1.416 4 P 0 0;4=6,6=0
P 10.7067 1.50786998 4 P 0 0;4=6,6=0
P 12.2126 1.43701004 4 P 0 0;4=6,6=0
P 12.25196998 1.52756004 4 P 0 0;4=6,6=0
P 12.2126 1.61811004 4 P 0 0;4=6,6=0
P 12.0315 1.61811004 4 P 0 0;4=6,6=0
P 11.99213002 1.52756004 4 P 0 0;4=6,6=0
P 12.0315 1.43701004 4 P 0 0;4=6,6=0
P 4.83268002 1.50786998 21 P 0 0;4=16,6=0
P 4.83268002 1.50788002 21 P 0 0;4=16,6=0
P 2.24606004 1.50788002 21 P 0 0;4=16,6=0
P 2.24606004 1.50786998 21 P 0 0;4=16,6=0
P 0.96063002 1.52756004 21 P 0 0;4=16,6=0
P 0.96063002 1.52756004 21 P 0 0;4=16,6=0
P 0.96063002 4.20471998 21 P 0 0;4=16,6=0
P 0.96063002 4.20473002 21 P 0 0;4=16,6=0
P 2.24606004 4.22441004 21 P 0 0;4=16,6=0
P 2.24606004 4.22441004 21 P 0 0;4=16,6=0
P 4.83268002 4.22441004 21 P 0 0;4=16,6=0
P 4.83268002 4.22441004 21 P 0 0;4=16,6=0
P 6.11811004 4.20471998 21 P 0 0;4=16,6=0
P 6.11811004 4.20473002 21 P 0 0;4=16,6=0
P 6.11811004 1.52756004 21 P 0 0;4=16,6=0
P 6.11811004 1.52756004 21 P 0 0;4=16,6=0
P 5.98818996 4.20473002 4 P 0 0;4=6,6=0
P 6.02623996 4.11286004 4 P 0 0;4=6,6=0
P 6.02623996 4.2966 4 P 0 0;4=6,6=0
P 6.20998002 4.11286004 4 P 0 0;4=6,6=0
P 6.24803002 4.20473002 4 P 0 0;4=6,6=0
P 6.20998002 4.2966 4 P 0 0;4=6,6=0
P 4.70276004 4.22441004 4 P 0 0;4=6,6=0
P 4.74081004 4.13253996 4 P 0 0;4=6,6=0
P 4.74081004 4.31628002 4 P 0 0;4=6,6=0
P 4.92455 4.13253996 4 P 0 0;4=6,6=0
P 4.9626 4.22441004 4 P 0 0;4=6,6=0
P 4.92455 4.31628002 4 P 0 0;4=6,6=0
P 2.11613996 4.22441004 4 P 0 0;4=6,6=0
P 2.15418996 4.13253996 4 P 0 0;4=6,6=0
P 2.15418996 4.31628002 4 P 0 0;4=6,6=0
P 2.33793002 4.13253996 4 P 0 0;4=6,6=0
P 2.37598002 4.22441004 4 P 0 0;4=6,6=0
P 2.33793002 4.31628002 4 P 0 0;4=6,6=0
P 0.83071004 4.20473002 4 P 0 0;4=6,6=0
P 0.86876004 4.11286004 4 P 0 0;4=6,6=0
P 0.86876004 4.2966 4 P 0 0;4=6,6=0
P 1.0525 4.11286004 4 P 0 0;4=6,6=0
P 1.09055 4.20473002 4 P 0 0;4=6,6=0
P 1.0525 4.2966 4 P 0 0;4=6,6=0
P 0.83071004 1.52756004 4 P 0 0;4=6,6=0
P 0.86876004 1.43568996 4 P 0 0;4=6,6=0
P 0.86876004 1.61943002 4 P 0 0;4=6,6=0
P 1.0525 1.43568996 4 P 0 0;4=6,6=0
P 1.09055 1.52756004 4 P 0 0;4=6,6=0
P 1.0525 1.61943002 4 P 0 0;4=6,6=0
P 2.15418996 1.416 4 P 0 0;4=6,6=0
P 2.11613996 1.50786998 4 P 0 0;4=6,6=0
P 2.15418996 1.59975 4 P 0 0;4=6,6=0
P 2.33793002 1.416 4 P 0 0;4=6,6=0
P 2.33793002 1.59975 4 P 0 0;4=6,6=0
P 2.37598002 1.50786998 4 P 0 0;4=6,6=0
P 4.74081004 1.59975 4 P 0 0;4=6,6=0
P 4.92455 1.59975 4 P 0 0;4=6,6=0
P 4.9626 1.50786998 4 P 0 0;4=6,6=0
P 4.92455 1.416 4 P 0 0;4=6,6=0
P 4.74081004 1.416 4 P 0 0;4=6,6=0
P 4.70276004 1.50786998 4 P 0 0;4=6,6=0
P 6.20866004 1.43701004 4 P 0 0;4=6,6=0
P 6.24803002 1.52756004 4 P 0 0;4=6,6=0
P 6.20866004 1.61811004 4 P 0 0;4=6,6=0
P 6.02756004 1.61811004 4 P 0 0;4=6,6=0
P 5.98818996 1.52756004 4 P 0 0;4=6,6=0
P 6.02756004 1.43701004 4 P 0 0;4=6,6=0
P 12.59646998 0.8189 4 P 0 0;4=6,6=0
P 12.5571 0.72835 4 P 0 0;4=6,6=0
P 12.59646998 0.6378 4 P 0 0;4=6,6=0
P 12.68701998 0.72835 21 P 0 0;4=16,6=0
P 12.77756998 0.6378 4 P 0 0;4=6,6=0
P 12.81693996 0.72835 4 P 0 0;4=6,6=0
P 12.77756998 0.8189 4 P 0 0;4=6,6=0
P 12.68701998 0.72835 21 P 0 0;4=16,6=0
P 12.59646998 5.24803002 4 P 0 0;4=6,6=0
P 12.5571 5.15748002 4 P 0 0;4=6,6=0
P 12.59646998 5.06693002 4 P 0 0;4=6,6=0
P 12.68701998 5.15748002 21 P 0 0;4=16,6=0
P 12.77756998 5.06693002 4 P 0 0;4=6,6=0
P 12.81693996 5.15748002 4 P 0 0;4=6,6=0
P 12.77756998 5.24803002 4 P 0 0;4=6,6=0
P 12.68701998 5.15748002 21 P 0 0;4=16,6=0
P 0.1319 5.20866004 4 P 0 0;4=6,6=0
P 0.09253002 5.11811004 4 P 0 0;4=6,6=0
P 0.1319 5.02756004 4 P 0 0;4=6,6=0
P 0.22245 5.11811004 21 P 0 0;4=16,6=0
P 0.313 5.02756004 4 P 0 0;4=6,6=0
P 0.35236998 5.11811004 4 P 0 0;4=6,6=0
P 0.313 5.20866004 4 P 0 0;4=6,6=0
P 0.22245 5.11811004 21 P 0 0;4=16,6=0
P 0.1319 0.77953002 4 P 0 0;4=6,6=0
P 0.09253002 0.68898002 4 P 0 0;4=6,6=0
P 0.1319 0.59843002 4 P 0 0;4=6,6=0
P 0.22245 0.68898002 21 P 0 0;4=16,6=0
P 0.313 0.59843002 4 P 0 0;4=6,6=0
P 0.35236998 0.68898002 4 P 0 0;4=6,6=0
P 0.313 0.77953002 4 P 0 0;4=6,6=0
P 0.22245 0.68898002 21 P 0 0;4=16,6=0
P 10.80498996 5.56656004 4 P 0 0;4=6,6=1
P 10.84498996 5.56656004 4 P 0 0;4=6,6=1
P 10.80498996 5.42656004 4 P 0 0;4=6,6=1
P 10.84498996 5.42656004 4 P 0 0;4=6,6=1
P 11.01035 5.42656004 4 P 0 0;4=6,6=1
P 10.97035 5.42656004 4 P 0 0;4=6,6=1
P 11.01035 5.56656004 4 P 0 0;4=6,6=1
P 10.97035 5.56656004 4 P 0 0;4=6,6=1
P 11.17571004 5.42656004 4 P 0 0;4=6,6=1
P 11.13571004 5.42656004 4 P 0 0;4=6,6=1
P 11.17571004 5.56656004 4 P 0 0;4=6,6=1
P 11.13571004 5.56656004 4 P 0 0;4=6,6=1
P 11.34106998 5.42656004 4 P 0 0;4=6,6=1
P 11.30106998 5.42656004 4 P 0 0;4=6,6=1
P 11.34106998 5.56656004 4 P 0 0;4=6,6=1
P 11.30106998 5.56656004 4 P 0 0;4=6,6=1
P 11.50643002 5.42656004 4 P 0 0;4=6,6=1
P 11.46643002 5.42656004 4 P 0 0;4=6,6=1
P 11.50643002 5.56656004 4 P 0 0;4=6,6=1
P 11.46643002 5.56656004 4 P 0 0;4=6,6=1
P 11.67178996 5.42656004 4 P 0 0;4=6,6=1
P 11.63178996 5.42656004 4 P 0 0;4=6,6=1
P 11.67178996 5.56656004 4 P 0 0;4=6,6=1
P 11.63178996 5.56656004 4 P 0 0;4=6,6=1
P 11.83715 5.42656004 4 P 0 0;4=6,6=1
P 11.79715 5.42656004 4 P 0 0;4=6,6=1
P 11.83715 5.56656004 4 P 0 0;4=6,6=1
P 11.79715 5.56656004 4 P 0 0;4=6,6=1
P 12.00251004 5.42656004 4 P 0 0;4=6,6=1
P 11.96251004 5.42656004 4 P 0 0;4=6,6=1
P 12.00251004 5.56656004 4 P 0 0;4=6,6=1
P 11.96251004 5.56656004 4 P 0 0;4=6,6=1
P 12.16786998 5.42656004 4 P 0 0;4=6,6=1
P 12.12786998 5.42656004 4 P 0 0;4=6,6=1
P 12.16786998 5.56656004 4 P 0 0;4=6,6=1
P 12.12786998 5.56656004 4 P 0 0;4=6,6=1
P 6.645 4.83 6 P 0 0;2,4=5,6=1
P 4.755 5.03 6 P 0 0;2,4=5,6=1
P 7.32283996 0.23621998 4 P 0 0;4=6,6=0
P 7.28016998 0.33921998 4 P 0 0;4=6,6=0
P 7.17716998 0.23621998 22 P 0 0;4=17,6=0
P 7.28016998 0.13321998 4 P 0 0;4=6,6=0
P 7.17716998 0.23621998 22 P 0 0;4=17,6=0
P 7.07416998 0.13321998 4 P 0 0;4=6,6=0
P 7.0315 0.23621998 4 P 0 0;4=6,6=0
P 7.07416998 0.33921998 4 P 0 0;4=6,6=0
P 7.32283996 5.7874 4 P 0 0;4=6,6=0
P 7.28016998 5.8904 4 P 0 0;4=6,6=0
P 7.17716998 5.7874 22 P 0 0;4=17,6=0
P 7.28016998 5.6844 4 P 0 0;4=6,6=0
P 7.17716998 5.7874 22 P 0 0;4=17,6=0
P 7.07416998 5.6844 4 P 0 0;4=6,6=0
P 7.0315 5.7874 4 P 0 0;4=6,6=0
P 7.07416998 5.8904 4 P 0 0;4=6,6=0
P 1.857 3.56 24 P 0 0;1,4=0,6=0
P 2.24606004 3.56615 3 P 0 0;4=4,6=1
P 1.9 3.56 6 P 0 0;2,4=5,6=1
P 8.2 3.26615 3 P 0 0;4=4,6=1
P 7.65203996 5.0535 3 P 0 0;4=4,6=1
P 2.29606004 2.86615 3 P 0 0;4=4,6=1
P 2.63685 2.87 24 P 0 0;1,4=0,6=0
P 1.857 3.51 24 P 0 0;1,4=0,6=0
P 2.29606004 3.56615 3 P 0 0;4=4,6=1
P 1.9 3.51 6 P 0 0;2,4=5,6=1
P 7.69203996 5.0535 3 P 0 0;4=4,6=1
P 8.2 3.31615 3 P 0 0;4=4,6=1
P 1.33906004 4.69351004 6 P 0 0;2,4=1,6=1
P 1.31906004 4.94151004 24 P 0 0;1,4=0,6=0
P 1.823 3.56 24 P 0 0;1,4=0,6=0
P 0.80806998 5.46193996 6 P 0 0;2,4=1,6=1
P 3.733 5.075 4 P 0 0;4=6,6=1
P 1.28906004 4.69351004 6 P 0 0;2,4=1,6=1
P 1.26906004 4.94151004 24 P 0 0;1,4=0,6=0
P 1.823 3.51 24 P 0 0;1,4=0,6=0
P 8.2 3.41615 3 P 0 0;4=4,6=1
P 7.86465 5.169 3 P 0 0;4=4,6=1
P 3.94 4.765 6 P 0 0;2,4=1,6=1
P 2.34606004 3.26615 3 P 0 0;4=4,6=1
P 2.39716998 4.742 3 P 0 0;4=4,6=1
P 8.2 3.46615 3 P 0 0;4=4,6=1
P 7.90465 5.169 3 P 0 0;4=4,6=1
P 2.06646004 5.343 24 P 0 0;1,4=0,6=0
P 2.11646004 5.343 24 P 0 0;1,4=0,6=0
P 2.06646004 5.29 6 P 0 0;2,4=1,6=1
P 2.34606004 3.31615 3 P 0 0;4=4,6=1
P 2.35716998 4.742 3 P 0 0;4=4,6=1
P 1.33906004 5.15351004 6 P 0 0;2,4=1,6=1
P 3.105 4.47 4 P 0 0;4=6,6=1
P 3.11 4.508 24 P 0 0;1,4=0,6=0
P 8 3.46615 3 P 0 0;4=4,6=1
P 7.93551004 5.0535 3 P 0 0;4=4,6=1
P 2.00146004 5.343 24 P 0 0;1,4=0,6=0
P 1.95146004 5.343 24 P 0 0;1,4=0,6=0
P 2.00146004 5.29 6 P 0 0;2,4=1,6=1
P 2.25855 4.667 3 P 0 0;4=4,6=1
P 2.39606004 3.31615 3 P 0 0;4=4,6=1
P 3.16 4.508 24 P 0 0;1,4=0,6=0
P 1.18906004 5.15351004 6 P 0 0;2,4=1,6=1
P 3.07 4.42 4 P 0 0;4=6,6=1
P 8 3.51615 3 P 0 0;4=4,6=1
P 7.97551004 5.0535 3 P 0 0;4=4,6=1
P 2.21855 4.667 3 P 0 0;4=4,6=1
P 2.39606004 3.36615 3 P 0 0;4=4,6=1
P 8.11725 5.169 3 P 0 0;4=4,6=1
P 8.4 3.46615 3 P 0 0;4=4,6=1
P 3.635 0.715 6 P 0 0;2,4=1,6=1
P 4.63268002 2.81615 3 P 0 0;4=4,6=1
P 2.44606004 3.26615 3 P 0 0;4=4,6=1
P 2.39716998 5.115 3 P 0 0;4=4,6=1
P 8.07725 5.169 3 P 0 0;4=4,6=1
P 8.4 3.51615 3 P 0 0;4=4,6=1
P 2.44606004 3.31615 3 P 0 0;4=4,6=1
P 2.35716998 5.115 3 P 0 0;4=4,6=1
P 8.5 3.46615 3 P 0 0;4=4,6=1
P 8.07206998 4.66688996 3 P 0 0;4=4,6=1
P 2.25543996 4.78291998 3 P 0 0;4=4,6=1
P 2.49606004 3.31615 3 P 0 0;4=4,6=1
P 8.5 3.51615 3 P 0 0;4=4,6=1
P 8.03206998 4.66688996 3 P 0 0;4=4,6=1
P 4.02 4.42 6 P 0 0;2,4=1,6=1
P 4.58268002 2.76615 3 P 0 0;4=4,6=1
P 2.21543996 4.78291998 3 P 0 0;4=4,6=1
P 2.49606004 3.36615 3 P 0 0;4=4,6=1
P 8.35 3.41615 3 P 0 0;4=4,6=1
P 8.11725 4.78291998 3 P 0 0;4=4,6=1
P 4.78268002 2.71615 3 P 0 0;4=4,6=1
P 5.71638002 2.82441004 29 P 0 0;1,4=8,6=0
P 5.64668996 2.785 24 P 0 0;1,4=0,6=0
P 5.56 2.82 6 P 0 0;2,4=5,6=1
P 2.11371004 4.78291998 3 P 0 0;4=4,6=1
P 2.34606004 3.41615 3 P 0 0;4=4,6=1
P 8.35 3.46615 3 P 0 0;4=4,6=1
P 8.07725 4.78291998 3 P 0 0;4=4,6=1
P 5.08268002 2.71615 3 P 0 0;4=4,6=1
P 4.06 4.86 6 P 0 0;2,4=1,6=1
P 2.07371004 4.78291998 3 P 0 0;4=4,6=1
P 2.34606004 3.46615 3 P 0 0;4=4,6=1
P 2.18456998 5.0535 3 P 0 0;4=4,6=1
P 2.44606004 3.41615 3 P 0 0;4=4,6=1
P 10.93661004 2.41615 3 P 0 0;4=4,6=1
P 11.62193002 2.61 24 P 0 0;1,4=0,6=0
P 2.14456998 5.0535 3 P 0 0;4=4,6=1
P 2.44606004 3.46615 3 P 0 0;4=4,6=1
P 10.93661004 2.46615 3 P 0 0;4=4,6=1
P 11.62193002 2.655 24 P 0 0;1,4=0,6=0
P 8.5 3.31615 3 P 0 0;4=4,6=1
P 8.25898002 4.78291998 3 P 0 0;4=4,6=1
P 4.88268002 2.71615 3 P 0 0;4=4,6=1
P 5.71638002 2.87558996 29 P 0 0;1,4=8,6=0
P 5.64668996 2.905 24 P 0 0;1,4=0,6=0
P 5.56 2.955 6 P 0 0;2,4=5,6=1
P 2.06853002 4.66688996 3 P 0 0;4=4,6=1
P 2.49606004 3.46615 3 P 0 0;4=4,6=1
P 8.5 3.36615 3 P 0 0;4=4,6=1
P 8.21898002 4.78291998 3 P 0 0;4=4,6=1
P 2.02853002 4.66688996 3 P 0 0;4=4,6=1
P 2.49606004 3.51615 3 P 0 0;4=4,6=1
P 8.4 3.31615 3 P 0 0;4=4,6=1
P 8.26208996 4.667 3 P 0 0;4=4,6=1
P 2.11371004 5.169 3 P 0 0;4=4,6=1
P 2.39606004 3.46615 3 P 0 0;4=4,6=1
P 8.4 3.36615 3 P 0 0;4=4,6=1
P 8.22208996 4.667 3 P 0 0;4=4,6=1
P 3.84 0.69 6 P 0 0;2,4=1,6=1
P 4.68268002 2.76615 3 P 0 0;4=4,6=1
P 2.07371004 5.169 3 P 0 0;4=4,6=1
P 2.39606004 3.51615 3 P 0 0;4=4,6=1
P 3.56 0.49 6 P 0 0;2,4=1,6=1
P 4.73268002 2.81615 3 P 0 0;4=4,6=1
P 1.57765 5.169 3 P 0 0;4=4,6=1
P 2.04606004 3.31615 3 P 0 0;4=4,6=1
P 9.10853996 4.47 4 P 0 0;4=6,6=1
P 7.3426 5.15351004 6 P 0 0;2,4=1,6=1
P 9.11353996 4.508 24 P 0 0;1,4=0,6=0
P 3.785 0.69 6 P 0 0;2,4=1,6=1
P 4.78268002 2.81615 3 P 0 0;4=4,6=1
P 1.61765 5.169 3 P 0 0;4=4,6=1
P 2.04606004 3.36615 3 P 0 0;4=4,6=1
P 8.1 3.26615 3 P 0 0;4=4,6=1
P 7.58118996 4.707 3 P 0 0;4=4,6=1
P 2.09606004 3.26615 3 P 0 0;4=4,6=1
P 1.57765 4.707 3 P 0 0;4=4,6=1
P 5.08268002 1.96615 3 P 0 0;4=4,6=1
P 5.46358002 1.8533 24 P 0 0;1,4=0,6=0
P 8.1 3.31615 3 P 0 0;4=4,6=1
P 7.62118996 4.707 3 P 0 0;4=4,6=1
P 3.75998996 0.345 6 P 0 0;2,4=1,6=1
P 4.68268002 2.81615 3 P 0 0;4=4,6=1
P 2.09606004 3.31615 3 P 0 0;4=4,6=1
P 1.61765 4.707 3 P 0 0;4=4,6=1
P 0.58 5.591 6 P 0 0;2,4=1,6=1
P 2.06646004 5.377 24 P 0 0;1,4=0,6=0
P 3.33646004 5.332 24 P 0 0;1,4=0,6=0
P 3.18646004 5.332 24 P 0 0;1,4=0,6=0
P 3.14146004 5.332 24 P 0 0;1,4=0,6=0
P 2.00146004 5.377 24 P 0 0;1,4=0,6=0
P 9.34 5.332 24 P 0 0;1,4=0,6=0
P 9.19 5.332 24 P 0 0;1,4=0,6=0
P 11.65061998 2.855 24 P 0 0;1,4=0,6=0
P 11.72031004 2.85 29 P 0 0;1,4=8,6=0
P 11.67761998 2.85 4 P 0 0;4=6,6=1
P 11.865 4.455 6 P 0 0;2,4=1,6=1
P 9.145 5.332 24 P 0 0;1,4=0,6=0
P 8.005 5.377 24 P 0 0;1,4=0,6=0
P 8.07 5.377 24 P 0 0;1,4=0,6=0
P 5.71638002 2.85 29 P 0 0;1,4=8,6=0
P 5.67368996 2.85 4 P 0 0;4=6,6=1
P 5.64668996 2.855 24 P 0 0;1,4=0,6=0
P 5.855 3.07 4 P 0 0;4=6,6=1
P 5.883 3.07 24 P 0 0;1,4=0,6=0
P 5.883 2.97 24 P 0 0;1,4=0,6=0
P 5.8522 2.97 4 P 0 0;4=6,6=1
P 5.80255 2.97441004 29 P 0 0;1,4=8,6=0
P 7.2926 5.15351004 4 P 0 0;4=6,6=1
P 7.2426 5.15351004 4 P 0 0;4=6,6=1
P 7.1926 4.95351004 4 P 0 0;4=6,6=1
P 7.42603996 5.15895 6 P 0 0;2,4=1,6=1
P 3.94 4.655 4 P 0 0;4=6,6=1
P 3.77 4.765 4 P 0 0;4=6,6=1
P 4.14 4.745 4 P 0 0;4=6,6=1
P 4.76 5.375 4 P 0 0;4=6,6=1
P 4.96 5.5 4 P 0 0;4=6,6=1
P 5.16 5.555 4 P 0 0;4=6,6=1
P 4.892 5.767 4 P 0 0;4=6,6=1
P 5.088 5.767 4 P 0 0;4=6,6=1
P 0.91 5.075 4 P 0 0;4=6,6=1
P 1.03 4.96 4 P 0 0;4=6,6=1
P 1.03 5.155 4 P 0 0;4=6,6=1
P 1.38906004 5.15351004 6 P 0 0;2,4=1,6=1
P 1.23906004 5.15351004 4 P 0 0;4=6,6=1
P 1.28906004 5.15351004 4 P 0 0;4=6,6=1
P 1.18906004 4.95351004 4 P 0 0;4=6,6=1
P 0.83 5.355 4 P 0 0;4=6,6=1
P 0.9 5.355 4 P 0 0;4=6,6=1
P 0.755 5.355 4 P 0 0;4=6,6=1
P 0.73 5.205 4 P 0 0;4=6,6=1
P 0.81016004 5.17 4 P 0 0;4=6,6=1
P 1.094 5.356 6 P 0 0;2,4=1,6=1
P 1.044 5.448 4 P 0 0;4=6,6=1
P 1.4 5.46 4 P 0 0;4=6,6=1
P 1.32 5.46 4 P 0 0;4=6,6=1
P 1.43798996 5.46016004 4 P 0 0;4=6,6=1
P 1.35925 5.46016004 4 P 0 0;4=6,6=1
P 0.89 5.885 4 P 0 0;4=6,6=1
P 0.81 5.885 4 P 0 0;4=6,6=1
P 0.73 5.885 4 P 0 0;4=6,6=1
P 0.97 5.885 4 P 0 0;4=6,6=1
P 1.04 5.885 4 P 0 0;4=6,6=1
P 1.12 5.885 4 P 0 0;4=6,6=1
P 1.825 4.562 24 P 0 0;1,4=0,6=0
P 1.88 4.562 24 P 0 0;1,4=0,6=0
P 7.88353996 4.562 24 P 0 0;1,4=0,6=0
P 7.82853996 4.562 24 P 0 0;1,4=0,6=0
P 8.15 3.31615 3 P 0 0;4=4,6=1
P 7.65205 4.78291998 3 P 0 0;4=4,6=1
P 5.917 3.02 24 P 0 0;1,4=0,6=0
P 5.917 3.07 24 P 0 0;1,4=0,6=0
P 11.80693002 2.82441004 29 P 0 0;1,4=8,6=0
P 5.803 2.82441004 29 P 0 0;1,4=8,6=0
P 11.235 3.3 4 P 0 0;4=6,6=1
P 5.815 0.925 6 P 0 0;2,4=1,6=1
P 3.635 0.49 6 P 0 0;2,4=1,6=1
P 4.58268002 2.81615 3 P 0 0;4=4,6=1
P 2.19606004 3.26615 3 P 0 0;4=4,6=1
P 1.6485 5.0535 3 P 0 0;4=4,6=1
P 8.15 3.36615 3 P 0 0;4=4,6=1
P 7.69205 4.78291998 3 P 0 0;4=4,6=1
P 2.19606004 3.31615 3 P 0 0;4=4,6=1
P 1.6885 5.0535 3 P 0 0;4=4,6=1
P 8.1 3.41615 3 P 0 0;4=4,6=1
P 7.79378996 4.78291998 3 P 0 0;4=4,6=1
P 2.14606004 3.31615 3 P 0 0;4=4,6=1
P 1.64851004 4.78291998 3 P 0 0;4=4,6=1
P 8.1 3.46615 3 P 0 0;4=4,6=1
P 7.83378996 4.78291998 3 P 0 0;4=4,6=1
P 2.14606004 3.36615 3 P 0 0;4=4,6=1
P 1.68851004 4.78291998 3 P 0 0;4=4,6=1
P 0.73 4.96 6 P 0 0;2,4=1,6=1
P 3.795 4.6 4 P 0 0;4=6,6=1
P 4.86 5.375 4 P 0 0;4=6,6=1
P 6.57318996 5.09705 24 P 0 0;1,4=0,6=0
P 8.15 3.46615 3 P 0 0;4=4,6=1
P 7.86465 4.657 3 P 0 0;4=4,6=1
P 2.09606004 3.41615 3 P 0 0;4=4,6=1
P 1.79025 4.78291998 3 P 0 0;4=4,6=1
P 8.15 3.51615 3 P 0 0;4=4,6=1
P 7.90465 4.657 3 P 0 0;4=4,6=1
P 2.09606004 3.46615 3 P 0 0;4=4,6=1
P 1.83025 4.78291998 3 P 0 0;4=4,6=1
P 2.19606004 3.41615 3 P 0 0;4=4,6=1
P 1.86111004 5.169 3 P 0 0;4=4,6=1
P 2.19606004 3.46615 3 P 0 0;4=4,6=1
P 1.90111004 5.169 3 P 0 0;4=4,6=1
P 6.72708996 4.5652 4 P 0 0;4=6,6=1
P 6.76208996 4.5652 4 P 0 0;4=6,6=1
P 6.79708996 4.5652 4 P 0 0;4=6,6=1
P 6.83708996 4.5652 6 P 0 0;2,4=1,6=1
P 6.90208996 4.5652 4 P 0 0;4=6,6=1
P 6.87208996 4.5652 4 P 0 0;4=6,6=1
P 10.99998996 4.9531 4 P 0 0;4=6,6=1
P 11.03998996 4.9531 4 P 0 0;4=6,6=1
P 10.99998996 4.9131 4 P 0 0;4=6,6=1
P 11.03998996 4.9131 4 P 0 0;4=6,6=1
P 11.21998996 4.9531 4 P 0 0;4=6,6=1
P 11.17998996 4.9531 4 P 0 0;4=6,6=1
P 11.13498996 4.9531 4 P 0 0;4=6,6=1
P 11.08498996 4.9531 4 P 0 0;4=6,6=1
P 11.21998996 4.9131 4 P 0 0;4=6,6=1
P 11.17998996 4.9131 4 P 0 0;4=6,6=1
P 11.08498996 4.9131 4 P 0 0;4=6,6=1
P 11.13498996 4.9131 4 P 0 0;4=6,6=1
P 10.99998996 5.1631 4 P 0 0;4=6,6=1
P 11.03998996 5.1631 4 P 0 0;4=6,6=1
P 10.99998996 5.1231 4 P 0 0;4=6,6=1
P 10.99998996 5.0381 4 P 0 0;4=6,6=1
P 10.99998996 5.0831 4 P 0 0;4=6,6=1
P 10.99998996 4.9931 4 P 0 0;4=6,6=1
P 11.03998996 4.9931 4 P 0 0;4=6,6=1
P 11.03998996 5.0831 4 P 0 0;4=6,6=1
P 11.03998996 5.0381 4 P 0 0;4=6,6=1
P 11.03998996 5.1231 4 P 0 0;4=6,6=1
P 11.21998996 5.1631 4 P 0 0;4=6,6=1
P 11.17998996 5.1631 4 P 0 0;4=6,6=1
P 11.08498996 5.1631 4 P 0 0;4=6,6=1
P 11.13498996 5.1631 4 P 0 0;4=6,6=1
P 11.21998996 5.1231 4 P 0 0;4=6,6=1
P 11.21998996 5.0381 4 P 0 0;4=6,6=1
P 11.21998996 5.0831 4 P 0 0;4=6,6=1
P 11.21998996 4.9931 4 P 0 0;4=6,6=1
P 11.17998996 4.9931 4 P 0 0;4=6,6=1
P 11.17998996 5.1231 4 P 0 0;4=6,6=1
P 11.17998996 5.0831 4 P 0 0;4=6,6=1
P 11.17998996 5.0381 4 P 0 0;4=6,6=1
P 11.13498996 5.1231 4 P 0 0;4=6,6=1
P 11.08498996 5.1231 4 P 0 0;4=6,6=1
P 11.6269 4.90498996 4 P 0 0;4=6,6=1
P 11.6269 4.85498996 4 P 0 0;4=6,6=1
P 11.4269 4.80998996 4 P 0 0;4=6,6=1
P 11.4269 4.85498996 4 P 0 0;4=6,6=1
P 11.4269 4.90498996 4 P 0 0;4=6,6=1
P 11.4269 4.94998996 4 P 0 0;4=6,6=1
P 11.4769 4.94998996 4 P 0 0;4=6,6=1
P 11.4769 4.80998996 4 P 0 0;4=6,6=1
P 11.5269 4.94998996 4 P 0 0;4=6,6=1
P 11.5269 4.80998996 4 P 0 0;4=6,6=1
P 11.5769 4.94998996 4 P 0 0;4=6,6=1
P 11.6269 4.94998996 4 P 0 0;4=6,6=1
P 11.6269 4.80998996 4 P 0 0;4=6,6=1
P 11.5769 4.80998996 4 P 0 0;4=6,6=1
P 10.82676998 5.71338996 11 P 0 0;2,4=14,6=0
P 10.99213002 5.71338996 11 P 0 0;4=14,6=0
P 11.15748002 5.71338996 11 P 0 0;2,4=14,6=0
P 11.32283996 5.71338996 11 P 0 0;4=14,6=0
P 11.48818996 5.71338996 11 P 0 0;2,4=14,6=0
P 11.65353996 5.71338996 11 P 0 0;4=14,6=0
P 11.8189 5.71338996 11 P 0 0;2,4=14,6=0
P 11.98425 5.71338996 11 P 0 0;4=14,6=0
P 12.14961004 5.71338996 11 P 0 0;2,4=14,6=0
P 10.80498996 5.7831 4 P 0 0;4=6,6=1
P 10.84498996 5.7831 4 P 0 0;4=6,6=1
P 10.80498996 5.6431 4 P 0 0;4=6,6=1
P 10.84498996 5.6431 4 P 0 0;4=6,6=1
P 11.01035 5.6431 4 P 0 0;4=6,6=1
P 10.97035 5.6431 4 P 0 0;4=6,6=1
P 11.01035 5.7831 4 P 0 0;4=6,6=1
P 10.97035 5.7831 4 P 0 0;4=6,6=1
P 11.17571004 5.6431 4 P 0 0;4=6,6=1
P 11.13571004 5.6431 4 P 0 0;4=6,6=1
P 11.17571004 5.7831 4 P 0 0;4=6,6=1
P 11.13571004 5.7831 4 P 0 0;4=6,6=1
P 11.34106998 5.6431 4 P 0 0;4=6,6=1
P 11.30106998 5.6431 4 P 0 0;4=6,6=1
P 11.34106998 5.7831 4 P 0 0;4=6,6=1
P 11.30106998 5.7831 4 P 0 0;4=6,6=1
P 11.50643002 5.6431 4 P 0 0;4=6,6=1
P 11.46643002 5.6431 4 P 0 0;4=6,6=1
P 11.50643002 5.7831 4 P 0 0;4=6,6=1
P 11.46643002 5.7831 4 P 0 0;4=6,6=1
P 11.67178996 5.6431 4 P 0 0;4=6,6=1
P 11.63178996 5.6431 4 P 0 0;4=6,6=1
P 11.67178996 5.7831 4 P 0 0;4=6,6=1
P 11.63178996 5.7831 4 P 0 0;4=6,6=1
P 11.83715 5.6431 4 P 0 0;4=6,6=1
P 11.79715 5.6431 4 P 0 0;4=6,6=1
P 11.83715 5.7831 4 P 0 0;4=6,6=1
P 11.79715 5.7831 4 P 0 0;4=6,6=1
P 12.00251004 5.6431 4 P 0 0;4=6,6=1
P 11.96251004 5.6431 4 P 0 0;4=6,6=1
P 12.00251004 5.7831 4 P 0 0;4=6,6=1
P 11.96251004 5.7831 4 P 0 0;4=6,6=1
P 12.16786998 5.6431 4 P 0 0;4=6,6=1
P 12.12786998 5.6431 4 P 0 0;4=6,6=1
P 12.16786998 5.7831 4 P 0 0;4=6,6=1
P 12.12786998 5.7831 4 P 0 0;4=6,6=1
P 11.295 4.88 6 P 0 0;2,4=5,6=1
P 5.03605 5.1631 4 P 0 0;4=6,6=1
P 5.03605 4.9931 4 P 0 0;4=6,6=1
P 5.03605 5.0831 4 P 0 0;4=6,6=1
P 5.03605 5.0381 4 P 0 0;4=6,6=1
P 5.03605 5.1231 4 P 0 0;4=6,6=1
P 5.21605 5.1631 4 P 0 0;4=6,6=1
P 5.17605 5.1631 4 P 0 0;4=6,6=1
P 5.08105 5.1631 4 P 0 0;4=6,6=1
P 5.13105 5.1631 4 P 0 0;4=6,6=1
P 5.21605 5.1231 4 P 0 0;4=6,6=1
P 5.21605 5.0381 4 P 0 0;4=6,6=1
P 5.21605 5.0831 4 P 0 0;4=6,6=1
P 5.21605 4.9931 4 P 0 0;4=6,6=1
P 5.17605 4.9931 4 P 0 0;4=6,6=1
P 5.17605 5.1231 4 P 0 0;4=6,6=1
P 5.17605 5.0831 4 P 0 0;4=6,6=1
P 5.17605 5.0381 4 P 0 0;4=6,6=1
P 5.13105 5.1231 4 P 0 0;4=6,6=1
P 5.08105 5.1231 4 P 0 0;4=6,6=1
P 4.99605 5.1631 4 P 0 0;4=6,6=1
P 4.99605 5.1231 4 P 0 0;4=6,6=1
P 4.99605 5.0381 4 P 0 0;4=6,6=1
P 4.99605 5.0831 4 P 0 0;4=6,6=1
P 4.99605 4.9931 4 P 0 0;4=6,6=1
P 5.03605 4.9531 4 P 0 0;4=6,6=1
P 5.03605 4.9131 4 P 0 0;4=6,6=1
P 5.21605 4.9531 4 P 0 0;4=6,6=1
P 5.17605 4.9531 4 P 0 0;4=6,6=1
P 5.13105 4.9531 4 P 0 0;4=6,6=1
P 5.08105 4.9531 4 P 0 0;4=6,6=1
P 5.21605 4.9131 4 P 0 0;4=6,6=1
P 5.17605 4.9131 4 P 0 0;4=6,6=1
P 5.08105 4.9131 4 P 0 0;4=6,6=1
P 5.13105 4.9131 4 P 0 0;4=6,6=1
P 4.99605 4.9531 4 P 0 0;4=6,6=1
P 4.99605 4.9131 4 P 0 0;4=6,6=1
P 5.105 5.05 6 P 0 0;2,4=5,6=1
P 6.34948996 5.03 4 P 0 0;4=6,6=1
P 2.74225 5.14 3 P 0 0;4=4,6=1
P 2.04606004 3.61615 3 P 0 0;4=4,6=1
P 2.14606004 3.46615 3 P 0 0;4=4,6=1
P 1.86111004 4.657 3 P 0 0;4=4,6=1
P 2.78225 5.14 3 P 0 0;4=4,6=1
P 2.04606004 3.66615 3 P 0 0;4=4,6=1
P 2.14606004 3.51615 3 P 0 0;4=4,6=1
P 1.90111004 4.657 3 P 0 0;4=4,6=1
P 1.93196998 5.0535 3 P 0 0;4=4,6=1
P 1.99606004 3.46615 3 P 0 0;4=4,6=1
P 4.58268002 2.56615 3 P 0 0;4=4,6=1
P 1.97196998 5.0535 3 P 0 0;4=4,6=1
P 1.99606004 3.51615 3 P 0 0;4=4,6=1
P 2.88086998 5.17001998 3 P 0 0;4=4,6=1
P 2.14606004 3.61615 3 P 0 0;4=4,6=1
P 2.34606004 3.66615 3 P 0 0;4=4,6=1
P 3.56176998 4.71973002 3 P 0 0;4=4,6=1
P 2.92086998 5.17001998 3 P 0 0;4=4,6=1
P 2.14606004 3.66615 3 P 0 0;4=4,6=1
P 2.34606004 3.71615 3 P 0 0;4=4,6=1
P 3.52176998 4.71973002 3 P 0 0;4=4,6=1
P 2.39606004 3.61615 3 P 0 0;4=4,6=1
P 3.49091004 4.587 3 P 0 0;4=4,6=1
P 2.39606004 3.66615 3 P 0 0;4=4,6=1
P 3.45091004 4.587 3 P 0 0;4=4,6=1
P 2.49606004 3.61615 3 P 0 0;4=4,6=1
P 3.56176998 5.14 3 P 0 0;4=4,6=1
P 2.49606004 3.66615 3 P 0 0;4=4,6=1
P 3.52176998 5.14 3 P 0 0;4=4,6=1
P 2.44606004 3.66615 3 P 0 0;4=4,6=1
P 3.42003996 4.78291998 3 P 0 0;4=4,6=1
P 4.30605 4.6631 4 P 0 0;4=6,6=1
P 4.34105 4.6431 4 P 0 0;4=6,6=1
P 4.38605 4.6431 4 P 0 0;4=6,6=1
P 4.42605 4.6631 4 P 0 0;4=6,6=1
P 4.46605 4.6631 4 P 0 0;4=6,6=1
P 4.30605 4.7031 4 P 0 0;4=6,6=1
P 4.42605 4.7031 4 P 0 0;4=6,6=1
P 4.46605 4.7031 4 P 0 0;4=6,6=1
P 4.26605 4.6631 4 P 0 0;4=6,6=1
P 4.26605 4.7031 4 P 0 0;4=6,6=1
P 4.65605 4.6631 4 P 0 0;4=6,6=1
P 4.69605 4.6631 4 P 0 0;4=6,6=1
P 4.65605 4.7031 4 P 0 0;4=6,6=1
P 4.69605 4.7031 4 P 0 0;4=6,6=1
P 4.73105 4.6431 4 P 0 0;4=6,6=1
P 4.81605 4.6631 4 P 0 0;4=6,6=1
P 4.85605 4.6631 4 P 0 0;4=6,6=1
P 4.81605 4.7031 4 P 0 0;4=6,6=1
P 4.85605 4.7031 4 P 0 0;4=6,6=1
P 4.77605 4.6431 4 P 0 0;4=6,6=1
P 5.17605 4.7131 4 P 0 0;4=6,6=1
P 5.17605 4.6731 4 P 0 0;4=6,6=1
P 5.08105 4.6731 4 P 0 0;4=6,6=1
P 5.13105 4.6731 4 P 0 0;4=6,6=1
P 5.03605 4.6731 4 P 0 0;4=6,6=1
P 5.03605 4.7131 4 P 0 0;4=6,6=1
P 4.30605 4.7481 4 P 0 0;4=6,6=1
P 4.30605 4.7931 4 P 0 0;4=6,6=1
P 4.30605 4.8381 4 P 0 0;4=6,6=1
P 4.38605 4.8381 4 P 0 0;4=6,6=1
P 4.34605 4.8381 4 P 0 0;4=6,6=1
P 4.46605 4.8381 4 P 0 0;4=6,6=1
P 4.42605 4.8381 4 P 0 0;4=6,6=1
P 4.42605 4.7931 4 P 0 0;4=6,6=1
P 4.42605 4.7481 4 P 0 0;4=6,6=1
P 4.46605 4.7931 4 P 0 0;4=6,6=1
P 4.46605 4.7481 4 P 0 0;4=6,6=1
P 4.26605 4.7481 4 P 0 0;4=6,6=1
P 4.26605 4.7931 4 P 0 0;4=6,6=1
P 4.26605 4.8381 4 P 0 0;4=6,6=1
P 4.65605 4.8381 4 P 0 0;4=6,6=1
P 4.65605 4.7931 4 P 0 0;4=6,6=1
P 4.65605 4.7481 4 P 0 0;4=6,6=1
P 4.69605 4.8381 4 P 0 0;4=6,6=1
P 4.69605 4.7931 4 P 0 0;4=6,6=1
P 4.69605 4.7481 4 P 0 0;4=6,6=1
P 4.73605 4.8381 4 P 0 0;4=6,6=1
P 4.81605 4.8381 4 P 0 0;4=6,6=1
P 4.81605 4.7931 4 P 0 0;4=6,6=1
P 4.81605 4.7481 4 P 0 0;4=6,6=1
P 4.85605 4.8381 4 P 0 0;4=6,6=1
P 4.85605 4.7931 4 P 0 0;4=6,6=1
P 4.85605 4.7481 4 P 0 0;4=6,6=1
P 4.77605 4.8381 4 P 0 0;4=6,6=1
P 5.08105 4.8431 4 P 0 0;4=6,6=1
P 5.13105 4.8431 4 P 0 0;4=6,6=1
P 5.17605 4.8431 4 P 0 0;4=6,6=1
P 5.17605 4.8031 4 P 0 0;4=6,6=1
P 5.17605 4.7581 4 P 0 0;4=6,6=1
P 5.03605 4.8431 4 P 0 0;4=6,6=1
P 5.03605 4.8031 4 P 0 0;4=6,6=1
P 5.03605 4.7581 4 P 0 0;4=6,6=1
P 4.58268002 2.96615 3 P 0 0;4=4,6=1
P 4.63268002 2.96615 3 P 0 0;4=4,6=1
P 4.63268002 3.11615 3 P 0 0;4=4,6=1
P 4.58268002 3.01615 3 P 0 0;4=4,6=1
P 4.58268002 3.11615 3 P 0 0;4=4,6=1
P 4.63268002 3.01615 3 P 0 0;4=4,6=1
P 4.63268002 3.31615 3 P 0 0;4=4,6=1
P 4.58268002 3.26615 3 P 0 0;4=4,6=1
P 4.58268002 3.31615 3 P 0 0;4=4,6=1
P 4.63268002 3.26615 3 P 0 0;4=4,6=1
P 4.63268002 3.16615 3 P 0 0;4=4,6=1
P 4.58268002 3.16615 3 P 0 0;4=4,6=1
P 4.58268002 3.46615 3 P 0 0;4=4,6=1
P 4.63268002 3.41615 3 P 0 0;4=4,6=1
P 4.63268002 3.46615 3 P 0 0;4=4,6=1
P 4.58268002 3.41615 3 P 0 0;4=4,6=1
P 4.58268002 3.61615 3 P 0 0;4=4,6=1
P 4.58268002 3.56615 3 P 0 0;4=4,6=1
P 4.63268002 3.61615 3 P 0 0;4=4,6=1
P 4.63268002 3.56615 3 P 0 0;4=4,6=1
P 4.58268002 3.71615 3 P 0 0;4=4,6=1
P 4.63268002 3.71615 3 P 0 0;4=4,6=1
P 4.58268002 3.76615 3 P 0 0;4=4,6=1
P 4.58268002 3.86615 3 P 0 0;4=4,6=1
P 4.63268002 3.76615 3 P 0 0;4=4,6=1
P 4.63268002 3.86615 3 P 0 0;4=4,6=1
P 4.68268002 2.96615 3 P 0 0;4=4,6=1
P 4.73268002 2.96615 3 P 0 0;4=4,6=1
P 4.78268002 2.96615 3 P 0 0;4=4,6=1
P 4.68268002 3.11615 3 P 0 0;4=4,6=1
P 4.68268002 3.01615 3 P 0 0;4=4,6=1
P 4.73268002 3.11615 3 P 0 0;4=4,6=1
P 4.73268002 3.01615 3 P 0 0;4=4,6=1
P 4.78268002 3.11615 3 P 0 0;4=4,6=1
P 4.78268002 3.01615 3 P 0 0;4=4,6=1
P 4.73268002 3.31615 3 P 0 0;4=4,6=1
P 4.73268002 3.26615 3 P 0 0;4=4,6=1
P 4.68268002 3.26615 3 P 0 0;4=4,6=1
P 4.68268002 3.31615 3 P 0 0;4=4,6=1
P 4.78268002 3.26615 3 P 0 0;4=4,6=1
P 4.78268002 3.31615 3 P 0 0;4=4,6=1
P 4.73268002 3.16615 3 P 0 0;4=4,6=1
P 4.68268002 3.16615 3 P 0 0;4=4,6=1
P 4.78268002 3.16615 3 P 0 0;4=4,6=1
P 4.73268002 3.41615 3 P 0 0;4=4,6=1
P 4.68268002 3.41615 3 P 0 0;4=4,6=1
P 4.68268002 3.46615 3 P 0 0;4=4,6=1
P 4.73268002 3.46615 3 P 0 0;4=4,6=1
P 4.78268002 3.46615 3 P 0 0;4=4,6=1
P 4.78268002 3.41615 3 P 0 0;4=4,6=1
P 4.73268002 3.56615 3 P 0 0;4=4,6=1
P 4.73268002 3.61615 3 P 0 0;4=4,6=1
P 4.68268002 3.56615 3 P 0 0;4=4,6=1
P 4.68268002 3.61615 3 P 0 0;4=4,6=1
P 4.78268002 3.61615 3 P 0 0;4=4,6=1
P 4.78268002 3.56615 3 P 0 0;4=4,6=1
P 4.73268002 3.71615 3 P 0 0;4=4,6=1
P 4.68268002 3.71615 3 P 0 0;4=4,6=1
P 4.78268002 3.71615 3 P 0 0;4=4,6=1
P 4.73268002 3.76615 3 P 0 0;4=4,6=1
P 4.73268002 3.86615 3 P 0 0;4=4,6=1
P 4.68268002 3.76615 3 P 0 0;4=4,6=1
P 4.68268002 3.86615 3 P 0 0;4=4,6=1
P 4.78268002 3.76615 3 P 0 0;4=4,6=1
P 4.78268002 3.86615 3 P 0 0;4=4,6=1
P 4.88268002 3.86615 3 P 0 0;4=4,6=1
P 4.83268002 3.86615 3 P 0 0;4=4,6=1
P 5.03268002 3.86615 3 P 0 0;4=4,6=1
P 4.93268002 3.86615 3 P 0 0;4=4,6=1
P 4.98268002 3.86615 3 P 0 0;4=4,6=1
P 4.88268002 3.76615 3 P 0 0;4=4,6=1
P 4.83268002 3.76615 3 P 0 0;4=4,6=1
P 5.03268002 3.76615 3 P 0 0;4=4,6=1
P 4.93268002 3.76615 3 P 0 0;4=4,6=1
P 4.98268002 3.76615 3 P 0 0;4=4,6=1
P 4.88268002 3.71615 3 P 0 0;4=4,6=1
P 4.83268002 3.71615 3 P 0 0;4=4,6=1
P 5.03268002 3.71615 3 P 0 0;4=4,6=1
P 4.93268002 3.71615 3 P 0 0;4=4,6=1
P 4.98268002 3.71615 3 P 0 0;4=4,6=1
P 4.88268002 3.61615 3 P 0 0;4=4,6=1
P 4.83268002 3.61615 3 P 0 0;4=4,6=1
P 5.03268002 3.61615 3 P 0 0;4=4,6=1
P 4.93268002 3.61615 3 P 0 0;4=4,6=1
P 4.98268002 3.61615 3 P 0 0;4=4,6=1
P 4.88268002 3.56615 3 P 0 0;4=4,6=1
P 4.83268002 3.56615 3 P 0 0;4=4,6=1
P 5.03268002 3.56615 3 P 0 0;4=4,6=1
P 4.93268002 3.56615 3 P 0 0;4=4,6=1
P 4.98268002 3.56615 3 P 0 0;4=4,6=1
P 4.88268002 3.46615 3 P 0 0;4=4,6=1
P 4.83268002 3.46615 3 P 0 0;4=4,6=1
P 5.03268002 3.46615 3 P 0 0;4=4,6=1
P 4.93268002 3.46615 3 P 0 0;4=4,6=1
P 4.98268002 3.46615 3 P 0 0;4=4,6=1
P 4.88268002 3.41615 3 P 0 0;4=4,6=1
P 4.83268002 3.41615 3 P 0 0;4=4,6=1
P 5.03268002 3.41615 3 P 0 0;4=4,6=1
P 4.93268002 3.41615 3 P 0 0;4=4,6=1
P 4.98268002 3.41615 3 P 0 0;4=4,6=1
P 4.88268002 3.31615 3 P 0 0;4=4,6=1
P 4.83268002 3.31615 3 P 0 0;4=4,6=1
P 5.03268002 3.31615 3 P 0 0;4=4,6=1
P 4.93268002 3.31615 3 P 0 0;4=4,6=1
P 4.98268002 3.31615 3 P 0 0;4=4,6=1
P 4.83268002 3.26615 3 P 0 0;4=4,6=1
P 4.88268002 3.26615 3 P 0 0;4=4,6=1
P 4.98268002 3.26615 3 P 0 0;4=4,6=1
P 4.93268002 3.26615 3 P 0 0;4=4,6=1
P 5.03268002 3.26615 3 P 0 0;4=4,6=1
P 4.83268002 3.16615 3 P 0 0;4=4,6=1
P 4.88268002 3.16615 3 P 0 0;4=4,6=1
P 4.98268002 3.16615 3 P 0 0;4=4,6=1
P 4.93268002 3.16615 3 P 0 0;4=4,6=1
P 5.03268002 3.16615 3 P 0 0;4=4,6=1
P 4.83268002 3.11615 3 P 0 0;4=4,6=1
P 4.88268002 3.11615 3 P 0 0;4=4,6=1
P 4.98268002 3.11615 3 P 0 0;4=4,6=1
P 4.93268002 3.11615 3 P 0 0;4=4,6=1
P 5.03268002 3.11615 3 P 0 0;4=4,6=1
P 4.83268002 3.01615 3 P 0 0;4=4,6=1
P 4.88268002 3.01615 3 P 0 0;4=4,6=1
P 4.98268002 3.01615 3 P 0 0;4=4,6=1
P 4.93268002 3.01615 3 P 0 0;4=4,6=1
P 5.03268002 3.01615 3 P 0 0;4=4,6=1
P 4.83268002 2.96615 3 P 0 0;4=4,6=1
P 4.88268002 2.96615 3 P 0 0;4=4,6=1
P 4.98268002 2.96615 3 P 0 0;4=4,6=1
P 4.93268002 2.96615 3 P 0 0;4=4,6=1
P 5.03268002 2.96615 3 P 0 0;4=4,6=1
P 4.41 4.21 6 P 0 0;2,4=5,6=1
P 2.44606004 3.71615 3 P 0 0;4=4,6=1
P 3.38003996 4.78291998 3 P 0 0;4=4,6=1
P 2.19606004 3.81615 3 P 0 0;4=4,6=1
P 3.02571004 4.667 3 P 0 0;4=4,6=1
P 2.19606004 3.86615 3 P 0 0;4=4,6=1
P 3.06571004 4.667 3 P 0 0;4=4,6=1
P 3.27831004 4.642 3 P 0 0;4=4,6=1
P 2.39606004 3.76615 3 P 0 0;4=4,6=1
P 4.73268002 2.66615 3 P 0 0;4=4,6=1
P 10.73661004 2.66615 3 P 0 0;4=4,6=1
P 3.23831004 4.642 3 P 0 0;4=4,6=1
P 2.39606004 3.81615 3 P 0 0;4=4,6=1
P 5.03268002 2.61615 3 P 0 0;4=4,6=1
P 3.34916998 5.1035 3 P 0 0;4=4,6=1
P 2.49606004 3.76615 3 P 0 0;4=4,6=1
P 3.30916998 5.1035 3 P 0 0;4=4,6=1
P 2.49606004 3.81615 3 P 0 0;4=4,6=1
P 11.03661004 2.61615 3 P 0 0;4=4,6=1
P 2.74225 4.667 3 P 0 0;4=4,6=1
P 2.09606004 3.66615 3 P 0 0;4=4,6=1
P 2.44606004 3.81615 3 P 0 0;4=4,6=1
P 3.20743996 4.78291998 3 P 0 0;4=4,6=1
P 2.78225 4.667 3 P 0 0;4=4,6=1
P 2.09606004 3.71615 3 P 0 0;4=4,6=1
P 2.44606004 3.86615 3 P 0 0;4=4,6=1
P 3.16743996 4.78291998 3 P 0 0;4=4,6=1
P 2.34606004 3.81615 3 P 0 0;4=4,6=1
P 3.27831004 5.22001998 3 P 0 0;4=4,6=1
P 2.34606004 3.86615 3 P 0 0;4=4,6=1
P 3.23831004 5.22001998 3 P 0 0;4=4,6=1
P 4.63268002 2.61615 3 P 0 0;4=4,6=1
P 10.98661004 2.61615 3 P 0 0;4=4,6=1
P 2.19606004 3.66615 3 P 0 0;4=4,6=1
P 2.81311004 4.78291998 3 P 0 0;4=4,6=1
P 10.98661004 2.56615 3 P 0 0;4=4,6=1
P 2.19606004 3.71615 3 P 0 0;4=4,6=1
P 2.85311004 4.78291998 3 P 0 0;4=4,6=1
P 5.803 2.87558996 29 P 0 0;1,4=8,6=0
P 0.61698002 1.655 24 P 0 0;1,4=0,6=0
P 0.64808996 1.655 4 P 0 0;4=6,6=1
P 5.76 2.66 6 P 0 0;2,4=1,6=1
P 10.63661004 2.61615 3 P 0 0;4=4,6=1
P 2.09606004 3.81615 3 P 0 0;4=4,6=1
P 3.09656998 5.0535 3 P 0 0;4=4,6=1
P 2.09606004 3.86615 3 P 0 0;4=4,6=1
P 3.13656998 5.0535 3 P 0 0;4=4,6=1
P 2.88708002 4.667 3 P 0 0;4=4,6=1
P 2.04606004 3.76615 3 P 0 0;4=4,6=1
P 10.73661004 2.61615 3 P 0 0;4=4,6=1
P 2.92708002 4.667 3 P 0 0;4=4,6=1
P 2.04606004 3.81615 3 P 0 0;4=4,6=1
P 10.68661004 2.61615 3 P 0 0;4=4,6=1
P 5.03268002 2.46615 3 P 0 0;4=4,6=1
P 5.30875 2.5629 24 P 0 0;1,4=0,6=0
P 5.03268002 2.51615 3 P 0 0;4=4,6=1
P 5.30875 2.6079 24 P 0 0;1,4=0,6=0
P 5.80255 3.02558996 29 P 0 0;1,4=8,6=0
P 5.883 3.02 24 P 0 0;1,4=0,6=0
P 5.795 3.09 6 P 0 0;2,4=5,6=1
P 11.08661004 2.56615 3 P 0 0;4=4,6=1
P 10.68661004 2.56615 3 P 0 0;4=4,6=1
P 9.19 5.298 24 P 0 0;1,4=0,6=0
P 9.235 5.298 24 P 0 0;1,4=0,6=0
P 9.175 5.255 6 P 0 0;2,4=1,6=1
P 4.73268002 2.61615 3 P 0 0;4=4,6=1
P 9.145 5.298 24 P 0 0;1,4=0,6=0
P 9.1 5.298 24 P 0 0;1,4=0,6=0
P 9.11853996 5.255 6 P 0 0;2,4=1,6=1
P 5.30875 2.4687 24 P 0 0;1,4=0,6=0
P 5.08268002 2.41615 3 P 0 0;4=4,6=1
P 10.93661004 2.66615 3 P 0 0;4=4,6=1
P 10.58661004 2.61615 3 P 0 0;4=4,6=1
P 8.15 3.76615 3 P 0 0;4=4,6=1
P 9.02925 5.165 3 P 0 0;4=4,6=1
P 4.98268002 2.21615 3 P 0 0;4=4,6=1
P 5.30875 2.1529 24 P 0 0;1,4=0,6=0
P 10.58661004 2.56615 3 P 0 0;4=4,6=1
P 8.15 3.81615 3 P 0 0;4=4,6=1
P 9.06925 5.165 3 P 0 0;4=4,6=1
P 11.03661004 2.66615 3 P 0 0;4=4,6=1
P 4.98268002 2.26615 3 P 0 0;4=4,6=1
P 5.30875 2.1979 24 P 0 0;1,4=0,6=0
P 10.93661004 2.61615 3 P 0 0;4=4,6=1
P 5.30875 2.2883 24 P 0 0;1,4=0,6=0
P 5.03268002 2.26615 3 P 0 0;4=4,6=1
P 11.08661004 2.61615 3 P 0 0;4=4,6=1
P 5.30875 2.3333 24 P 0 0;1,4=0,6=0
P 5.03268002 2.31615 3 P 0 0;4=4,6=1
P 10.63661004 2.66615 3 P 0 0;4=4,6=1
P 3.775 5.295 6 P 0 0;2,4=1,6=1
P 0.73 5.78 4 P 0 0;4=6,6=1
P 8.07 5.343 24 P 0 0;1,4=0,6=0
P 8.12 5.343 24 P 0 0;1,4=0,6=0
P 8.07 5.29 6 P 0 0;2,4=1,6=1
P 3.8399 4.765 6 P 0 0;2,4=1,6=1
P 0.81 5.78 4 P 0 0;4=6,6=1
P 7.955 5.343 24 P 0 0;1,4=0,6=0
P 8.005 5.343 24 P 0 0;1,4=0,6=0
P 8.005 5.29 6 P 0 0;2,4=1,6=1
P 11.08661004 1.91615 3 P 0 0;4=4,6=1
P 11.62193002 1.65 24 P 0 0;1,4=0,6=0
P 4.98268002 1.91615 3 P 0 0;4=4,6=1
P 5.30875 1.7371 24 P 0 0;1,4=0,6=0
P 4.98268002 1.96615 3 P 0 0;4=4,6=1
P 5.30875 1.7821 24 P 0 0;1,4=0,6=0
P 4.93268002 1.86615 3 P 0 0;4=4,6=1
P 5.30875 1.6458 24 P 0 0;1,4=0,6=0
P 5.30875 1.6008 24 P 0 0;1,4=0,6=0
P 4.93268002 1.91615 3 P 0 0;4=4,6=1
P 5.03268002 1.86615 3 P 0 0;4=4,6=1
P 5.46358002 1.7143 24 P 0 0;1,4=0,6=0
P 5.08268002 1.91615 3 P 0 0;4=4,6=1
P 5.46358002 1.8083 24 P 0 0;1,4=0,6=0
P 5.08268002 2.56615 3 P 0 0;4=4,6=1
P 7.85815 2.4781 24 P 0 0;1,4=0,6=0
P 7.90393996 2.48 6 P 0 0;2,4=5,6=1
P 8.15 2.51615 3 P 0 0;4=4,6=1
P 4.98268002 2.61615 3 P 0 0;4=4,6=1
P 10.68661004 2.71615 3 P 0 0;4=4,6=1
P 11.31661998 2.73 24 P 0 0;1,4=0,6=0
P 11.43661998 2.73 24 P 0 0;1,4=0,6=0
P 11.27 2.73 6 P 0 0;2,4=5,6=1
P 10.98661004 2.71615 3 P 0 0;4=4,6=1
P 11.31661998 2.8 24 P 0 0;1,4=0,6=0
P 11.43661998 2.8 24 P 0 0;1,4=0,6=0
P 11.27 2.8 6 P 0 0;2,4=5,6=1
P 10.78661004 2.71615 3 P 0 0;4=4,6=1
P 11.65061998 2.785 24 P 0 0;1,4=0,6=0
P 11.72031004 2.82441004 29 P 0 0;1,4=8,6=0
P 11.555 2.82 6 P 0 0;2,4=5,6=1
P 4.93268002 2.66615 3 P 0 0;4=4,6=1
P 10.88661004 2.71615 3 P 0 0;4=4,6=1
P 11.65061998 2.905 24 P 0 0;1,4=0,6=0
P 11.72031004 2.87558996 29 P 0 0;1,4=8,6=0
P 11.56 2.945 6 P 0 0;2,4=5,6=1
P 10.68661004 2.76615 3 P 0 0;4=4,6=1
P 9.64 0.71 6 P 0 0;2,4=1,6=1
P 10.58661004 2.81615 3 P 0 0;4=4,6=1
P 9.43296004 0.49133002 6 P 0 0;2,4=1,6=1
P 9.43296004 0.73633002 6 P 0 0;2,4=1,6=1
P 10.63661004 2.81615 3 P 0 0;4=4,6=1
P 4.68268002 2.56615 3 P 0 0;4=4,6=1
P 10.68661004 2.81615 3 P 0 0;4=4,6=1
P 9.55795 0.36633002 6 P 0 0;2,4=1,6=1
P 10.73661004 2.81615 3 P 0 0;4=4,6=1
P 9.35796004 0.49133002 6 P 0 0;2,4=1,6=1
P 5.03268002 2.66615 3 P 0 0;4=4,6=1
P 10.78661004 2.81615 3 P 0 0;4=4,6=1
P 9.58296004 0.71133002 6 P 0 0;2,4=1,6=1
P 5.08268002 2.61615 3 P 0 0;4=4,6=1
P 11.08661004 1.96615 3 P 0 0;4=4,6=1
P 11.62193002 1.695 24 P 0 0;1,4=0,6=0
P 11.03661004 1.86615 3 P 0 0;4=4,6=1
P 11.62193002 1.535 24 P 0 0;1,4=0,6=0
P 11.62193002 1.49 24 P 0 0;1,4=0,6=0
P 11.03661004 1.91615 3 P 0 0;4=4,6=1
P 10.93661004 1.86615 3 P 0 0;4=4,6=1
P 11.42193002 1.455 24 P 0 0;1,4=0,6=0
P 10.93661004 1.91615 3 P 0 0;4=4,6=1
P 11.42193002 1.41 24 P 0 0;1,4=0,6=0
P 10.98661004 1.91615 3 P 0 0;4=4,6=1
P 11.42193002 1.57 24 P 0 0;1,4=0,6=0
P 10.98661004 1.96615 3 P 0 0;4=4,6=1
P 11.42193002 1.615 24 P 0 0;1,4=0,6=0
P 4.93268002 2.61615 3 P 0 0;4=4,6=1
P 11.03661004 2.01615 3 P 0 0;4=4,6=1
P 11.62193002 1.81 24 P 0 0;1,4=0,6=0
P 11.03661004 2.06615 3 P 0 0;4=4,6=1
P 11.62193002 1.855 24 P 0 0;1,4=0,6=0
P 10.93661004 2.01615 3 P 0 0;4=4,6=1
P 11.42193002 1.73 24 P 0 0;1,4=0,6=0
P 10.93661004 2.06615 3 P 0 0;4=4,6=1
P 11.42193002 1.775 24 P 0 0;1,4=0,6=0
P 10.98661004 2.06615 3 P 0 0;4=4,6=1
P 11.62193002 1.97 24 P 0 0;1,4=0,6=0
P 10.98661004 2.11615 3 P 0 0;4=4,6=1
P 11.62193002 2.015 24 P 0 0;1,4=0,6=0
P 11.08661004 2.06615 3 P 0 0;4=4,6=1
P 11.42193002 1.89 24 P 0 0;1,4=0,6=0
P 11.08661004 2.11615 3 P 0 0;4=4,6=1
P 11.42193002 1.935 24 P 0 0;1,4=0,6=0
P 3.14146004 5.298 24 P 0 0;1,4=0,6=0
P 3.09646004 5.298 24 P 0 0;1,4=0,6=0
P 3.115 5.255 6 P 0 0;2,4=1,6=1
P 4.63268002 2.66615 3 P 0 0;4=4,6=1
P 11.08661004 2.21615 3 P 0 0;4=4,6=1
P 11.62193002 2.13 24 P 0 0;1,4=0,6=0
P 4.98268002 2.56615 3 P 0 0;4=4,6=1
P 11.08661004 2.26615 3 P 0 0;4=4,6=1
P 11.62193002 2.175 24 P 0 0;1,4=0,6=0
P 11.03661004 2.26615 3 P 0 0;4=4,6=1
P 11.42193002 2.21 24 P 0 0;1,4=0,6=0
P 2.14606004 3.76615 3 P 0 0;4=4,6=1
P 3.02571004 5.165 3 P 0 0;4=4,6=1
P 11.03661004 2.31615 3 P 0 0;4=4,6=1
P 11.42193002 2.255 24 P 0 0;1,4=0,6=0
P 11.42193002 2.05 24 P 0 0;1,4=0,6=0
P 10.98661004 2.21615 3 P 0 0;4=4,6=1
P 11.42193002 2.095 24 P 0 0;1,4=0,6=0
P 10.98661004 2.26615 3 P 0 0;4=4,6=1
P 3.17146004 5.255 6 P 0 0;2,4=1,6=1
P 3.23146004 5.298 24 P 0 0;1,4=0,6=0
P 3.18646004 5.298 24 P 0 0;1,4=0,6=0
P 4.68268002 2.61615 3 P 0 0;4=4,6=1
P 10.93661004 2.26615 3 P 0 0;4=4,6=1
P 11.62193002 2.29 24 P 0 0;1,4=0,6=0
P 10.58661004 2.76615 3 P 0 0;4=4,6=1
P 4 5.29 6 P 0 0;2,4=1,6=1
P 10.93661004 2.31615 3 P 0 0;4=4,6=1
P 11.62193002 2.335 24 P 0 0;1,4=0,6=0
P 10.88661004 2.16615 3 P 0 0;4=4,6=1
P 12.30501004 1.98958996 24 P 0 0;1,4=0,6=0
P 10.73661004 1.91615 3 P 0 0;4=4,6=1
P 10.395 1.28555 3 P 0 0;4=4,6=1
P 12.81495 1.96456998 7 P 0 0;2,4=2,6=0
P 9.42358002 5.22001998 3 P 0 0;4=4,6=1
P 8.67478996 2.82 24 P 0 0;1,4=0,6=0
P 8.98115 2.825 3 P 0 0;4=4,6=1
P 4.58268002 2.61615 3 P 0 0;4=4,6=1
P 9.38358002 5.22001998 3 P 0 0;4=4,6=1
P 8.67478996 2.87 24 P 0 0;1,4=0,6=0
P 8.98115 2.865 3 P 0 0;4=4,6=1
P 2.14606004 3.81615 3 P 0 0;4=4,6=1
P 3.06571004 5.165 3 P 0 0;4=4,6=1
P 11.08661004 2.71615 3 P 0 0;4=4,6=1
P 3.985 4.88998996 6 P 0 0;2,4=1,6=1
P 11.73316004 2.652 3 P 0 0;4=4,6=1
P 11.65593002 2.655 24 P 0 0;1,4=0,6=0
P 12.55905 4.40551004 7 P 0 0;2,4=2,6=0
P 11.73316004 2.612 3 P 0 0;4=4,6=1
P 11.65593002 2.61 24 P 0 0;1,4=0,6=0
P 12.63778996 4.44488002 7 P 0 0;2,4=2,6=0
P 8.64078996 2.87 24 P 0 0;1,4=0,6=0
P 8.3 2.86615 3 P 0 0;4=4,6=1
P 4.83268002 2.16615 3 P 0 0;4=4,6=1
P 0.61698996 1.91181998 24 P 0 0;1,4=0,6=0
P 0.69348996 1.90611998 3 P 0 0;4=4,6=1
P 11.73316004 2.492 3 P 0 0;4=4,6=1
P 11.65593002 2.495 24 P 0 0;1,4=0,6=0
P 12.55905 4.24803002 7 P 0 0;2,4=2,6=0
P 4.88268002 2.16615 3 P 0 0;4=4,6=1
P 0.61698996 1.86181998 24 P 0 0;1,4=0,6=0
P 0.69348996 1.86611998 3 P 0 0;4=4,6=1
P 11.73316004 2.452 3 P 0 0;4=4,6=1
P 11.65593002 2.45 24 P 0 0;1,4=0,6=0
P 12.63778996 4.2874 7 P 0 0;2,4=2,6=0
P 8.64078996 2.82 24 P 0 0;1,4=0,6=0
P 8.25 2.86615 3 P 0 0;4=4,6=1
P 12.55905 3.93306998 7 P 0 0;2,4=2,6=0
P 11.73316004 2.332 3 P 0 0;4=4,6=1
P 11.65593002 2.335 24 P 0 0;1,4=0,6=0
P 12.63778996 3.97243996 7 P 0 0;2,4=2,6=0
P 11.73316004 2.292 3 P 0 0;4=4,6=1
P 11.65593002 2.29 24 P 0 0;1,4=0,6=0
P 10.83661004 2.16615 3 P 0 0;4=4,6=1
P 12.30501004 1.93958996 24 P 0 0;1,4=0,6=0
P 11.53316004 2.092 3 P 0 0;4=4,6=1
P 11.45593002 2.095 24 P 0 0;1,4=0,6=0
P 12.55905 3.77558996 7 P 0 0;2,4=2,6=0
P 11.53316004 2.052 3 P 0 0;4=4,6=1
P 11.45593002 2.05 24 P 0 0;1,4=0,6=0
P 12.63778996 3.81496004 7 P 0 0;2,4=2,6=0
P 12.81495 3.53936998 7 P 0 0;2,4=2,6=0
P 10.68661004 2.26615 3 P 0 0;4=4,6=1
P 9.975 2.3758 3 P 0 0;4=4,6=1
P 12.81495 3.38188996 7 P 0 0;2,4=2,6=0
P 10.73661004 2.31615 3 P 0 0;4=4,6=1
P 9.975 2.23955 3 P 0 0;4=4,6=1
P 12.81495 2.20078996 7 P 0 0;2,4=2,6=0
P 10.68661004 1.91615 3 P 0 0;4=4,6=1
P 10.42445 1.395 3 P 0 0;4=4,6=1
P 12.81495 2.75196998 7 P 0 0;2,4=2,6=0
P 10.73661004 2.01615 3 P 0 0;4=4,6=1
P 10.26025 1.82845 3 P 0 0;4=4,6=1
P 12.73621004 3.73621998 7 P 0 0;2,4=2,6=0
P 10.58661004 2.21615 3 P 0 0;4=4,6=1
P 10.09 2.26825 3 P 0 0;4=4,6=1
P 10.73661004 2.41615 3 P 0 0;4=4,6=1
P 10.09 2.69655 3 P 0 0;4=4,6=1
P 12.73621004 4.52361998 7 P 0 0;2,4=2,6=0
P 7.3226 4.94151004 24 P 0 0;1,4=0,6=0
P 7.3426 4.69351004 6 P 0 0;2,4=1,6=1
P 7.82693996 3.56 24 P 0 0;1,4=0,6=0
P 11.73316004 1.532 3 P 0 0;4=4,6=1
P 11.65593002 1.535 24 P 0 0;1,4=0,6=0
P 12.55905 2.27953002 7 P 0 0;2,4=2,6=0
P 7.2726 4.94151004 24 P 0 0;1,4=0,6=0
P 7.2926 4.69351004 6 P 0 0;2,4=1,6=1
P 7.82693996 3.51 24 P 0 0;1,4=0,6=0
P 12.73621004 3.57873996 7 P 0 0;2,4=2,6=0
P 10.68661004 2.21615 3 P 0 0;4=4,6=1
P 9.975 2.3358 3 P 0 0;4=4,6=1
P 12.73621004 3.42126004 7 P 0 0;2,4=2,6=0
P 10.73661004 2.26615 3 P 0 0;4=4,6=1
P 9.975 2.19955 3 P 0 0;4=4,6=1
P 11.73316004 2.172 3 P 0 0;4=4,6=1
P 11.65593002 2.175 24 P 0 0;1,4=0,6=0
P 12.55905 3.46063002 7 P 0 0;2,4=2,6=0
P 4.98268002 2.36615 3 P 0 0;4=4,6=1
P 5.46358002 2.4953 24 P 0 0;1,4=0,6=0
P 10.73661004 1.86615 3 P 0 0;4=4,6=1
P 10.395 1.32555 3 P 0 0;4=4,6=1
P 12.73621004 2.00393996 7 P 0 0;2,4=2,6=0
P 11.73316004 2.132 3 P 0 0;4=4,6=1
P 11.65593002 2.13 24 P 0 0;1,4=0,6=0
P 12.63778996 3.5 7 P 0 0;2,4=2,6=0
P 3.38003996 5.22001998 3 P 0 0;4=4,6=1
P 2.67085 2.87 24 P 0 0;1,4=0,6=0
P 2.97721004 2.865 3 P 0 0;4=4,6=1
P 5.46358002 2.5403 24 P 0 0;1,4=0,6=0
P 4.98268002 2.41615 3 P 0 0;4=4,6=1
P 12.63778996 1.76771998 7 P 0 0;2,4=2,6=0
P 12.342 2.11 24 P 0 0;1,4=0,6=0
P 3.42003996 5.22001998 3 P 0 0;4=4,6=1
P 2.67085 2.82 24 P 0 0;1,4=0,6=0
P 2.97721004 2.825 3 P 0 0;4=4,6=1
P 4.88268002 2.81615 3 P 0 0;4=4,6=1
P 4.93268002 2.81615 3 P 0 0;4=4,6=1
P 4.98268002 2.81615 3 P 0 0;4=4,6=1
P 5.03268002 2.81615 3 P 0 0;4=4,6=1
P 5.08268002 2.81615 3 P 0 0;4=4,6=1
P 11.03661004 2.81615 3 P 0 0;4=4,6=1
P 11.08661004 2.81615 3 P 0 0;4=4,6=1
P 10.98661004 2.81615 3 P 0 0;4=4,6=1
P 10.93661004 2.81615 3 P 0 0;4=4,6=1
P 10.88661004 2.81615 3 P 0 0;4=4,6=1
P 5.32386004 2.96 26 P 0 0;1,4=11,6=0
P 5.32386004 3.04 26 P 0 0;1,4=11,6=0
P 5.32386004 3.12 26 P 0 0;1,4=11,6=0
P 5.27886004 3.0214 4 P 0 0;4=6,6=1
P 5.27886004 3.0564 4 P 0 0;4=6,6=1
P 5.27886004 3.1014 4 P 0 0;4=6,6=1
P 5.27886004 3.1364 4 P 0 0;4=6,6=1
P 5.27886004 2.9764 4 P 0 0;4=6,6=1
P 5.27886004 2.9414 4 P 0 0;4=6,6=1
P 5.32386004 3.2 26 P 0 0;1,4=11,6=0
P 5.32386004 3.28 26 P 0 0;1,4=11,6=0
P 5.27886004 3.2614 4 P 0 0;4=6,6=1
P 5.27886004 3.2964 4 P 0 0;4=6,6=1
P 5.27886004 3.2164 4 P 0 0;4=6,6=1
P 5.27886004 3.1814 4 P 0 0;4=6,6=1
P 11.28278996 3.1814 4 P 0 0;4=6,6=1
P 11.28278996 3.2164 4 P 0 0;4=6,6=1
P 11.28278996 3.2964 4 P 0 0;4=6,6=1
P 11.28278996 3.2614 4 P 0 0;4=6,6=1
P 11.32778996 3.2 26 P 0 0;1,4=11,6=0
P 11.32778996 3.28 26 P 0 0;1,4=11,6=0
P 11.28278996 2.9414 4 P 0 0;4=6,6=1
P 11.28278996 2.9764 4 P 0 0;4=6,6=1
P 11.28278996 3.1364 4 P 0 0;4=6,6=1
P 11.28278996 3.1014 4 P 0 0;4=6,6=1
P 11.28278996 3.0564 4 P 0 0;4=6,6=1
P 11.28278996 3.0214 4 P 0 0;4=6,6=1
P 11.32778996 2.96 26 P 0 0;1,4=11,6=0
P 11.32778996 3.12 26 P 0 0;1,4=11,6=0
P 11.32778996 3.04 26 P 0 0;1,4=11,6=0
P 5.59708996 4.7302 4 P 0 0;4=6,6=1
P 5.57708996 4.6802 4 P 0 0;4=6,6=1
P 5.59778996 4.6352 26 P 0 0;1,4=11,6=0
P 5.75708996 4.7302 4 P 0 0;4=6,6=1
P 5.83708996 4.7302 4 P 0 0;4=6,6=1
P 5.69708996 4.6802 4 P 0 0;4=6,6=1
P 5.73708996 4.6802 4 P 0 0;4=6,6=1
P 5.77708996 4.6802 4 P 0 0;4=6,6=1
P 5.81708996 4.6802 4 P 0 0;4=6,6=1
P 5.85708996 4.6802 4 P 0 0;4=6,6=1
P 5.67708996 4.7302 4 P 0 0;4=6,6=1
P 5.65708996 4.6802 4 P 0 0;4=6,6=1
P 5.61708996 4.6802 4 P 0 0;4=6,6=1
P 5.67708996 4.6352 26 P 0 0;1,4=11,6=0
P 5.75708996 4.6352 26 P 0 0;1,4=11,6=0
P 5.83708996 4.6352 26 P 0 0;1,4=11,6=0
P 6.13708996 4.7602 4 P 0 0;4=6,6=1
P 6.09708996 4.6802 4 P 0 0;4=6,6=1
P 6.13708996 4.6402 4 P 0 0;4=6,6=1
P 6.13708996 4.6802 4 P 0 0;4=6,6=1
P 6.13708996 4.7202 4 P 0 0;4=6,6=1
P 5.91708996 4.7302 4 P 0 0;4=6,6=1
P 5.99708996 4.7302 4 P 0 0;4=6,6=1
P 6.07708996 4.7302 4 P 0 0;4=6,6=1
P 5.89708996 4.6802 4 P 0 0;4=6,6=1
P 5.93708996 4.6802 4 P 0 0;4=6,6=1
P 5.97708996 4.6802 4 P 0 0;4=6,6=1
P 6.01708996 4.6802 4 P 0 0;4=6,6=1
P 6.05708996 4.6802 4 P 0 0;4=6,6=1
P 6.07708996 4.6352 26 P 0 0;1,4=11,6=0
P 5.91708996 4.6352 26 P 0 0;1,4=11,6=0
P 5.99708996 4.6352 26 P 0 0;1,4=11,6=0
P 6.19208996 4.7202 26 P 0 0;1,4=11,6=0
P 6.19208996 4.6402 26 P 0 0;1,4=11,6=0
P 5.59708996 4.7702 4 P 0 0;4=6,6=1
P 5.59708996 4.8102 4 P 0 0;4=6,6=1
P 5.75708996 4.8102 4 P 0 0;4=6,6=1
P 5.83708996 4.8102 4 P 0 0;4=6,6=1
P 5.75708996 4.7702 4 P 0 0;4=6,6=1
P 5.83708996 4.7702 4 P 0 0;4=6,6=1
P 5.67708996 4.8102 4 P 0 0;4=6,6=1
P 5.67708996 4.7702 4 P 0 0;4=6,6=1
P 6.13708996 4.9252 4 P 0 0;4=6,6=1
P 6.13708996 4.8402 4 P 0 0;4=6,6=1
P 6.13708996 4.8002 4 P 0 0;4=6,6=1
P 6.13708996 4.8852 4 P 0 0;4=6,6=1
P 5.91708996 4.8102 4 P 0 0;4=6,6=1
P 5.99708996 4.8102 4 P 0 0;4=6,6=1
P 5.91708996 4.7702 4 P 0 0;4=6,6=1
P 5.99708996 4.7702 4 P 0 0;4=6,6=1
P 6.07708996 4.8102 4 P 0 0;4=6,6=1
P 6.07708996 4.7702 4 P 0 0;4=6,6=1
P 6.19208996 4.8802 26 P 0 0;1,4=11,6=0
P 6.19208996 4.8002 26 P 0 0;1,4=11,6=0
P 6.09 4.925 6 P 0 0;2,4=5,6=1
P 4.93268002 2.26615 3 P 0 0;4=4,6=1
P 5.46358002 2.3561 24 P 0 0;1,4=0,6=0
P 4.93268002 2.31615 3 P 0 0;4=4,6=1
P 5.46358002 2.4011 24 P 0 0;1,4=0,6=0
P 5.08268002 2.36615 3 P 0 0;4=4,6=1
P 5.30875 2.4237 24 P 0 0;1,4=0,6=0
P 12.81495 3.22441004 7 P 0 0;2,4=2,6=0
P 10.68661004 2.06615 3 P 0 0;4=4,6=1
P 10.09 2.13095 3 P 0 0;4=4,6=1
P 10.63661004 2.31615 3 P 0 0;4=4,6=1
P 10.09 2.40335 3 P 0 0;4=4,6=1
P 12.81495 3.85433002 7 P 0 0;2,4=2,6=0
P 11.73316004 2.012 3 P 0 0;4=4,6=1
P 11.65593002 2.015 24 P 0 0;1,4=0,6=0
P 12.63778996 3.1063 7 P 0 0;2,4=2,6=0
P 11.73316004 1.972 3 P 0 0;4=4,6=1
P 11.65593002 1.97 24 P 0 0;1,4=0,6=0
P 12.55905 3.14566998 7 P 0 0;2,4=2,6=0
P 11.45593002 1.73 24 P 0 0;1,4=0,6=0
P 11.53316004 1.732 3 P 0 0;4=4,6=1
P 12.55905 2.98818996 7 P 0 0;2,4=2,6=0
P 12.81495 3.69685 7 P 0 0;2,4=2,6=0
P 10.58661004 2.26615 3 P 0 0;4=4,6=1
P 10.09 2.30825 3 P 0 0;4=4,6=1
P 11.53316004 1.772 3 P 0 0;4=4,6=1
P 11.45593002 1.775 24 P 0 0;1,4=0,6=0
P 12.63778996 2.94881998 7 P 0 0;2,4=2,6=0
P 12.81495 4.32676998 7 P 0 0;2,4=2,6=0
P 10.63661004 2.46615 3 P 0 0;4=4,6=1
P 9.975 2.62445 3 P 0 0;4=4,6=1
P 12.63778996 2.79133996 7 P 0 0;2,4=2,6=0
P 11.73316004 1.852 3 P 0 0;4=4,6=1
P 11.65593002 1.855 24 P 0 0;1,4=0,6=0
P 12.55905 2.83071004 7 P 0 0;2,4=2,6=0
P 11.73316004 1.812 3 P 0 0;4=4,6=1
P 11.65593002 1.81 24 P 0 0;1,4=0,6=0
P 10.73661004 2.46615 3 P 0 0;4=4,6=1
P 10.09 2.73655 3 P 0 0;4=4,6=1
P 12.81495 4.48425 7 P 0 0;2,4=2,6=0
P 10.63661004 2.26615 3 P 0 0;4=4,6=1
P 10.09 2.44335 3 P 0 0;4=4,6=1
P 12.73621004 3.8937 7 P 0 0;2,4=2,6=0
P 10.58661004 2.41615 3 P 0 0;4=4,6=1
P 9.975 2.5109 3 P 0 0;4=4,6=1
P 12.81495 4.16928996 7 P 0 0;2,4=2,6=0
P 1.025 -0.35 25 P 0 0;2,4=9,6=0
P 1.325 -0.35 25 P 0 0;4=9,6=0
P 1.175 -0.35 25 P 0 0;4=9,6=0
P 0.725 -0.35 25 P 0 0;4=9,6=0
P 0.875 -0.35 25 P 0 0;4=9,6=0
P 12.73621004 4.05118002 7 P 0 0;2,4=2,6=0
P 10.68661004 2.36615 3 P 0 0;4=4,6=1
P 10.09 2.53845 3 P 0 0;4=4,6=1
P 12.81495 2.35826998 7 P 0 0;2,4=2,6=0
P 10.63661004 1.86615 3 P 0 0;4=4,6=1
P 10.35543002 1.52156998 3 P 0 0;4=4,6=1
P 5.03268002 2.01615 3 P 0 0;4=4,6=1
P 5.46358002 1.9444 24 P 0 0;1,4=0,6=0
P 5.08268002 2.21615 3 P 0 0;4=4,6=1
P 5.46358002 2.2207 24 P 0 0;1,4=0,6=0
P 12.73621004 2.16141998 7 P 0 0;2,4=2,6=0
P 10.68661004 1.96615 3 P 0 0;4=4,6=1
P 10.46445 1.395 3 P 0 0;4=4,6=1
P 5.72185 2.97441004 29 P 0 0;1,4=8
P 9.95743996 2.82441004 29 P 0 0;1,4=8
P 3.91351004 2.59441004 29 P 0 0;1,4=8
P 0.2 -0.293 16 P 0 0;4=18
P 12.27 0.29 16 P 0 0;4=18
P 0.66 0.29 16 P 0 0;4=18
P 0.2 5.82361998 16 P 0 0;4=18
P 11.99518996 0.29 12 P 0 0;1,4=19
P 0.9211 0.2854 12 P 0 0;1,4=19
P 0.5836 5.36731998 12 P 0 0;1,4=19
P 0.5 -0.293 12 P 0 0;1,4=19
P 12.4252 6.31661998 12 P 0 0;1,4=19
P 0.5 6.31661998 12 P 0 0;1,4=19
P 12.4252 -0.293 12 P 0 0;1,4=19
P 12.81495 1.57086998 7 P 0 0;4=2
P 12.73621004 1.5315 7 P 0 0;4=2
P 12.63778996 2.7126 7 P 0 0;4=2
P 12.55905 2.67323002 7 P 0 0;4=2
P 12.55905 1.64961004 7 P 0 0;4=2
P 12.63778996 1.61023996 7 P 0 0;4=2
P 12.55905 1.57086998 7 P 0 0;4=2
P 12.63778996 1.5315 7 P 0 0;4=2
P 12.73621004 1.68898002 7 P 0 0;4=2
P 12.81495 1.64961004 7 P 0 0;4=2
P 12.63778996 1.68898002 7 P 0 0;4=2
P 12.55905 1.72835 7 P 0 0;4=2
P 12.81495 1.72835 7 P 0 0;4=2
P 12.73621004 1.45276004 7 P 0 0;4=2
P 12.81495 1.41338996 7 P 0 0;4=2
P 12.73621004 1.37401998 25 P 0 0;4=10
P 12.63778996 1.45276004 7 P 0 0;4=2
P 12.55905 1.41338996 7 P 0 0;4=2
P 0.35038996 1.5315 7 P 0 0;4=2
P 0.27165 1.49213002 7 P 0 0;4=2
P 0.17323002 2.67323002 7 P 0 0;4=2
P 0.09448996 2.63386004 7 P 0 0;4=2
P 0.09448996 1.61023996 7 P 0 0;4=2
P 0.17323002 1.57086998 7 P 0 0;4=2
P 0.09448996 1.5315 7 P 0 0;4=2
P 0.17323002 1.49213002 7 P 0 0;4=2
P 0.27165 1.64961004 7 P 0 0;4=2
P 0.35038996 1.61023996 7 P 0 0;4=2
P 0.17323002 1.64961004 7 P 0 0;4=2
P 0.09448996 1.68898002 7 P 0 0;4=2
P 0.35038996 1.68898002 7 P 0 0;4=2
P 0.27165 1.41338996 7 P 0 0;4=2
P 0.35038996 1.37401998 7 P 0 0;4=2
P 0.27165 1.33465 25 P 0 0;4=10
P 0.17323002 1.41338996 7 P 0 0;4=2
P 0.09448996 1.37401998 7 P 0 0;4=2
P 10.20866004 5.4441 23 P 0 0;4=20
P 5.78346004 5.4441 23 P 0 0;4=20
P 12.7252 6.31661998 16 P 0 0;4=18
P 0.2 6.31661998 16 P 0 0;4=18
P 12.7252 -0.293 16 P 0 0;4=18
P 0.22245 4.87401004 14 P 0 0;4=7
P 12.68701004 0.46063002 17 P 0 0;4=21
P 12.68701998 5.4252 17 P 0 0;4=21
P 0.22245 0.42126004 17 P 0 0;4=21
P 0.22255 5.38583002 17 P 0 0;4=21
L 1.88908002 -1.91246004 1.89293002 -1.91246004 0 P 0 
L 1.89126998 -1.91146004 1.89656998 -1.91146004 0 P 0 
L 1.89393996 -1.91046004 1.9155 -1.91046004 0 P 0 
L 1.91593996 -1.91246004 1.92048996 -1.91246004 0 P 0 
L 1.9126 -1.91146004 1.9184 -1.91146004 0 P 0 
L 1.89763002 -1.90946004 1.91016998 -1.90946004 0 P 0 
L 1.89053002 -1.96001004 1.8974 -1.96001004 0 P 0 
L 1.89053002 -1.95901004 1.8974 -1.95901004 0 P 0 
L 1.89053002 -1.95801004 1.8974 -1.95801004 0 P 0 
L 1.89053002 -1.95701004 1.8974 -1.95701004 0 P 0 
L 1.89053002 -1.95601004 1.8974 -1.95601004 0 P 0 
L 1.89053002 -1.95501004 1.8974 -1.95501004 0 P 0 
L 1.89053002 -1.95401004 1.8974 -1.95401004 0 P 0 
L 1.89053002 -1.95301004 1.89741004 -1.95301004 0 P 0 
L 1.89053002 -1.95201004 1.89741998 -1.95201004 0 P 0 
L 1.89053002 -1.95101004 1.89743996 -1.95101004 0 P 0 
L 1.89053002 -1.95001004 1.89745 -1.95001004 0 P 0 
L 1.89053002 -1.94901004 1.89746004 -1.94901004 0 P 0 
L 1.89053002 -1.94801004 1.89753002 -1.94801004 0 P 0 
L 1.89053002 -1.94701004 1.8977 -1.94701004 0 P 0 
L 1.89053002 -1.94601004 1.89798002 -1.94601004 0 P 0 
L 1.89053002 -1.94501004 1.89861004 -1.94501004 0 P 0 
L 1.89053002 -1.94401004 1.90005 -1.94401004 0 P 0 
L 1.89053002 -1.94301004 1.9113 -1.94301004 0 P 0 
L 1.89053002 -1.94201004 1.91168002 -1.94201004 0 P 0 
L 1.89053002 -1.94101004 1.91246998 -1.94101004 0 P 0 
L 1.89053002 -1.94001004 1.90093996 -1.94001004 0 P 0 
L 1.89053002 -1.93901004 1.89856004 -1.93901004 0 P 0 
L 1.89053002 -1.93801004 1.89786998 -1.93801004 0 P 0 
L 1.89053002 -1.93701004 1.89753996 -1.93701004 0 P 0 
L 1.89053002 -1.93601004 1.89746998 -1.93601004 0 P 0 
L 1.89053002 -1.93501004 1.89743996 -1.93501004 0 P 0 
L 1.89053002 -1.93401004 1.89741998 -1.93401004 0 P 0 
L 1.89053002 -1.93301004 1.8974 -1.93301004 0 P 0 
L 1.89053002 -1.93201004 1.8974 -1.93201004 0 P 0 
L 1.89053002 -1.93101004 1.8974 -1.93101004 0 P 0 
L 1.89053002 -1.93001004 1.8974 -1.93001004 0 P 0 
L 1.89053002 -1.92901004 1.8974 -1.92901004 0 P 0 
L 1.89053002 -1.92801004 1.89753002 -1.92801004 0 P 0 
L 1.89053002 -1.92701004 1.89793996 -1.92701004 0 P 0 
L 1.89053002 -1.92601004 1.91713002 -1.92601004 0 P 0 
L 1.89053002 -1.92501004 1.91628996 -1.92501004 0 P 0 
L 1.89053002 -1.92401004 1.91513996 -1.92401004 0 P 0 
L 1.89053002 -1.92301004 1.91321998 -1.92301004 0 P 0 
L 1.89053002 -1.92201004 1.90551004 -1.92201004 0 P 0 
L 1.89438996 -1.97246004 1.91331004 -1.97246004 0 P 0 
L 1.89106998 -1.97146004 1.89973002 -1.97146004 0 P 0 
L 1.88878002 -1.97046004 1.8949 -1.97046004 0 P 0 
L 1.88698002 -1.96946004 1.89206998 -1.96946004 0 P 0 
L 1.88546004 -1.96846004 1.88986998 -1.96846004 0 P 0 
L 1.88416998 -1.96746004 1.88808996 -1.96746004 0 P 0 
L 1.88288002 -1.96646004 1.88655 -1.96646004 0 P 0 
L 1.88176998 -1.96546004 1.88518002 -1.96546004 0 P 0 
L 1.88068996 -1.96446004 1.88393996 -1.96446004 0 P 0 
L 1.87968996 -1.96346004 1.88286004 -1.96346004 0 P 0 
L 1.87878002 -1.96246004 1.88186004 -1.96246004 0 P 0 
L 1.8786 -1.92046004 1.88126998 -1.92046004 0 P 0 
L 1.87946998 -1.91946004 1.88223002 -1.91946004 0 P 0 
L 1.88048002 -1.91846004 1.88321004 -1.91846004 0 P 0 
L 1.88153996 -1.91746004 1.88436998 -1.91746004 0 P 0 
L 1.88273002 -1.91646004 1.88558996 -1.91646004 0 P 0 
L 1.88406004 -1.91546004 1.88696998 -1.91546004 0 P 0 
L 1.88548996 -1.91446004 1.88853002 -1.91446004 0 P 0 
L 1.88718002 -1.91346004 1.89041998 -1.91346004 0 P 0 
L 1.90896004 -1.92963996 1.90921998 -1.92991998 0 P 0 
L 1.90921998 -1.92991998 1.90945 -1.93021998 0 P 0 
L 1.90945 -1.93021998 1.90966004 -1.93053002 0 P 0 
L 1.90966004 -1.93053002 1.90983002 -1.93086004 0 P 0 
L 1.90983002 -1.93086004 1.90998002 -1.93121004 0 P 0 
L 1.90998002 -1.93121004 1.9101 -1.93156998 0 P 0 
L 1.9101 -1.93156998 1.91018996 -1.93193996 0 P 0 
L 1.91018996 -1.93193996 1.91023996 -1.93231004 0 P 0 
L 1.91023996 -1.93231004 1.91026998 -1.93265 0 P 0 
L 1.91026998 -1.93265 1.91026004 -1.93298002 0 P 0 
L 1.91026004 -1.93298002 1.91023002 -1.93331004 0 P 0 
L 1.91023002 -1.93331004 1.91016998 -1.93363996 0 P 0 
L 1.91016998 -1.93363996 1.91008996 -1.93396004 0 P 0 
L 1.91008996 -1.93396004 1.90998002 -1.93428002 0 P 0 
L 1.90998002 -1.93428002 1.90983996 -1.93458002 0 P 0 
L 1.90983996 -1.93458002 1.90968996 -1.93486998 0 P 0 
L 1.90968996 -1.93486998 1.90951004 -1.93516004 0 P 0 
L 1.90951004 -1.93516004 1.90921004 -1.93556004 0 P 0 
L 1.90921004 -1.93556004 1.90888002 -1.93593002 0 P 0 
L 1.90888002 -1.93593002 1.90853002 -1.93626998 0 P 0 
L 1.90853002 -1.93626998 1.90815 -1.93658996 0 P 0 
L 1.90815 -1.93658996 1.90773996 -1.93686998 0 P 0 
L 1.90773996 -1.93686998 1.90731998 -1.93711998 0 P 0 
L 1.90731998 -1.93711998 1.90686998 -1.93733996 0 P 0 
L 1.90686998 -1.93733996 1.90615 -1.93761004 0 P 0 
L 1.90615 -1.93761004 1.90541998 -1.93783002 0 P 0 
L 1.90541998 -1.93783002 1.90466004 -1.93798002 0 P 0 
L 1.90466004 -1.93798002 1.9039 -1.93808002 0 P 0 
L 1.9039 -1.93808002 1.90311998 -1.9381 0 P 0 
L 1.90311998 -1.9381 1.90196004 -1.93808002 0 P 0 
L 1.90196004 -1.93808002 1.90078996 -1.93798996 0 P 0 
L 1.90078996 -1.93798996 1.90068002 -1.93798002 0 P 0 
L 1.90068002 -1.93798002 1.90058002 -1.93795 0 P 0 
L 1.90058002 -1.93795 1.90046998 -1.93791998 0 P 0 
L 1.90046998 -1.93791998 1.90038002 -1.93788002 0 P 0 
L 1.90038002 -1.93788002 1.90028002 -1.93783002 0 P 0 
L 1.90028002 -1.93783002 1.90018996 -1.93778002 0 P 0 
L 1.90018996 -1.93778002 1.9001 -1.93771004 0 P 0 
L 1.9001 -1.93771004 1.90001998 -1.93763996 0 P 0 
L 1.90001998 -1.93763996 1.89988002 -1.93748002 0 P 0 
L 1.89988002 -1.93748002 1.89978002 -1.93733996 0 P 0 
L 1.89978002 -1.93733996 1.89961998 -1.93703996 0 P 0 
L 1.89961998 -1.93703996 1.89956998 -1.93688002 0 P 0 
L 1.89956998 -1.93688002 1.89951998 -1.93671004 0 P 0 
L 1.89951998 -1.93671004 1.89948996 -1.93655 0 P 0 
L 1.89948996 -1.93655 1.89946998 -1.93636998 0 P 0 
L 1.89946998 -1.93636998 1.8994 -1.93323002 0 P 0 
L 1.8994 -1.93323002 1.8994 -1.92833002 0 P 0 
L 1.8994 -1.92833002 1.90353996 -1.92833002 0 P 0 
L 1.90353996 -1.92833002 1.90436998 -1.92835 0 P 0 
L 1.90436998 -1.92835 1.9052 -1.92843002 0 P 0 
L 1.9052 -1.92843002 1.90603002 -1.92853996 0 P 0 
L 1.90603002 -1.92853996 1.90683996 -1.92871004 0 P 0 
L 1.90683996 -1.92871004 1.90751004 -1.9289 0 P 0 
L 1.90751004 -1.9289 1.90818002 -1.92913002 0 P 0 
L 1.90818002 -1.92913002 1.90851998 -1.92928996 0 P 0 
L 1.90851998 -1.92928996 1.90868002 -1.92938996 0 P 0 
L 1.90868002 -1.92938996 1.90883002 -1.92951004 0 P 0 
L 1.90883002 -1.92951004 1.90896004 -1.92963996 0 P 0 
L 1.91188996 -1.96001004 1.91638996 -1.96001004 0 P 0 
L 1.91156998 -1.95901004 1.91926998 -1.95901004 0 P 0 
L 1.91125 -1.95801004 1.91891998 -1.95801004 0 P 0 
L 1.91091998 -1.95701004 1.91853002 -1.95701004 0 P 0 
L 1.9106 -1.95601004 1.91811004 -1.95601004 0 P 0 
L 1.91025 -1.95501004 1.91765 -1.95501004 0 P 0 
L 1.90988996 -1.95401004 1.91718996 -1.95401004 0 P 0 
L 1.90953002 -1.95301004 1.91673002 -1.95301004 0 P 0 
L 1.90918002 -1.95201004 1.91626998 -1.95201004 0 P 0 
L 1.90881998 -1.95101004 1.91576004 -1.95101004 0 P 0 
L 1.90841004 -1.95001004 1.91523996 -1.95001004 0 P 0 
L 1.90793996 -1.94901004 1.91471004 -1.94901004 0 P 0 
L 1.90738996 -1.94801004 1.91418002 -1.94801004 0 P 0 
L 1.90676998 -1.94701004 1.9136 -1.94701004 0 P 0 
L 1.90598996 -1.94601004 1.91261004 -1.94601004 0 P 0 
L 1.90495 -1.94501004 1.91175 -1.94501004 0 P 0 
L 1.90325 -1.94401004 1.91133002 -1.94401004 0 P 0 
L 1.90456004 -1.94001004 1.91383002 -1.94001004 0 P 0 
L 1.90801004 -1.93901004 1.91523002 -1.93901004 0 P 0 
L 1.90956998 -1.93801004 1.91635 -1.93801004 0 P 0 
L 1.9106 -1.93701004 1.91718002 -1.93701004 0 P 0 
L 1.91133996 -1.93601004 1.91781004 -1.93601004 0 P 0 
L 1.91183996 -1.93501004 1.91826004 -1.93501004 0 P 0 
L 1.91213002 -1.93401004 1.9186 -1.93401004 0 P 0 
L 1.91226004 -1.93301004 1.9188 -1.93301004 0 P 0 
L 1.91221998 -1.93201004 1.9189 -1.93201004 0 P 0 
L 1.91201998 -1.93101004 1.9189 -1.93101004 0 P 0 
L 1.91163996 -1.93001004 1.91878996 -1.93001004 0 P 0 
L 1.91105 -1.92901004 1.91856998 -1.92901004 0 P 0 
L 1.91013996 -1.92801004 1.91823002 -1.92801004 0 P 0 
L 1.90816998 -1.92701004 1.91776004 -1.92701004 0 P 0 
L 1.90313996 -1.94011004 1.90316998 -1.9401 0 P 0 
L 1.90316998 -1.9401 1.9032 -1.9401 0 P 0 
L 1.9032 -1.9401 1.90398002 -1.94006998 0 P 0 
L 1.90398002 -1.94006998 1.90406004 -1.94006998 0 P 0 
L 1.90406004 -1.94006998 1.90413996 -1.94006004 0 P 0 
L 1.90413996 -1.94006004 1.9049 -1.93996998 0 P 0 
L 1.9049 -1.93996998 1.90493996 -1.93996004 0 P 0 
L 1.90493996 -1.93996004 1.90498996 -1.93996004 0 P 0 
L 1.90498996 -1.93996004 1.90506998 -1.93993996 0 P 0 
L 1.90506998 -1.93993996 1.90581998 -1.93978002 0 P 0 
L 1.90581998 -1.93978002 1.90586004 -1.93978002 0 P 0 
L 1.90586004 -1.93978002 1.90593996 -1.93976004 0 P 0 
L 1.90593996 -1.93976004 1.90596998 -1.93973996 0 P 0 
L 1.90596998 -1.93973996 1.90671004 -1.93953002 0 P 0 
L 1.90671004 -1.93953002 1.90678996 -1.93951004 0 P 0 
L 1.90678996 -1.93951004 1.90758996 -1.93921004 0 P 0 
L 1.90758996 -1.93921004 1.90766004 -1.93916998 0 P 0 
L 1.90766004 -1.93916998 1.9077 -1.93915 0 P 0 
L 1.9077 -1.93915 1.90773996 -1.93913996 0 P 0 
L 1.90773996 -1.93913996 1.90818996 -1.93891998 0 P 0 
L 1.90818996 -1.93891998 1.90821998 -1.9389 0 P 0 
L 1.90821998 -1.9389 1.90826004 -1.93888996 0 P 0 
L 1.90826004 -1.93888996 1.90828996 -1.93886998 0 P 0 
L 1.90828996 -1.93886998 1.90833002 -1.93885 0 P 0 
L 1.90833002 -1.93885 1.90875 -1.9386 0 P 0 
L 1.90875 -1.9386 1.90883002 -1.93856004 0 P 0 
L 1.90883002 -1.93856004 1.90888996 -1.93851004 0 P 0 
L 1.90888996 -1.93851004 1.90928996 -1.93823002 0 P 0 
L 1.90928996 -1.93823002 1.90933002 -1.9382 0 P 0 
L 1.90933002 -1.9382 1.90936004 -1.93818002 0 P 0 
L 1.90936004 -1.93818002 1.90938996 -1.93815 0 P 0 
L 1.90938996 -1.93815 1.90941998 -1.93813002 0 P 0 
L 1.90941998 -1.93813002 1.9098 -1.93781998 0 P 0 
L 1.9098 -1.93781998 1.90986004 -1.93776004 0 P 0 
L 1.90986004 -1.93776004 1.90988996 -1.93773996 0 P 0 
L 1.90988996 -1.93773996 1.90991998 -1.93771004 0 P 0 
L 1.90991998 -1.93771004 1.91028002 -1.93736004 0 P 0 
L 1.91028002 -1.93736004 1.91038996 -1.93725 0 P 0 
L 1.91038996 -1.93725 1.91071004 -1.93688002 0 P 0 
L 1.91071004 -1.93688002 1.91073996 -1.93685 0 P 0 
L 1.91073996 -1.93685 1.91116004 -1.9363 0 P 0 
L 1.91116004 -1.9363 1.9112 -1.93623002 0 P 0 
L 1.9112 -1.93623002 1.91138002 -1.93595 0 P 0 
L 1.91138002 -1.93595 1.9114 -1.93591004 0 P 0 
L 1.9114 -1.93591004 1.91143996 -1.93585 0 P 0 
L 1.91143996 -1.93585 1.91146004 -1.93581004 0 P 0 
L 1.91146004 -1.93581004 1.91161004 -1.93551998 0 P 0 
L 1.91161004 -1.93551998 1.91163002 -1.93548996 0 P 0 
L 1.91163002 -1.93548996 1.91165 -1.93545 0 P 0 
L 1.91165 -1.93545 1.91166004 -1.93541004 0 P 0 
L 1.91166004 -1.93541004 1.91168002 -1.93538002 0 P 0 
L 1.91168002 -1.93538002 1.91181004 -1.93506998 0 P 0 
L 1.91181004 -1.93506998 1.91183996 -1.935 0 P 0 
L 1.91183996 -1.935 1.91186004 -1.93496004 0 P 0 
L 1.91186004 -1.93496004 1.91186998 -1.93493002 0 P 0 
L 1.91186998 -1.93493002 1.91198002 -1.93461004 0 P 0 
L 1.91198002 -1.93461004 1.91198996 -1.93456998 0 P 0 
L 1.91198996 -1.93456998 1.912 -1.93453996 0 P 0 
L 1.912 -1.93453996 1.9121 -1.93413996 0 P 0 
L 1.9121 -1.93413996 1.91211998 -1.9341 0 P 0 
L 1.91211998 -1.9341 1.91211998 -1.93406004 0 P 0 
L 1.91211998 -1.93406004 1.91213002 -1.93401998 0 P 0 
L 1.91213002 -1.93401998 1.91213996 -1.93398996 0 P 0 
L 1.91213996 -1.93398996 1.9122 -1.93366004 0 P 0 
L 1.9122 -1.93366004 1.91221004 -1.93358002 0 P 0 
L 1.91221004 -1.93358002 1.91221004 -1.93353996 0 P 0 
L 1.91221004 -1.93353996 1.91221998 -1.9335 0 P 0 
L 1.91221998 -1.9335 1.91225 -1.93316998 0 P 0 
L 1.91225 -1.93316998 1.91226004 -1.93308996 0 P 0 
L 1.91226004 -1.93308996 1.91226004 -1.93268002 0 P 0 
L 1.91226004 -1.93268002 1.91226998 -1.93263996 0 P 0 
L 1.91226998 -1.93263996 1.91226998 -1.9326 0 P 0 
L 1.91226998 -1.9326 1.91226004 -1.93251998 0 P 0 
L 1.91226004 -1.93251998 1.91223996 -1.93218996 0 P 0 
L 1.91223996 -1.93218996 1.91223996 -1.93215 0 P 0 
L 1.91223996 -1.93215 1.91223002 -1.9321 0 P 0 
L 1.91223002 -1.9321 1.91223002 -1.93206004 0 P 0 
L 1.91223002 -1.93206004 1.91221998 -1.93201998 0 P 0 
L 1.91221998 -1.93201998 1.91216998 -1.93163996 0 P 0 
L 1.91216998 -1.93163996 1.91216004 -1.9316 0 P 0 
L 1.91216004 -1.9316 1.91213996 -1.93151004 0 P 0 
L 1.91213996 -1.93151004 1.91213002 -1.93146998 0 P 0 
L 1.91213002 -1.93146998 1.91205 -1.93111004 0 P 0 
L 1.91205 -1.93111004 1.91203996 -1.93106004 0 P 0 
L 1.91203996 -1.93106004 1.91203002 -1.93101998 0 P 0 
L 1.91203002 -1.93101998 1.91201004 -1.93098002 0 P 0 
L 1.91201004 -1.93098002 1.912 -1.93093996 0 P 0 
L 1.912 -1.93093996 1.91188002 -1.93058002 0 P 0 
L 1.91188002 -1.93058002 1.91186998 -1.93053996 0 P 0 
L 1.91186998 -1.93053996 1.91185 -1.9305 0 P 0 
L 1.91185 -1.9305 1.91183996 -1.93046004 0 P 0 
L 1.91183996 -1.93046004 1.91181998 -1.93043002 0 P 0 
L 1.91181998 -1.93043002 1.91166998 -1.93008002 0 P 0 
L 1.91166998 -1.93008002 1.91166004 -1.93003996 0 P 0 
L 1.91166004 -1.93003996 1.9116 -1.92991998 0 P 0 
L 1.9116 -1.92991998 1.91141998 -1.92958996 0 P 0 
L 1.91141998 -1.92958996 1.9114 -1.92955 0 P 0 
L 1.9114 -1.92955 1.91138002 -1.92951998 0 P 0 
L 1.91138002 -1.92951998 1.91133002 -1.92945 0 P 0 
L 1.91133002 -1.92945 1.91113002 -1.92913002 0 P 0 
L 1.91113002 -1.92913002 1.91111004 -1.92908996 0 P 0 
L 1.91111004 -1.92908996 1.91108996 -1.92906004 0 P 0 
L 1.91108996 -1.92906004 1.91106004 -1.92901998 0 P 0 
L 1.91106004 -1.92901998 1.91103002 -1.92898996 0 P 0 
L 1.91103002 -1.92898996 1.9108 -1.92868996 0 P 0 
L 1.9108 -1.92868996 1.91076998 -1.92866004 0 P 0 
L 1.91076998 -1.92866004 1.91075 -1.92861998 0 P 0 
L 1.91075 -1.92861998 1.91068996 -1.92856004 0 P 0 
L 1.91068996 -1.92856004 1.91043002 -1.92828002 0 P 0 
L 1.91043002 -1.92828002 1.91035 -1.9282 0 P 0 
L 1.91035 -1.9282 1.91033002 -1.92816998 0 P 0 
L 1.91033002 -1.92816998 1.91018996 -1.92803996 0 P 0 
L 1.91018996 -1.92803996 1.91018002 -1.92803996 0 P 0 
L 1.91018002 -1.92803996 1.91016004 -1.92801998 0 P 0 
L 1.91016004 -1.92801998 1.91011998 -1.92798996 0 P 0 
L 1.91011998 -1.92798996 1.91006004 -1.92793002 0 P 0 
L 1.91006004 -1.92793002 1.90991004 -1.92781998 0 P 0 
L 1.90991004 -1.92781998 1.90988002 -1.9278 0 P 0 
L 1.90988002 -1.9278 1.90983996 -1.92776998 0 P 0 
L 1.90983996 -1.92776998 1.90976998 -1.92771998 0 P 0 
L 1.90976998 -1.92771998 1.90961004 -1.92761998 0 P 0 
L 1.90961004 -1.92761998 1.90953996 -1.92756998 0 P 0 
L 1.90953996 -1.92756998 1.9095 -1.92755 0 P 0 
L 1.9095 -1.92755 1.90946998 -1.92753002 0 P 0 
L 1.90946998 -1.92753002 1.9093 -1.92743996 0 P 0 
L 1.9093 -1.92743996 1.90926004 -1.92741998 0 P 0 
L 1.90926004 -1.92741998 1.90923002 -1.9274 0 P 0 
L 1.90923002 -1.9274 1.90915 -1.92736998 0 P 0 
L 1.90915 -1.92736998 1.90896998 -1.92728996 0 P 0 
L 1.90896998 -1.92728996 1.90893996 -1.92728002 0 P 0 
L 1.90893996 -1.92728002 1.9089 -1.92726004 0 P 0 
L 1.9089 -1.92726004 1.90886998 -1.92725 0 P 0 
L 1.90886998 -1.92725 1.90883002 -1.92723996 0 P 0 
L 1.90883002 -1.92723996 1.90816004 -1.92701004 0 P 0 
L 1.90816004 -1.92701004 1.90813996 -1.927 0 P 0 
L 1.90813996 -1.927 1.9081 -1.92698996 0 P 0 
L 1.9081 -1.92698996 1.90803996 -1.92696998 0 P 0 
L 1.90803996 -1.92696998 1.90736998 -1.92678002 0 P 0 
L 1.90736998 -1.92678002 1.90723996 -1.92675 0 P 0 
L 1.90723996 -1.92675 1.90643002 -1.92658996 0 P 0 
L 1.90643002 -1.92658996 1.90636998 -1.92656998 0 P 0 
L 1.90636998 -1.92656998 1.90633996 -1.92656998 0 P 0 
L 1.90633996 -1.92656998 1.90631004 -1.92656004 0 P 0 
L 1.90631004 -1.92656004 1.90548996 -1.92645 0 P 0 
L 1.90548996 -1.92645 1.90543996 -1.92643996 0 P 0 
L 1.90543996 -1.92643996 1.9054 -1.92643002 0 P 0 
L 1.9054 -1.92643002 1.90538002 -1.92643002 0 P 0 
L 1.90538002 -1.92643002 1.90455 -1.92636004 0 P 0 
L 1.90455 -1.92636004 1.90443002 -1.92636004 0 P 0 
L 1.90443002 -1.92636004 1.9036 -1.92633002 0 P 0 
L 1.9036 -1.92633002 1.8994 -1.92633002 0 P 0 
L 1.8994 -1.92633002 1.89798002 -1.92691004 0 P 0 
L 1.89798002 -1.92691004 1.8974 -1.92833002 0 P 0 
L 1.8974 -1.92833002 1.8974 -1.93328002 0 P 0 
L 1.8974 -1.93328002 1.89748002 -1.93643002 0 P 0 
L 1.89748002 -1.93643002 1.89748002 -1.93656004 0 P 0 
L 1.89748002 -1.93656004 1.8975 -1.93673002 0 P 0 
L 1.8975 -1.93673002 1.89751004 -1.93681004 0 P 0 
L 1.89751004 -1.93681004 1.89751998 -1.9369 0 P 0 
L 1.89751998 -1.9369 1.89755 -1.93706004 0 P 0 
L 1.89755 -1.93706004 1.89758002 -1.93718996 0 P 0 
L 1.89758002 -1.93718996 1.89758996 -1.93723002 0 P 0 
L 1.89758996 -1.93723002 1.89763002 -1.9374 0 P 0 
L 1.89763002 -1.9374 1.89763996 -1.93743996 0 P 0 
L 1.89763996 -1.93743996 1.89766004 -1.93748002 0 P 0 
L 1.89766004 -1.93748002 1.89768002 -1.93756004 0 P 0 
L 1.89768002 -1.93756004 1.89773996 -1.93771998 0 P 0 
L 1.89773996 -1.93771998 1.89776004 -1.93776004 0 P 0 
L 1.89776004 -1.93776004 1.89776998 -1.9378 0 P 0 
L 1.89776998 -1.9378 1.89781004 -1.93788002 0 P 0 
L 1.89781004 -1.93788002 1.89788002 -1.93803996 0 P 0 
L 1.89788002 -1.93803996 1.8979 -1.93808002 0 P 0 
L 1.8979 -1.93808002 1.89791998 -1.93811004 0 P 0 
L 1.89791998 -1.93811004 1.89796004 -1.93818996 0 P 0 
L 1.89796004 -1.93818996 1.89803996 -1.93833996 0 P 0 
L 1.89803996 -1.93833996 1.89813996 -1.93848002 0 P 0 
L 1.89813996 -1.93848002 1.89823002 -1.93861998 0 P 0 
L 1.89823002 -1.93861998 1.89828002 -1.93868996 0 P 0 
L 1.89828002 -1.93868996 1.89831004 -1.93873002 0 P 0 
L 1.89831004 -1.93873002 1.89833996 -1.93876004 0 P 0 
L 1.89833996 -1.93876004 1.8984 -1.93883996 0 P 0 
L 1.8984 -1.93883996 1.89848996 -1.93893002 0 P 0 
L 1.89848996 -1.93893002 1.89851004 -1.93896004 0 P 0 
L 1.89851004 -1.93896004 1.89868002 -1.93913002 0 P 0 
L 1.89868002 -1.93913002 1.89871004 -1.93915 0 P 0 
L 1.89871004 -1.93915 1.89878996 -1.93921998 0 P 0 
L 1.89878996 -1.93921998 1.89885 -1.93928002 0 P 0 
L 1.89885 -1.93928002 1.89888002 -1.9393 0 P 0 
L 1.89888002 -1.9393 1.89891998 -1.93931998 0 P 0 
L 1.89891998 -1.93931998 1.89901004 -1.93938996 0 P 0 
L 1.89901004 -1.93938996 1.89903996 -1.93941004 0 P 0 
L 1.89903996 -1.93941004 1.89906998 -1.93943996 0 P 0 
L 1.89906998 -1.93943996 1.8991 -1.93946004 0 P 0 
L 1.8991 -1.93946004 1.89913996 -1.93948002 0 P 0 
L 1.89913996 -1.93948002 1.89923002 -1.93953996 0 P 0 
L 1.89923002 -1.93953996 1.89926998 -1.93956004 0 P 0 
L 1.89926998 -1.93956004 1.8993 -1.93958002 0 P 0 
L 1.8993 -1.93958002 1.89933996 -1.9396 0 P 0 
L 1.89933996 -1.9396 1.89936998 -1.93961004 0 P 0 
L 1.89936998 -1.93961004 1.89938002 -1.93961004 0 P 0 
L 1.89938002 -1.93961004 1.89946998 -1.93966004 0 P 0 
L 1.89946998 -1.93966004 1.89953996 -1.9397 0 P 0 
L 1.89953996 -1.9397 1.89971998 -1.93976998 0 P 0 
L 1.89971998 -1.93976998 1.89975 -1.93978996 0 P 0 
L 1.89975 -1.93978996 1.89978996 -1.9398 0 P 0 
L 1.89978996 -1.9398 1.89986998 -1.93983002 0 P 0 
L 1.89986998 -1.93983002 1.89996998 -1.93986004 0 P 0 
L 1.89996998 -1.93986004 1.90001004 -1.93986998 0 P 0 
L 1.90001004 -1.93986998 1.90005 -1.93988996 0 P 0 
L 1.90005 -1.93988996 1.90013002 -1.9399 0 P 0 
L 1.90013002 -1.9399 1.90023002 -1.93993002 0 P 0 
L 1.90023002 -1.93993002 1.90023996 -1.93993002 0 P 0 
L 1.90023996 -1.93993002 1.90028002 -1.93993996 0 P 0 
L 1.90028002 -1.93993996 1.90031004 -1.93995 0 P 0 
L 1.90031004 -1.93995 1.90036004 -1.93995 0 P 0 
L 1.90036004 -1.93995 1.9004 -1.93996004 0 P 0 
L 1.9004 -1.93996004 1.9005 -1.93996998 0 P 0 
L 1.9005 -1.93996998 1.90061004 -1.93998996 0 P 0 
L 1.90061004 -1.93998996 1.90063996 -1.93998996 0 P 0 
L 1.90063996 -1.93998996 1.90181004 -1.94006998 0 P 0 
L 1.90181004 -1.94006998 1.90183996 -1.94008002 0 P 0 
L 1.90183996 -1.94008002 1.90191004 -1.94008002 0 P 0 
L 1.90191004 -1.94008002 1.90308002 -1.9401 0 P 0 
L 1.90308002 -1.9401 1.90311004 -1.9401 0 P 0 
L 1.90311004 -1.9401 1.90313996 -1.94011004 0 P 0 
L 1.90841004 -1.97146004 1.91683996 -1.97146004 0 P 0 
L 1.9135 -1.97046004 1.91931004 -1.97046004 0 P 0 
L 1.91655 -1.96946004 1.92131004 -1.96946004 0 P 0 
L 1.91891998 -1.96846004 1.92301004 -1.96846004 0 P 0 
L 1.92088996 -1.96746004 1.9245 -1.96746004 0 P 0 
L 1.92251004 -1.96646004 1.9258 -1.96646004 0 P 0 
L 1.92391004 -1.96546004 1.92696004 -1.96546004 0 P 0 
L 1.92513002 -1.96446004 1.92803002 -1.96446004 0 P 0 
L 1.9262 -1.96346004 1.92898996 -1.96346004 0 P 0 
L 1.92713996 -1.96246004 1.92986004 -1.96246004 0 P 0 
L 1.928 -1.96146004 1.93068996 -1.96146004 0 P 0 
L 1.92878002 -1.96046004 1.93143002 -1.96046004 0 P 0 
L 1.92951004 -1.95946004 1.93216004 -1.95946004 0 P 0 
L 1.93016998 -1.95846004 1.93278996 -1.95846004 0 P 0 
L 1.93078002 -1.95746004 1.93341004 -1.95746004 0 P 0 
L 1.93133002 -1.95646004 1.93396004 -1.95646004 0 P 0 
L 1.93185 -1.95546004 1.93448996 -1.95546004 0 P 0 
L 1.93231004 -1.95446004 1.93495 -1.95446004 0 P 0 
L 1.93275 -1.95346004 1.93541004 -1.95346004 0 P 0 
L 1.93311998 -1.95246004 1.93586004 -1.95246004 0 P 0 
L 1.93348002 -1.95146004 1.93628996 -1.95146004 0 P 0 
L 1.93376998 -1.95046004 1.93666004 -1.95046004 0 P 0 
L 1.93405 -1.94946004 1.93693002 -1.94946004 0 P 0 
L 1.93428002 -1.94846004 1.93715 -1.94846004 0 P 0 
L 1.93446998 -1.94746004 1.93733002 -1.94746004 0 P 0 
L 1.93466004 -1.94646004 1.93743002 -1.94646004 0 P 0 
L 1.93478996 -1.94546004 1.93748996 -1.94546004 0 P 0 
L 1.9349 -1.94446998 1.93751998 -1.94446998 0 P 0 
L 1.93496998 -1.94346004 1.93755 -1.94346004 0 P 0 
L 1.93501998 -1.94246004 1.93758002 -1.94246004 0 P 0 
L 1.93505 -1.94146998 1.93758996 -1.94146998 0 P 0 
L 1.93503002 -1.94046004 1.93755 -1.94046004 0 P 0 
L 1.935 -1.93946004 1.93751998 -1.93946004 0 P 0 
L 1.93491998 -1.93846004 1.93748002 -1.93846004 0 P 0 
L 1.93481004 -1.93746004 1.93738996 -1.93746004 0 P 0 
L 1.93468996 -1.93646004 1.93726998 -1.93646004 0 P 0 
L 1.93451004 -1.93546004 1.93716004 -1.93546004 0 P 0 
L 1.93433002 -1.93446004 1.93703996 -1.93446004 0 P 0 
L 1.93408996 -1.93346004 1.93685 -1.93346004 0 P 0 
L 1.93383002 -1.93246004 1.93666004 -1.93246004 0 P 0 
L 1.93353002 -1.93146004 1.93638996 -1.93146004 0 P 0 
L 1.9332 -1.93046004 1.93611998 -1.93046004 0 P 0 
L 1.93283996 -1.92946004 1.93576998 -1.92946004 0 P 0 
L 1.93241004 -1.92846004 1.93541004 -1.92846004 0 P 0 
L 1.93198996 -1.92746004 1.93498002 -1.92746004 0 P 0 
L 1.93146998 -1.92646004 1.93451004 -1.92646004 0 P 0 
L 1.93096004 -1.92546004 1.93398002 -1.92546004 0 P 0 
L 1.93035 -1.92446998 1.93338002 -1.92446998 0 P 0 
L 1.92973002 -1.92346004 1.93275 -1.92346004 0 P 0 
L 1.92903002 -1.92246004 1.93201004 -1.92246004 0 P 0 
L 1.92831004 -1.92146004 1.93125 -1.92146004 0 P 0 
L 1.92746998 -1.92046004 1.93041004 -1.92046004 0 P 0 
L 1.92661004 -1.91946004 1.92948996 -1.91946004 0 P 0 
L 1.92558996 -1.91846004 1.92851004 -1.91846004 0 P 0 
L 1.9245 -1.91746004 1.92741998 -1.91746004 0 P 0 
L 1.92328996 -1.91646004 1.92621998 -1.91646004 0 P 0 
L 1.92188002 -1.91546004 1.92491998 -1.91546004 0 P 0 
L 1.92026004 -1.91446004 1.92358996 -1.91446004 0 P 0 
L 1.91835 -1.91346004 1.92208002 -1.91346004 0 P 0 
L 1.82446998 -2.08323996 1.87608002 -2.08323996 0 P 0 
L 1.82403002 -2.08223996 1.87601004 -2.08223996 0 P 0 
L 1.8234 -2.08123996 1.87591004 -2.08123996 0 P 0 
L 1.82256004 -2.08023996 1.87578002 -2.08023996 0 P 0 
L 1.82166004 -2.07923996 1.87558996 -2.07923996 0 P 0 
L 1.82061998 -2.07823996 1.87533002 -2.07823996 0 P 0 
L 1.81946004 -2.07723996 1.87498996 -2.07723996 0 P 0 
L 1.81818002 -2.07623996 1.8746 -2.07623996 0 P 0 
L 1.8168 -2.07523996 1.87416998 -2.07523996 0 P 0 
L 1.81541998 -2.07423996 1.87371004 -2.07423996 0 P 0 
L 1.81403002 -2.07323996 1.87316998 -2.07323996 0 P 0 
L 1.81265 -2.07223996 1.87261004 -2.07223996 0 P 0 
L 1.81126998 -2.07123996 1.87196004 -2.07123996 0 P 0 
L 1.80986004 -2.07023996 1.87128002 -2.07023996 0 P 0 
L 1.80843996 -2.06923996 1.87051998 -2.06923996 0 P 0 
L 1.80703002 -2.06823996 1.8697 -2.06823996 0 P 0 
L 1.80561004 -2.06723996 1.86883002 -2.06723996 0 P 0 
L 1.8042 -2.06623996 1.86796004 -2.06623996 0 P 0 
L 1.80278002 -2.06523996 1.86705 -2.06523996 0 P 0 
L 1.80136004 -2.06423996 1.86608002 -2.06423996 0 P 0 
L 1.79995 -2.06323996 1.8651 -2.06323996 0 P 0 
L 1.79865 -2.06223996 1.86411004 -2.06223996 0 P 0 
L 1.79735 -2.06123996 1.86301998 -2.06123996 0 P 0 
L 1.79605 -2.06023996 1.86193002 -2.06023996 0 P 0 
L 1.79475 -2.05923996 1.86083996 -2.05923996 0 P 0 
L 1.79345 -2.05823996 1.85966998 -2.05823996 0 P 0 
L 1.79215 -2.05723996 1.85846004 -2.05723996 0 P 0 
L 1.79088002 -2.05623996 1.85726004 -2.05623996 0 P 0 
L 1.78971998 -2.05523996 1.85598996 -2.05523996 0 P 0 
L 1.78856004 -2.05423996 1.85461998 -2.05423996 0 P 0 
L 1.7874 -2.05323996 1.85326004 -2.05323996 0 P 0 
L 1.78623002 -2.05223996 1.8519 -2.05223996 0 P 0 
L 1.78506998 -2.05123996 1.85053996 -2.05123996 0 P 0 
L 1.78398002 -2.05023996 1.84918002 -2.05023996 0 P 0 
L 1.783 -2.04923996 1.84781004 -2.04923996 0 P 0 
L 1.87086004 -2.03023996 1.87535 -2.03023996 0 P 0 
L 1.91633002 -1.91473002 1.9183 -1.91565 0 P 0 
L 1.9183 -1.91565 1.92018996 -1.91673002 0 P 0 
L 1.92018996 -1.91673002 1.92196998 -1.91796998 0 P 0 
L 1.92196998 -1.91796998 1.92365 -1.91936004 0 P 0 
L 1.92365 -1.91936004 1.9252 -1.92088002 0 P 0 
L 1.9252 -1.92088002 1.92661004 -1.92253996 0 P 0 
L 1.92661004 -1.92253996 1.92795 -1.92436998 0 P 0 
L 1.92795 -1.92436998 1.92913996 -1.9263 0 P 0 
L 1.92913996 -1.9263 1.93018002 -1.92831998 0 P 0 
L 1.93018002 -1.92831998 1.93106998 -1.93041004 0 P 0 
L 1.93106998 -1.93041004 1.93178996 -1.93256004 0 P 0 
L 1.93178996 -1.93256004 1.93236004 -1.93476004 0 P 0 
L 1.93236004 -1.93476004 1.93276004 -1.93703996 0 P 0 
L 1.93276004 -1.93703996 1.93298996 -1.93933996 0 P 0 
L 1.93298996 -1.93933996 1.93306004 -1.94165 0 P 0 
L 1.93306004 -1.94165 1.93295 -1.94396998 0 P 0 
L 1.93295 -1.94396998 1.93268002 -1.94626004 0 P 0 
L 1.93268002 -1.94626004 1.93223002 -1.94853996 0 P 0 
L 1.93223002 -1.94853996 1.93161998 -1.95071998 0 P 0 
L 1.93161998 -1.95071998 1.93085 -1.95285 0 P 0 
L 1.93085 -1.95285 1.92991004 -1.95491004 0 P 0 
L 1.92991004 -1.95491004 1.92881004 -1.95688996 0 P 0 
L 1.92881004 -1.95688996 1.92756004 -1.95878002 0 P 0 
L 1.92756004 -1.95878002 1.92616004 -1.96056998 0 P 0 
L 1.92616004 -1.96056998 1.92493996 -1.9619 0 P 0 
L 1.92493996 -1.9619 1.92361998 -1.96313996 0 P 0 
L 1.92361998 -1.96313996 1.9222 -1.96426004 0 P 0 
L 1.9222 -1.96426004 1.9207 -1.96526998 0 P 0 
L 1.9207 -1.96526998 1.91911004 -1.96616998 0 P 0 
L 1.91911004 -1.96616998 1.91686998 -1.96721004 0 P 0 
L 1.91686998 -1.96721004 1.91456004 -1.96806998 0 P 0 
L 1.91456004 -1.96806998 1.91218996 -1.96876004 0 P 0 
L 1.91218996 -1.96876004 1.90975 -1.96926998 0 P 0 
L 1.90975 -1.96926998 1.90725 -1.9696 0 P 0 
L 1.90725 -1.9696 1.90473002 -1.96973996 0 P 0 
L 1.90473002 -1.96973996 1.9022 -1.96968996 0 P 0 
L 1.9022 -1.96968996 1.89966998 -1.96945 0 P 0 
L 1.89966998 -1.96945 1.89778002 -1.96913002 0 P 0 
L 1.89778002 -1.96913002 1.89591998 -1.96868996 0 P 0 
L 1.89591998 -1.96868996 1.8941 -1.96811004 0 P 0 
L 1.8941 -1.96811004 1.89231004 -1.96741004 0 P 0 
L 1.89231004 -1.96741004 1.89058002 -1.96658002 0 P 0 
L 1.89058002 -1.96658002 1.88875 -1.96553996 0 P 0 
L 1.88875 -1.96553996 1.88698996 -1.96435 0 P 0 
L 1.88698996 -1.96435 1.88533996 -1.96303002 0 P 0 
L 1.88533996 -1.96303002 1.88378996 -1.9616 0 P 0 
L 1.88378996 -1.9616 1.88235 -1.96003996 0 P 0 
L 1.88235 -1.96003996 1.88103002 -1.95838996 0 P 0 
L 1.88103002 -1.95838996 1.87983996 -1.95663002 0 P 0 
L 1.87983996 -1.95663002 1.87861998 -1.95446998 0 P 0 
L 1.87861998 -1.95446998 1.87758002 -1.9522 0 P 0 
L 1.87758002 -1.9522 1.87673996 -1.94986004 0 P 0 
L 1.87673996 -1.94986004 1.8761 -1.94745 0 P 0 
L 1.8761 -1.94745 1.87568002 -1.945 0 P 0 
L 1.87568002 -1.945 1.87546004 -1.94248996 0 P 0 
L 1.87546004 -1.94248996 1.87546004 -1.93998996 0 P 0 
L 1.87546004 -1.93998996 1.87566998 -1.93748996 0 P 0 
L 1.87566998 -1.93748996 1.87608996 -1.93501998 0 P 0 
L 1.87608996 -1.93501998 1.87671998 -1.9326 0 P 0 
L 1.87671998 -1.9326 1.87755 -1.93023002 0 P 0 
L 1.87755 -1.93023002 1.8786 -1.92793002 0 P 0 
L 1.8786 -1.92793002 1.87981998 -1.92575 0 P 0 
L 1.87981998 -1.92575 1.88123002 -1.92368002 0 P 0 
L 1.88123002 -1.92368002 1.88281004 -1.92175 0 P 0 
L 1.88281004 -1.92175 1.88455 -1.91996004 0 P 0 
L 1.88455 -1.91996004 1.88643002 -1.91831998 0 P 0 
L 1.88643002 -1.91831998 1.88845 -1.91686004 0 P 0 
L 1.88845 -1.91686004 1.88986998 -1.91598996 0 P 0 
L 1.88986998 -1.91598996 1.89135 -1.91523002 0 P 0 
L 1.89135 -1.91523002 1.89288002 -1.91458996 0 P 0 
L 1.89288002 -1.91458996 1.89446998 -1.91406004 0 P 0 
L 1.89446998 -1.91406004 1.89688996 -1.91343996 0 P 0 
L 1.89688996 -1.91343996 1.89935 -1.91298996 0 P 0 
L 1.89935 -1.91298996 1.90183996 -1.91271004 0 P 0 
L 1.90183996 -1.91271004 1.9044 -1.91261004 0 P 0 
L 1.9044 -1.91261004 1.90695 -1.91268002 0 P 0 
L 1.90695 -1.91268002 1.90948996 -1.91291998 0 P 0 
L 1.90948996 -1.91291998 1.91181998 -1.91331998 0 P 0 
L 1.91181998 -1.91331998 1.91408996 -1.91393002 0 P 0 
L 1.91408996 -1.91393002 1.91633002 -1.91473002 0 P 0 
L 1.89498002 -1.90801998 1.8922 -1.90893002 0 P 0 
L 1.8922 -1.90893002 1.88948002 -1.91003002 0 P 0 
L 1.88948002 -1.91003002 1.88686004 -1.91133002 0 P 0 
L 1.88686004 -1.91133002 1.88431004 -1.91283996 0 P 0 
L 1.88431004 -1.91283996 1.88201004 -1.91446004 0 P 0 
L 1.88201004 -1.91446004 1.87985 -1.91626998 0 P 0 
L 1.87985 -1.91626998 1.87785 -1.91826004 0 P 0 
L 1.87785 -1.91826004 1.87601998 -1.92041004 0 P 0 
L 1.87601998 -1.92041004 1.87441004 -1.92266998 0 P 0 
L 1.87441004 -1.92266998 1.87298996 -1.92505 0 P 0 
L 1.87298996 -1.92505 1.87178002 -1.92756004 0 P 0 
L 1.87178002 -1.92756004 1.87078996 -1.93015 0 P 0 
L 1.87078996 -1.93015 1.87 -1.93286998 0 P 0 
L 1.87 -1.93286998 1.86943996 -1.93563996 0 P 0 
L 1.86943996 -1.93563996 1.86908996 -1.93845 0 P 0 
L 1.86908996 -1.93845 1.86898002 -1.94128996 0 P 0 
L 1.86898002 -1.94128996 1.86911998 -1.94485 0 P 0 
L 1.86911998 -1.94485 1.86953996 -1.94841004 0 P 0 
L 1.86953996 -1.94841004 1.86996004 -1.95048996 0 P 0 
L 1.86996004 -1.95048996 1.87053002 -1.95251998 0 P 0 
L 1.87053002 -1.95251998 1.87125 -1.95451998 0 P 0 
L 1.87125 -1.95451998 1.87211004 -1.95643002 0 P 0 
L 1.87211004 -1.95643002 1.8731 -1.95826004 0 P 0 
L 1.8731 -1.95826004 1.87423996 -1.96001998 0 P 0 
L 1.87423996 -1.96001998 1.87636998 -1.96278996 0 P 0 
L 1.87636998 -1.96278996 1.87871998 -1.96536998 0 P 0 
L 1.87871998 -1.96536998 1.88145 -1.96788002 0 P 0 
L 1.88145 -1.96788002 1.88436998 -1.97015 0 P 0 
L 1.88436998 -1.97015 1.88621004 -1.97135 0 P 0 
L 1.88621004 -1.97135 1.88813002 -1.97238002 0 P 0 
L 1.88813002 -1.97238002 1.89013002 -1.97326004 0 P 0 
L 1.89013002 -1.97326004 1.89228002 -1.97398996 0 P 0 
L 1.89228002 -1.97398996 1.89446998 -1.97455 0 P 0 
L 1.89446998 -1.97455 1.89671004 -1.97493996 0 P 0 
L 1.89671004 -1.97493996 1.90076998 -1.97533996 0 P 0 
L 1.90076998 -1.97533996 1.90485 -1.97546998 0 P 0 
L 1.90485 -1.97546998 1.90821004 -1.97531998 0 P 0 
L 1.90821004 -1.97531998 1.91153996 -1.97488996 0 P 0 
L 1.91153996 -1.97488996 1.91481998 -1.97418996 0 P 0 
L 1.91481998 -1.97418996 1.9171 -1.9735 0 P 0 
L 1.9171 -1.9735 1.91933002 -1.97266004 0 P 0 
L 1.91933002 -1.97266004 1.92148002 -1.97166004 0 P 0 
L 1.92148002 -1.97166004 1.92356998 -1.97048996 0 P 0 
L 1.92356998 -1.97048996 1.92553996 -1.96918996 0 P 0 
L 1.92553996 -1.96918996 1.92741004 -1.96773996 0 P 0 
L 1.92741004 -1.96773996 1.92916004 -1.96616998 0 P 0 
L 1.92916004 -1.96616998 1.93081004 -1.96446004 0 P 0 
L 1.93081004 -1.96446004 1.93236998 -1.96256998 0 P 0 
L 1.93236998 -1.96256998 1.93381004 -1.96058996 0 P 0 
L 1.93381004 -1.96058996 1.93511998 -1.95851004 0 P 0 
L 1.93511998 -1.95851004 1.93628996 -1.95633996 0 P 0 
L 1.93628996 -1.95633996 1.93803996 -1.95251998 0 P 0 
L 1.93803996 -1.95251998 1.93858002 -1.95101998 0 P 0 
L 1.93858002 -1.95101998 1.93898996 -1.94948002 0 P 0 
L 1.93898996 -1.94948002 1.93928996 -1.94786998 0 P 0 
L 1.93928996 -1.94786998 1.93946004 -1.94625 0 P 0 
L 1.93946004 -1.94625 1.9396 -1.94178002 0 P 0 
L 1.9396 -1.94178002 1.93946004 -1.93803996 0 P 0 
L 1.93946004 -1.93803996 1.93905 -1.9343 0 P 0 
L 1.93905 -1.9343 1.93863996 -1.93213996 0 P 0 
L 1.93863996 -1.93213996 1.93808002 -1.93001998 0 P 0 
L 1.93808002 -1.93001998 1.93736004 -1.92795 0 P 0 
L 1.93736004 -1.92795 1.93653002 -1.92601004 0 P 0 
L 1.93653002 -1.92601004 1.93555 -1.92415 0 P 0 
L 1.93555 -1.92415 1.93441998 -1.92236004 0 P 0 
L 1.93441998 -1.92236004 1.9331 -1.92056004 0 P 0 
L 1.9331 -1.92056004 1.93166998 -1.91885 0 P 0 
L 1.93166998 -1.91885 1.93011998 -1.91723002 0 P 0 
L 1.93011998 -1.91723002 1.92896004 -1.91615 0 P 0 
L 1.92896004 -1.91615 1.92775 -1.91511004 0 P 0 
L 1.92775 -1.91511004 1.92493002 -1.91295 0 P 0 
L 1.92493002 -1.91295 1.9221 -1.91108002 0 P 0 
L 1.9221 -1.91108002 1.92095 -1.91043002 0 P 0 
L 1.92095 -1.91043002 1.91975 -1.90985 0 P 0 
L 1.91975 -1.90985 1.91796004 -1.90913996 0 P 0 
L 1.91796004 -1.90913996 1.91613002 -1.90856004 0 P 0 
L 1.91613002 -1.90856004 1.91423996 -1.9081 0 P 0 
L 1.91423996 -1.9081 1.91086004 -1.90751998 0 P 0 
L 1.91086004 -1.90751998 1.90743002 -1.90716004 0 P 0 
L 1.90743002 -1.90716004 1.90401004 -1.90701004 0 P 0 
L 1.90401004 -1.90701004 1.90058002 -1.90708002 0 P 0 
L 1.90058002 -1.90708002 1.8987 -1.90726004 0 P 0 
L 1.8987 -1.90726004 1.89683002 -1.90756998 0 P 0 
L 1.89683002 -1.90756998 1.89498002 -1.90801998 0 P 0 
L 1.86643002 -2.02923996 1.87525 -2.02923996 0 P 0 
L 1.86176998 -2.02823996 1.87515 -2.02823996 0 P 0 
L 1.85588996 -2.02723996 1.87505 -2.02723996 0 P 0 
L 1.78365 -2.00523996 1.87281004 -2.00523996 0 P 0 
L 1.78451004 -2.00423996 1.87271004 -2.00423996 0 P 0 
L 1.78546998 -2.00323996 1.87261004 -2.00323996 0 P 0 
L 1.78655 -2.00223996 1.8725 -2.00223996 0 P 0 
L 1.78776004 -2.00123996 1.8724 -2.00123996 0 P 0 
L 1.78915 -2.00023996 1.8723 -2.00023996 0 P 0 
L 1.79078996 -1.99923996 1.8722 -1.99923996 0 P 0 
L 1.79263996 -1.99823996 1.87208996 -1.99823996 0 P 0 
L 1.79458996 -1.99723996 1.87198996 -1.99723996 0 P 0 
L 1.79686998 -1.99623996 1.87188002 -1.99623996 0 P 0 
L 1.79946004 -1.99523996 1.87178002 -1.99523996 0 P 0 
L 1.80231004 -1.99423996 1.86961998 -1.99423996 0 P 0 
L 1.80596004 -1.99323996 1.86218002 -1.99323996 0 P 0 
L 1.81051004 -1.99223996 1.85398002 -1.99223996 0 P 0 
L 1.81676004 -1.99123996 1.84395 -1.99123996 0 P 0 
L 1.87786998 -1.96146004 1.88093996 -1.96146004 0 P 0 
L 1.8771 -1.96046004 1.88013002 -1.96046004 0 P 0 
L 1.87633996 -1.95946004 1.87933996 -1.95946004 0 P 0 
L 1.87561998 -1.95846004 1.87866998 -1.95846004 0 P 0 
L 1.87496998 -1.95746004 1.87801998 -1.95746004 0 P 0 
L 1.8744 -1.95646004 1.87745 -1.95646004 0 P 0 
L 1.87386998 -1.95546004 1.87688002 -1.95546004 0 P 0 
L 1.87341998 -1.95446004 1.87641998 -1.95446004 0 P 0 
L 1.87298996 -1.95346004 1.87596004 -1.95346004 0 P 0 
L 1.87263002 -1.95246004 1.87555 -1.95246004 0 P 0 
L 1.87231004 -1.95146004 1.87518996 -1.95146004 0 P 0 
L 1.87203002 -1.95046004 1.87483002 -1.95046004 0 P 0 
L 1.87178996 -1.94946004 1.87456998 -1.94946004 0 P 0 
L 1.87158996 -1.94846004 1.87431004 -1.94846004 0 P 0 
L 1.87143996 -1.94746004 1.87408002 -1.94746004 0 P 0 
L 1.87133002 -1.94646004 1.8739 -1.94646004 0 P 0 
L 1.87121004 -1.94546004 1.87373002 -1.94546004 0 P 0 
L 1.8711 -1.94446998 1.87361998 -1.94446998 0 P 0 
L 1.87106998 -1.94346004 1.87353996 -1.94346004 0 P 0 
L 1.87103002 -1.94246004 1.87346004 -1.94246004 0 P 0 
L 1.87098996 -1.94146998 1.87346004 -1.94146998 0 P 0 
L 1.87101004 -1.94046004 1.87346004 -1.94046004 0 P 0 
L 1.87106004 -1.93946004 1.87348996 -1.93946004 0 P 0 
L 1.87111004 -1.93846004 1.87358002 -1.93846004 0 P 0 
L 1.87123002 -1.93746004 1.87366004 -1.93746004 0 P 0 
L 1.87135 -1.93646004 1.87381998 -1.93646004 0 P 0 
L 1.87151004 -1.93546004 1.87398996 -1.93546004 0 P 0 
L 1.87171998 -1.93446004 1.87416998 -1.93446004 0 P 0 
L 1.87191998 -1.93346004 1.87443002 -1.93346004 0 P 0 
L 1.8722 -1.93246004 1.87468996 -1.93246004 0 P 0 
L 1.87248996 -1.93146004 1.875 -1.93146004 0 P 0 
L 1.87281004 -1.93046004 1.87535 -1.93046004 0 P 0 
L 1.87318996 -1.92946004 1.87571004 -1.92946004 0 P 0 
L 1.87356998 -1.92846004 1.87616004 -1.92846004 0 P 0 
L 1.87405 -1.92746004 1.87661004 -1.92746004 0 P 0 
L 1.87453002 -1.92646004 1.87711998 -1.92646004 0 P 0 
L 1.87506998 -1.92546004 1.87768996 -1.92546004 0 P 0 
L 1.87566004 -1.92446998 1.87826998 -1.92446998 0 P 0 
L 1.87628996 -1.92346004 1.87896004 -1.92346004 0 P 0 
L 1.87701004 -1.92246004 1.87963996 -1.92246004 0 P 0 
L 1.87775 -1.92146004 1.88046004 -1.92146004 0 P 0 
L 1.90483996 -1.97346004 1.9009 -1.97333996 0 P 0 
L 1.9009 -1.97333996 1.89698002 -1.97295 0 P 0 
L 1.89698002 -1.97295 1.89488996 -1.97258996 0 P 0 
L 1.89488996 -1.97258996 1.89285 -1.97206998 0 P 0 
L 1.89285 -1.97206998 1.89086004 -1.97138996 0 P 0 
L 1.89086004 -1.97138996 1.889 -1.97058002 0 P 0 
L 1.889 -1.97058002 1.88723002 -1.96961998 0 P 0 
L 1.88723002 -1.96961998 1.88553002 -1.96851998 0 P 0 
L 1.88553002 -1.96851998 1.88273996 -1.96636004 0 P 0 
L 1.88273996 -1.96636004 1.88013996 -1.96396004 0 P 0 
L 1.88013996 -1.96396004 1.8779 -1.9615 0 P 0 
L 1.8779 -1.9615 1.87588002 -1.95886998 0 P 0 
L 1.87588002 -1.95886998 1.87483002 -1.95723996 0 P 0 
L 1.87483002 -1.95723996 1.8739 -1.95553996 0 P 0 
L 1.8739 -1.95553996 1.87311004 -1.95376998 0 P 0 
L 1.87311004 -1.95376998 1.87243002 -1.95191004 0 P 0 
L 1.87243002 -1.95191004 1.8719 -1.95001998 0 P 0 
L 1.8719 -1.95001998 1.87151998 -1.9481 0 P 0 
L 1.87151998 -1.9481 1.87111004 -1.94468996 0 P 0 
L 1.87111004 -1.94468996 1.87098002 -1.94128996 0 P 0 
L 1.87098002 -1.94128996 1.87108996 -1.93861004 0 P 0 
L 1.87108996 -1.93861004 1.87141004 -1.93596998 0 P 0 
L 1.87141004 -1.93596998 1.87195 -1.93335 0 P 0 
L 1.87195 -1.93335 1.87268996 -1.93078996 0 P 0 
L 1.87268996 -1.93078996 1.87361998 -1.92835 0 P 0 
L 1.87361998 -1.92835 1.87475 -1.926 0 P 0 
L 1.87475 -1.926 1.87608996 -1.92376004 0 P 0 
L 1.87608996 -1.92376004 1.8776 -1.92163996 0 P 0 
L 1.8776 -1.92163996 1.87931998 -1.91961998 0 P 0 
L 1.87931998 -1.91961998 1.8812 -1.91775 0 P 0 
L 1.8812 -1.91775 1.88323002 -1.91605 0 P 0 
L 1.88323002 -1.91605 1.8854 -1.91451998 0 P 0 
L 1.8854 -1.91451998 1.88781004 -1.91308996 0 P 0 
L 1.88781004 -1.91308996 1.89031004 -1.91186004 0 P 0 
L 1.89031004 -1.91186004 1.89288002 -1.9108 0 P 0 
L 1.89288002 -1.9108 1.89553002 -1.90995 0 P 0 
L 1.89553002 -1.90995 1.89723002 -1.90953002 0 P 0 
L 1.89723002 -1.90953002 1.89896004 -1.90923996 0 P 0 
L 1.89896004 -1.90923996 1.90068996 -1.90908002 0 P 0 
L 1.90068996 -1.90908002 1.90398996 -1.90901004 0 P 0 
L 1.90398996 -1.90901004 1.90728002 -1.90915 0 P 0 
L 1.90728002 -1.90915 1.91058996 -1.90951004 0 P 0 
L 1.91058996 -1.90951004 1.91383996 -1.91006004 0 P 0 
L 1.91383996 -1.91006004 1.91558996 -1.91048996 0 P 0 
L 1.91558996 -1.91048996 1.91728996 -1.91101998 0 P 0 
L 1.91728996 -1.91101998 1.91895 -1.91168002 0 P 0 
L 1.91895 -1.91168002 1.92001998 -1.9122 0 P 0 
L 1.92001998 -1.9122 1.92105 -1.91278996 0 P 0 
L 1.92105 -1.91278996 1.92376998 -1.91458002 0 P 0 
L 1.92376998 -1.91458002 1.92648996 -1.91666998 0 P 0 
L 1.92648996 -1.91666998 1.92763002 -1.91763996 0 P 0 
L 1.92763002 -1.91763996 1.92871004 -1.91865 0 P 0 
L 1.92871004 -1.91865 1.93018002 -1.92018996 0 P 0 
L 1.93018002 -1.92018996 1.93153002 -1.9218 0 P 0 
L 1.93153002 -1.9218 1.93276998 -1.92348996 0 P 0 
L 1.93276998 -1.92348996 1.93381004 -1.92515 0 P 0 
L 1.93381004 -1.92515 1.93471998 -1.92686998 0 P 0 
L 1.93471998 -1.92686998 1.9355 -1.92866998 0 P 0 
L 1.9355 -1.92866998 1.93616998 -1.93061004 0 P 0 
L 1.93616998 -1.93061004 1.93668996 -1.93258002 0 P 0 
L 1.93668996 -1.93258002 1.93706998 -1.93458996 0 P 0 
L 1.93706998 -1.93458996 1.93746998 -1.93818996 0 P 0 
L 1.93746998 -1.93818996 1.9376 -1.94178996 0 P 0 
L 1.9376 -1.94178996 1.93746004 -1.94611004 0 P 0 
L 1.93746004 -1.94611004 1.93731004 -1.94758996 0 P 0 
L 1.93731004 -1.94758996 1.93705 -1.94903996 0 P 0 
L 1.93705 -1.94903996 1.93666998 -1.95041998 0 P 0 
L 1.93666998 -1.95041998 1.93618002 -1.95176004 0 P 0 
L 1.93618002 -1.95176004 1.9345 -1.95545 0 P 0 
L 1.9345 -1.95545 1.93338996 -1.9575 0 P 0 
L 1.93338996 -1.9575 1.93216004 -1.95946998 0 P 0 
L 1.93216004 -1.95946998 1.93078996 -1.96133996 0 P 0 
L 1.93078996 -1.96133996 1.92931004 -1.96311998 0 P 0 
L 1.92931004 -1.96311998 1.92776998 -1.96473002 0 P 0 
L 1.92776998 -1.96473002 1.92613002 -1.96621004 0 P 0 
L 1.92613002 -1.96621004 1.92438002 -1.96756004 0 P 0 
L 1.92438002 -1.96756004 1.92253002 -1.96878002 0 P 0 
L 1.92253002 -1.96878002 1.92056998 -1.96986998 0 P 0 
L 1.92056998 -1.96986998 1.91855 -1.97081998 0 P 0 
L 1.91855 -1.97081998 1.91646004 -1.97161004 0 P 0 
L 1.91646004 -1.97161004 1.91433002 -1.97223996 0 P 0 
L 1.91433002 -1.97223996 1.9112 -1.97291004 0 P 0 
L 1.9112 -1.97291004 1.90803996 -1.97331998 0 P 0 
L 1.90803996 -1.97331998 1.90483996 -1.97346004 0 P 0 
L 1.90476004 -1.97173996 1.9048 -1.97173996 0 P 0 
L 1.9048 -1.97173996 1.90483996 -1.97173002 0 P 0 
L 1.90483996 -1.97173002 1.90736004 -1.9716 0 P 0 
L 1.90736004 -1.9716 1.9074 -1.97158996 0 P 0 
L 1.9074 -1.97158996 1.90746998 -1.97158996 0 P 0 
L 1.90746998 -1.97158996 1.90751004 -1.97158002 0 P 0 
L 1.90751004 -1.97158002 1.91001004 -1.97126004 0 P 0 
L 1.91001004 -1.97126004 1.91005 -1.97125 0 P 0 
L 1.91005 -1.97125 1.91008002 -1.97123996 0 P 0 
L 1.91008002 -1.97123996 1.91011998 -1.97123996 0 P 0 
L 1.91011998 -1.97123996 1.91016004 -1.97123002 0 P 0 
L 1.91016004 -1.97123002 1.9126 -1.97071998 0 P 0 
L 1.9126 -1.97071998 1.9126 -1.97071004 0 P 0 
L 1.9126 -1.97071004 1.91266998 -1.97071004 0 P 0 
L 1.91266998 -1.97071004 1.91271004 -1.97068996 0 P 0 
L 1.91271004 -1.97068996 1.91275 -1.97068002 0 P 0 
L 1.91275 -1.97068002 1.91511998 -1.96998996 0 P 0 
L 1.91511998 -1.96998996 1.91515 -1.96998996 0 P 0 
L 1.91515 -1.96998996 1.91518996 -1.96996998 0 P 0 
L 1.91518996 -1.96996998 1.91523002 -1.96996004 0 P 0 
L 1.91523002 -1.96996004 1.91526004 -1.96995 0 P 0 
L 1.91526004 -1.96995 1.91756998 -1.96908002 0 P 0 
L 1.91756998 -1.96908002 1.91761004 -1.96906998 0 P 0 
L 1.91761004 -1.96906998 1.91768002 -1.96903996 0 P 0 
L 1.91768002 -1.96903996 1.91771004 -1.96901998 0 P 0 
L 1.91771004 -1.96901998 1.91995 -1.96798002 0 P 0 
L 1.91995 -1.96798002 1.92001998 -1.96795 0 P 0 
L 1.92001998 -1.96795 1.92005 -1.96793002 0 P 0 
L 1.92005 -1.96793002 1.92008996 -1.96791004 0 P 0 
L 1.92008996 -1.96791004 1.92168002 -1.96701998 0 P 0 
L 1.92168002 -1.96701998 1.92171998 -1.967 0 P 0 
L 1.92171998 -1.967 1.92175 -1.96698002 0 P 0 
L 1.92175 -1.96698002 1.92178996 -1.96695 0 P 0 
L 1.92178996 -1.96695 1.92181998 -1.96693002 0 P 0 
L 1.92181998 -1.96693002 1.92331998 -1.96591998 0 P 0 
L 1.92331998 -1.96591998 1.92336004 -1.9659 0 P 0 
L 1.92336004 -1.9659 1.92341998 -1.96586004 0 P 0 
L 1.92341998 -1.96586004 1.92345 -1.96583002 0 P 0 
L 1.92345 -1.96583002 1.92486004 -1.9647 0 P 0 
L 1.92486004 -1.9647 1.92493002 -1.96465 0 P 0 
L 1.92493002 -1.96465 1.92496004 -1.96463002 0 P 0 
L 1.92496004 -1.96463002 1.92498996 -1.9646 0 P 0 
L 1.92498996 -1.9646 1.92631004 -1.96336998 0 P 0 
L 1.92631004 -1.96336998 1.9264 -1.96328002 0 P 0 
L 1.9264 -1.96328002 1.92641998 -1.96325 0 P 0 
L 1.92641998 -1.96325 1.92763996 -1.96191998 0 P 0 
L 1.92763996 -1.96191998 1.92766998 -1.96188996 0 P 0 
L 1.92766998 -1.96188996 1.92768996 -1.96186004 0 P 0 
L 1.92768996 -1.96186004 1.92771998 -1.96183002 0 P 0 
L 1.92771998 -1.96183002 1.92773996 -1.9618 0 P 0 
L 1.92773996 -1.9618 1.92913996 -1.96001004 0 P 0 
L 1.92913996 -1.96001004 1.92918996 -1.95995 0 P 0 
L 1.92918996 -1.95995 1.92921004 -1.95991004 0 P 0 
L 1.92921004 -1.95991004 1.92923002 -1.95988002 0 P 0 
L 1.92923002 -1.95988002 1.93048002 -1.95798996 0 P 0 
L 1.93048002 -1.95798996 1.93051998 -1.95793002 0 P 0 
L 1.93051998 -1.95793002 1.93053996 -1.95788996 0 P 0 
L 1.93053996 -1.95788996 1.93056004 -1.95786004 0 P 0 
L 1.93056004 -1.95786004 1.93166004 -1.95588002 0 P 0 
L 1.93166004 -1.95588002 1.93171004 -1.95576998 0 P 0 
L 1.93171004 -1.95576998 1.93173002 -1.95573996 0 P 0 
L 1.93173002 -1.95573996 1.93266998 -1.95366998 0 P 0 
L 1.93266998 -1.95366998 1.93271004 -1.95356998 0 P 0 
L 1.93271004 -1.95356998 1.93273002 -1.95353002 0 P 0 
L 1.93273002 -1.95353002 1.9335 -1.9514 0 P 0 
L 1.9335 -1.9514 1.93351004 -1.95136998 0 P 0 
L 1.93351004 -1.95136998 1.93353002 -1.95133002 0 P 0 
L 1.93353002 -1.95133002 1.93355 -1.95125 0 P 0 
L 1.93355 -1.95125 1.93416004 -1.94906998 0 P 0 
L 1.93416004 -1.94906998 1.93416998 -1.94903002 0 P 0 
L 1.93416998 -1.94903002 1.93418002 -1.949 0 P 0 
L 1.93418002 -1.949 1.93418002 -1.94896004 0 P 0 
L 1.93418002 -1.94896004 1.93418996 -1.94891998 0 P 0 
L 1.93418996 -1.94891998 1.93463996 -1.94665 0 P 0 
L 1.93463996 -1.94665 1.93463996 -1.94661004 0 P 0 
L 1.93463996 -1.94661004 1.93465 -1.94656998 0 P 0 
L 1.93465 -1.94656998 1.93466004 -1.9465 0 P 0 
L 1.93466004 -1.9465 1.93493996 -1.9442 0 P 0 
L 1.93493996 -1.9442 1.93493996 -1.94413002 0 P 0 
L 1.93493996 -1.94413002 1.93495 -1.94408996 0 P 0 
L 1.93495 -1.94408996 1.93495 -1.94406004 0 P 0 
L 1.93495 -1.94406004 1.93505 -1.94173996 0 P 0 
L 1.93505 -1.94173996 1.93506004 -1.94171004 0 P 0 
L 1.93506004 -1.94171004 1.93506004 -1.9416 0 P 0 
L 1.93506004 -1.9416 1.93498996 -1.93928996 0 P 0 
L 1.93498996 -1.93928996 1.93498996 -1.93921004 0 P 0 
L 1.93498996 -1.93921004 1.93498002 -1.93913996 0 P 0 
L 1.93498002 -1.93913996 1.93475 -1.93683996 0 P 0 
L 1.93475 -1.93683996 1.93473996 -1.93676998 0 P 0 
L 1.93473996 -1.93676998 1.93473002 -1.93673002 0 P 0 
L 1.93473002 -1.93673002 1.93473002 -1.93668996 0 P 0 
L 1.93473002 -1.93668996 1.93433002 -1.93441004 0 P 0 
L 1.93433002 -1.93441004 1.93431998 -1.93436998 0 P 0 
L 1.93431998 -1.93436998 1.93431004 -1.93433996 0 P 0 
L 1.93431004 -1.93433996 1.93428996 -1.93426004 0 P 0 
L 1.93428996 -1.93426004 1.93373002 -1.93206004 0 P 0 
L 1.93373002 -1.93206004 1.93368996 -1.93191998 0 P 0 
L 1.93368996 -1.93191998 1.93296004 -1.92976998 0 P 0 
L 1.93296004 -1.92976998 1.93293996 -1.9297 0 P 0 
L 1.93293996 -1.9297 1.93291004 -1.92963002 0 P 0 
L 1.93291004 -1.92963002 1.93201998 -1.92753996 0 P 0 
L 1.93201998 -1.92753996 1.93196998 -1.92743002 0 P 0 
L 1.93196998 -1.92743002 1.93196004 -1.9274 0 P 0 
L 1.93196004 -1.9274 1.93091998 -1.92538996 0 P 0 
L 1.93091998 -1.92538996 1.9309 -1.92536004 0 P 0 
L 1.9309 -1.92536004 1.93088002 -1.92531998 0 P 0 
L 1.93088002 -1.92531998 1.93086004 -1.92528996 0 P 0 
L 1.93086004 -1.92528996 1.93083996 -1.92525 0 P 0 
L 1.93083996 -1.92525 1.92965 -1.92331998 0 P 0 
L 1.92965 -1.92331998 1.92956998 -1.9232 0 P 0 
L 1.92956998 -1.9232 1.92823002 -1.92136004 0 P 0 
L 1.92823002 -1.92136004 1.92818002 -1.9213 0 P 0 
L 1.92818002 -1.9213 1.92816004 -1.92126998 0 P 0 
L 1.92816004 -1.92126998 1.92813002 -1.92123996 0 P 0 
L 1.92813002 -1.92123996 1.92671998 -1.91958002 0 P 0 
L 1.92671998 -1.91958002 1.9266 -1.91946004 0 P 0 
L 1.9266 -1.91946004 1.92505 -1.91793002 0 P 0 
L 1.92505 -1.91793002 1.92498996 -1.91786998 0 P 0 
L 1.92498996 -1.91786998 1.92493002 -1.91781998 0 P 0 
L 1.92493002 -1.91781998 1.92325 -1.91643002 0 P 0 
L 1.92325 -1.91643002 1.92318996 -1.91636998 0 P 0 
L 1.92318996 -1.91636998 1.92311998 -1.91631998 0 P 0 
L 1.92311998 -1.91631998 1.92133002 -1.91508002 0 P 0 
L 1.92133002 -1.91508002 1.92126004 -1.91503996 0 P 0 
L 1.92126004 -1.91503996 1.92121998 -1.91501004 0 P 0 
L 1.92121998 -1.91501004 1.92118002 -1.91498996 0 P 0 
L 1.92118002 -1.91498996 1.91928996 -1.91391004 0 P 0 
L 1.91928996 -1.91391004 1.91926004 -1.91388996 0 P 0 
L 1.91926004 -1.91388996 1.91913996 -1.91383002 0 P 0 
L 1.91913996 -1.91383002 1.91716998 -1.91291004 0 P 0 
L 1.91716998 -1.91291004 1.91711998 -1.91288996 0 P 0 
L 1.91711998 -1.91288996 1.91705 -1.91286004 0 P 0 
L 1.91705 -1.91286004 1.917 -1.91285 0 P 0 
L 1.917 -1.91285 1.91476998 -1.91203996 0 P 0 
L 1.91476998 -1.91203996 1.91468996 -1.91201998 0 P 0 
L 1.91468996 -1.91201998 1.91465 -1.912 0 P 0 
L 1.91465 -1.912 1.9146 -1.91198996 0 P 0 
L 1.9146 -1.91198996 1.91233002 -1.91138996 0 P 0 
L 1.91233002 -1.91138996 1.91228002 -1.91138002 0 P 0 
L 1.91228002 -1.91138002 1.91223996 -1.91136998 0 P 0 
L 1.91223996 -1.91136998 1.91216004 -1.91136004 0 P 0 
L 1.91216004 -1.91136004 1.90983002 -1.91095 0 P 0 
L 1.90983002 -1.91095 1.9098 -1.91093996 0 P 0 
L 1.9098 -1.91093996 1.90976004 -1.91093996 0 P 0 
L 1.90976004 -1.91093996 1.90971998 -1.91093002 0 P 0 
L 1.90971998 -1.91093002 1.90968002 -1.91093002 0 P 0 
L 1.90968002 -1.91093002 1.90713996 -1.91068996 0 P 0 
L 1.90713996 -1.91068996 1.9071 -1.91068002 0 P 0 
L 1.9071 -1.91068002 1.907 -1.91068002 0 P 0 
L 1.907 -1.91068002 1.90445 -1.91061004 0 P 0 
L 1.90445 -1.91061004 1.90431004 -1.91061004 0 P 0 
L 1.90431004 -1.91061004 1.90176004 -1.91071004 0 P 0 
L 1.90176004 -1.91071004 1.90173002 -1.91071998 0 P 0 
L 1.90173002 -1.91071998 1.90166004 -1.91071998 0 P 0 
L 1.90166004 -1.91071998 1.90161998 -1.91073002 0 P 0 
L 1.90161998 -1.91073002 1.89913002 -1.911 0 P 0 
L 1.89913002 -1.911 1.89906004 -1.91101004 0 P 0 
L 1.89906004 -1.91101004 1.89901998 -1.91101998 0 P 0 
L 1.89901998 -1.91101998 1.89898996 -1.91101998 0 P 0 
L 1.89898996 -1.91101998 1.89653002 -1.91146998 0 P 0 
L 1.89653002 -1.91146998 1.8965 -1.91148002 0 P 0 
L 1.8965 -1.91148002 1.89646004 -1.91148002 0 P 0 
L 1.89646004 -1.91148002 1.8964 -1.9115 0 P 0 
L 1.8964 -1.9115 1.89396998 -1.91211998 0 P 0 
L 1.89396998 -1.91211998 1.89393996 -1.91213002 0 P 0 
L 1.89393996 -1.91213002 1.89383002 -1.91216004 0 P 0 
L 1.89383002 -1.91216004 1.89225 -1.91268996 0 P 0 
L 1.89225 -1.91268996 1.89218002 -1.91271998 0 P 0 
L 1.89218002 -1.91271998 1.89211004 -1.91273996 0 P 0 
L 1.89211004 -1.91273996 1.8921 -1.91273996 0 P 0 
L 1.8921 -1.91273996 1.89058002 -1.91338996 0 P 0 
L 1.89058002 -1.91338996 1.89043996 -1.91345 0 P 0 
L 1.89043996 -1.91345 1.88896004 -1.91421004 0 P 0 
L 1.88896004 -1.91421004 1.88893002 -1.91423002 0 P 0 
L 1.88893002 -1.91423002 1.8889 -1.91423996 0 P 0 
L 1.8889 -1.91423996 1.88886004 -1.91426004 0 P 0 
L 1.88886004 -1.91426004 1.88883002 -1.91428002 0 P 0 
L 1.88883002 -1.91428002 1.88741004 -1.91515 0 P 0 
L 1.88741004 -1.91515 1.88733996 -1.91518996 0 P 0 
L 1.88733996 -1.91518996 1.88728002 -1.91523996 0 P 0 
L 1.88728002 -1.91523996 1.88526004 -1.9167 0 P 0 
L 1.88526004 -1.9167 1.88521998 -1.91673002 0 P 0 
L 1.88521998 -1.91673002 1.88518996 -1.91675 0 P 0 
L 1.88518996 -1.91675 1.88516004 -1.91678002 0 P 0 
L 1.88516004 -1.91678002 1.88511998 -1.91681004 0 P 0 
L 1.88511998 -1.91681004 1.88323002 -1.91845 0 P 0 
L 1.88323002 -1.91845 1.8832 -1.91846998 0 P 0 
L 1.8832 -1.91846998 1.88311004 -1.91856004 0 P 0 
L 1.88311004 -1.91856004 1.88136998 -1.92036004 0 P 0 
L 1.88136998 -1.92036004 1.88128002 -1.92045 0 P 0 
L 1.88128002 -1.92045 1.88125 -1.92048996 0 P 0 
L 1.88125 -1.92048996 1.87968002 -1.92241998 0 P 0 
L 1.87968002 -1.92241998 1.87965 -1.92245 0 P 0 
L 1.87965 -1.92245 1.87961998 -1.92248996 0 P 0 
L 1.87961998 -1.92248996 1.87956998 -1.92256004 0 P 0 
L 1.87956998 -1.92256004 1.87816998 -1.92461998 0 P 0 
L 1.87816998 -1.92461998 1.8781 -1.92473002 0 P 0 
L 1.8781 -1.92473002 1.87808002 -1.92476998 0 P 0 
L 1.87808002 -1.92476998 1.87685 -1.92695 0 P 0 
L 1.87685 -1.92695 1.87683002 -1.92698996 0 P 0 
L 1.87683002 -1.92698996 1.87681004 -1.92701998 0 P 0 
L 1.87681004 -1.92701998 1.87678996 -1.92706998 0 P 0 
L 1.87678996 -1.92706998 1.87676998 -1.92711004 0 P 0 
L 1.87676998 -1.92711004 1.87573002 -1.92941004 0 P 0 
L 1.87573002 -1.92941004 1.87571004 -1.92945 0 P 0 
L 1.87571004 -1.92945 1.8757 -1.92948996 0 P 0 
L 1.8757 -1.92948996 1.87568002 -1.92951998 0 P 0 
L 1.87568002 -1.92951998 1.87566998 -1.92956998 0 P 0 
L 1.87566998 -1.92956998 1.87483996 -1.93193002 0 P 0 
L 1.87483996 -1.93193002 1.87481004 -1.93201004 0 P 0 
L 1.87481004 -1.93201004 1.87478996 -1.93208996 0 P 0 
L 1.87478996 -1.93208996 1.87416004 -1.93451998 0 P 0 
L 1.87416004 -1.93451998 1.87413996 -1.93456004 0 P 0 
L 1.87413996 -1.93456004 1.87413002 -1.9346 0 P 0 
L 1.87413002 -1.9346 1.87413002 -1.93463996 0 P 0 
L 1.87413002 -1.93463996 1.87411998 -1.93468002 0 P 0 
L 1.87411998 -1.93468002 1.8737 -1.93715 0 P 0 
L 1.8737 -1.93715 1.87368996 -1.93718996 0 P 0 
L 1.87368996 -1.93718996 1.87368002 -1.93723996 0 P 0 
L 1.87368002 -1.93723996 1.87368002 -1.93731998 0 P 0 
L 1.87368002 -1.93731998 1.87346998 -1.93981998 0 P 0 
L 1.87346998 -1.93981998 1.87346004 -1.93986004 0 P 0 
L 1.87346004 -1.93986004 1.87346004 -1.94258002 0 P 0 
L 1.87346004 -1.94258002 1.87346998 -1.94266004 0 P 0 
L 1.87346998 -1.94266004 1.87368002 -1.94516998 0 P 0 
L 1.87368002 -1.94516998 1.87368996 -1.94521004 0 P 0 
L 1.87368996 -1.94521004 1.87368996 -1.94525 0 P 0 
L 1.87368996 -1.94525 1.87371004 -1.94533996 0 P 0 
L 1.87371004 -1.94533996 1.87413996 -1.94778996 0 P 0 
L 1.87413996 -1.94778996 1.87413996 -1.94783996 0 P 0 
L 1.87413996 -1.94783996 1.87416998 -1.94796004 0 P 0 
L 1.87416998 -1.94796004 1.87481004 -1.95036998 0 P 0 
L 1.87481004 -1.95036998 1.87483996 -1.95048996 0 P 0 
L 1.87483996 -1.95048996 1.87486004 -1.95053002 0 P 0 
L 1.87486004 -1.95053002 1.8757 -1.95288002 0 P 0 
L 1.8757 -1.95288002 1.87571004 -1.95291998 0 P 0 
L 1.87571004 -1.95291998 1.87575 -1.953 0 P 0 
L 1.87575 -1.953 1.87576004 -1.95303996 0 P 0 
L 1.87576004 -1.95303996 1.8768 -1.9553 0 P 0 
L 1.8768 -1.9553 1.87686004 -1.95541998 0 P 0 
L 1.87686004 -1.95541998 1.87688002 -1.95545 0 P 0 
L 1.87688002 -1.95545 1.8781 -1.95761004 0 P 0 
L 1.8781 -1.95761004 1.87811998 -1.95761004 0 P 0 
L 1.87811998 -1.95761004 1.8781 -1.95761998 0 P 0 
L 1.8781 -1.95761998 1.87813996 -1.95768996 0 P 0 
L 1.87813996 -1.95768996 1.87816998 -1.95771998 0 P 0 
L 1.87816998 -1.95771998 1.87818996 -1.95775 0 P 0 
L 1.87818996 -1.95775 1.87938002 -1.95951004 0 P 0 
L 1.87938002 -1.95951004 1.87943996 -1.9596 0 P 0 
L 1.87943996 -1.9596 1.87946998 -1.95963002 0 P 0 
L 1.87946998 -1.95963002 1.88078002 -1.96128996 0 P 0 
L 1.88078002 -1.96128996 1.88081004 -1.96131998 0 P 0 
L 1.88081004 -1.96131998 1.88083002 -1.96135 0 P 0 
L 1.88083002 -1.96135 1.88086004 -1.96136998 0 P 0 
L 1.88086004 -1.96136998 1.88088002 -1.9614 0 P 0 
L 1.88088002 -1.9614 1.88231998 -1.96295 0 P 0 
L 1.88231998 -1.96295 1.88233996 -1.96298002 0 P 0 
L 1.88233996 -1.96298002 1.8824 -1.96303996 0 P 0 
L 1.8824 -1.96303996 1.88243002 -1.96306004 0 P 0 
L 1.88243002 -1.96306004 1.88398002 -1.9645 0 P 0 
L 1.88398002 -1.9645 1.88401004 -1.96451998 0 P 0 
L 1.88401004 -1.96451998 1.88403002 -1.96455 0 P 0 
L 1.88403002 -1.96455 1.88406998 -1.96458002 0 P 0 
L 1.88406998 -1.96458002 1.88408996 -1.9646 0 P 0 
L 1.88408996 -1.9646 1.88575 -1.96591004 0 P 0 
L 1.88575 -1.96591004 1.88578002 -1.96593996 0 P 0 
L 1.88578002 -1.96593996 1.88586998 -1.966 0 P 0 
L 1.88586998 -1.966 1.88761998 -1.96718996 0 P 0 
L 1.88761998 -1.96718996 1.88766004 -1.96721004 0 P 0 
L 1.88766004 -1.96721004 1.88775 -1.96726998 0 P 0 
L 1.88775 -1.96726998 1.88958996 -1.96831998 0 P 0 
L 1.88958996 -1.96831998 1.88965 -1.96836004 0 P 0 
L 1.88965 -1.96836004 1.88968002 -1.96836998 0 P 0 
L 1.88968002 -1.96836998 1.88971998 -1.96838996 0 P 0 
L 1.88971998 -1.96838996 1.89145 -1.96921998 0 P 0 
L 1.89145 -1.96921998 1.89151004 -1.96925 0 P 0 
L 1.89151004 -1.96925 1.89155 -1.96926004 0 P 0 
L 1.89155 -1.96926004 1.89158002 -1.96926998 0 P 0 
L 1.89158002 -1.96926998 1.89336004 -1.96996998 0 P 0 
L 1.89336004 -1.96996998 1.89336004 -1.96998002 0 P 0 
L 1.89336004 -1.96998002 1.89346004 -1.97001004 0 P 0 
L 1.89346004 -1.97001004 1.89348996 -1.97001998 0 P 0 
L 1.89348996 -1.97001998 1.89531998 -1.9706 0 P 0 
L 1.89531998 -1.9706 1.89536004 -1.97061004 0 P 0 
L 1.89536004 -1.97061004 1.89541998 -1.97063002 0 P 0 
L 1.89541998 -1.97063002 1.89546004 -1.97063002 0 P 0 
L 1.89546004 -1.97063002 1.89731998 -1.97108002 0 P 0 
L 1.89731998 -1.97108002 1.89741998 -1.9711 0 P 0 
L 1.89741998 -1.9711 1.89746004 -1.9711 0 P 0 
L 1.89746004 -1.9711 1.89746004 -1.97111004 0 P 0 
L 1.89746004 -1.97111004 1.89933996 -1.97141998 0 P 0 
L 1.89933996 -1.97141998 1.89936998 -1.97143002 0 P 0 
L 1.89936998 -1.97143002 1.89941004 -1.97143002 0 P 0 
L 1.89941004 -1.97143002 1.89945 -1.97143996 0 P 0 
L 1.89945 -1.97143996 1.89948002 -1.97143996 0 P 0 
L 1.89948002 -1.97143996 1.90201004 -1.97168002 0 P 0 
L 1.90201004 -1.97168002 1.90205 -1.97168002 0 P 0 
L 1.90205 -1.97168002 1.90208996 -1.97168996 0 P 0 
L 1.90208996 -1.97168996 1.90216004 -1.97168996 0 P 0 
L 1.90216004 -1.97168996 1.90468996 -1.97173996 0 P 0 
L 1.90468996 -1.97173996 1.90476004 -1.97173996 0 P 0 
L 1.80616004 -2.12823996 1.83348996 -2.12823996 0 P 0 
L 1.79591998 -2.12723996 1.8396 -2.12723996 0 P 0 
L 1.78818002 -2.12623996 1.84465 -2.12623996 0 P 0 
L 1.82003996 -2.09123996 1.87618996 -2.09123996 0 P 0 
L 1.82198996 -2.09023996 1.8762 -2.09023996 0 P 0 
L 1.82325 -2.08923996 1.8762 -2.08923996 0 P 0 
L 1.82411998 -2.08823996 1.87618996 -2.08823996 0 P 0 
L 1.82463002 -2.08723996 1.87616998 -2.08723996 0 P 0 
L 1.82488002 -2.08623996 1.87615 -2.08623996 0 P 0 
L 1.82493002 -2.08523996 1.87613002 -2.08523996 0 P 0 
L 1.82476998 -2.08423996 1.87611004 -2.08423996 0 P 0 
L 1.64846004 -2.08295 1.73316998 -2.08295 0 P 0 
L 1.64811998 -2.08195 1.73356998 -2.08195 0 P 0 
L 1.64776998 -2.08095 1.73398002 -2.08095 0 P 0 
L 1.64743002 -2.07995 1.73438002 -2.07995 0 P 0 
L 1.64708996 -2.07895 1.73478996 -2.07895 0 P 0 
L 1.64673996 -2.07795 1.7352 -2.07795 0 P 0 
L 1.6464 -2.07695 1.7356 -2.07695 0 P 0 
L 1.64605 -2.07595 1.73601004 -2.07595 0 P 0 
L 1.64571004 -2.07495 1.73641004 -2.07495 0 P 0 
L 1.64536004 -2.07395 1.73681004 -2.07395 0 P 0 
L 1.64501998 -2.07295 1.73721998 -2.07295 0 P 0 
L 1.64466998 -2.07195 1.73761998 -2.07195 0 P 0 
L 1.64433002 -2.07095 1.73803002 -2.07095 0 P 0 
L 1.64398002 -2.06995 1.69251004 -2.06995 0 P 0 
L 1.69583002 -2.06995 1.73843996 -2.06995 0 P 0 
L 1.64363002 -2.06895 1.69168002 -2.06895 0 P 0 
L 1.69671998 -2.06895 1.73883996 -2.06895 0 P 0 
L 1.64328996 -2.06795 1.69136004 -2.06795 0 P 0 
L 1.69708996 -2.06795 1.73925 -2.06795 0 P 0 
L 1.64293996 -2.06695 1.69108002 -2.06695 0 P 0 
L 1.69738002 -2.06695 1.73965 -2.06695 0 P 0 
L 1.64258996 -2.06595 1.6908 -2.06595 0 P 0 
L 1.69768002 -2.06595 1.74006004 -2.06595 0 P 0 
L 1.64223996 -2.06495 1.69051998 -2.06495 0 P 0 
L 1.69796998 -2.06495 1.74046004 -2.06495 0 P 0 
L 1.6419 -2.06395 1.69023002 -2.06395 0 P 0 
L 1.69826998 -2.06395 1.74086004 -2.06395 0 P 0 
L 1.64155 -2.06295 1.68996004 -2.06295 0 P 0 
L 1.69856004 -2.06295 1.74126998 -2.06295 0 P 0 
L 1.6412 -2.06195 1.68966998 -2.06195 0 P 0 
L 1.69886004 -2.06195 1.74168002 -2.06195 0 P 0 
L 1.64085 -2.06095 1.68938996 -2.06095 0 P 0 
L 1.69915 -2.06095 1.74208002 -2.06095 0 P 0 
L 1.6405 -2.05995 1.68911004 -2.05995 0 P 0 
L 1.69945 -2.05995 1.74248002 -2.05995 0 P 0 
L 1.64016004 -2.05895 1.68883002 -2.05895 0 P 0 
L 1.69973996 -2.05895 1.74288996 -2.05895 0 P 0 
L 1.63981004 -2.05795 1.68855 -2.05795 0 P 0 
L 1.70003996 -2.05795 1.74328996 -2.05795 0 P 0 
L 1.63946004 -2.05695 1.68826998 -2.05695 0 P 0 
L 1.70033002 -2.05695 1.7437 -2.05695 0 P 0 
L 1.63911004 -2.05595 1.68798996 -2.05595 0 P 0 
L 1.70063002 -2.05595 1.7441 -2.05595 0 P 0 
L 1.63876998 -2.05495 1.68771004 -2.05495 0 P 0 
L 1.70091998 -2.05495 1.74451004 -2.05495 0 P 0 
L 1.63841998 -2.05395 1.68741998 -2.05395 0 P 0 
L 1.70121998 -2.05395 1.74491004 -2.05395 0 P 0 
L 1.63806998 -2.05295 1.68713996 -2.05295 0 P 0 
L 1.70151004 -2.05295 1.74531004 -2.05295 0 P 0 
L 1.63771998 -2.05195 1.68686004 -2.05195 0 P 0 
L 1.70181004 -2.05195 1.74571998 -2.05195 0 P 0 
L 1.63738002 -2.05095 1.68658002 -2.05095 0 P 0 
L 1.7021 -2.05095 1.74611998 -2.05095 0 P 0 
L 1.63703002 -2.04995 1.6863 -2.04995 0 P 0 
L 1.7024 -2.04995 1.74653002 -2.04995 0 P 0 
L 1.63668002 -2.04895 1.68601998 -2.04895 0 P 0 
L 1.70268996 -2.04895 1.74693002 -2.04895 0 P 0 
L 1.63633002 -2.04795 1.68573996 -2.04795 0 P 0 
L 1.70298996 -2.04795 1.74733002 -2.04795 0 P 0 
L 1.63598002 -2.04695 1.68546004 -2.04695 0 P 0 
L 1.70328002 -2.04695 1.74773996 -2.04695 0 P 0 
L 1.63563996 -2.04595 1.68518002 -2.04595 0 P 0 
L 1.70358002 -2.04595 1.74813996 -2.04595 0 P 0 
L 1.63528996 -2.04495 1.6849 -2.04495 0 P 0 
L 1.70386998 -2.04495 1.74855 -2.04495 0 P 0 
L 1.63493996 -2.04395 1.68461004 -2.04395 0 P 0 
L 1.70416998 -2.04395 1.74895 -2.04395 0 P 0 
L 1.63458996 -2.04295 1.68433002 -2.04295 0 P 0 
L 1.70446004 -2.04295 1.74936004 -2.04295 0 P 0 
L 1.63425 -2.04195 1.68405 -2.04195 0 P 0 
L 1.70475 -2.04195 1.74976004 -2.04195 0 P 0 
L 1.6339 -2.04095 1.68376998 -2.04095 0 P 0 
L 1.70503002 -2.04095 1.75016004 -2.04095 0 P 0 
L 1.63355 -2.03995 1.68348996 -2.03995 0 P 0 
L 1.70531998 -2.03995 1.75056998 -2.03995 0 P 0 
L 1.6332 -2.03895 1.68321004 -2.03895 0 P 0 
L 1.7056 -2.03895 1.75096998 -2.03895 0 P 0 
L 1.63286004 -2.03795 1.68293002 -2.03795 0 P 0 
L 1.70588996 -2.03795 1.75138002 -2.03795 0 P 0 
L 1.63251004 -2.03695 1.68266004 -2.03695 0 P 0 
L 1.70618002 -2.03695 1.75178002 -2.03695 0 P 0 
L 1.63216004 -2.03595 1.68238002 -2.03595 0 P 0 
L 1.70646998 -2.03595 1.75218996 -2.03595 0 P 0 
L 1.63181004 -2.03495 1.6821 -2.03495 0 P 0 
L 1.70675 -2.03495 1.75258996 -2.03495 0 P 0 
L 1.63146998 -2.03395 1.68183002 -2.03395 0 P 0 
L 1.70703996 -2.03395 1.75298996 -2.03395 0 P 0 
L 1.63111998 -2.03295 1.68155 -2.03295 0 P 0 
L 1.70733002 -2.03295 1.7534 -2.03295 0 P 0 
L 1.63076998 -2.03195 1.68126998 -2.03195 0 P 0 
L 1.70761004 -2.03195 1.75381004 -2.03195 0 P 0 
L 1.63041998 -2.03095 1.68098996 -2.03095 0 P 0 
L 1.7079 -2.03095 1.75421004 -2.03095 0 P 0 
L 1.63006998 -2.02995 1.68071004 -2.02995 0 P 0 
L 1.70818996 -2.02995 1.75461004 -2.02995 0 P 0 
L 1.62973002 -2.02895 1.68043996 -2.02895 0 P 0 
L 1.70846998 -2.02895 1.75501998 -2.02895 0 P 0 
L 1.62938002 -2.02795 1.68016004 -2.02795 0 P 0 
L 1.70876004 -2.02795 1.75541998 -2.02795 0 P 0 
L 1.62903002 -2.02695 1.67988002 -2.02695 0 P 0 
L 1.70905 -2.02695 1.75583002 -2.02695 0 P 0 
L 1.62868002 -2.02595 1.6796 -2.02595 0 P 0 
L 1.70933996 -2.02595 1.75623002 -2.02595 0 P 0 
L 1.62831004 -2.02495 1.67933002 -2.02495 0 P 0 
L 1.70961998 -2.02495 1.75663996 -2.02495 0 P 0 
L 1.62793996 -2.02395 1.67905 -2.02395 0 P 0 
L 1.70991004 -2.02395 1.75703996 -2.02395 0 P 0 
L 1.62756998 -2.02295 1.67876998 -2.02295 0 P 0 
L 1.7102 -2.02295 1.75743996 -2.02295 0 P 0 
L 1.6272 -2.02195 1.6785 -2.02195 0 P 0 
L 1.71048002 -2.02195 1.75785 -2.02195 0 P 0 
L 1.62683002 -2.02095 1.67821998 -2.02095 0 P 0 
L 1.71076004 -2.02095 1.75825 -2.02095 0 P 0 
L 1.62646998 -2.01995 1.67793996 -2.01995 0 P 0 
L 1.71101004 -2.01995 1.75866004 -2.01995 0 P 0 
L 1.6261 -2.01895 1.67766004 -2.01895 0 P 0 
L 1.71126998 -2.01895 1.75906004 -2.01895 0 P 0 
L 1.62573002 -2.01795 1.67738996 -2.01795 0 P 0 
L 1.71151998 -2.01795 1.75946998 -2.01795 0 P 0 
L 1.62536004 -2.01695 1.67711004 -2.01695 0 P 0 
L 1.71176998 -2.01695 1.75986998 -2.01695 0 P 0 
L 1.62498996 -2.01595 1.67683002 -2.01595 0 P 0 
L 1.71203002 -2.01595 1.76026998 -2.01595 0 P 0 
L 1.62461998 -2.01495 1.67656004 -2.01495 0 P 0 
L 1.71228002 -2.01495 1.76068002 -2.01495 0 P 0 
L 1.62425 -2.01395 1.67628002 -2.01395 0 P 0 
L 1.71253996 -2.01395 1.76108002 -2.01395 0 P 0 
L 1.62388002 -2.01295 1.67601998 -2.01295 0 P 0 
L 1.71278996 -2.01295 1.76148996 -2.01295 0 P 0 
L 1.62351004 -2.01195 1.67576998 -2.01195 0 P 0 
L 1.71305 -2.01195 1.76188996 -2.01195 0 P 0 
L 1.62313996 -2.01095 1.67551998 -2.01095 0 P 0 
L 1.7133 -2.01095 1.76228996 -2.01095 0 P 0 
L 1.62276998 -2.00995 1.67528002 -2.00995 0 P 0 
L 1.71355 -2.00995 1.7627 -2.00995 0 P 0 
L 1.6224 -2.00895 1.67503002 -2.00895 0 P 0 
L 1.71381004 -2.00895 1.7631 -2.00895 0 P 0 
L 1.62203002 -2.00795 1.67478996 -2.00795 0 P 0 
L 1.71406004 -2.00795 1.76351004 -2.00795 0 P 0 
L 1.62166004 -2.00695 1.67453996 -2.00695 0 P 0 
L 1.71431004 -2.00695 1.76391004 -2.00695 0 P 0 
L 1.62128996 -2.00595 1.67428996 -2.00595 0 P 0 
L 1.71453996 -2.00595 1.76431998 -2.00595 0 P 0 
L 1.62091004 -2.00495 1.67405 -2.00495 0 P 0 
L 1.71476998 -2.00495 1.76471998 -2.00495 0 P 0 
L 1.62051998 -2.00395 1.6738 -2.00395 0 P 0 
L 1.715 -2.00395 1.76511998 -2.00395 0 P 0 
L 1.62013002 -2.00295 1.67355 -2.00295 0 P 0 
L 1.71523002 -2.00295 1.76553002 -2.00295 0 P 0 
L 1.61973996 -2.00195 1.67331004 -2.00195 0 P 0 
L 1.71546004 -2.00195 1.76593996 -2.00195 0 P 0 
L 1.61935 -2.00095 1.67306004 -2.00095 0 P 0 
L 1.71568996 -2.00095 1.76633996 -2.00095 0 P 0 
L 1.61896004 -1.99995 1.67283996 -1.99995 0 P 0 
L 1.71591998 -1.99995 1.76673996 -1.99995 0 P 0 
L 1.61856998 -1.99895 1.67261998 -1.99895 0 P 0 
L 1.71613996 -1.99895 1.76715 -1.99895 0 P 0 
L 1.71638002 -1.99795 1.76755 -1.99795 0 P 0 
L 1.7166 -1.99695 1.76796004 -1.99695 0 P 0 
L 1.71683002 -1.99595 1.76836004 -1.99595 0 P 0 
L 1.71866998 -1.99495 1.76876998 -1.99495 0 P 0 
L 1.78213996 -2.04823996 1.84641998 -2.04823996 0 P 0 
L 1.78138002 -2.04723996 1.84498996 -2.04723996 0 P 0 
L 1.78071004 -2.04623996 1.84356004 -2.04623996 0 P 0 
L 1.7801 -2.04523996 1.84213996 -2.04523996 0 P 0 
L 1.77956004 -2.04423996 1.84071004 -2.04423996 0 P 0 
L 1.77908996 -2.04323996 1.83928002 -2.04323996 0 P 0 
L 1.77866004 -2.04223996 1.83786004 -2.04223996 0 P 0 
L 1.77831004 -2.04123996 1.83658996 -2.04123996 0 P 0 
L 1.77796004 -2.04023996 1.83536004 -2.04023996 0 P 0 
L 1.77761004 -2.03923996 1.83428002 -2.03923996 0 P 0 
L 1.77733996 -2.03823996 1.83321998 -2.03823996 0 P 0 
L 1.77706998 -2.03723996 1.83236998 -2.03723996 0 P 0 
L 1.7768 -2.03623996 1.83171004 -2.03623996 0 P 0 
L 1.7766 -2.03523996 1.83121004 -2.03523996 0 P 0 
L 1.77641004 -2.03423996 1.83085 -2.03423996 0 P 0 
L 1.77621004 -2.03323996 1.83071004 -2.03323996 0 P 0 
L 1.77608002 -2.03223996 1.83076998 -2.03223996 0 P 0 
L 1.77596004 -2.03123996 1.83106004 -2.03123996 0 P 0 
L 1.77583996 -2.03023996 1.83158996 -2.03023996 0 P 0 
L 1.77576004 -2.02923996 1.83238002 -2.02923996 0 P 0 
L 1.7757 -2.02823996 1.83356998 -2.02823996 0 P 0 
L 1.7757 -2.02723996 1.83591998 -2.02723996 0 P 0 
L 1.77571998 -2.02623996 1.87495 -2.02623996 0 P 0 
L 1.7758 -2.02523996 1.87485 -2.02523996 0 P 0 
L 1.77588996 -2.02423996 1.87475 -2.02423996 0 P 0 
L 1.77605 -2.02323996 1.87465 -2.02323996 0 P 0 
L 1.77621004 -2.02223996 1.87455 -2.02223996 0 P 0 
L 1.7764 -2.02123996 1.87445 -2.02123996 0 P 0 
L 1.77665 -2.02023996 1.87433996 -2.02023996 0 P 0 
L 1.7769 -2.01923996 1.87425 -2.01923996 0 P 0 
L 1.7772 -2.01823996 1.87413996 -2.01823996 0 P 0 
L 1.77753002 -2.01723996 1.87405 -2.01723996 0 P 0 
L 1.77786004 -2.01623996 1.87393996 -2.01623996 0 P 0 
L 1.77823002 -2.01523996 1.87383996 -2.01523996 0 P 0 
L 1.77863996 -2.01423996 1.87373996 -2.01423996 0 P 0 
L 1.77903996 -2.01323996 1.87363996 -2.01323996 0 P 0 
L 1.7795 -2.01223996 1.87353996 -2.01223996 0 P 0 
L 1.77998996 -2.01123996 1.87343996 -2.01123996 0 P 0 
L 1.78046998 -2.01023996 1.87333002 -2.01023996 0 P 0 
L 1.78103996 -2.00923996 1.87323002 -2.00923996 0 P 0 
L 1.78161004 -2.00823996 1.87311998 -2.00823996 0 P 0 
L 1.78221004 -2.00723996 1.87301998 -2.00723996 0 P 0 
L 1.78288002 -2.00623996 1.87291998 -2.00623996 0 P 0 
L 1.64213996 -2.14795 1.70566004 -2.14795 0 P 0 
L 1.64518996 -2.14695 1.7062 -2.14695 0 P 0 
L 1.64728996 -2.14595 1.70673996 -2.14595 0 P 0 
L 1.64906998 -2.14495 1.70728002 -2.14495 0 P 0 
L 1.65058002 -2.14395 1.70783002 -2.14395 0 P 0 
L 1.6519 -2.14295 1.70836998 -2.14295 0 P 0 
L 1.65311998 -2.14195 1.70881998 -2.14195 0 P 0 
L 1.65416998 -2.14095 1.70926998 -2.14095 0 P 0 
L 1.65508996 -2.13995 1.70973002 -2.13995 0 P 0 
L 1.65588002 -2.13895 1.71018002 -2.13895 0 P 0 
L 1.65658002 -2.13795 1.71063002 -2.13795 0 P 0 
L 1.65726998 -2.13695 1.71108996 -2.13695 0 P 0 
L 1.65791998 -2.13595 1.71153996 -2.13595 0 P 0 
L 1.65853002 -2.13495 1.71198996 -2.13495 0 P 0 
L 1.65913002 -2.13395 1.71245 -2.13395 0 P 0 
L 1.65968002 -2.13295 1.7129 -2.13295 0 P 0 
L 1.66021998 -2.13195 1.71331004 -2.13195 0 P 0 
L 1.66071998 -2.13095 1.71371998 -2.13095 0 P 0 
L 1.66121004 -2.12995 1.71411998 -2.12995 0 P 0 
L 1.66166998 -2.12895 1.71453002 -2.12895 0 P 0 
L 1.66201004 -2.12795 1.71493996 -2.12795 0 P 0 
L 1.66223996 -2.12695 1.71533996 -2.12695 0 P 0 
L 1.66235 -2.12595 1.71575 -2.12595 0 P 0 
L 1.66236004 -2.12495 1.71615 -2.12495 0 P 0 
L 1.66228002 -2.12395 1.71656004 -2.12395 0 P 0 
L 1.66211998 -2.12295 1.71696004 -2.12295 0 P 0 
L 1.66188002 -2.12195 1.71736004 -2.12195 0 P 0 
L 1.66156004 -2.12095 1.71776998 -2.12095 0 P 0 
L 1.66121004 -2.11995 1.71818002 -2.11995 0 P 0 
L 1.66086998 -2.11895 1.71858002 -2.11895 0 P 0 
L 1.66053002 -2.11795 1.71898996 -2.11795 0 P 0 
L 1.66018002 -2.11695 1.71938996 -2.11695 0 P 0 
L 1.65983996 -2.11595 1.7198 -2.11595 0 P 0 
L 1.65948996 -2.11495 1.7202 -2.11495 0 P 0 
L 1.65913996 -2.11395 1.72061004 -2.11395 0 P 0 
L 1.6588 -2.11295 1.72101004 -2.11295 0 P 0 
L 1.65846004 -2.11195 1.72141998 -2.11195 0 P 0 
L 1.65811004 -2.11095 1.72181998 -2.11095 0 P 0 
L 1.65776998 -2.10995 1.72223002 -2.10995 0 P 0 
L 1.65741998 -2.10895 1.72263002 -2.10895 0 P 0 
L 1.65708002 -2.10795 1.72303996 -2.10795 0 P 0 
L 1.65673002 -2.10695 1.72343996 -2.10695 0 P 0 
L 1.65638996 -2.10595 1.72385 -2.10595 0 P 0 
L 1.65605 -2.10495 1.72425 -2.10495 0 P 0 
L 1.6557 -2.10395 1.72466004 -2.10395 0 P 0 
L 1.65536004 -2.10295 1.72506998 -2.10295 0 P 0 
L 1.65501004 -2.10195 1.72546998 -2.10195 0 P 0 
L 1.65466998 -2.10095 1.72588002 -2.10095 0 P 0 
L 1.65431998 -2.09995 1.72628002 -2.09995 0 P 0 
L 1.65398002 -2.09895 1.72668996 -2.09895 0 P 0 
L 1.65363002 -2.09795 1.72708996 -2.09795 0 P 0 
L 1.65328996 -2.09695 1.72748996 -2.09695 0 P 0 
L 1.65293996 -2.09595 1.7279 -2.09595 0 P 0 
L 1.6526 -2.09495 1.72831004 -2.09495 0 P 0 
L 1.65225 -2.09395 1.72871004 -2.09395 0 P 0 
L 1.65191004 -2.09295 1.72911998 -2.09295 0 P 0 
L 1.65156998 -2.09195 1.72951998 -2.09195 0 P 0 
L 1.65121998 -2.09095 1.72993002 -2.09095 0 P 0 
L 1.65088002 -2.08995 1.73033002 -2.08995 0 P 0 
L 1.65053002 -2.08895 1.73073996 -2.08895 0 P 0 
L 1.65018996 -2.08795 1.73113996 -2.08795 0 P 0 
L 1.64983996 -2.08695 1.73155 -2.08695 0 P 0 
L 1.6495 -2.08595 1.73195 -2.08595 0 P 0 
L 1.64915 -2.08495 1.73236004 -2.08495 0 P 0 
L 1.64881004 -2.08395 1.73276004 -2.08395 0 P 0 
L 1.81726998 -1.98915 1.81196004 -1.9899 0 P 0 
L 1.81196004 -1.9899 1.80668996 -1.99096998 0 P 0 
L 1.80668996 -1.99096998 1.8019 -1.99226004 0 P 0 
L 1.8019 -1.99226004 1.79718996 -1.99391004 0 P 0 
L 1.79718996 -1.99391004 1.79316004 -1.99568002 0 P 0 
L 1.79316004 -1.99568002 1.78926998 -1.99778002 0 P 0 
L 1.78926998 -1.99778002 1.78771004 -1.99878002 0 P 0 
L 1.78771004 -1.99878002 1.78623002 -1.99988002 0 P 0 
L 1.78623002 -1.99988002 1.78481004 -2.00108002 0 P 0 
L 1.78481004 -2.00108002 1.78346998 -2.00238996 0 P 0 
L 1.78346998 -2.00238996 1.78228996 -2.00371998 0 P 0 
L 1.78228996 -2.00371998 1.78121004 -2.00513002 0 P 0 
L 1.78121004 -2.00513002 1.78023002 -2.00661004 0 P 0 
L 1.78023002 -2.00661004 1.77868002 -2.00933996 0 P 0 
L 1.77868002 -2.00933996 1.77731998 -2.01216998 0 P 0 
L 1.77731998 -2.01216998 1.77611004 -2.01516004 0 P 0 
L 1.77611004 -2.01516004 1.77508996 -2.01823002 0 P 0 
L 1.77508996 -2.01823002 1.77436998 -2.02111004 0 P 0 
L 1.77436998 -2.02111004 1.77388996 -2.02406004 0 P 0 
L 1.77388996 -2.02406004 1.77371998 -2.02603996 0 P 0 
L 1.77371998 -2.02603996 1.77368996 -2.02801998 0 P 0 
L 1.77368996 -2.02801998 1.7738 -2.03001998 0 P 0 
L 1.7738 -2.03001998 1.7742 -2.03338996 0 P 0 
L 1.7742 -2.03338996 1.77485 -2.03671004 0 P 0 
L 1.77485 -2.03671004 1.77573002 -2.03993996 0 P 0 
L 1.77573002 -2.03993996 1.77683996 -2.04308002 0 P 0 
L 1.77683996 -2.04308002 1.7776 -2.04481998 0 P 0 
L 1.7776 -2.04481998 1.7785 -2.04648996 0 P 0 
L 1.7785 -2.04648996 1.77953002 -2.04808996 0 P 0 
L 1.77953002 -2.04808996 1.78061004 -2.04953996 0 P 0 
L 1.78061004 -2.04953996 1.78181004 -2.05091004 0 P 0 
L 1.78181004 -2.05091004 1.78311004 -2.05218996 0 P 0 
L 1.78311004 -2.05218996 1.78988996 -2.05801998 0 P 0 
L 1.78988996 -2.05801998 1.79883996 -2.06491004 0 P 0 
L 1.79883996 -2.06491004 1.80976998 -2.07261004 0 P 0 
L 1.80976998 -2.07261004 1.81753002 -2.07823002 0 P 0 
L 1.81753002 -2.07823002 1.81896998 -2.07943002 0 P 0 
L 1.81896998 -2.07943002 1.82033002 -2.08073002 0 P 0 
L 1.82033002 -2.08073002 1.82156998 -2.08213996 0 P 0 
L 1.82156998 -2.08213996 1.82186004 -2.08251004 0 P 0 
L 1.82186004 -2.08251004 1.82211004 -2.0829 0 P 0 
L 1.82211004 -2.0829 1.82233002 -2.08331004 0 P 0 
L 1.82233002 -2.08331004 1.82253002 -2.08373996 0 P 0 
L 1.82253002 -2.08373996 1.82268002 -2.08418002 0 P 0 
L 1.82268002 -2.08418002 1.82281004 -2.08463002 0 P 0 
L 1.82281004 -2.08463002 1.8229 -2.0851 0 P 0 
L 1.8229 -2.0851 1.82293002 -2.08533996 0 P 0 
L 1.82293002 -2.08533996 1.82293996 -2.08558996 0 P 0 
L 1.82293996 -2.08558996 1.82291998 -2.08583996 0 P 0 
L 1.82291998 -2.08583996 1.82288002 -2.08608002 0 P 0 
L 1.82288002 -2.08608002 1.82283002 -2.08631998 0 P 0 
L 1.82283002 -2.08631998 1.82275 -2.08656004 0 P 0 
L 1.82275 -2.08656004 1.82265 -2.08678996 0 P 0 
L 1.82265 -2.08678996 1.82253996 -2.087 0 P 0 
L 1.82253996 -2.087 1.8224 -2.08721004 0 P 0 
L 1.8224 -2.08721004 1.82225 -2.08741004 0 P 0 
L 1.82225 -2.08741004 1.82208996 -2.08758996 0 P 0 
L 1.82208996 -2.08758996 1.8216 -2.08803996 0 P 0 
L 1.8216 -2.08803996 1.82106998 -2.08845 0 P 0 
L 1.82106998 -2.08845 1.82051004 -2.08881004 0 P 0 
L 1.82051004 -2.08881004 1.81991998 -2.08911998 0 P 0 
L 1.81991998 -2.08911998 1.81931004 -2.08936998 0 P 0 
L 1.81931004 -2.08936998 1.81868002 -2.08958002 0 P 0 
L 1.81868002 -2.08958002 1.81803002 -2.08973002 0 P 0 
L 1.81803002 -2.08973002 1.81736004 -2.08981998 0 P 0 
L 1.81736004 -2.08981998 1.81293002 -2.09001998 0 P 0 
L 1.81293002 -2.09001998 1.80846998 -2.08986004 0 P 0 
L 1.80846998 -2.08986004 1.80256998 -2.08923002 0 P 0 
L 1.80256998 -2.08923002 1.79668002 -2.08818996 0 P 0 
L 1.79668002 -2.08818996 1.78223002 -2.08458002 0 P 0 
L 1.78223002 -2.08458002 1.77788996 -2.08338002 0 P 0 
L 1.77788996 -2.08338002 1.77415 -2.08246004 0 P 0 
L 1.77415 -2.08246004 1.77095 -2.08175 0 P 0 
L 1.77095 -2.08175 1.7709 -2.08173996 0 P 0 
L 1.7709 -2.08173996 1.77076998 -2.08173996 0 P 0 
L 1.77076998 -2.08173996 1.77068996 -2.08176004 0 P 0 
L 1.77068996 -2.08176004 1.77053002 -2.08183996 0 P 0 
L 1.77053002 -2.08183996 1.77043002 -2.08193996 0 P 0 
L 1.77043002 -2.08193996 1.77036998 -2.08201998 0 P 0 
L 1.77036998 -2.08201998 1.77031998 -2.08211998 0 P 0 
L 1.77031998 -2.08211998 1.7703 -2.08216998 0 P 0 
L 1.7703 -2.08216998 1.77028996 -2.08223002 0 P 0 
L 1.77028996 -2.08223002 1.77028002 -2.08228002 0 P 0 
L 1.77028002 -2.08228002 1.77028002 -2.08238996 0 P 0 
L 1.77028002 -2.08238996 1.77056998 -2.08838996 0 P 0 
L 1.77056998 -2.08838996 1.77096004 -2.09526004 0 P 0 
L 1.77096004 -2.09526004 1.77153996 -2.1033 0 P 0 
L 1.77153996 -2.1033 1.77236004 -2.11291004 0 P 0 
L 1.77236004 -2.11291004 1.77311004 -2.1194 0 P 0 
L 1.77311004 -2.1194 1.77383002 -2.12398002 0 P 0 
L 1.77383002 -2.12398002 1.77386004 -2.12411004 0 P 0 
L 1.77386004 -2.12411004 1.7739 -2.12423002 0 P 0 
L 1.7739 -2.12423002 1.77395 -2.12436004 0 P 0 
L 1.77395 -2.12436004 1.77401004 -2.12448002 0 P 0 
L 1.77401004 -2.12448002 1.77408002 -2.12458996 0 P 0 
L 1.77408002 -2.12458996 1.77416004 -2.1247 0 P 0 
L 1.77416004 -2.1247 1.77425 -2.1248 0 P 0 
L 1.77425 -2.1248 1.77435 -2.12488996 0 P 0 
L 1.77435 -2.12488996 1.77445 -2.12496998 0 P 0 
L 1.77445 -2.12496998 1.77456998 -2.12505 0 P 0 
L 1.77456998 -2.12505 1.77571004 -2.12568996 0 P 0 
L 1.77571004 -2.12568996 1.7769 -2.12623996 0 P 0 
L 1.7769 -2.12623996 1.77813002 -2.12668996 0 P 0 
L 1.77813002 -2.12668996 1.7794 -2.12703996 0 P 0 
L 1.7794 -2.12703996 1.78068996 -2.12728996 0 P 0 
L 1.78068996 -2.12728996 1.79791998 -2.12951004 0 P 0 
L 1.79791998 -2.12951004 1.81536004 -2.13106004 0 P 0 
L 1.81536004 -2.13106004 1.82125 -2.13123996 0 P 0 
L 1.82125 -2.13123996 1.82716004 -2.13098996 0 P 0 
L 1.82716004 -2.13098996 1.83583996 -2.12998002 0 P 0 
L 1.83583996 -2.12998002 1.84445 -2.12836004 0 P 0 
L 1.84445 -2.12836004 1.84911998 -2.12711004 0 P 0 
L 1.84911998 -2.12711004 1.85366004 -2.12548002 0 P 0 
L 1.85366004 -2.12548002 1.85806998 -2.12348002 0 P 0 
L 1.85806998 -2.12348002 1.86078996 -2.12196998 0 P 0 
L 1.86078996 -2.12196998 1.8634 -2.12026998 0 P 0 
L 1.8634 -2.12026998 1.86586998 -2.11836998 0 P 0 
L 1.86586998 -2.11836998 1.86821004 -2.11628002 0 P 0 
L 1.86821004 -2.11628002 1.87026004 -2.11413002 0 P 0 
L 1.87026004 -2.11413002 1.8721 -2.11181998 0 P 0 
L 1.8721 -2.11181998 1.87375 -2.10936004 0 P 0 
L 1.87375 -2.10936004 1.87516998 -2.10673996 0 P 0 
L 1.87516998 -2.10673996 1.87605 -2.10483996 0 P 0 
L 1.87605 -2.10483996 1.87683996 -2.10291004 0 P 0 
L 1.87683996 -2.10291004 1.8772 -2.10188002 0 P 0 
L 1.8772 -2.10188002 1.87748996 -2.10083002 0 P 0 
L 1.87748996 -2.10083002 1.87771004 -2.09976998 0 P 0 
L 1.87771004 -2.09976998 1.87798002 -2.09788996 0 P 0 
L 1.87798002 -2.09788996 1.87811998 -2.09601004 0 P 0 
L 1.87811998 -2.09601004 1.87821004 -2.08966998 0 P 0 
L 1.87821004 -2.08966998 1.8781 -2.08353996 0 P 0 
L 1.8781 -2.08353996 1.87798002 -2.08166004 0 P 0 
L 1.87798002 -2.08166004 1.87773002 -2.07976998 0 P 0 
L 1.87773002 -2.07976998 1.87753002 -2.07873996 0 P 0 
L 1.87753002 -2.07873996 1.87726998 -2.07773996 0 P 0 
L 1.87726998 -2.07773996 1.87695 -2.07673996 0 P 0 
L 1.87695 -2.07673996 1.87628996 -2.07505 0 P 0 
L 1.87628996 -2.07505 1.87553002 -2.07338002 0 P 0 
L 1.87553002 -2.07338002 1.87441004 -2.07133996 0 P 0 
L 1.87441004 -2.07133996 1.87313996 -2.06938002 0 P 0 
L 1.87313996 -2.06938002 1.87171004 -2.06751004 0 P 0 
L 1.87171004 -2.06751004 1.8688 -2.06416004 0 P 0 
L 1.8688 -2.06416004 1.86566998 -2.06095 0 P 0 
L 1.86566998 -2.06095 1.86181998 -2.05741998 0 P 0 
L 1.86181998 -2.05741998 1.85778002 -2.05406998 0 P 0 
L 1.85778002 -2.05406998 1.84833996 -2.04715 0 P 0 
L 1.84833996 -2.04715 1.83913996 -2.0407 0 P 0 
L 1.83913996 -2.0407 1.83686004 -2.0389 0 P 0 
L 1.83686004 -2.0389 1.83471998 -2.03691998 0 P 0 
L 1.83471998 -2.03691998 1.83428002 -2.03643002 0 P 0 
L 1.83428002 -2.03643002 1.83386998 -2.0359 0 P 0 
L 1.83386998 -2.0359 1.83351004 -2.03535 0 P 0 
L 1.83351004 -2.03535 1.83318996 -2.03476004 0 P 0 
L 1.83318996 -2.03476004 1.83291998 -2.03415 0 P 0 
L 1.83291998 -2.03415 1.83283996 -2.03393996 0 P 0 
L 1.83283996 -2.03393996 1.83278002 -2.03371004 0 P 0 
L 1.83278002 -2.03371004 1.83273002 -2.03348996 0 P 0 
L 1.83273002 -2.03348996 1.83271004 -2.03326004 0 P 0 
L 1.83271004 -2.03326004 1.8327 -2.03303002 0 P 0 
L 1.8327 -2.03303002 1.83271004 -2.0328 0 P 0 
L 1.83271004 -2.0328 1.83275 -2.03258002 0 P 0 
L 1.83275 -2.03258002 1.83278996 -2.03235 0 P 0 
L 1.83278996 -2.03235 1.83286004 -2.03213002 0 P 0 
L 1.83286004 -2.03213002 1.83293996 -2.03191998 0 P 0 
L 1.83293996 -2.03191998 1.83305 -2.03171004 0 P 0 
L 1.83305 -2.03171004 1.83325 -2.03135 0 P 0 
L 1.83325 -2.03135 1.83348996 -2.03101998 0 P 0 
L 1.83348996 -2.03101998 1.83375 -2.03071004 0 P 0 
L 1.83375 -2.03071004 1.83403002 -2.03041004 0 P 0 
L 1.83403002 -2.03041004 1.83433996 -2.03015 0 P 0 
L 1.83433996 -2.03015 1.83466998 -2.02991004 0 P 0 
L 1.83466998 -2.02991004 1.83501998 -2.02968996 0 P 0 
L 1.83501998 -2.02968996 1.83538002 -2.02951004 0 P 0 
L 1.83538002 -2.02951004 1.83576004 -2.02936004 0 P 0 
L 1.83576004 -2.02936004 1.83615 -2.02923996 0 P 0 
L 1.83615 -2.02923996 1.83655 -2.02915 0 P 0 
L 1.83655 -2.02915 1.8392 -2.02873996 0 P 0 
L 1.8392 -2.02873996 1.84188002 -2.0285 0 P 0 
L 1.84188002 -2.0285 1.84458002 -2.02841004 0 P 0 
L 1.84458002 -2.02841004 1.84993996 -2.02858002 0 P 0 
L 1.84993996 -2.02858002 1.85526998 -2.02916004 0 P 0 
L 1.85526998 -2.02916004 1.86155 -2.03023002 0 P 0 
L 1.86155 -2.03023002 1.86778002 -2.03158002 0 P 0 
L 1.86778002 -2.03158002 1.8713 -2.03238996 0 P 0 
L 1.8713 -2.03238996 1.87428996 -2.03303002 0 P 0 
L 1.87428996 -2.03303002 1.8769 -2.03356004 0 P 0 
L 1.8769 -2.03356004 1.87691998 -2.03356998 0 P 0 
L 1.87691998 -2.03356998 1.87696004 -2.03356998 0 P 0 
L 1.87696004 -2.03356998 1.87696998 -2.03356004 0 P 0 
L 1.87696998 -2.03356004 1.87701004 -2.03356004 0 P 0 
L 1.87701004 -2.03356004 1.87703996 -2.03353996 0 P 0 
L 1.87703996 -2.03353996 1.87706004 -2.03353002 0 P 0 
L 1.87706004 -2.03353002 1.87706998 -2.03351998 0 P 0 
L 1.87706998 -2.03351998 1.87708996 -2.03351004 0 P 0 
L 1.87708996 -2.03351004 1.8771 -2.03348996 0 P 0 
L 1.8771 -2.03348996 1.87711004 -2.03348002 0 P 0 
L 1.87711004 -2.03348002 1.87721998 -2.0333 0 P 0 
L 1.87721998 -2.0333 1.87731998 -2.0331 0 P 0 
L 1.87731998 -2.0331 1.8774 -2.0329 0 P 0 
L 1.8774 -2.0329 1.87746004 -2.03268996 0 P 0 
L 1.87746004 -2.03268996 1.87751004 -2.03248002 0 P 0 
L 1.87751004 -2.03248002 1.87753002 -2.03226998 0 P 0 
L 1.87753002 -2.03226998 1.87753996 -2.03205 0 P 0 
L 1.87753996 -2.03205 1.87753002 -2.03183002 0 P 0 
L 1.87753002 -2.03183002 1.87565 -2.01323996 0 P 0 
L 1.87565 -2.01323996 1.87371004 -1.99451998 0 P 0 
L 1.87371004 -1.99451998 1.8737 -1.99438996 0 P 0 
L 1.8737 -1.99438996 1.87366998 -1.99426998 0 P 0 
L 1.87366998 -1.99426998 1.87363002 -1.99415 0 P 0 
L 1.87363002 -1.99415 1.87358002 -1.99403002 0 P 0 
L 1.87358002 -1.99403002 1.87351998 -1.99391004 0 P 0 
L 1.87351998 -1.99391004 1.87346004 -1.9938 0 P 0 
L 1.87346004 -1.9938 1.87338002 -1.9937 0 P 0 
L 1.87338002 -1.9937 1.87328996 -1.9936 0 P 0 
L 1.87328996 -1.9936 1.8732 -1.99351004 0 P 0 
L 1.8732 -1.99351004 1.8731 -1.99343002 0 P 0 
L 1.8731 -1.99343002 1.87298996 -1.99335 0 P 0 
L 1.87298996 -1.99335 1.87248002 -1.99305 0 P 0 
L 1.87248002 -1.99305 1.87193996 -1.99278002 0 P 0 
L 1.87193996 -1.99278002 1.87136998 -1.99256998 0 P 0 
L 1.87136998 -1.99256998 1.87078996 -1.99241004 0 P 0 
L 1.87078996 -1.99241004 1.8702 -1.9923 0 P 0 
L 1.8702 -1.9923 1.85876004 -1.99076004 0 P 0 
L 1.85876004 -1.99076004 1.84691998 -1.98943002 0 P 0 
L 1.84691998 -1.98943002 1.83693002 -1.98876004 0 P 0 
L 1.83693002 -1.98876004 1.8318 -1.98863002 0 P 0 
L 1.8318 -1.98863002 1.82623002 -1.98866998 0 P 0 
L 1.82623002 -1.98866998 1.82106004 -1.98883996 0 P 0 
L 1.82106004 -1.98883996 1.81726998 -1.98915 0 P 0 
L 1.78061004 -2.12523996 1.84838002 -2.12523996 0 P 0 
L 1.77733002 -2.12423996 1.85121004 -2.12423996 0 P 0 
L 1.77573996 -2.12323996 1.85376998 -2.12323996 0 P 0 
L 1.77558002 -2.12223996 1.85596998 -2.12223996 0 P 0 
L 1.77541998 -2.12123996 1.85798996 -2.12123996 0 P 0 
L 1.77526998 -2.12023996 1.85978996 -2.12023996 0 P 0 
L 1.77511004 -2.11923996 1.86131998 -2.11923996 0 P 0 
L 1.77498996 -2.11823996 1.86276004 -2.11823996 0 P 0 
L 1.77486998 -2.11723996 1.86406998 -2.11723996 0 P 0 
L 1.77475 -2.11623996 1.86526004 -2.11623996 0 P 0 
L 1.77463996 -2.11523996 1.86638002 -2.11523996 0 P 0 
L 1.77451998 -2.11423996 1.8674 -2.11423996 0 P 0 
L 1.77441004 -2.11323996 1.86835 -2.11323996 0 P 0 
L 1.77431004 -2.11223996 1.86921004 -2.11223996 0 P 0 
L 1.77421998 -2.11123996 1.87001004 -2.11123996 0 P 0 
L 1.77413996 -2.11023996 1.87075 -2.11023996 0 P 0 
L 1.77405 -2.10923996 1.87141998 -2.10923996 0 P 0 
L 1.77396998 -2.10823996 1.87208002 -2.10823996 0 P 0 
L 1.77388002 -2.10723996 1.87261998 -2.10723996 0 P 0 
L 1.7738 -2.10623996 1.87316998 -2.10623996 0 P 0 
L 1.77371004 -2.10523996 1.87366004 -2.10523996 0 P 0 
L 1.77363002 -2.10423996 1.87411998 -2.10423996 0 P 0 
L 1.77353996 -2.10323996 1.87453996 -2.10323996 0 P 0 
L 1.77346998 -2.10223996 1.87495 -2.10223996 0 P 0 
L 1.7734 -2.10123996 1.8753 -2.10123996 0 P 0 
L 1.77333002 -2.10023996 1.87556998 -2.10023996 0 P 0 
L 1.77325 -2.09923996 1.87576998 -2.09923996 0 P 0 
L 1.77318002 -2.09823996 1.87591998 -2.09823996 0 P 0 
L 1.77311004 -2.09723996 1.87603002 -2.09723996 0 P 0 
L 1.77303996 -2.09623996 1.8761 -2.09623996 0 P 0 
L 1.77296998 -2.09523996 1.87613002 -2.09523996 0 P 0 
L 1.77291004 -2.09423996 1.87613996 -2.09423996 0 P 0 
L 1.77285 -2.09323996 1.87616004 -2.09323996 0 P 0 
L 1.77278996 -2.09223996 1.87616998 -2.09223996 0 P 0 
L 1.77273002 -2.09123996 1.80256998 -2.09123996 0 P 0 
L 1.77268002 -2.09023996 1.7968 -2.09023996 0 P 0 
L 1.77261998 -2.08923996 1.79263002 -2.08923996 0 P 0 
L 1.77256004 -2.08823996 1.78861998 -2.08823996 0 P 0 
L 1.77251004 -2.08723996 1.7846 -2.08723996 0 P 0 
L 1.77246004 -2.08623996 1.7807 -2.08623996 0 P 0 
L 1.77241998 -2.08523996 1.77705 -2.08523996 0 P 0 
L 1.77236998 -2.08423996 1.77293996 -2.08423996 0 P 0 
L 1.62463996 -2.18195 1.65948996 -2.18195 0 P 0 
L 1.61963996 -2.18095 1.66483002 -2.18095 0 P 0 
L 1.61818002 -1.99795 1.6724 -1.99795 0 P 0 
L 1.61778996 -1.99695 1.67218002 -1.99695 0 P 0 
L 1.6174 -1.99595 1.67196004 -1.99595 0 P 0 
L 1.61701004 -1.99495 1.67173996 -1.99495 0 P 0 
L 1.61391998 -2.15695 1.70026004 -2.15695 0 P 0 
L 1.61386004 -2.15595 1.70088002 -2.15595 0 P 0 
L 1.61381004 -2.15495 1.70151004 -2.15495 0 P 0 
L 1.61375 -2.15395 1.70213996 -2.15395 0 P 0 
L 1.6137 -2.15295 1.70276004 -2.15295 0 P 0 
L 1.61365 -2.15195 1.70338996 -2.15195 0 P 0 
L 1.6136 -2.15095 1.70401004 -2.15095 0 P 0 
L 1.61355 -2.14995 1.70456998 -2.14995 0 P 0 
L 1.61348996 -2.14895 1.70511998 -2.14895 0 P 0 
L 1.61343996 -2.14795 1.61738002 -2.14795 0 P 0 
L 1.55341004 -2.08286998 1.60538002 -2.08286998 0 P 0 
L 1.55286004 -2.08186998 1.60526998 -2.08186998 0 P 0 
L 1.5521 -2.08086998 1.6051 -2.08086998 0 P 0 
L 1.55126998 -2.07986998 1.6049 -2.07986998 0 P 0 
L 1.55033996 -2.07886998 1.60463996 -2.07886998 0 P 0 
L 1.54928996 -2.07786998 1.60433002 -2.07786998 0 P 0 
L 1.54806998 -2.07686998 1.60398996 -2.07686998 0 P 0 
L 1.5467 -2.07586998 1.60356998 -2.07586998 0 P 0 
L 1.54531004 -2.07486998 1.6031 -2.07486998 0 P 0 
L 1.54391004 -2.07386998 1.60258996 -2.07386998 0 P 0 
L 1.54251004 -2.07286998 1.60201004 -2.07286998 0 P 0 
L 1.54111998 -2.07186998 1.60138002 -2.07186998 0 P 0 
L 1.53971998 -2.07086998 1.60068002 -2.07086998 0 P 0 
L 1.53833002 -2.06986998 1.59993002 -2.06986998 0 P 0 
L 1.53693002 -2.06886998 1.59908002 -2.06886998 0 P 0 
L 1.53556004 -2.06786998 1.59821004 -2.06786998 0 P 0 
L 1.53418996 -2.06686998 1.59733996 -2.06686998 0 P 0 
L 1.53281998 -2.06586998 1.59646998 -2.06586998 0 P 0 
L 1.53145 -2.06486998 1.5955 -2.06486998 0 P 0 
L 1.53008002 -2.06386998 1.59453002 -2.06386998 0 P 0 
L 1.52871004 -2.06286998 1.59356004 -2.06286998 0 P 0 
L 1.52733996 -2.06186998 1.59253002 -2.06186998 0 P 0 
L 1.52596998 -2.06086998 1.59145 -2.06086998 0 P 0 
L 1.5246 -2.05986998 1.59038002 -2.05986998 0 P 0 
L 1.52323002 -2.05886998 1.5893 -2.05886998 0 P 0 
L 1.52186004 -2.05786998 1.58813996 -2.05786998 0 P 0 
L 1.52053996 -2.05686998 1.58696004 -2.05686998 0 P 0 
L 1.51935 -2.05586998 1.58576998 -2.05586998 0 P 0 
L 1.51816004 -2.05486998 1.58456998 -2.05486998 0 P 0 
L 1.51706998 -2.05386998 1.58321004 -2.05386998 0 P 0 
L 1.51603996 -2.05286998 1.58185 -2.05286998 0 P 0 
L 1.51501998 -2.05186998 1.58048996 -2.05186998 0 P 0 
L 1.51408996 -2.05086998 1.57913002 -2.05086998 0 P 0 
L 1.5132 -2.04986998 1.57776998 -2.04986998 0 P 0 
L 1.51231998 -2.04886998 1.57641998 -2.04886998 0 P 0 
L 1.51151004 -2.04786998 1.57505 -2.04786998 0 P 0 
L 1.51075 -2.04686998 1.57365 -2.04686998 0 P 0 
L 1.51008002 -2.04586998 1.57223002 -2.04586998 0 P 0 
L 1.50945 -2.04486998 1.57081004 -2.04486998 0 P 0 
L 1.50888002 -2.04386998 1.56938996 -2.04386998 0 P 0 
L 1.50836004 -2.04286998 1.56796998 -2.04286998 0 P 0 
L 1.5079 -2.04186998 1.56655 -2.04186998 0 P 0 
L 1.50748002 -2.04086998 1.56518996 -2.04086998 0 P 0 
L 1.50708996 -2.03986998 1.564 -2.03986998 0 P 0 
L 1.50676004 -2.03886998 1.56296998 -2.03886998 0 P 0 
L 1.50641998 -2.03786998 1.56206004 -2.03786998 0 P 0 
L 1.50616998 -2.03686998 1.56125 -2.03686998 0 P 0 
L 1.50591004 -2.03586998 1.56066998 -2.03586998 0 P 0 
L 1.5057 -2.03486998 1.56031998 -2.03486998 0 P 0 
L 1.50551998 -2.03386998 1.56016004 -2.03386998 0 P 0 
L 1.50533996 -2.03286998 1.56016998 -2.03286998 0 P 0 
L 1.50523996 -2.03186998 1.56036004 -2.03186998 0 P 0 
L 1.50513002 -2.03086998 1.56071998 -2.03086998 0 P 0 
L 1.50506998 -2.02986998 1.56131004 -2.02986998 0 P 0 
L 1.50503996 -2.02886998 1.5622 -2.02886998 0 P 0 
L 1.50501004 -2.02786998 1.56355 -2.02786998 0 P 0 
L 1.50501998 -2.02686998 1.5657 -2.02686998 0 P 0 
L 1.50506998 -2.02586998 1.60378996 -2.02586998 0 P 0 
L 1.50511998 -2.02486998 1.60371004 -2.02486998 0 P 0 
L 1.50521004 -2.02386998 1.60363996 -2.02386998 0 P 0 
L 1.50533996 -2.02286998 1.60356998 -2.02286998 0 P 0 
L 1.50546998 -2.02186998 1.6035 -2.02186998 0 P 0 
L 1.50563996 -2.02086998 1.60343002 -2.02086998 0 P 0 
L 1.50585 -2.01986998 1.60336004 -2.01986998 0 P 0 
L 1.50606004 -2.01886998 1.60328996 -2.01886998 0 P 0 
L 1.50633002 -2.01786998 1.60321998 -2.01786998 0 P 0 
L 1.50661998 -2.01686998 1.60315 -2.01686998 0 P 0 
L 1.50691004 -2.01586998 1.60308002 -2.01586998 0 P 0 
L 1.50726998 -2.01486998 1.603 -2.01486998 0 P 0 
L 1.50766004 -2.01386998 1.60293002 -2.01386998 0 P 0 
L 1.50808996 -2.01286998 1.60285 -2.01286998 0 P 0 
L 1.50856998 -2.01186998 1.60278002 -2.01186998 0 P 0 
L 1.50908996 -2.01086998 1.6027 -2.01086998 0 P 0 
L 1.50966004 -2.00986998 1.60261998 -2.00986998 0 P 0 
L 1.51028996 -2.00886998 1.60255 -2.00886998 0 P 0 
L 1.51096998 -2.00786998 1.60246998 -2.00786998 0 P 0 
L 1.51171998 -2.00686998 1.6024 -2.00686998 0 P 0 
L 1.51253996 -2.00586998 1.60233002 -2.00586998 0 P 0 
L 1.51343996 -2.00486998 1.60225 -2.00486998 0 P 0 
L 1.5144 -2.00386998 1.60218002 -2.00386998 0 P 0 
L 1.51551998 -2.00286998 1.6021 -2.00286998 0 P 0 
L 1.51663996 -2.00186998 1.60203002 -2.00186998 0 P 0 
L 1.51795 -2.00086998 1.60195 -2.00086998 0 P 0 
L 1.51928996 -1.99986998 1.60183996 -1.99986998 0 P 0 
L 1.52086998 -1.99886998 1.60173002 -1.99886998 0 P 0 
L 1.52258996 -1.99786998 1.60156998 -1.99786998 0 P 0 
L 1.52451004 -1.99686998 1.60138996 -1.99686998 0 P 0 
L 1.52686998 -1.99586998 1.60106998 -1.99586998 0 P 0 
L 1.52976004 -1.99486998 1.59943996 -1.99486998 0 P 0 
L 1.53283002 -1.99386998 1.59543002 -1.99386998 0 P 0 
L 1.53678996 -1.99286998 1.59003996 -1.99286998 0 P 0 
L 1.54173996 -1.99186998 1.58073996 -1.99186998 0 P 0 
L 1.55036998 -1.99086998 1.56493002 -1.99086998 0 P 0 
L 1.6036 -2.03086998 1.60413996 -2.03086998 0 P 0 
L 1.59891004 -2.02986998 1.60406998 -2.02986998 0 P 0 
L 1.59435 -2.02886998 1.604 -2.02886998 0 P 0 
L 1.58838996 -2.02786998 1.60393002 -2.02786998 0 P 0 
L 1.57981004 -2.02686998 1.60386004 -2.02686998 0 P 0 
L 1.54575 -1.98923996 1.53931998 -1.99021998 0 P 0 
L 1.53931998 -1.99021998 1.53298996 -1.99171998 0 P 0 
L 1.53298996 -1.99171998 1.52678996 -1.99373996 0 P 0 
L 1.52678996 -1.99373996 1.52376998 -1.995 0 P 0 
L 1.52376998 -1.995 1.52086998 -1.99651004 0 P 0 
L 1.52086998 -1.99651004 1.5181 -1.99826004 0 P 0 
L 1.5181 -1.99826004 1.51548002 -2.00023002 0 P 0 
L 1.51548002 -2.00023002 1.51301004 -2.00243002 0 P 0 
L 1.51301004 -2.00243002 1.51128996 -2.00423002 0 P 0 
L 1.51128996 -2.00423002 1.50971998 -2.00616004 0 P 0 
L 1.50971998 -2.00616004 1.50831004 -2.00821004 0 P 0 
L 1.50831004 -2.00821004 1.50706998 -2.01036998 0 P 0 
L 1.50706998 -2.01036998 1.50598996 -2.01261998 0 P 0 
L 1.50598996 -2.01261998 1.50508996 -2.01496998 0 P 0 
L 1.50508996 -2.01496998 1.5042 -2.01801004 0 P 0 
L 1.5042 -2.01801004 1.50355 -2.02111004 0 P 0 
L 1.50355 -2.02111004 1.50313996 -2.02426004 0 P 0 
L 1.50313996 -2.02426004 1.50298996 -2.02743002 0 P 0 
L 1.50298996 -2.02743002 1.50308996 -2.03063002 0 P 0 
L 1.50308996 -2.03063002 1.50338002 -2.03326998 0 P 0 
L 1.50338002 -2.03326998 1.50385 -2.03588002 0 P 0 
L 1.50385 -2.03588002 1.50451004 -2.03845 0 P 0 
L 1.50451004 -2.03845 1.50535 -2.04096998 0 P 0 
L 1.50535 -2.04096998 1.50633002 -2.0433 0 P 0 
L 1.50633002 -2.0433 1.5075 -2.04553002 0 P 0 
L 1.5075 -2.04553002 1.50883996 -2.04766998 0 P 0 
L 1.50883996 -2.04766998 1.51036998 -2.04968996 0 P 0 
L 1.51036998 -2.04968996 1.51323002 -2.05291998 0 P 0 
L 1.51323002 -2.05291998 1.51631998 -2.05593996 0 P 0 
L 1.51631998 -2.05593996 1.51961998 -2.05871004 0 P 0 
L 1.51961998 -2.05871004 1.53591004 -2.0706 0 P 0 
L 1.53591004 -2.0706 1.54668002 -2.07831004 0 P 0 
L 1.54668002 -2.07831004 1.54793996 -2.07933996 0 P 0 
L 1.54793996 -2.07933996 1.54911998 -2.08046998 0 P 0 
L 1.54911998 -2.08046998 1.55021004 -2.08168002 0 P 0 
L 1.55021004 -2.08168002 1.5512 -2.08298996 0 P 0 
L 1.5512 -2.08298996 1.55136004 -2.08323002 0 P 0 
L 1.55136004 -2.08323002 1.5515 -2.08348002 0 P 0 
L 1.5515 -2.08348002 1.55161004 -2.08373996 0 P 0 
L 1.55161004 -2.08373996 1.5517 -2.08401998 0 P 0 
L 1.5517 -2.08401998 1.55176998 -2.0843 0 P 0 
L 1.55176998 -2.0843 1.55181004 -2.08458002 0 P 0 
L 1.55181004 -2.08458002 1.55183002 -2.08486998 0 P 0 
L 1.55183002 -2.08486998 1.55181998 -2.08516004 0 P 0 
L 1.55181998 -2.08516004 1.55178996 -2.08545 0 P 0 
L 1.55178996 -2.08545 1.55173996 -2.08573002 0 P 0 
L 1.55173996 -2.08573002 1.55166004 -2.086 0 P 0 
L 1.55166004 -2.086 1.55156004 -2.08628002 0 P 0 
L 1.55156004 -2.08628002 1.55136998 -2.08666998 0 P 0 
L 1.55136998 -2.08666998 1.55115 -2.08703996 0 P 0 
L 1.55115 -2.08703996 1.5509 -2.08738996 0 P 0 
L 1.5509 -2.08738996 1.55063002 -2.08771998 0 P 0 
L 1.55063002 -2.08771998 1.55033002 -2.08803002 0 P 0 
L 1.55033002 -2.08803002 1.55 -2.08831004 0 P 0 
L 1.55 -2.08831004 1.54966004 -2.08856004 0 P 0 
L 1.54966004 -2.08856004 1.54928996 -2.08878996 0 P 0 
L 1.54928996 -2.08878996 1.5489 -2.08898996 0 P 0 
L 1.5489 -2.08898996 1.54786004 -2.08941004 0 P 0 
L 1.54786004 -2.08941004 1.54678996 -2.08973996 0 P 0 
L 1.54678996 -2.08973996 1.54568002 -2.08998002 0 P 0 
L 1.54568002 -2.08998002 1.54456998 -2.09011998 0 P 0 
L 1.54456998 -2.09011998 1.54343996 -2.09016998 0 P 0 
L 1.54343996 -2.09016998 1.53906998 -2.09003002 0 P 0 
L 1.53906998 -2.09003002 1.53468002 -2.08961998 0 P 0 
L 1.53468002 -2.08961998 1.52908996 -2.08878996 0 P 0 
L 1.52908996 -2.08878996 1.52351004 -2.08766004 0 P 0 
L 1.52351004 -2.08766004 1.51005 -2.08418996 0 P 0 
L 1.51005 -2.08418996 1.50631004 -2.08318002 0 P 0 
L 1.50631004 -2.08318002 1.50308002 -2.08238996 0 P 0 
L 1.50308002 -2.08238996 1.50033996 -2.08183002 0 P 0 
L 1.50033996 -2.08183002 1.5003 -2.08181998 0 P 0 
L 1.5003 -2.08181998 1.50016004 -2.08181998 0 P 0 
L 1.50016004 -2.08181998 1.50011998 -2.08183002 0 P 0 
L 1.50011998 -2.08183002 1.50006998 -2.08183996 0 P 0 
L 1.50006998 -2.08183996 1.50003002 -2.08186004 0 P 0 
L 1.50003002 -2.08186004 1.49998996 -2.08186998 0 P 0 
L 1.49998996 -2.08186998 1.49995 -2.08188996 0 P 0 
L 1.49995 -2.08188996 1.49991004 -2.08191998 0 P 0 
L 1.49991004 -2.08191998 1.49988002 -2.08195 0 P 0 
L 1.49988002 -2.08195 1.49983996 -2.08198002 0 P 0 
L 1.49983996 -2.08198002 1.4997 -2.08213996 0 P 0 
L 1.4997 -2.08213996 1.49956004 -2.08231998 0 P 0 
L 1.49956004 -2.08231998 1.49943996 -2.0825 0 P 0 
L 1.49943996 -2.0825 1.49933996 -2.0827 0 P 0 
L 1.49933996 -2.0827 1.49925 -2.0829 0 P 0 
L 1.49925 -2.0829 1.49918996 -2.08311004 0 P 0 
L 1.49918996 -2.08311004 1.49913996 -2.08333002 0 P 0 
L 1.49913996 -2.08333002 1.49911004 -2.08355 0 P 0 
L 1.49911004 -2.08355 1.4991 -2.08376998 0 P 0 
L 1.4991 -2.08376998 1.49911004 -2.08398996 0 P 0 
L 1.49911004 -2.08398996 1.50071004 -2.10395 0 P 0 
L 1.50071004 -2.10395 1.5024 -2.12403996 0 P 0 
L 1.5024 -2.12403996 1.50241998 -2.12418002 0 P 0 
L 1.50241998 -2.12418002 1.50246004 -2.12431004 0 P 0 
L 1.50246004 -2.12431004 1.50248996 -2.12445 0 P 0 
L 1.50248996 -2.12445 1.50255 -2.12456998 0 P 0 
L 1.50255 -2.12456998 1.50261004 -2.1247 0 P 0 
L 1.50261004 -2.1247 1.50276998 -2.12491998 0 P 0 
L 1.50276998 -2.12491998 1.50286004 -2.12501998 0 P 0 
L 1.50286004 -2.12501998 1.50296998 -2.12511998 0 P 0 
L 1.50296998 -2.12511998 1.50308002 -2.12521004 0 P 0 
L 1.50308002 -2.12521004 1.50318996 -2.12528002 0 P 0 
L 1.50318996 -2.12528002 1.50331998 -2.12535 0 P 0 
L 1.50331998 -2.12535 1.50343996 -2.1254 0 P 0 
L 1.50343996 -2.1254 1.50391998 -2.12556004 0 P 0 
L 1.50391998 -2.12556004 1.5044 -2.12568996 0 P 0 
L 1.5044 -2.12568996 1.50848002 -2.12648996 0 P 0 
L 1.50848002 -2.12648996 1.51328996 -2.12738002 0 P 0 
L 1.51328996 -2.12738002 1.51873996 -2.12833996 0 P 0 
L 1.51873996 -2.12833996 1.52606004 -2.12945 0 P 0 
L 1.52606004 -2.12945 1.53343996 -2.13023002 0 P 0 
L 1.53343996 -2.13023002 1.54886998 -2.13086998 0 P 0 
L 1.54886998 -2.13086998 1.56305 -2.1303 0 P 0 
L 1.56305 -2.1303 1.56666004 -2.12988996 0 P 0 
L 1.56666004 -2.12988996 1.57023002 -2.12926998 0 P 0 
L 1.57023002 -2.12926998 1.5738 -2.12843002 0 P 0 
L 1.5738 -2.12843002 1.57945 -2.12668996 0 P 0 
L 1.57945 -2.12668996 1.58498002 -2.12456998 0 P 0 
L 1.58498002 -2.12456998 1.58793996 -2.12318002 0 P 0 
L 1.58793996 -2.12318002 1.59078996 -2.12156004 0 P 0 
L 1.59078996 -2.12156004 1.59348996 -2.11971998 0 P 0 
L 1.59348996 -2.11971998 1.59525 -2.11833002 0 P 0 
L 1.59525 -2.11833002 1.5969 -2.11681998 0 P 0 
L 1.5969 -2.11681998 1.59846004 -2.11521004 0 P 0 
L 1.59846004 -2.11521004 1.59991004 -2.11348002 0 P 0 
L 1.59991004 -2.11348002 1.60175 -2.11093996 0 P 0 
L 1.60175 -2.11093996 1.60338002 -2.10826998 0 P 0 
L 1.60338002 -2.10826998 1.60481004 -2.10548002 0 P 0 
L 1.60481004 -2.10548002 1.60573002 -2.10321004 0 P 0 
L 1.60573002 -2.10321004 1.60646004 -2.10088002 0 P 0 
L 1.60646004 -2.10088002 1.60698002 -2.09848996 0 P 0 
L 1.60698002 -2.09848996 1.60756004 -2.09421998 0 P 0 
L 1.60756004 -2.09421998 1.6078 -2.08991004 0 P 0 
L 1.6078 -2.08991004 1.60768996 -2.08565 0 P 0 
L 1.60768996 -2.08565 1.60723002 -2.08141998 0 P 0 
L 1.60723002 -2.08141998 1.60691998 -2.07968002 0 P 0 
L 1.60691998 -2.07968002 1.60646998 -2.07796998 0 P 0 
L 1.60646998 -2.07796998 1.60591998 -2.0763 0 P 0 
L 1.60591998 -2.0763 1.60523002 -2.07466998 0 P 0 
L 1.60523002 -2.07466998 1.60411998 -2.07246998 0 P 0 
L 1.60411998 -2.07246998 1.60281004 -2.07038002 0 P 0 
L 1.60281004 -2.07038002 1.60131998 -2.06838996 0 P 0 
L 1.60131998 -2.06838996 1.59803996 -2.06461998 0 P 0 
L 1.59803996 -2.06461998 1.59455 -2.06101998 0 P 0 
L 1.59455 -2.06101998 1.59031998 -2.05708996 0 P 0 
L 1.59031998 -2.05708996 1.58586004 -2.05333996 0 P 0 
L 1.58586004 -2.05333996 1.57588002 -2.04598996 0 P 0 
L 1.57588002 -2.04598996 1.56685 -2.03963996 0 P 0 
L 1.56685 -2.03963996 1.56578002 -2.03878996 0 P 0 
L 1.56578002 -2.03878996 1.56476998 -2.03786004 0 P 0 
L 1.56476998 -2.03786004 1.56383002 -2.03686998 0 P 0 
L 1.56383002 -2.03686998 1.56295 -2.0358 0 P 0 
L 1.56295 -2.0358 1.56276998 -2.03555 0 P 0 
L 1.56276998 -2.03555 1.56261004 -2.03528002 0 P 0 
L 1.56261004 -2.03528002 1.56246998 -2.035 0 P 0 
L 1.56246998 -2.035 1.56236004 -2.03471998 0 P 0 
L 1.56236004 -2.03471998 1.56226998 -2.03441998 0 P 0 
L 1.56226998 -2.03441998 1.5622 -2.03411998 0 P 0 
L 1.5622 -2.03411998 1.56216004 -2.03381998 0 P 0 
L 1.56216004 -2.03381998 1.56213996 -2.03351004 0 P 0 
L 1.56213996 -2.03351004 1.56215 -2.0332 0 P 0 
L 1.56215 -2.0332 1.56218002 -2.03288996 0 P 0 
L 1.56218002 -2.03288996 1.56225 -2.03253996 0 P 0 
L 1.56225 -2.03253996 1.56233996 -2.03221004 0 P 0 
L 1.56233996 -2.03221004 1.56246004 -2.03186998 0 P 0 
L 1.56246004 -2.03186998 1.56261004 -2.03156004 0 P 0 
L 1.56261004 -2.03156004 1.56278996 -2.03125 0 P 0 
L 1.56278996 -2.03125 1.56298002 -2.03096004 0 P 0 
L 1.56298002 -2.03096004 1.56321004 -2.03068996 0 P 0 
L 1.56321004 -2.03068996 1.56345 -2.03043996 0 P 0 
L 1.56345 -2.03043996 1.56371004 -2.0302 0 P 0 
L 1.56371004 -2.0302 1.56416004 -2.02986004 0 P 0 
L 1.56416004 -2.02986004 1.56463002 -2.02955 0 P 0 
L 1.56463002 -2.02955 1.56511998 -2.02928002 0 P 0 
L 1.56511998 -2.02928002 1.56561998 -2.02903002 0 P 0 
L 1.56561998 -2.02903002 1.56611998 -2.02883996 0 P 0 
L 1.56611998 -2.02883996 1.56663996 -2.02866998 0 P 0 
L 1.56663996 -2.02866998 1.56716004 -2.02855 0 P 0 
L 1.56716004 -2.02855 1.5677 -2.02846998 0 P 0 
L 1.5677 -2.02846998 1.56926998 -2.02835 0 P 0 
L 1.56926998 -2.02835 1.57085 -2.02833996 0 P 0 
L 1.57085 -2.02833996 1.57725 -2.02866998 0 P 0 
L 1.57725 -2.02866998 1.58205 -2.02906004 0 P 0 
L 1.58205 -2.02906004 1.58746998 -2.02975 0 P 0 
L 1.58746998 -2.02975 1.59271004 -2.03056998 0 P 0 
L 1.59271004 -2.03056998 1.59681004 -2.03143002 0 P 0 
L 1.59681004 -2.03143002 1.60016004 -2.03221998 0 P 0 
L 1.60016004 -2.03221998 1.60308002 -2.03281004 0 P 0 
L 1.60308002 -2.03281004 1.60553996 -2.03323996 0 P 0 
L 1.60553996 -2.03323996 1.60568996 -2.03323996 0 P 0 
L 1.60568996 -2.03323996 1.60576998 -2.03321998 0 P 0 
L 1.60576998 -2.03321998 1.60586004 -2.03316004 0 P 0 
L 1.60586004 -2.03316004 1.6059 -2.03313996 0 P 0 
L 1.6059 -2.03313996 1.60591998 -2.03311004 0 P 0 
L 1.60591998 -2.03311004 1.60598996 -2.03303996 0 P 0 
L 1.60598996 -2.03303996 1.60605 -2.03296998 0 P 0 
L 1.60605 -2.03296998 1.6061 -2.03288996 0 P 0 
L 1.6061 -2.03288996 1.60618002 -2.03273002 0 P 0 
L 1.60618002 -2.03273002 1.60621004 -2.03263002 0 P 0 
L 1.60621004 -2.03263002 1.60623002 -2.03253996 0 P 0 
L 1.60623002 -2.03253996 1.60625 -2.03236004 0 P 0 
L 1.60625 -2.03236004 1.60623996 -2.03226004 0 P 0 
L 1.60623996 -2.03226004 1.60508002 -2.01578002 0 P 0 
L 1.60508002 -2.01578002 1.60393996 -2.00068002 0 P 0 
L 1.60393996 -2.00068002 1.60368002 -1.99833996 0 P 0 
L 1.60368002 -1.99833996 1.60326998 -1.99601004 0 P 0 
L 1.60326998 -1.99601004 1.60321004 -1.99576998 0 P 0 
L 1.60321004 -1.99576998 1.60313996 -1.99553002 0 P 0 
L 1.60313996 -1.99553002 1.60303996 -1.9953 0 P 0 
L 1.60303996 -1.9953 1.60293002 -1.99508002 0 P 0 
L 1.60293002 -1.99508002 1.60281004 -1.99486004 0 P 0 
L 1.60281004 -1.99486004 1.60261998 -1.9946 0 P 0 
L 1.60261998 -1.9946 1.60241004 -1.99435 0 P 0 
L 1.60241004 -1.99435 1.60218002 -1.99411998 0 P 0 
L 1.60218002 -1.99411998 1.60191998 -1.99391004 0 P 0 
L 1.60191998 -1.99391004 1.60161004 -1.99368996 0 P 0 
L 1.60161004 -1.99368996 1.60128996 -1.99348996 0 P 0 
L 1.60128996 -1.99348996 1.60095 -1.99331998 0 P 0 
L 1.60095 -1.99331998 1.6006 -1.99316004 0 P 0 
L 1.6006 -1.99316004 1.59966004 -1.99283002 0 P 0 
L 1.59966004 -1.99283002 1.59871004 -1.99255 0 P 0 
L 1.59871004 -1.99255 1.5933 -1.99135 0 P 0 
L 1.5933 -1.99135 1.5878 -1.9905 0 P 0 
L 1.5878 -1.9905 1.57285 -1.98915 0 P 0 
L 1.57285 -1.98915 1.55763996 -1.98861004 0 P 0 
L 1.55763996 -1.98861004 1.55171004 -1.98876004 0 P 0 
L 1.55171004 -1.98876004 1.54575 -1.98923996 0 P 0 
L 1.53011998 -2.12786998 1.5666 -2.12786998 0 P 0 
L 1.52236004 -2.12686998 1.57168002 -2.12686998 0 P 0 
L 1.51621998 -2.12586998 1.5753 -2.12586998 0 P 0 
L 1.51071004 -2.12486998 1.57856004 -2.12486998 0 P 0 
L 1.50553002 -2.12386998 1.58121004 -2.12386998 0 P 0 
L 1.50431004 -2.12286998 1.58381998 -2.12286998 0 P 0 
L 1.50423002 -2.12186998 1.58601998 -2.12186998 0 P 0 
L 1.50413996 -2.12086998 1.58796004 -2.12086998 0 P 0 
L 1.50406004 -2.11986998 1.58971004 -2.11986998 0 P 0 
L 1.50396998 -2.11886998 1.59118002 -2.11886998 0 P 0 
L 1.50388996 -2.11786998 1.5926 -2.11786998 0 P 0 
L 1.50381004 -2.11686998 1.59386004 -2.11686998 0 P 0 
L 1.50371998 -2.11586998 1.59496998 -2.11586998 0 P 0 
L 1.50363996 -2.11486998 1.59601004 -2.11486998 0 P 0 
L 1.50355 -2.11386998 1.59696998 -2.11386998 0 P 0 
L 1.50346998 -2.11286998 1.59781004 -2.11286998 0 P 0 
L 1.50338002 -2.11186998 1.5986 -2.11186998 0 P 0 
L 1.5033 -2.11086998 1.59933002 -2.11086998 0 P 0 
L 1.50321004 -2.10986998 1.60005 -2.10986998 0 P 0 
L 1.50313002 -2.10886998 1.60066998 -2.10886998 0 P 0 
L 1.50305 -2.10786998 1.60128002 -2.10786998 0 P 0 
L 1.50296004 -2.10686998 1.60185 -2.10686998 0 P 0 
L 1.50288002 -2.10586998 1.60236004 -2.10586998 0 P 0 
L 1.50278996 -2.10486998 1.60286998 -2.10486998 0 P 0 
L 1.50271004 -2.10386998 1.6033 -2.10386998 0 P 0 
L 1.50263002 -2.10286998 1.60371004 -2.10286998 0 P 0 
L 1.50255 -2.10186998 1.60405 -2.10186998 0 P 0 
L 1.50246998 -2.10086998 1.60436004 -2.10086998 0 P 0 
L 1.50238996 -2.09986998 1.60463002 -2.09986998 0 P 0 
L 1.50231004 -2.09886998 1.60485 -2.09886998 0 P 0 
L 1.50223002 -2.09786998 1.60505 -2.09786998 0 P 0 
L 1.50215 -2.09686998 1.60518002 -2.09686998 0 P 0 
L 1.50206998 -2.09586998 1.60531998 -2.09586998 0 P 0 
L 1.50198996 -2.09486998 1.60545 -2.09486998 0 P 0 
L 1.50191004 -2.09386998 1.60558002 -2.09386998 0 P 0 
L 1.50183002 -2.09286998 1.60563002 -2.09286998 0 P 0 
L 1.50175 -2.09186998 1.53725 -2.09186998 0 P 0 
L 1.54638996 -2.09186998 1.60568996 -2.09186998 0 P 0 
L 1.50166998 -2.09086998 1.5295 -2.09086998 0 P 0 
L 1.54956998 -2.09086998 1.60573996 -2.09086998 0 P 0 
L 1.50158996 -2.08986998 1.52436004 -2.08986998 0 P 0 
L 1.55125 -2.08986998 1.60578996 -2.08986998 0 P 0 
L 1.50151004 -2.08886998 1.52021004 -2.08886998 0 P 0 
L 1.55226998 -2.08886998 1.60576998 -2.08886998 0 P 0 
L 1.50143002 -2.08786998 1.51633002 -2.08786998 0 P 0 
L 1.55298002 -2.08786998 1.60573996 -2.08786998 0 P 0 
L 1.50133996 -2.08686998 1.51246004 -2.08686998 0 P 0 
L 1.55346998 -2.08686998 1.60571998 -2.08686998 0 P 0 
L 1.50126998 -2.08586998 1.50861998 -2.08586998 0 P 0 
L 1.55375 -2.08586998 1.60568996 -2.08586998 0 P 0 
L 1.50118002 -2.08486998 1.50481004 -2.08486998 0 P 0 
L 1.55383002 -2.08486998 1.60558996 -2.08486998 0 P 0 
L 1.55371998 -2.08386998 1.60548996 -2.08386998 0 P 0 
L 1.54886998 -2.12886998 1.53358996 -2.12823996 0 P 0 
L 1.53358996 -2.12823996 1.52631998 -2.12746998 0 P 0 
L 1.52631998 -2.12746998 1.51906004 -2.12636998 0 P 0 
L 1.51906004 -2.12636998 1.51363002 -2.12541004 0 P 0 
L 1.51363002 -2.12541004 1.50886998 -2.12451998 0 P 0 
L 1.50886998 -2.12451998 1.50483996 -2.12373996 0 P 0 
L 1.50483996 -2.12373996 1.50448996 -2.12365 0 P 0 
L 1.50448996 -2.12365 1.50438002 -2.12361004 0 P 0 
L 1.50438002 -2.12361004 1.5027 -2.10378002 0 P 0 
L 1.5027 -2.10378002 1.50111998 -2.08403002 0 P 0 
L 1.50111998 -2.08403002 1.50263996 -2.08433996 0 P 0 
L 1.50263996 -2.08433996 1.50581004 -2.08511004 0 P 0 
L 1.50581004 -2.08511004 1.50955 -2.08611998 0 P 0 
L 1.50955 -2.08611998 1.52306004 -2.08961004 0 P 0 
L 1.52306004 -2.08961004 1.52311004 -2.08961998 0 P 0 
L 1.52311004 -2.08961998 1.52875 -2.09076004 0 P 0 
L 1.52875 -2.09076004 1.5288 -2.09076004 0 P 0 
L 1.5288 -2.09076004 1.53443996 -2.09161004 0 P 0 
L 1.53443996 -2.09161004 1.53893996 -2.09203002 0 P 0 
L 1.53893996 -2.09203002 1.54346004 -2.09216998 0 P 0 
L 1.54346004 -2.09216998 1.54473996 -2.09211004 0 P 0 
L 1.54473996 -2.09211004 1.54603002 -2.09195 0 P 0 
L 1.54603002 -2.09195 1.54728996 -2.09166998 0 P 0 
L 1.54728996 -2.09166998 1.54853002 -2.09128996 0 P 0 
L 1.54853002 -2.09128996 1.54973002 -2.09081004 0 P 0 
L 1.54973002 -2.09081004 1.55026998 -2.09053996 0 P 0 
L 1.55026998 -2.09053996 1.55076998 -2.09023002 0 P 0 
L 1.55076998 -2.09023002 1.55118002 -2.08991998 0 P 0 
L 1.55118002 -2.08991998 1.55118002 -2.08991004 0 P 0 
L 1.55118002 -2.08991004 1.5512 -2.08991004 0 P 0 
L 1.5512 -2.08991004 1.55125 -2.08986998 0 P 0 
L 1.55125 -2.08986998 1.55131004 -2.08981998 0 P 0 
L 1.55131004 -2.08981998 1.55126998 -2.08978002 0 P 0 
L 1.55126998 -2.08978002 1.55136004 -2.08978002 0 P 0 
L 1.55136004 -2.08978002 1.5517 -2.08948996 0 P 0 
L 1.5517 -2.08948996 1.55206004 -2.08911998 0 P 0 
L 1.55206004 -2.08911998 1.55205 -2.08911004 0 P 0 
L 1.55205 -2.08911004 1.55206004 -2.08911004 0 P 0 
L 1.55206004 -2.08911004 1.55211998 -2.08906004 0 P 0 
L 1.55211998 -2.08906004 1.55248996 -2.08861004 0 P 0 
L 1.55248996 -2.08861004 1.55283996 -2.08811998 0 P 0 
L 1.55283996 -2.08811998 1.55313996 -2.08761004 0 P 0 
L 1.55313996 -2.08761004 1.5534 -2.08706998 0 P 0 
L 1.5534 -2.08706998 1.55356004 -2.08663002 0 P 0 
L 1.55356004 -2.08663002 1.55368996 -2.08618996 0 P 0 
L 1.55368996 -2.08618996 1.55376998 -2.08573996 0 P 0 
L 1.55376998 -2.08573996 1.55378002 -2.08565 0 P 0 
L 1.55378002 -2.08565 1.55381998 -2.08528002 0 P 0 
L 1.55381998 -2.08528002 1.55383002 -2.08481998 0 P 0 
L 1.55383002 -2.08481998 1.5538 -2.08436998 0 P 0 
L 1.5538 -2.08436998 1.55373002 -2.08391998 0 P 0 
L 1.55373002 -2.08391998 1.55361998 -2.08346998 0 P 0 
L 1.55361998 -2.08346998 1.55348002 -2.08303996 0 P 0 
L 1.55348002 -2.08303996 1.5533 -2.08261004 0 P 0 
L 1.5533 -2.08261004 1.55308996 -2.08221004 0 P 0 
L 1.55308996 -2.08221004 1.55283996 -2.08183002 0 P 0 
L 1.55283996 -2.08183002 1.55175 -2.0804 0 P 0 
L 1.55175 -2.0804 1.55055 -2.07908002 0 P 0 
L 1.55055 -2.07908002 1.54926004 -2.07783996 0 P 0 
L 1.54926004 -2.07783996 1.54788996 -2.07671998 0 P 0 
L 1.54788996 -2.07671998 1.53706998 -2.06898002 0 P 0 
L 1.53706998 -2.06898002 1.52085 -2.05713996 0 P 0 
L 1.52085 -2.05713996 1.51766004 -2.05445 0 P 0 
L 1.51766004 -2.05445 1.51468002 -2.05153996 0 P 0 
L 1.51468002 -2.05153996 1.51191998 -2.04841998 0 P 0 
L 1.51191998 -2.04841998 1.51048996 -2.04651998 0 P 0 
L 1.51048996 -2.04651998 1.50923002 -2.04453002 0 P 0 
L 1.50923002 -2.04453002 1.50813996 -2.04245 0 P 0 
L 1.50813996 -2.04245 1.50721998 -2.04026004 0 P 0 
L 1.50721998 -2.04026004 1.50643002 -2.03788002 0 P 0 
L 1.50643002 -2.03788002 1.50581004 -2.03545 0 P 0 
L 1.50581004 -2.03545 1.50536004 -2.03298996 0 P 0 
L 1.50536004 -2.03298996 1.50508996 -2.0305 0 P 0 
L 1.50508996 -2.0305 1.50498996 -2.02745 0 P 0 
L 1.50498996 -2.02745 1.50513996 -2.02443996 0 P 0 
L 1.50513996 -2.02443996 1.50551998 -2.02145 0 P 0 
L 1.50551998 -2.02145 1.50613996 -2.0185 0 P 0 
L 1.50613996 -2.0185 1.50698996 -2.01561004 0 P 0 
L 1.50698996 -2.01561004 1.50783002 -2.01341004 0 P 0 
L 1.50783002 -2.01341004 1.50883002 -2.0113 0 P 0 
L 1.50883002 -2.0113 1.51 -2.00928002 0 P 0 
L 1.51 -2.00928002 1.51133002 -2.00736004 0 P 0 
L 1.51133002 -2.00736004 1.5128 -2.00555 0 P 0 
L 1.5128 -2.00555 1.5144 -2.00386004 0 P 0 
L 1.5144 -2.00386004 1.51675 -2.00176998 0 P 0 
L 1.51675 -2.00176998 1.51923002 -1.9999 0 P 0 
L 1.51923002 -1.9999 1.52186004 -1.99823996 0 P 0 
L 1.52186004 -1.99823996 1.52461998 -1.99681004 0 P 0 
L 1.52461998 -1.99681004 1.52748996 -1.99561004 0 P 0 
L 1.52748996 -1.99561004 1.53353002 -1.99363996 0 P 0 
L 1.53353002 -1.99363996 1.5397 -1.99218002 0 P 0 
L 1.5397 -1.99218002 1.54598002 -1.99123002 0 P 0 
L 1.54598002 -1.99123002 1.55181004 -1.99075 0 P 0 
L 1.55181004 -1.99075 1.55763002 -1.99061998 0 P 0 
L 1.55763002 -1.99061998 1.57273002 -1.99113996 0 P 0 
L 1.57273002 -1.99113996 1.58755 -1.99248996 0 P 0 
L 1.58755 -1.99248996 1.59293002 -1.99331998 0 P 0 
L 1.59293002 -1.99331998 1.59821004 -1.99448996 0 P 0 
L 1.59821004 -1.99448996 1.59905 -1.99473002 0 P 0 
L 1.59905 -1.99473002 1.59986004 -1.99501998 0 P 0 
L 1.59986004 -1.99501998 1.60008002 -1.99511998 0 P 0 
L 1.60008002 -1.99511998 1.6003 -1.99523002 0 P 0 
L 1.6003 -1.99523002 1.60051004 -1.99536004 0 P 0 
L 1.60051004 -1.99536004 1.60071004 -1.9955 0 P 0 
L 1.60071004 -1.9955 1.60083002 -1.99561004 0 P 0 
L 1.60083002 -1.99561004 1.60093996 -1.99571004 0 P 0 
L 1.60093996 -1.99571004 1.60103996 -1.99583002 0 P 0 
L 1.60103996 -1.99583002 1.60111998 -1.99595 0 P 0 
L 1.60111998 -1.99595 1.60116998 -1.99601998 0 P 0 
L 1.60116998 -1.99601998 1.60121004 -1.99611004 0 P 0 
L 1.60121004 -1.99611004 1.60125 -1.99621004 0 P 0 
L 1.60125 -1.99621004 1.60128002 -1.9963 0 P 0 
L 1.60128002 -1.9963 1.60131004 -1.99641004 0 P 0 
L 1.60131004 -1.99641004 1.6017 -1.99861998 0 P 0 
L 1.6017 -1.99861998 1.60195 -2.00086998 0 P 0 
L 1.60195 -2.00086998 1.60308002 -2.01593002 0 P 0 
L 1.60308002 -2.01593002 1.60415 -2.03096998 0 P 0 
L 1.60415 -2.03096998 1.60345 -2.03083996 0 P 0 
L 1.60345 -2.03083996 1.60058996 -2.03026004 0 P 0 
L 1.60058996 -2.03026004 1.59723002 -2.02948002 0 P 0 
L 1.59723002 -2.02948002 1.59721998 -2.02948002 0 P 0 
L 1.59721998 -2.02948002 1.59306998 -2.0286 0 P 0 
L 1.59306998 -2.0286 1.58776004 -2.02776998 0 P 0 
L 1.58776004 -2.02776998 1.58226004 -2.02708002 0 P 0 
L 1.58226004 -2.02708002 1.57738002 -2.02666998 0 P 0 
L 1.57738002 -2.02666998 1.5709 -2.02633996 0 P 0 
L 1.5709 -2.02633996 1.56918996 -2.02635 0 P 0 
L 1.56918996 -2.02635 1.56746998 -2.02648996 0 P 0 
L 1.56746998 -2.02648996 1.56678996 -2.02658996 0 P 0 
L 1.56678996 -2.02658996 1.56611998 -2.02673996 0 P 0 
L 1.56611998 -2.02673996 1.56546004 -2.02695 0 P 0 
L 1.56546004 -2.02695 1.56481998 -2.0272 0 P 0 
L 1.56481998 -2.0272 1.56418996 -2.0275 0 P 0 
L 1.56418996 -2.0275 1.56358002 -2.02785 0 P 0 
L 1.56358002 -2.02785 1.563 -2.02823002 0 P 0 
L 1.563 -2.02823002 1.56245 -2.02865 0 P 0 
L 1.56245 -2.02865 1.56206998 -2.02898996 0 P 0 
L 1.56206998 -2.02898996 1.56171004 -2.02936004 0 P 0 
L 1.56171004 -2.02936004 1.56138002 -2.02976004 0 P 0 
L 1.56138002 -2.02976004 1.56108996 -2.03018996 0 P 0 
L 1.56108996 -2.03018996 1.56083002 -2.03063996 0 P 0 
L 1.56083002 -2.03063996 1.56061998 -2.0311 0 P 0 
L 1.56061998 -2.0311 1.56043996 -2.03158996 0 P 0 
L 1.56043996 -2.03158996 1.5603 -2.03208002 0 P 0 
L 1.5603 -2.03208002 1.5602 -2.0326 0 P 0 
L 1.5602 -2.0326 1.56015 -2.03308002 0 P 0 
L 1.56015 -2.03308002 1.56013996 -2.03353996 0 P 0 
L 1.56013996 -2.03353996 1.56016004 -2.03391004 0 P 0 
L 1.56016004 -2.03391004 1.56048002 -2.03391004 0 P 0 
L 1.56048002 -2.03391004 1.56016004 -2.03393002 0 P 0 
L 1.56016004 -2.03393002 1.56016998 -2.03401004 0 P 0 
L 1.56016998 -2.03401004 1.56023002 -2.03448002 0 P 0 
L 1.56023002 -2.03448002 1.56025 -2.03456004 0 P 0 
L 1.56025 -2.03456004 1.56033002 -2.03493002 0 P 0 
L 1.56033002 -2.03493002 1.56046998 -2.03538002 0 P 0 
L 1.56046998 -2.03538002 1.56063996 -2.03581998 0 P 0 
L 1.56063996 -2.03581998 1.56085 -2.03623996 0 P 0 
L 1.56085 -2.03623996 1.56108996 -2.03663996 0 P 0 
L 1.56108996 -2.03663996 1.56136004 -2.03701998 0 P 0 
L 1.56136004 -2.03701998 1.56233002 -2.03818996 0 P 0 
L 1.56233002 -2.03818996 1.56336998 -2.03928996 0 P 0 
L 1.56336998 -2.03928996 1.56448002 -2.04031004 0 P 0 
L 1.56448002 -2.04031004 1.56566004 -2.04123996 0 P 0 
L 1.56566004 -2.04123996 1.57471004 -2.04761998 0 P 0 
L 1.57471004 -2.04761998 1.58461998 -2.05491004 0 P 0 
L 1.58461998 -2.05491004 1.58898996 -2.05858996 0 P 0 
L 1.58898996 -2.05858996 1.59315 -2.06245 0 P 0 
L 1.59315 -2.06245 1.59656998 -2.06596998 0 P 0 
L 1.59656998 -2.06596998 1.59976004 -2.06965 0 P 0 
L 1.59976004 -2.06965 1.60116004 -2.07151004 0 P 0 
L 1.60116004 -2.07151004 1.60238002 -2.07346004 0 P 0 
L 1.60238002 -2.07346004 1.60341998 -2.0755 0 P 0 
L 1.60341998 -2.0755 1.60403996 -2.077 0 P 0 
L 1.60403996 -2.077 1.60456004 -2.07853996 0 P 0 
L 1.60456004 -2.07853996 1.60496004 -2.08011004 0 P 0 
L 1.60496004 -2.08011004 1.60525 -2.0817 0 P 0 
L 1.60525 -2.0817 1.60568996 -2.08578002 0 P 0 
L 1.60568996 -2.08578002 1.60578996 -2.08988002 0 P 0 
L 1.60578996 -2.08988002 1.60556998 -2.09403002 0 P 0 
L 1.60556998 -2.09403002 1.60501004 -2.09813996 0 P 0 
L 1.60501004 -2.09813996 1.60451998 -2.10036998 0 P 0 
L 1.60451998 -2.10036998 1.60383996 -2.10253996 0 P 0 
L 1.60383996 -2.10253996 1.60298996 -2.10465 0 P 0 
L 1.60298996 -2.10465 1.60163996 -2.1073 0 P 0 
L 1.60163996 -2.1073 1.60008002 -2.10983002 0 P 0 
L 1.60008002 -2.10983002 1.59833002 -2.11225 0 P 0 
L 1.59833002 -2.11225 1.59696998 -2.11386998 0 P 0 
L 1.59696998 -2.11386998 1.59551004 -2.11538996 0 P 0 
L 1.59551004 -2.11538996 1.59395 -2.1168 0 P 0 
L 1.59395 -2.1168 1.59231004 -2.11811004 0 P 0 
L 1.59231004 -2.11811004 1.58973002 -2.11986004 0 P 0 
L 1.58973002 -2.11986004 1.58701998 -2.1214 0 P 0 
L 1.58701998 -2.1214 1.5842 -2.12273002 0 P 0 
L 1.5842 -2.12273002 1.5788 -2.1248 0 P 0 
L 1.5788 -2.1248 1.57326998 -2.12648996 0 P 0 
L 1.57326998 -2.12648996 1.56983002 -2.12731004 0 P 0 
L 1.56983002 -2.12731004 1.56638002 -2.12791004 0 P 0 
L 1.56638002 -2.12791004 1.56288996 -2.1283 0 P 0 
L 1.56288996 -2.1283 1.54886998 -2.12886998 0 P 0 
L 1.35851998 -2.06545 1.47866004 -2.06545 0 P 0 
L 1.35936004 -2.06445 1.47871004 -2.06445 0 P 0 
L 1.36041004 -2.06345 1.47875 -2.06345 0 P 0 
L 1.36163996 -2.06245 1.4788 -2.06245 0 P 0 
L 1.36293996 -2.06145 1.47883996 -2.06145 0 P 0 
L 1.36436004 -2.06045 1.47888996 -2.06045 0 P 0 
L 1.36598002 -2.05945 1.47893996 -2.05945 0 P 0 
L 1.36776004 -2.05845 1.47898996 -2.05845 0 P 0 
L 1.36971004 -2.05745 1.47903002 -2.05745 0 P 0 
L 1.37166004 -2.05645 1.47908002 -2.05645 0 P 0 
L 1.37391004 -2.05545 1.47911998 -2.05545 0 P 0 
L 1.37616998 -2.05445 1.47916998 -2.05445 0 P 0 
L 1.37873002 -2.05345 1.47921004 -2.05345 0 P 0 
L 1.38136004 -2.05245 1.47926004 -2.05245 0 P 0 
L 1.36875 -2.03345 1.37108996 -2.03345 0 P 0 
L 1.36886004 -2.03245 1.37385 -2.03245 0 P 0 
L 1.36896998 -2.03145 1.37678002 -2.03145 0 P 0 
L 1.36908996 -2.03045 1.3797 -2.03045 0 P 0 
L 1.36921004 -2.02945 1.38261998 -2.02945 0 P 0 
L 1.36933002 -2.02845 1.38638996 -2.02845 0 P 0 
L 1.36946004 -2.02745 1.39023996 -2.02745 0 P 0 
L 1.36958002 -2.02645 1.39503002 -2.02645 0 P 0 
L 1.3697 -2.02545 1.40068002 -2.02545 0 P 0 
L 1.36981998 -2.02445 1.41053996 -2.02445 0 P 0 
L 1.36993996 -2.02345 1.47993996 -2.02345 0 P 0 
L 1.37008002 -2.02245 1.47988002 -2.02245 0 P 0 
L 1.37021004 -2.02145 1.47978002 -2.02145 0 P 0 
L 1.37033996 -2.02045 1.47968002 -2.02045 0 P 0 
L 1.37046998 -2.01945 1.47953002 -2.01945 0 P 0 
L 1.3706 -2.01845 1.47936004 -2.01845 0 P 0 
L 1.37073002 -2.01745 1.47918002 -2.01745 0 P 0 
L 1.37086004 -2.01645 1.47893002 -2.01645 0 P 0 
L 1.37098996 -2.01545 1.47868002 -2.01545 0 P 0 
L 1.37113002 -2.01445 1.4784 -2.01445 0 P 0 
L 1.37126998 -2.01345 1.47806004 -2.01345 0 P 0 
L 1.3714 -2.01245 1.47773002 -2.01245 0 P 0 
L 1.37153996 -2.01145 1.47733002 -2.01145 0 P 0 
L 1.37168002 -2.01045 1.47691004 -2.01045 0 P 0 
L 1.37181004 -2.00945 1.47641004 -2.00945 0 P 0 
L 1.37195 -2.00845 1.47588996 -2.00845 0 P 0 
L 1.37208002 -2.00745 1.47528002 -2.00745 0 P 0 
L 1.37221004 -2.00645 1.47463996 -2.00645 0 P 0 
L 1.37235 -2.00545 1.47391998 -2.00545 0 P 0 
L 1.37248996 -2.00445 1.47311004 -2.00445 0 P 0 
L 1.37261998 -2.00345 1.47225 -2.00345 0 P 0 
L 1.37276004 -2.00245 1.47126998 -2.00245 0 P 0 
L 1.3729 -2.00145 1.4702 -2.00145 0 P 0 
L 1.37303002 -2.00045 1.46903996 -2.00045 0 P 0 
L 1.37316998 -1.99945 1.46775 -1.99945 0 P 0 
L 1.3733 -1.99845 1.46625 -1.99845 0 P 0 
L 1.37343996 -1.99745 1.46455 -1.99745 0 P 0 
L 1.37356998 -1.99645 1.46253996 -1.99645 0 P 0 
L 1.37753002 -1.99545 1.46041004 -1.99545 0 P 0 
L 1.38218996 -1.99445 1.45781004 -1.99445 0 P 0 
L 1.42925 -2.08345 1.47785 -2.08345 0 P 0 
L 1.42931998 -2.08245 1.47788996 -2.08245 0 P 0 
L 1.42938002 -2.08145 1.47793002 -2.08145 0 P 0 
L 1.42945 -2.08045 1.47796998 -2.08045 0 P 0 
L 1.42951004 -2.07945 1.47801004 -2.07945 0 P 0 
L 1.42958002 -2.07845 1.47806004 -2.07845 0 P 0 
L 1.42963996 -2.07745 1.4781 -2.07745 0 P 0 
L 1.4297 -2.07645 1.47815 -2.07645 0 P 0 
L 1.42976998 -2.07545 1.4782 -2.07545 0 P 0 
L 1.42983002 -2.07445 1.47825 -2.07445 0 P 0 
L 1.4299 -2.07345 1.47828996 -2.07345 0 P 0 
L 1.42963996 -2.07245 1.47833996 -2.07245 0 P 0 
L 1.42918996 -2.07145 1.47838002 -2.07145 0 P 0 
L 1.38425 -2.05145 1.47931004 -2.05145 0 P 0 
L 1.38731998 -2.05045 1.47933996 -2.05045 0 P 0 
L 1.39088002 -2.04945 1.47938002 -2.04945 0 P 0 
L 1.3947 -2.04845 1.47941004 -2.04845 0 P 0 
L 1.39851004 -2.04745 1.47945 -2.04745 0 P 0 
L 1.40233002 -2.04645 1.47948002 -2.04645 0 P 0 
L 1.40608002 -2.04545 1.47951004 -2.04545 0 P 0 
L 1.40983002 -2.04445 1.47955 -2.04445 0 P 0 
L 1.41306998 -2.04345 1.47958996 -2.04345 0 P 0 
L 1.41591998 -2.04245 1.47961998 -2.04245 0 P 0 
L 1.41876998 -2.04145 1.47965 -2.04145 0 P 0 
L 1.42133996 -2.04045 1.47968996 -2.04045 0 P 0 
L 1.42361998 -2.03945 1.47971998 -2.03945 0 P 0 
L 1.42591004 -2.03845 1.47975 -2.03845 0 P 0 
L 1.42805 -2.03745 1.47978002 -2.03745 0 P 0 
L 1.42936004 -2.03645 1.47981004 -2.03645 0 P 0 
L 1.43003002 -2.03545 1.47983002 -2.03545 0 P 0 
L 1.43081998 -2.03445 1.47986004 -2.03445 0 P 0 
L 1.43121004 -2.03345 1.47988002 -2.03345 0 P 0 
L 1.43141998 -2.03245 1.4799 -2.03245 0 P 0 
L 1.43146998 -2.03145 1.47993002 -2.03145 0 P 0 
L 1.43136004 -2.03045 1.47996004 -2.03045 0 P 0 
L 1.43108002 -2.02945 1.47998002 -2.02945 0 P 0 
L 1.4306 -2.02845 1.48001004 -2.02845 0 P 0 
L 1.42986998 -2.02745 1.48001004 -2.02745 0 P 0 
L 1.42875 -2.02645 1.47998996 -2.02645 0 P 0 
L 1.42658996 -2.02545 1.47996998 -2.02545 0 P 0 
L 1.42203996 -2.02445 1.47996004 -2.02445 0 P 0 
L 1.38748002 -1.99345 1.45483002 -1.99345 0 P 0 
L 1.39331998 -1.99245 1.45108996 -1.99245 0 P 0 
L 1.40051004 -1.99145 1.44503002 -1.99145 0 P 0 
L 1.38096998 -2.12745 1.4051 -2.12745 0 P 0 
L 1.37671004 -2.12645 1.41113996 -2.12645 0 P 0 
L 1.3736 -2.12545 1.41238996 -2.12545 0 P 0 
L 1.37096998 -2.12445 1.41268002 -2.12445 0 P 0 
L 1.36876998 -2.12345 1.41296998 -2.12345 0 P 0 
L 1.36685 -2.12245 1.41326998 -2.12245 0 P 0 
L 1.36516004 -2.12145 1.41356004 -2.12145 0 P 0 
L 1.36366004 -2.12045 1.41385 -2.12045 0 P 0 
L 1.36225 -2.11945 1.41413996 -2.11945 0 P 0 
L 1.361 -2.11845 1.41443002 -2.11845 0 P 0 
L 1.35983002 -2.11745 1.41471998 -2.11745 0 P 0 
L 1.35876004 -2.11645 1.41501004 -2.11645 0 P 0 
L 1.42661998 -2.12445 1.47693002 -2.12445 0 P 0 
L 1.42665 -2.12345 1.47693002 -2.12345 0 P 0 
L 1.4267 -2.12245 1.47693002 -2.12245 0 P 0 
L 1.42675 -2.12145 1.47693002 -2.12145 0 P 0 
L 1.42681004 -2.12045 1.47693002 -2.12045 0 P 0 
L 1.42686998 -2.11945 1.47693002 -2.11945 0 P 0 
L 1.42691998 -2.11845 1.47693002 -2.11845 0 P 0 
L 1.42698996 -2.11745 1.47693002 -2.11745 0 P 0 
L 1.42705 -2.11645 1.47693002 -2.11645 0 P 0 
L 1.42711004 -2.11545 1.47693002 -2.11545 0 P 0 
L 1.42716998 -2.11445 1.47693002 -2.11445 0 P 0 
L 1.42723002 -2.11345 1.47693996 -2.11345 0 P 0 
L 1.4273 -2.11245 1.47695 -2.11245 0 P 0 
L 1.42736998 -2.11145 1.47696004 -2.11145 0 P 0 
L 1.42743996 -2.11045 1.47698002 -2.11045 0 P 0 
L 1.42751004 -2.10945 1.47698996 -2.10945 0 P 0 
L 1.42758002 -2.10845 1.47701004 -2.10845 0 P 0 
L 1.42765 -2.10745 1.47703002 -2.10745 0 P 0 
L 1.42771004 -2.10645 1.47703996 -2.10645 0 P 0 
L 1.42778002 -2.10545 1.47706998 -2.10545 0 P 0 
L 1.42783996 -2.10445 1.4771 -2.10445 0 P 0 
L 1.42791004 -2.10345 1.47713002 -2.10345 0 P 0 
L 1.42798002 -2.10245 1.47716004 -2.10245 0 P 0 
L 1.42805 -2.10145 1.4772 -2.10145 0 P 0 
L 1.42811004 -2.10045 1.47723002 -2.10045 0 P 0 
L 1.40953002 -2.09945 1.41973002 -2.09945 0 P 0 
L 1.42818002 -2.09945 1.47726004 -2.09945 0 P 0 
L 1.41618002 -2.09845 1.41996998 -2.09845 0 P 0 
L 1.42825 -2.09845 1.47728996 -2.09845 0 P 0 
L 1.42831998 -2.09745 1.47733002 -2.09745 0 P 0 
L 1.42838996 -2.09645 1.47736004 -2.09645 0 P 0 
L 1.42846004 -2.09545 1.47738996 -2.09545 0 P 0 
L 1.42851998 -2.09445 1.47741998 -2.09445 0 P 0 
L 1.42858996 -2.09345 1.47746004 -2.09345 0 P 0 
L 1.42866004 -2.09245 1.4775 -2.09245 0 P 0 
L 1.42873002 -2.09145 1.47753996 -2.09145 0 P 0 
L 1.42878996 -2.09045 1.47758002 -2.09045 0 P 0 
L 1.42886004 -2.08945 1.47761998 -2.08945 0 P 0 
L 1.42893002 -2.08845 1.47766004 -2.08845 0 P 0 
L 1.42898996 -2.08745 1.4777 -2.08745 0 P 0 
L 1.42906004 -2.08645 1.47773002 -2.08645 0 P 0 
L 1.42911998 -2.08545 1.47776998 -2.08545 0 P 0 
L 1.42918996 -2.08445 1.47781004 -2.08445 0 P 0 
L 1.61686004 -2.17995 1.66846004 -2.17995 0 P 0 
L 1.61591004 -2.17895 1.67158996 -2.17895 0 P 0 
L 1.61553996 -2.17795 1.67431998 -2.17795 0 P 0 
L 1.61526998 -2.17695 1.67675 -2.17695 0 P 0 
L 1.61508002 -2.17595 1.67903996 -2.17595 0 P 0 
L 1.61496998 -2.17495 1.68108002 -2.17495 0 P 0 
L 1.61491004 -2.17395 1.68295 -2.17395 0 P 0 
L 1.61485 -2.17295 1.68458996 -2.17295 0 P 0 
L 1.61478996 -2.17195 1.6861 -2.17195 0 P 0 
L 1.61473002 -2.17095 1.6875 -2.17095 0 P 0 
L 1.61466998 -2.16995 1.68876998 -2.16995 0 P 0 
L 1.61461004 -2.16895 1.68998002 -2.16895 0 P 0 
L 1.61455 -2.16795 1.69108002 -2.16795 0 P 0 
L 1.61448996 -2.16695 1.69211998 -2.16695 0 P 0 
L 1.61443002 -2.16595 1.69316004 -2.16595 0 P 0 
L 1.61436998 -2.16495 1.69411998 -2.16495 0 P 0 
L 1.61431004 -2.16395 1.69498996 -2.16395 0 P 0 
L 1.61425 -2.16295 1.69586004 -2.16295 0 P 0 
L 1.61418996 -2.16195 1.69673002 -2.16195 0 P 0 
L 1.61413002 -2.16095 1.69746998 -2.16095 0 P 0 
L 1.61406998 -2.15995 1.6982 -2.15995 0 P 0 
L 1.61401998 -2.15895 1.69893996 -2.15895 0 P 0 
L 1.61396998 -2.15795 1.69963002 -2.15795 0 P 0 
L 1.64433002 -2.18295 1.63151004 -2.18271004 0 P 0 
L 1.63151004 -2.18271004 1.62658002 -2.18226998 0 P 0 
L 1.62658002 -2.18226998 1.62168996 -2.18146998 0 P 0 
L 1.62168996 -2.18146998 1.6201 -2.1811 0 P 0 
L 1.6201 -2.1811 1.61853996 -2.18061004 0 P 0 
L 1.61853996 -2.18061004 1.61701004 -2.18001998 0 P 0 
L 1.61701004 -2.18001998 1.61686004 -2.17995 0 P 0 
L 1.61686004 -2.17995 1.61671004 -2.17986998 0 P 0 
L 1.61671004 -2.17986998 1.61656998 -2.17976998 0 P 0 
L 1.61656998 -2.17976998 1.61643996 -2.17966998 0 P 0 
L 1.61643996 -2.17966998 1.61631998 -2.17955 0 P 0 
L 1.61631998 -2.17955 1.61621004 -2.17943002 0 P 0 
L 1.61621004 -2.17943002 1.6161 -2.1793 0 P 0 
L 1.6161 -2.1793 1.61601004 -2.17915 0 P 0 
L 1.61601004 -2.17915 1.61593002 -2.179 0 P 0 
L 1.61593002 -2.179 1.61586004 -2.17885 0 P 0 
L 1.61586004 -2.17885 1.61553002 -2.17791004 0 P 0 
L 1.61553002 -2.17791004 1.61526998 -2.17696004 0 P 0 
L 1.61526998 -2.17696004 1.61508996 -2.17598996 0 P 0 
L 1.61508996 -2.17598996 1.61496998 -2.17496998 0 P 0 
L 1.61496998 -2.17496998 1.61408002 -2.16011004 0 P 0 
L 1.61408002 -2.16011004 1.61341998 -2.14758996 0 P 0 
L 1.61341998 -2.14758996 1.6202 -2.14821004 0 P 0 
L 1.6202 -2.14821004 1.62023002 -2.14821004 0 P 0 
L 1.62023002 -2.14821004 1.63216998 -2.14893996 0 P 0 
L 1.63216998 -2.14893996 1.6349 -2.14893002 0 P 0 
L 1.6349 -2.14893002 1.63761998 -2.14873002 0 P 0 
L 1.63761998 -2.14873002 1.64031998 -2.14835 0 P 0 
L 1.64031998 -2.14835 1.64198996 -2.14798996 0 P 0 
L 1.64198996 -2.14798996 1.64363002 -2.14751998 0 P 0 
L 1.64363002 -2.14751998 1.64523002 -2.14693002 0 P 0 
L 1.64523002 -2.14693002 1.64678996 -2.14623002 0 P 0 
L 1.64678996 -2.14623002 1.64888002 -2.14506998 0 P 0 
L 1.64888002 -2.14506998 1.65086998 -2.14376004 0 P 0 
L 1.65086998 -2.14376004 1.65093996 -2.14371004 0 P 0 
L 1.65093996 -2.14371004 1.65275 -2.14228996 0 P 0 
L 1.65275 -2.14228996 1.6539 -2.14123996 0 P 0 
L 1.6539 -2.14123996 1.65496004 -2.14011004 0 P 0 
L 1.65496004 -2.14011004 1.65591998 -2.13891004 0 P 0 
L 1.65591998 -2.13891004 1.65755 -2.13653996 0 P 0 
L 1.65755 -2.13653996 1.65901998 -2.13415 0 P 0 
L 1.65901998 -2.13415 1.65903002 -2.13413002 0 P 0 
L 1.65903002 -2.13413002 1.66035 -2.13171998 0 P 0 
L 1.66035 -2.13171998 1.66155 -2.12925 0 P 0 
L 1.66155 -2.12925 1.66183996 -2.12851998 0 P 0 
L 1.66183996 -2.12851998 1.66206998 -2.12776004 0 P 0 
L 1.66206998 -2.12776004 1.66223996 -2.12696998 0 P 0 
L 1.66223996 -2.12696998 1.66233996 -2.12618002 0 P 0 
L 1.66233996 -2.12618002 1.66236998 -2.12538996 0 P 0 
L 1.66236998 -2.12538996 1.66233002 -2.12436004 0 P 0 
L 1.66233002 -2.12436004 1.66221004 -2.12335 0 P 0 
L 1.66221004 -2.12335 1.662 -2.12235 0 P 0 
L 1.662 -2.12235 1.66171004 -2.12141004 0 P 0 
L 1.66171004 -2.12141004 1.64438996 -2.07113002 0 P 0 
L 1.64438996 -2.07113002 1.62871998 -2.02606004 0 P 0 
L 1.62871998 -2.02606004 1.62116004 -2.00558996 0 P 0 
L 1.62116004 -2.00558996 1.62116004 -2.00556998 0 P 0 
L 1.62116004 -2.00556998 1.61681004 -1.99443996 0 P 0 
L 1.61681004 -1.99443996 1.67163002 -1.99443996 0 P 0 
L 1.67163002 -1.99443996 1.67301004 -2.00076004 0 P 0 
L 1.67301004 -2.00076004 1.67613002 -2.01341998 0 P 0 
L 1.67613002 -2.01341998 1.68331004 -2.03931998 0 P 0 
L 1.68331004 -2.03931998 1.69153002 -2.06856998 0 P 0 
L 1.69153002 -2.06856998 1.6916 -2.06876004 0 P 0 
L 1.6916 -2.06876004 1.69168996 -2.06896998 0 P 0 
L 1.69168996 -2.06896998 1.69181004 -2.06918002 0 P 0 
L 1.69181004 -2.06918002 1.69193002 -2.06936998 0 P 0 
L 1.69193002 -2.06936998 1.69208002 -2.06956004 0 P 0 
L 1.69208002 -2.06956004 1.69223996 -2.06973002 0 P 0 
L 1.69223996 -2.06973002 1.69241998 -2.06988002 0 P 0 
L 1.69241998 -2.06988002 1.6926 -2.07001998 0 P 0 
L 1.6926 -2.07001998 1.6928 -2.07015 0 P 0 
L 1.6928 -2.07015 1.69301004 -2.07025 0 P 0 
L 1.69301004 -2.07025 1.69323002 -2.07033996 0 P 0 
L 1.69323002 -2.07033996 1.69346004 -2.07041004 0 P 0 
L 1.69346004 -2.07041004 1.69368002 -2.07045 0 P 0 
L 1.69368002 -2.07045 1.69391998 -2.07048002 0 P 0 
L 1.69391998 -2.07048002 1.69413996 -2.07048996 0 P 0 
L 1.69413996 -2.07048996 1.6944 -2.07048002 0 P 0 
L 1.6944 -2.07048002 1.69465 -2.07045 0 P 0 
L 1.69465 -2.07045 1.69488996 -2.07038996 0 P 0 
L 1.69488996 -2.07038996 1.69513996 -2.07031998 0 P 0 
L 1.69513996 -2.07031998 1.69536998 -2.07021998 0 P 0 
L 1.69536998 -2.07021998 1.69558996 -2.0701 0 P 0 
L 1.69558996 -2.0701 1.69581004 -2.06996998 0 P 0 
L 1.69581004 -2.06996998 1.69601004 -2.06981998 0 P 0 
L 1.69601004 -2.06981998 1.6962 -2.06965 0 P 0 
L 1.6962 -2.06965 1.69636998 -2.06946004 0 P 0 
L 1.69636998 -2.06946004 1.69653002 -2.06926004 0 P 0 
L 1.69653002 -2.06926004 1.69666004 -2.06905 0 P 0 
L 1.69666004 -2.06905 1.69678996 -2.06883002 0 P 0 
L 1.69678996 -2.06883002 1.69688002 -2.0686 0 P 0 
L 1.69688002 -2.0686 1.69695 -2.0684 0 P 0 
L 1.69695 -2.0684 1.70426004 -2.04365 0 P 0 
L 1.70426004 -2.04365 1.70426004 -2.04363002 0 P 0 
L 1.70426004 -2.04363002 1.71066998 -2.0213 0 P 0 
L 1.71066998 -2.0213 1.71068002 -2.02126004 0 P 0 
L 1.71068002 -2.02126004 1.71431998 -2.00693996 0 P 0 
L 1.71431998 -2.00693996 1.71706004 -1.99496998 0 P 0 
L 1.71706004 -1.99496998 1.74335 -1.9947 0 P 0 
L 1.74335 -1.9947 1.75403002 -1.99461004 0 P 0 
L 1.75403002 -1.99461004 1.76301004 -1.99465 0 P 0 
L 1.76301004 -1.99465 1.76886004 -1.99471004 0 P 0 
L 1.76886004 -1.99471004 1.76883996 -1.99476004 0 P 0 
L 1.76883996 -1.99476004 1.74021004 -2.06556004 0 P 0 
L 1.74021004 -2.06556004 1.71298002 -2.13276998 0 P 0 
L 1.71298002 -2.13276998 1.70836998 -2.14293996 0 P 0 
L 1.70836998 -2.14293996 1.70413996 -2.15076004 0 P 0 
L 1.70413996 -2.15076004 1.69941998 -2.15828996 0 P 0 
L 1.69941998 -2.15828996 1.6967 -2.16198996 0 P 0 
L 1.6967 -2.16198996 1.6937 -2.16541998 0 P 0 
L 1.6937 -2.16541998 1.69041998 -2.1686 0 P 0 
L 1.69041998 -2.1686 1.68793996 -2.17063002 0 P 0 
L 1.68793996 -2.17063002 1.68535 -2.17248002 0 P 0 
L 1.68535 -2.17248002 1.68263996 -2.17413996 0 P 0 
L 1.68263996 -2.17413996 1.67981004 -2.17561004 0 P 0 
L 1.67981004 -2.17561004 1.67525 -2.17761004 0 P 0 
L 1.67525 -2.17761004 1.6706 -2.17931998 0 P 0 
L 1.6706 -2.17931998 1.66586004 -2.18073002 0 P 0 
L 1.66586004 -2.18073002 1.66141998 -2.1817 0 P 0 
L 1.66141998 -2.1817 1.65691998 -2.18228996 0 P 0 
L 1.65691998 -2.18228996 1.64433002 -2.18295 0 P 0 
L 1.61928996 -2.00628002 1.62683996 -2.02673002 0 P 0 
L 1.62683996 -2.02673002 1.6425 -2.07178002 0 P 0 
L 1.6425 -2.07178002 1.65981004 -2.12201998 0 P 0 
L 1.65981004 -2.12201998 1.66006004 -2.12283996 0 P 0 
L 1.66006004 -2.12283996 1.66023002 -2.12368002 0 P 0 
L 1.66023002 -2.12368002 1.66033996 -2.12451998 0 P 0 
L 1.66033996 -2.12451998 1.66036998 -2.12538002 0 P 0 
L 1.66036998 -2.12538002 1.66033996 -2.12601004 0 P 0 
L 1.66033996 -2.12601004 1.66026998 -2.12663996 0 P 0 
L 1.66026998 -2.12663996 1.66013996 -2.12725 0 P 0 
L 1.66013996 -2.12725 1.65995 -2.12786004 0 P 0 
L 1.65995 -2.12786004 1.65971004 -2.12843996 0 P 0 
L 1.65971004 -2.12843996 1.65856998 -2.1308 0 P 0 
L 1.65856998 -2.1308 1.6573 -2.13313002 0 P 0 
L 1.6573 -2.13313002 1.65586998 -2.13545 0 P 0 
L 1.65586998 -2.13545 1.65431004 -2.13771998 0 P 0 
L 1.65431004 -2.13771998 1.65343996 -2.1388 0 P 0 
L 1.65343996 -2.1388 1.65248996 -2.13981998 0 P 0 
L 1.65248996 -2.13981998 1.65146004 -2.14076004 0 P 0 
L 1.65146004 -2.14076004 1.64971004 -2.14213002 0 P 0 
L 1.64971004 -2.14213002 1.64785 -2.14336004 0 P 0 
L 1.64785 -2.14336004 1.64588996 -2.14443996 0 P 0 
L 1.64588996 -2.14443996 1.64446998 -2.14508002 0 P 0 
L 1.64446998 -2.14508002 1.64301004 -2.14561998 0 P 0 
L 1.64301004 -2.14561998 1.64151004 -2.14605 0 P 0 
L 1.64151004 -2.14605 1.63996998 -2.14636998 0 P 0 
L 1.63996998 -2.14636998 1.63741004 -2.14673996 0 P 0 
L 1.63741004 -2.14673996 1.63483002 -2.14693002 0 P 0 
L 1.63483002 -2.14693002 1.63223002 -2.14693996 0 P 0 
L 1.63223002 -2.14693996 1.62036004 -2.14621998 0 P 0 
L 1.62036004 -2.14621998 1.6113 -2.14538002 0 P 0 
L 1.6113 -2.14538002 1.61208996 -2.16023002 0 P 0 
L 1.61208996 -2.16023002 1.61298002 -2.17515 0 P 0 
L 1.61298002 -2.17515 1.6131 -2.17628002 0 P 0 
L 1.6131 -2.17628002 1.61331998 -2.17741004 0 P 0 
L 1.61331998 -2.17741004 1.61361998 -2.17851004 0 P 0 
L 1.61361998 -2.17851004 1.614 -2.17958996 0 P 0 
L 1.614 -2.17958996 1.61413996 -2.17988996 0 P 0 
L 1.61413996 -2.17988996 1.61428996 -2.18018002 0 P 0 
L 1.61428996 -2.18018002 1.61446998 -2.18045 0 P 0 
L 1.61446998 -2.18045 1.61466998 -2.18071004 0 P 0 
L 1.61466998 -2.18071004 1.61488996 -2.18095 0 P 0 
L 1.61488996 -2.18095 1.61511998 -2.18116998 0 P 0 
L 1.61511998 -2.18116998 1.61538002 -2.18138002 0 P 0 
L 1.61538002 -2.18138002 1.61565 -2.18156004 0 P 0 
L 1.61565 -2.18156004 1.61593002 -2.18173002 0 P 0 
L 1.61593002 -2.18173002 1.61623002 -2.18186004 0 P 0 
L 1.61623002 -2.18186004 1.61788002 -2.1825 0 P 0 
L 1.61788002 -2.1825 1.61956998 -2.18301998 0 P 0 
L 1.61956998 -2.18301998 1.6213 -2.18343002 0 P 0 
L 1.6213 -2.18343002 1.62633002 -2.18426004 0 P 0 
L 1.62633002 -2.18426004 1.6314 -2.18471004 0 P 0 
L 1.6314 -2.18471004 1.64436004 -2.18495 0 P 0 
L 1.64436004 -2.18495 1.65711004 -2.18428002 0 P 0 
L 1.65711004 -2.18428002 1.66176998 -2.18366998 0 P 0 
L 1.66176998 -2.18366998 1.66636004 -2.18266998 0 P 0 
L 1.66636004 -2.18266998 1.67123002 -2.18121004 0 P 0 
L 1.67123002 -2.18121004 1.676 -2.17946998 0 P 0 
L 1.676 -2.17946998 1.68068002 -2.17741998 0 P 0 
L 1.68068002 -2.17741998 1.68361998 -2.17588002 0 P 0 
L 1.68361998 -2.17588002 1.68646004 -2.17415 0 P 0 
L 1.68646004 -2.17415 1.68916004 -2.17221998 0 P 0 
L 1.68916004 -2.17221998 1.69175 -2.17008996 0 P 0 
L 1.69175 -2.17008996 1.69515 -2.1668 0 P 0 
L 1.69515 -2.1668 1.69826004 -2.16323996 0 P 0 
L 1.69826004 -2.16323996 1.70108002 -2.15941998 0 P 0 
L 1.70108002 -2.15941998 1.70586004 -2.15176998 0 P 0 
L 1.70586004 -2.15176998 1.71016004 -2.14383002 0 P 0 
L 1.71016004 -2.14383002 1.71481998 -2.13356004 0 P 0 
L 1.71481998 -2.13356004 1.74206998 -2.06631004 0 P 0 
L 1.74206998 -2.06631004 1.77071004 -1.99548002 0 P 0 
L 1.77071004 -1.99548002 1.77088002 -1.99498996 0 P 0 
L 1.77088002 -1.99498996 1.77101998 -1.99448996 0 P 0 
L 1.77101998 -1.99448996 1.77111998 -1.99398996 0 P 0 
L 1.77111998 -1.99398996 1.77118002 -1.99346998 0 P 0 
L 1.77118002 -1.99346998 1.7712 -1.99295 0 P 0 
L 1.7712 -1.99295 1.7712 -1.99293002 0 P 0 
L 1.7712 -1.99293002 1.77118996 -1.99286998 0 P 0 
L 1.77118996 -1.99286998 1.77118002 -1.99286004 0 P 0 
L 1.77118002 -1.99286004 1.77118002 -1.99283996 0 P 0 
L 1.77118002 -1.99283996 1.77111004 -1.99276998 0 P 0 
L 1.77111004 -1.99276998 1.77106998 -1.99275 0 P 0 
L 1.77106998 -1.99275 1.77106004 -1.99273996 0 P 0 
L 1.77106004 -1.99273996 1.771 -1.99273002 0 P 0 
L 1.771 -1.99273002 1.77098002 -1.99273002 0 P 0 
L 1.77098002 -1.99273002 1.76301004 -1.99265 0 P 0 
L 1.76301004 -1.99265 1.75401998 -1.99261004 0 P 0 
L 1.75401998 -1.99261004 1.74333002 -1.9927 0 P 0 
L 1.74333002 -1.9927 1.71546004 -1.99298996 0 P 0 
L 1.71546004 -1.99298996 1.71236998 -2.00646998 0 P 0 
L 1.71236998 -2.00646998 1.70873996 -2.02078002 0 P 0 
L 1.70873996 -2.02078002 1.70233996 -2.04308002 0 P 0 
L 1.70233996 -2.04308002 1.69505 -2.0678 0 P 0 
L 1.69505 -2.0678 1.69501998 -2.06788002 0 P 0 
L 1.69501998 -2.06788002 1.69498996 -2.06795 0 P 0 
L 1.69498996 -2.06795 1.69495 -2.06801998 0 P 0 
L 1.69495 -2.06801998 1.69485 -2.06816004 0 P 0 
L 1.69485 -2.06816004 1.69478996 -2.06821998 0 P 0 
L 1.69478996 -2.06821998 1.69466998 -2.06831998 0 P 0 
L 1.69466998 -2.06831998 1.69453002 -2.0684 0 P 0 
L 1.69453002 -2.0684 1.69445 -2.06843002 0 P 0 
L 1.69445 -2.06843002 1.69438002 -2.06846004 0 P 0 
L 1.69438002 -2.06846004 1.69428996 -2.06846998 0 P 0 
L 1.69428996 -2.06846998 1.69421004 -2.06848996 0 P 0 
L 1.69421004 -2.06848996 1.69406998 -2.06848996 0 P 0 
L 1.69406998 -2.06848996 1.69395 -2.06846998 0 P 0 
L 1.69395 -2.06846998 1.69383002 -2.06843002 0 P 0 
L 1.69383002 -2.06843002 1.69373002 -2.06836998 0 P 0 
L 1.69373002 -2.06836998 1.69363002 -2.06828996 0 P 0 
L 1.69363002 -2.06828996 1.69358996 -2.06823996 0 P 0 
L 1.69358996 -2.06823996 1.69355 -2.0682 0 P 0 
L 1.69355 -2.0682 1.69351998 -2.06815 0 P 0 
L 1.69351998 -2.06815 1.69346004 -2.06803996 0 P 0 
L 1.69346004 -2.06803996 1.69343996 -2.06798002 0 P 0 
L 1.69343996 -2.06798002 1.68523002 -2.03878002 0 P 0 
L 1.68523002 -2.03878002 1.67806998 -2.01291998 0 P 0 
L 1.67806998 -2.01291998 1.67496004 -2.00031004 0 P 0 
L 1.67496004 -2.00031004 1.67323002 -1.99243996 0 P 0 
L 1.67323002 -1.99243996 1.61388002 -1.99243996 0 P 0 
L 1.61388002 -1.99243996 1.61928996 -2.00628002 0 P 0 
L 1.35018002 -2.08345 1.39488996 -2.08345 0 P 0 
L 1.35026004 -2.08245 1.39586004 -2.08245 0 P 0 
L 1.35041004 -2.08145 1.39708996 -2.08145 0 P 0 
L 1.35058996 -2.08045 1.39853002 -2.08045 0 P 0 
L 1.35083996 -2.07945 1.40031998 -2.07945 0 P 0 
L 1.35116998 -2.07845 1.40271004 -2.07845 0 P 0 
L 1.35158002 -2.07745 1.40561998 -2.07745 0 P 0 
L 1.35203002 -2.07645 1.4092 -2.07645 0 P 0 
L 1.35248002 -2.07545 1.41288996 -2.07545 0 P 0 
L 1.35293002 -2.07445 1.4164 -2.07445 0 P 0 
L 1.35338996 -2.07345 1.41975 -2.07345 0 P 0 
L 1.35393996 -2.07245 1.42293996 -2.07245 0 P 0 
L 1.35448996 -2.07145 1.42606998 -2.07145 0 P 0 
L 1.35505 -2.07045 1.47843002 -2.07045 0 P 0 
L 1.3557 -2.06945 1.47846998 -2.06945 0 P 0 
L 1.35635 -2.06845 1.47851998 -2.06845 0 P 0 
L 1.35701998 -2.06745 1.47856998 -2.06745 0 P 0 
L 1.35776998 -2.06645 1.47861004 -2.06645 0 P 0 
L 1.29346998 -2.00516004 1.33388996 -2.00516004 0 P 0 
L 1.29448996 -2.00416004 1.33385 -2.00416004 0 P 0 
L 1.29551004 -2.00316004 1.33381004 -2.00316004 0 P 0 
L 1.29653996 -2.00216004 1.33376004 -2.00216004 0 P 0 
L 1.29756004 -2.00116004 1.33371004 -2.00116004 0 P 0 
L 1.29861998 -2.00016004 1.33366004 -2.00016004 0 P 0 
L 1.29973002 -1.99916004 1.3336 -1.99916004 0 P 0 
L 1.30101004 -1.99816004 1.33355 -1.99816004 0 P 0 
L 1.30238996 -1.99716004 1.3335 -1.99716004 0 P 0 
L 1.30393996 -1.99616004 1.33345 -1.99616004 0 P 0 
L 1.30571004 -1.99516004 1.33338996 -1.99516004 0 P 0 
L 1.3077 -1.99416004 1.33333002 -1.99416004 0 P 0 
L 1.31001004 -1.99316004 1.33328002 -1.99316004 0 P 0 
L 1.31288002 -1.99216004 1.33321998 -1.99216004 0 P 0 
L 1.31688996 -1.99116004 1.33316004 -1.99116004 0 P 0 
L 1.39798996 -1.98971998 1.39326998 -1.99043002 0 P 0 
L 1.39326998 -1.99043002 1.38806998 -1.9913 0 P 0 
L 1.38806998 -1.9913 1.38316004 -1.9922 0 P 0 
L 1.38316004 -1.9922 1.37946004 -1.99296998 0 P 0 
L 1.37946004 -1.99296998 1.3718 -1.99466998 0 P 0 
L 1.3718 -1.99466998 1.36896004 -2.01553996 0 P 0 
L 1.36896004 -2.01553996 1.36791004 -2.02358996 0 P 0 
L 1.36791004 -2.02358996 1.36708002 -2.03043002 0 P 0 
L 1.36708002 -2.03043002 1.36638996 -2.03646004 0 P 0 
L 1.36638996 -2.03646004 1.36638002 -2.03648996 0 P 0 
L 1.36638002 -2.03648996 1.36638996 -2.03653002 0 P 0 
L 1.36638996 -2.03653002 1.36638996 -2.03656998 0 P 0 
L 1.36638996 -2.03656998 1.3664 -2.03663996 0 P 0 
L 1.3664 -2.03663996 1.36641998 -2.03666998 0 P 0 
L 1.36641998 -2.03666998 1.36643002 -2.03671004 0 P 0 
L 1.36643002 -2.03671004 1.36648996 -2.0368 0 P 0 
L 1.36648996 -2.0368 1.36656004 -2.03686004 0 P 0 
L 1.36656004 -2.03686004 1.3666 -2.03688996 0 P 0 
L 1.3666 -2.03688996 1.36663002 -2.03691004 0 P 0 
L 1.36663002 -2.03691004 1.36666004 -2.03691004 0 P 0 
L 1.36666004 -2.03691004 1.36671004 -2.03693002 0 P 0 
L 1.36671004 -2.03693002 1.36676998 -2.03693002 0 P 0 
L 1.36676998 -2.03693002 1.36685 -2.03691998 0 P 0 
L 1.36685 -2.03691998 1.36895 -2.03628002 0 P 0 
L 1.36895 -2.03628002 1.37143002 -2.03545 0 P 0 
L 1.37143002 -2.03545 1.37428996 -2.03441004 0 P 0 
L 1.37428996 -2.03441004 1.38346004 -2.03126998 0 P 0 
L 1.38346004 -2.03126998 1.39251998 -2.02891998 0 P 0 
L 1.39251998 -2.02891998 1.40156004 -2.02731998 0 P 0 
L 1.40156004 -2.02731998 1.41068002 -2.02643996 0 P 0 
L 1.41068002 -2.02643996 1.41566998 -2.02628002 0 P 0 
L 1.41566998 -2.02628002 1.42066004 -2.02633996 0 P 0 
L 1.42066004 -2.02633996 1.42221004 -2.02646998 0 P 0 
L 1.42221004 -2.02646998 1.42375 -2.02671998 0 P 0 
L 1.42375 -2.02671998 1.42525 -2.0271 0 P 0 
L 1.42525 -2.0271 1.42671998 -2.02761004 0 P 0 
L 1.42671998 -2.02761004 1.42706004 -2.02776004 0 P 0 
L 1.42706004 -2.02776004 1.42738002 -2.02793002 0 P 0 
L 1.42738002 -2.02793002 1.42768002 -2.02813996 0 P 0 
L 1.42768002 -2.02813996 1.42796998 -2.02836004 0 P 0 
L 1.42796998 -2.02836004 1.42823002 -2.02861004 0 P 0 
L 1.42823002 -2.02861004 1.42848002 -2.02888996 0 P 0 
L 1.42848002 -2.02888996 1.4287 -2.02918002 0 P 0 
L 1.4287 -2.02918002 1.42888996 -2.02948996 0 P 0 
L 1.42888996 -2.02948996 1.42906004 -2.02981004 0 P 0 
L 1.42906004 -2.02981004 1.4292 -2.03015 0 P 0 
L 1.4292 -2.03015 1.42931998 -2.0305 0 P 0 
L 1.42931998 -2.0305 1.4294 -2.03086004 0 P 0 
L 1.4294 -2.03086004 1.42945 -2.03121998 0 P 0 
L 1.42945 -2.03121998 1.42946998 -2.03158002 0 P 0 
L 1.42946998 -2.03158002 1.42946004 -2.03195 0 P 0 
L 1.42946004 -2.03195 1.42941998 -2.03231004 0 P 0 
L 1.42941998 -2.03231004 1.42935 -2.03266998 0 P 0 
L 1.42935 -2.03266998 1.42925 -2.03301998 0 P 0 
L 1.42925 -2.03301998 1.42911998 -2.03336004 0 P 0 
L 1.42911998 -2.03336004 1.42896004 -2.03368996 0 P 0 
L 1.42896004 -2.03368996 1.42875 -2.03405 0 P 0 
L 1.42875 -2.03405 1.42851004 -2.03438996 0 P 0 
L 1.42851004 -2.03438996 1.42825 -2.03471004 0 P 0 
L 1.42825 -2.03471004 1.42796004 -2.03501004 0 P 0 
L 1.42796004 -2.03501004 1.42765 -2.03528996 0 P 0 
L 1.42765 -2.03528996 1.42731998 -2.03553996 0 P 0 
L 1.42731998 -2.03553996 1.42696998 -2.03576004 0 P 0 
L 1.42696998 -2.03576004 1.4266 -2.03596004 0 P 0 
L 1.4266 -2.03596004 1.41951004 -2.03906004 0 P 0 
L 1.41951004 -2.03906004 1.4109 -2.04208996 0 P 0 
L 1.4109 -2.04208996 1.40178002 -2.04451998 0 P 0 
L 1.40178002 -2.04451998 1.3878 -2.04818996 0 P 0 
L 1.3878 -2.04818996 1.38176998 -2.05015 0 P 0 
L 1.38176998 -2.05015 1.3758 -2.05243002 0 P 0 
L 1.3758 -2.05243002 1.37086998 -2.0546 0 P 0 
L 1.37086998 -2.0546 1.36603996 -2.05708002 0 P 0 
L 1.36603996 -2.05708002 1.36356004 -2.05856004 0 P 0 
L 1.36356004 -2.05856004 1.36118996 -2.06023002 0 P 0 
L 1.36118996 -2.06023002 1.35895 -2.06206004 0 P 0 
L 1.35895 -2.06206004 1.35805 -2.06291004 0 P 0 
L 1.35805 -2.06291004 1.35721998 -2.06385 0 P 0 
L 1.35721998 -2.06385 1.35518996 -2.06655 0 P 0 
L 1.35518996 -2.06655 1.3532 -2.06961998 0 P 0 
L 1.3532 -2.06961998 1.35156004 -2.07263002 0 P 0 
L 1.35156004 -2.07263002 1.34951004 -2.07718002 0 P 0 
L 1.34951004 -2.07718002 1.34911004 -2.07825 0 P 0 
L 1.34911004 -2.07825 1.34878996 -2.07935 0 P 0 
L 1.34878996 -2.07935 1.34853002 -2.08046998 0 P 0 
L 1.34853002 -2.08046998 1.34825 -2.08238002 0 P 0 
L 1.34825 -2.08238002 1.34811998 -2.08431004 0 P 0 
L 1.34811998 -2.08431004 1.348 -2.09128996 0 P 0 
L 1.348 -2.09128996 1.3481 -2.09761004 0 P 0 
L 1.3481 -2.09761004 1.34823002 -2.09961004 0 P 0 
L 1.34823002 -2.09961004 1.34846998 -2.10161004 0 P 0 
L 1.34846998 -2.10161004 1.34876998 -2.10321998 0 P 0 
L 1.34876998 -2.10321998 1.3492 -2.10478996 0 P 0 
L 1.3492 -2.10478996 1.3498 -2.10648996 0 P 0 
L 1.3498 -2.10648996 1.3505 -2.10815 0 P 0 
L 1.3505 -2.10815 1.35178996 -2.11066004 0 P 0 
L 1.35178996 -2.11066004 1.35328002 -2.11305 0 P 0 
L 1.35328002 -2.11305 1.35496998 -2.1153 0 P 0 
L 1.35496998 -2.1153 1.35685 -2.1174 0 P 0 
L 1.35685 -2.1174 1.35891998 -2.11933996 0 P 0 
L 1.35891998 -2.11933996 1.36126998 -2.12121998 0 P 0 
L 1.36126998 -2.12121998 1.36373996 -2.12293002 0 P 0 
L 1.36373996 -2.12293002 1.36633002 -2.12446004 0 P 0 
L 1.36633002 -2.12446004 1.36901004 -2.1258 0 P 0 
L 1.36901004 -2.1258 1.3718 -2.12695 0 P 0 
L 1.3718 -2.12695 1.37578996 -2.12828002 0 P 0 
L 1.37578996 -2.12828002 1.37986998 -2.12928996 0 P 0 
L 1.37986998 -2.12928996 1.38401998 -2.12998996 0 P 0 
L 1.38401998 -2.12998996 1.3882 -2.13036004 0 P 0 
L 1.3882 -2.13036004 1.39443002 -2.13045 0 P 0 
L 1.39443002 -2.13045 1.40066004 -2.13006998 0 P 0 
L 1.40066004 -2.13006998 1.40685 -2.12923002 0 P 0 
L 1.40685 -2.12923002 1.41371004 -2.12801998 0 P 0 
L 1.41371004 -2.12801998 1.41583002 -2.12081004 0 P 0 
L 1.41583002 -2.12081004 1.41953996 -2.10798996 0 P 0 
L 1.41953996 -2.10798996 1.42135 -2.10126998 0 P 0 
L 1.42135 -2.10126998 1.42236998 -2.097 0 P 0 
L 1.42236998 -2.097 1.42238996 -2.09691004 0 P 0 
L 1.42238996 -2.09691004 1.4224 -2.09681998 0 P 0 
L 1.4224 -2.09681998 1.4224 -2.09673996 0 P 0 
L 1.4224 -2.09673996 1.42238002 -2.09656004 0 P 0 
L 1.42238002 -2.09656004 1.42235 -2.09648002 0 P 0 
L 1.42235 -2.09648002 1.42233002 -2.09638996 0 P 0 
L 1.42233002 -2.09638996 1.42225 -2.09623002 0 P 0 
L 1.42225 -2.09623002 1.4222 -2.09616004 0 P 0 
L 1.4222 -2.09616004 1.42213996 -2.09608996 0 P 0 
L 1.42213996 -2.09608996 1.42208996 -2.09601998 0 P 0 
L 1.42208996 -2.09601998 1.42203996 -2.09598996 0 P 0 
L 1.42203996 -2.09598996 1.42198996 -2.09595 0 P 0 
L 1.42198996 -2.09595 1.42188996 -2.09588996 0 P 0 
L 1.42188996 -2.09588996 1.42183002 -2.09586004 0 P 0 
L 1.42183002 -2.09586004 1.42178002 -2.09585 0 P 0 
L 1.42178002 -2.09585 1.42171998 -2.09583002 0 P 0 
L 1.42171998 -2.09583002 1.42166004 -2.09581998 0 P 0 
L 1.42166004 -2.09581998 1.42153996 -2.09581998 0 P 0 
L 1.42153996 -2.09581998 1.41978002 -2.09591004 0 P 0 
L 1.41978002 -2.09591004 1.41763996 -2.09615 0 P 0 
L 1.41763996 -2.09615 1.41521998 -2.09658002 0 P 0 
L 1.41521998 -2.09658002 1.4107 -2.09733002 0 P 0 
L 1.4107 -2.09733002 1.40613002 -2.09775 0 P 0 
L 1.40613002 -2.09775 1.40481004 -2.09778002 0 P 0 
L 1.40481004 -2.09778002 1.40348996 -2.09771998 0 P 0 
L 1.40348996 -2.09771998 1.40216998 -2.09756004 0 P 0 
L 1.40216998 -2.09756004 1.40086998 -2.0973 0 P 0 
L 1.40086998 -2.0973 1.39958996 -2.09695 0 P 0 
L 1.39958996 -2.09695 1.39895 -2.09671998 0 P 0 
L 1.39895 -2.09671998 1.39831998 -2.09643002 0 P 0 
L 1.39831998 -2.09643002 1.39773002 -2.0961 0 P 0 
L 1.39773002 -2.0961 1.39716004 -2.09571004 0 P 0 
L 1.39716004 -2.09571004 1.39663002 -2.09528002 0 P 0 
L 1.39663002 -2.09528002 1.39613996 -2.0948 0 P 0 
L 1.39613996 -2.0948 1.39568002 -2.09428002 0 P 0 
L 1.39568002 -2.09428002 1.39533996 -2.09381998 0 P 0 
L 1.39533996 -2.09381998 1.39505 -2.09333996 0 P 0 
L 1.39505 -2.09333996 1.39478996 -2.09281998 0 P 0 
L 1.39478996 -2.09281998 1.39456998 -2.09228996 0 P 0 
L 1.39456998 -2.09228996 1.3944 -2.09173996 0 P 0 
L 1.3944 -2.09173996 1.39428002 -2.09118996 0 P 0 
L 1.39428002 -2.09118996 1.39421004 -2.09061998 0 P 0 
L 1.39421004 -2.09061998 1.39418002 -2.09003996 0 P 0 
L 1.39418002 -2.09003996 1.39421004 -2.08943002 0 P 0 
L 1.39421004 -2.08943002 1.39428002 -2.08883002 0 P 0 
L 1.39428002 -2.08883002 1.39441004 -2.08823002 0 P 0 
L 1.39441004 -2.08823002 1.3946 -2.08765 0 P 0 
L 1.3946 -2.08765 1.39483002 -2.08708002 0 P 0 
L 1.39483002 -2.08708002 1.39511004 -2.08653996 0 P 0 
L 1.39511004 -2.08653996 1.39555 -2.08583996 0 P 0 
L 1.39555 -2.08583996 1.39603996 -2.08518002 0 P 0 
L 1.39603996 -2.08518002 1.39658002 -2.08456004 0 P 0 
L 1.39658002 -2.08456004 1.39716004 -2.08396998 0 P 0 
L 1.39716004 -2.08396998 1.39778002 -2.08343002 0 P 0 
L 1.39778002 -2.08343002 1.39878996 -2.08266998 0 P 0 
L 1.39878996 -2.08266998 1.39985 -2.08196998 0 P 0 
L 1.39985 -2.08196998 1.40096004 -2.08135 0 P 0 
L 1.40096004 -2.08135 1.40211998 -2.08081004 0 P 0 
L 1.40211998 -2.08081004 1.40503002 -2.07971004 0 P 0 
L 1.40503002 -2.07971004 1.40801998 -2.07881998 0 P 0 
L 1.40801998 -2.07881998 1.41128996 -2.07796004 0 P 0 
L 1.41128996 -2.07796004 1.41506004 -2.07691998 0 P 0 
L 1.41506004 -2.07691998 1.41871998 -2.07585 0 P 0 
L 1.41871998 -2.07585 1.42165 -2.07495 0 P 0 
L 1.42165 -2.07495 1.42791998 -2.07295 0 P 0 
L 1.42791998 -2.07295 1.42731998 -2.08241004 0 P 0 
L 1.42731998 -2.08241004 1.42701004 -2.08708002 0 P 0 
L 1.42701004 -2.08708002 1.42658002 -2.09353996 0 P 0 
L 1.42658002 -2.09353996 1.4261 -2.10055 0 P 0 
L 1.4261 -2.10055 1.42566998 -2.10706004 0 P 0 
L 1.42566998 -2.10706004 1.42525 -2.11306004 0 P 0 
L 1.42525 -2.11306004 1.42491998 -2.11851998 0 P 0 
L 1.42491998 -2.11851998 1.42466004 -2.1231 0 P 0 
L 1.42466004 -2.1231 1.42461004 -2.12471004 0 P 0 
L 1.42461004 -2.12471004 1.4246 -2.12716004 0 P 0 
L 1.4246 -2.12716004 1.47893002 -2.12716004 0 P 0 
L 1.47893002 -2.12716004 1.47893002 -2.11358002 0 P 0 
L 1.47893002 -2.11358002 1.47905 -2.10616998 0 P 0 
L 1.47905 -2.10616998 1.47943996 -2.09385 0 P 0 
L 1.47943996 -2.09385 1.48 -2.07968996 0 P 0 
L 1.48 -2.07968996 1.48066004 -2.0655 0 P 0 
L 1.48066004 -2.0655 1.4813 -2.05168996 0 P 0 
L 1.4813 -2.05168996 1.48175 -2.03873996 0 P 0 
L 1.48175 -2.03873996 1.48201998 -2.02785 0 P 0 
L 1.48201998 -2.02785 1.48191998 -2.02286004 0 P 0 
L 1.48191998 -2.02286004 1.48165 -2.01995 0 P 0 
L 1.48165 -2.01995 1.48115 -2.01708002 0 P 0 
L 1.48115 -2.01708002 1.48043996 -2.01425 0 P 0 
L 1.48043996 -2.01425 1.47951004 -2.01146998 0 P 0 
L 1.47951004 -2.01146998 1.47866998 -2.00946998 0 P 0 
L 1.47866998 -2.00946998 1.47768002 -2.00753996 0 P 0 
L 1.47768002 -2.00753996 1.47655 -2.00568002 0 P 0 
L 1.47655 -2.00568002 1.47528002 -2.00391998 0 P 0 
L 1.47528002 -2.00391998 1.47388002 -2.00225 0 P 0 
L 1.47388002 -2.00225 1.47228996 -2.00063002 0 P 0 
L 1.47228996 -2.00063002 1.4706 -1.99911998 0 P 0 
L 1.4706 -1.99911998 1.4688 -1.99773002 0 P 0 
L 1.4688 -1.99773002 1.46691004 -1.99648002 0 P 0 
L 1.46691004 -1.99648002 1.46491998 -1.99535 0 P 0 
L 1.46491998 -1.99535 1.46098996 -1.99351004 0 P 0 
L 1.46098996 -1.99351004 1.45693002 -1.99196998 0 P 0 
L 1.45693002 -1.99196998 1.45276004 -1.99076004 0 P 0 
L 1.45276004 -1.99076004 1.44953996 -1.99006004 0 P 0 
L 1.44953996 -1.99006004 1.44628996 -1.98956004 0 P 0 
L 1.44628996 -1.98956004 1.44298002 -1.98923996 0 P 0 
L 1.44298002 -1.98923996 1.42695 -1.98856998 0 P 0 
L 1.42695 -1.98856998 1.41038996 -1.98865 0 P 0 
L 1.41038996 -1.98865 1.4042 -1.98901004 0 P 0 
L 1.4042 -1.98901004 1.39798996 -1.98971998 0 P 0 
L 1.35778996 -2.11545 1.4153 -2.11545 0 P 0 
L 1.35688996 -2.11445 1.41558996 -2.11445 0 P 0 
L 1.35608002 -2.11345 1.41588002 -2.11345 0 P 0 
L 1.35533002 -2.11245 1.41616998 -2.11245 0 P 0 
L 1.35463996 -2.11145 1.41646004 -2.11145 0 P 0 
L 1.35401004 -2.11045 1.41675 -2.11045 0 P 0 
L 1.35341004 -2.10945 1.41703996 -2.10945 0 P 0 
L 1.3529 -2.10845 1.41733002 -2.10845 0 P 0 
L 1.35238002 -2.10745 1.41761998 -2.10745 0 P 0 
L 1.35195 -2.10645 1.41788002 -2.10645 0 P 0 
L 1.35155 -2.10545 1.41816004 -2.10545 0 P 0 
L 1.3512 -2.10445 1.41841998 -2.10445 0 P 0 
L 1.35091004 -2.10345 1.41868996 -2.10345 0 P 0 
L 1.35066004 -2.10245 1.41896004 -2.10245 0 P 0 
L 1.35046998 -2.10145 1.41923002 -2.10145 0 P 0 
L 1.35033996 -2.10045 1.41948996 -2.10045 0 P 0 
L 1.35021998 -2.09945 1.40141004 -2.09945 0 P 0 
L 1.35016004 -2.09845 1.39791004 -2.09845 0 P 0 
L 1.3501 -2.09745 1.39616004 -2.09745 0 P 0 
L 1.35008002 -2.09645 1.39496004 -2.09645 0 P 0 
L 1.35006998 -2.09545 1.39406004 -2.09545 0 P 0 
L 1.35005 -2.09445 1.39338002 -2.09445 0 P 0 
L 1.35003996 -2.09345 1.39288002 -2.09345 0 P 0 
L 1.35001998 -2.09245 1.39253002 -2.09245 0 P 0 
L 1.35001004 -2.09145 1.3923 -2.09145 0 P 0 
L 1.35001998 -2.09045 1.3922 -2.09045 0 P 0 
L 1.35003002 -2.08945 1.3922 -2.08945 0 P 0 
L 1.35005 -2.08845 1.39231998 -2.08845 0 P 0 
L 1.35006998 -2.08745 1.39256004 -2.08745 0 P 0 
L 1.35008002 -2.08645 1.39293002 -2.08645 0 P 0 
L 1.3501 -2.08545 1.39343002 -2.08545 0 P 0 
L 1.35011004 -2.08445 1.39408996 -2.08445 0 P 0 
L 1.39438002 -2.12845 1.3883 -2.12836004 0 P 0 
L 1.3883 -2.12836004 1.38426998 -2.128 0 P 0 
L 1.38426998 -2.128 1.38028002 -2.12733002 0 P 0 
L 1.38028002 -2.12733002 1.37635 -2.12636004 0 P 0 
L 1.37635 -2.12636004 1.37248996 -2.12508002 0 P 0 
L 1.37248996 -2.12508002 1.36983996 -2.12398002 0 P 0 
L 1.36983996 -2.12398002 1.36728996 -2.1227 0 P 0 
L 1.36728996 -2.1227 1.36481998 -2.12123996 0 P 0 
L 1.36481998 -2.12123996 1.36246004 -2.11961004 0 P 0 
L 1.36246004 -2.11961004 1.36023002 -2.11781998 0 P 0 
L 1.36023002 -2.11781998 1.35828996 -2.116 0 P 0 
L 1.35828996 -2.116 1.35651998 -2.11403002 0 P 0 
L 1.35651998 -2.11403002 1.35493002 -2.11191004 0 P 0 
L 1.35493002 -2.11191004 1.35353002 -2.10966998 0 P 0 
L 1.35353002 -2.10966998 1.35231004 -2.10731004 0 P 0 
L 1.35231004 -2.10731004 1.35166998 -2.10576998 0 P 0 
L 1.35166998 -2.10576998 1.35111004 -2.1042 0 P 0 
L 1.35111004 -2.1042 1.35071998 -2.10276004 0 P 0 
L 1.35071998 -2.10276004 1.35045 -2.1013 0 P 0 
L 1.35045 -2.1013 1.35021998 -2.09943002 0 P 0 
L 1.35021998 -2.09943002 1.3501 -2.09753002 0 P 0 
L 1.3501 -2.09753002 1.35001004 -2.09128002 0 P 0 
L 1.35001004 -2.09128002 1.35011998 -2.0844 0 P 0 
L 1.35011998 -2.0844 1.35023996 -2.08258996 0 P 0 
L 1.35023996 -2.08258996 1.3505 -2.08083996 0 P 0 
L 1.3505 -2.08083996 1.35071998 -2.07985 0 P 0 
L 1.35071998 -2.07985 1.35101004 -2.07888002 0 P 0 
L 1.35101004 -2.07888002 1.35136004 -2.07793002 0 P 0 
L 1.35136004 -2.07793002 1.35335 -2.07351998 0 P 0 
L 1.35335 -2.07351998 1.35491998 -2.07065 0 P 0 
L 1.35491998 -2.07065 1.35683002 -2.0677 0 P 0 
L 1.35683002 -2.0677 1.35876998 -2.06511004 0 P 0 
L 1.35876998 -2.06511004 1.35948996 -2.0643 0 P 0 
L 1.35948996 -2.0643 1.36026998 -2.06356004 0 P 0 
L 1.36026998 -2.06356004 1.3624 -2.06181998 0 P 0 
L 1.3624 -2.06181998 1.36465 -2.06023996 0 P 0 
L 1.36465 -2.06023996 1.36701004 -2.05883002 0 P 0 
L 1.36701004 -2.05883002 1.37173002 -2.05641004 0 P 0 
L 1.37173002 -2.05641004 1.37656004 -2.05426998 0 P 0 
L 1.37656004 -2.05426998 1.38243002 -2.05203996 0 P 0 
L 1.38243002 -2.05203996 1.38836004 -2.0501 0 P 0 
L 1.38836004 -2.0501 1.4023 -2.04645 0 P 0 
L 1.4023 -2.04645 1.41148996 -2.044 0 P 0 
L 1.41148996 -2.044 1.42016998 -2.04095 0 P 0 
L 1.42016998 -2.04095 1.42016998 -2.04093996 0 P 0 
L 1.42016998 -2.04093996 1.42021004 -2.04093996 0 P 0 
L 1.42021004 -2.04093996 1.42023996 -2.04093002 0 P 0 
L 1.42023996 -2.04093002 1.42746998 -2.03776004 0 P 0 
L 1.42746998 -2.03776004 1.42753002 -2.03773002 0 P 0 
L 1.42753002 -2.03773002 1.42796998 -2.03748996 0 P 0 
L 1.42796998 -2.03748996 1.42846004 -2.03718996 0 P 0 
L 1.42846004 -2.03718996 1.42891998 -2.03683996 0 P 0 
L 1.42891998 -2.03683996 1.42935 -2.03646004 0 P 0 
L 1.42935 -2.03646004 1.42975 -2.03603996 0 P 0 
L 1.42975 -2.03603996 1.43011004 -2.0356 0 P 0 
L 1.43011004 -2.0356 1.43016004 -2.03553002 0 P 0 
L 1.43016004 -2.03553002 1.4299 -2.03535 0 P 0 
L 1.4299 -2.03535 1.43028002 -2.03535 0 P 0 
L 1.43028002 -2.03535 1.43043996 -2.03513002 0 P 0 
L 1.43043996 -2.03513002 1.43048002 -2.03506004 0 P 0 
L 1.43048002 -2.03506004 1.43041998 -2.03501998 0 P 0 
L 1.43041998 -2.03501998 1.4305 -2.03501998 0 P 0 
L 1.4305 -2.03501998 1.43073002 -2.03463002 0 P 0 
L 1.43073002 -2.03463002 1.43096004 -2.03415 0 P 0 
L 1.43096004 -2.03415 1.43115 -2.03365 0 P 0 
L 1.43115 -2.03365 1.4313 -2.03313002 0 P 0 
L 1.4313 -2.03313002 1.4314 -2.03261004 0 P 0 
L 1.4314 -2.03261004 1.43146004 -2.03208002 0 P 0 
L 1.43146004 -2.03208002 1.43146998 -2.03155 0 P 0 
L 1.43146998 -2.03155 1.43143996 -2.03101004 0 P 0 
L 1.43143996 -2.03101004 1.43143002 -2.03093002 0 P 0 
L 1.43143002 -2.03093002 1.43136004 -2.03048996 0 P 0 
L 1.43136004 -2.03048996 1.43125 -2.02996998 0 P 0 
L 1.43125 -2.02996998 1.43108002 -2.02946004 0 P 0 
L 1.43108002 -2.02946004 1.43086998 -2.02896004 0 P 0 
L 1.43086998 -2.02896004 1.43063002 -2.02848996 0 P 0 
L 1.43063002 -2.02848996 1.43033996 -2.02803996 0 P 0 
L 1.43033996 -2.02803996 1.43001998 -2.02761004 0 P 0 
L 1.43001998 -2.02761004 1.42966004 -2.02721004 0 P 0 
L 1.42966004 -2.02721004 1.42928002 -2.02685 0 P 0 
L 1.42928002 -2.02685 1.42886004 -2.02651998 0 P 0 
L 1.42886004 -2.02651998 1.42841998 -2.02623002 0 P 0 
L 1.42841998 -2.02623002 1.42795 -2.02596998 0 P 0 
L 1.42795 -2.02596998 1.42746004 -2.02575 0 P 0 
L 1.42746004 -2.02575 1.42583002 -2.02518002 0 P 0 
L 1.42583002 -2.02518002 1.42416004 -2.02476004 0 P 0 
L 1.42416004 -2.02476004 1.42245 -2.02448002 0 P 0 
L 1.42245 -2.02448002 1.42075 -2.02435 0 P 0 
L 1.42075 -2.02435 1.41565 -2.02428002 0 P 0 
L 1.41565 -2.02428002 1.4156 -2.02428002 0 P 0 
L 1.4156 -2.02428002 1.41055 -2.02445 0 P 0 
L 1.41055 -2.02445 1.41048002 -2.02445 0 P 0 
L 1.41048002 -2.02445 1.40128996 -2.02533996 0 P 0 
L 1.40128996 -2.02533996 1.39208996 -2.02696998 0 P 0 
L 1.39208996 -2.02696998 1.38288002 -2.02936004 0 P 0 
L 1.38288002 -2.02936004 1.37363002 -2.03251998 0 P 0 
L 1.37363002 -2.03251998 1.37076998 -2.03356004 0 P 0 
L 1.37076998 -2.03356004 1.36865 -2.03426998 0 P 0 
L 1.36865 -2.03426998 1.36906004 -2.03066998 0 P 0 
L 1.36906004 -2.03066998 1.36988996 -2.02383996 0 P 0 
L 1.36988996 -2.02383996 1.37095 -2.01581004 0 P 0 
L 1.37095 -2.01581004 1.37358996 -1.99631998 0 P 0 
L 1.37358996 -1.99631998 1.37988002 -1.99491998 0 P 0 
L 1.37988002 -1.99491998 1.38353996 -1.99416998 0 P 0 
L 1.38353996 -1.99416998 1.38841998 -1.99326998 0 P 0 
L 1.38841998 -1.99326998 1.39358002 -1.9924 0 P 0 
L 1.39358002 -1.9924 1.39825 -1.9917 0 P 0 
L 1.39825 -1.9917 1.40436998 -1.991 0 P 0 
L 1.40436998 -1.991 1.41045 -1.99065 0 P 0 
L 1.41045 -1.99065 1.42691004 -1.99056998 0 P 0 
L 1.42691004 -1.99056998 1.44283996 -1.99123996 0 P 0 
L 1.44283996 -1.99123996 1.44603996 -1.99153996 0 P 0 
L 1.44603996 -1.99153996 1.44918002 -1.99203002 0 P 0 
L 1.44918002 -1.99203002 1.45226004 -1.9927 0 P 0 
L 1.45226004 -1.9927 1.4563 -1.99386998 0 P 0 
L 1.4563 -1.99386998 1.46021004 -1.99535 0 P 0 
L 1.46021004 -1.99535 1.464 -1.99713002 0 P 0 
L 1.464 -1.99713002 1.46586004 -1.99818996 0 P 0 
L 1.46586004 -1.99818996 1.46763996 -1.99936004 0 P 0 
L 1.46763996 -1.99936004 1.46931998 -2.00066004 0 P 0 
L 1.46931998 -2.00066004 1.47091004 -2.00206998 0 P 0 
L 1.47091004 -2.00206998 1.47238996 -2.00358996 0 P 0 
L 1.47238996 -2.00358996 1.4737 -2.00515 0 P 0 
L 1.4737 -2.00515 1.47488002 -2.00678996 0 P 0 
L 1.47488002 -2.00678996 1.47593996 -2.00851004 0 P 0 
L 1.47593996 -2.00851004 1.47686004 -2.01031004 0 P 0 
L 1.47686004 -2.01031004 1.47763996 -2.01216998 0 P 0 
L 1.47763996 -2.01216998 1.47851998 -2.01481004 0 P 0 
L 1.47851998 -2.01481004 1.47918996 -2.01748996 0 P 0 
L 1.47918996 -2.01748996 1.47966004 -2.02021998 0 P 0 
L 1.47966004 -2.02021998 1.47993002 -2.02296998 0 P 0 
L 1.47993002 -2.02296998 1.48001998 -2.02783996 0 P 0 
L 1.48001998 -2.02783996 1.47975 -2.03868996 0 P 0 
L 1.47975 -2.03868996 1.4793 -2.05161004 0 P 0 
L 1.4793 -2.05161004 1.47866004 -2.06543002 0 P 0 
L 1.47866004 -2.06543002 1.47801004 -2.07961004 0 P 0 
L 1.47801004 -2.07961004 1.47743996 -2.09378996 0 P 0 
L 1.47743996 -2.09378996 1.47705 -2.10613002 0 P 0 
L 1.47705 -2.10613002 1.47693002 -2.11356004 0 P 0 
L 1.47693002 -2.11356004 1.47693002 -2.12516004 0 P 0 
L 1.47693002 -2.12516004 1.42661004 -2.12516004 0 P 0 
L 1.42661004 -2.12516004 1.42661004 -2.12473996 0 P 0 
L 1.42661004 -2.12473996 1.42666004 -2.12318002 0 P 0 
L 1.42666004 -2.12318002 1.42691004 -2.11863996 0 P 0 
L 1.42691004 -2.11863996 1.42725 -2.1132 0 P 0 
L 1.42725 -2.1132 1.42766004 -2.1072 0 P 0 
L 1.42766004 -2.1072 1.42766004 -2.10718996 0 P 0 
L 1.42766004 -2.10718996 1.4281 -2.10068996 0 P 0 
L 1.4281 -2.10068996 1.42858002 -2.09368002 0 P 0 
L 1.42858002 -2.09368002 1.42901004 -2.08721004 0 P 0 
L 1.42901004 -2.08721004 1.42901004 -2.0872 0 P 0 
L 1.42901004 -2.0872 1.42931004 -2.08256004 0 P 0 
L 1.42931004 -2.08256004 1.42991998 -2.07308002 0 P 0 
L 1.42991998 -2.07308002 1.42916004 -2.07136998 0 P 0 
L 1.42916004 -2.07136998 1.42731998 -2.07105 0 P 0 
L 1.42731998 -2.07105 1.42105 -2.07303996 0 P 0 
L 1.42105 -2.07303996 1.41815 -2.07393002 0 P 0 
L 1.41815 -2.07393002 1.41451004 -2.075 0 P 0 
L 1.41451004 -2.075 1.41076004 -2.07603002 0 P 0 
L 1.41076004 -2.07603002 1.40748002 -2.0769 0 P 0 
L 1.40748002 -2.0769 1.40438996 -2.07781004 0 P 0 
L 1.40438996 -2.07781004 1.40431998 -2.07783996 0 P 0 
L 1.40431998 -2.07783996 1.40133996 -2.07896998 0 P 0 
L 1.40133996 -2.07896998 1.40005 -2.07956998 0 P 0 
L 1.40005 -2.07956998 1.39881998 -2.08026004 0 P 0 
L 1.39881998 -2.08026004 1.39763996 -2.08103002 0 P 0 
L 1.39763996 -2.08103002 1.39651998 -2.08188002 0 P 0 
L 1.39651998 -2.08188002 1.39578996 -2.08251004 0 P 0 
L 1.39578996 -2.08251004 1.39573996 -2.08256004 0 P 0 
L 1.39573996 -2.08256004 1.3951 -2.08318996 0 P 0 
L 1.3951 -2.08318996 1.39446998 -2.08393002 0 P 0 
L 1.39446998 -2.08393002 1.3939 -2.08471004 0 P 0 
L 1.3939 -2.08471004 1.39336998 -2.08553996 0 P 0 
L 1.39336998 -2.08553996 1.39301004 -2.08623996 0 P 0 
L 1.39301004 -2.08623996 1.39271004 -2.08696998 0 P 0 
L 1.39271004 -2.08696998 1.39248002 -2.08771998 0 P 0 
L 1.39248002 -2.08771998 1.39231004 -2.08848996 0 P 0 
L 1.39231004 -2.08848996 1.39221004 -2.08926004 0 P 0 
L 1.39221004 -2.08926004 1.39218002 -2.09003996 0 P 0 
L 1.39218002 -2.09003996 1.39221004 -2.0908 0 P 0 
L 1.39221004 -2.0908 1.39231004 -2.09153002 0 P 0 
L 1.39231004 -2.09153002 1.39246998 -2.09226004 0 P 0 
L 1.39246998 -2.09226004 1.39268996 -2.09296998 0 P 0 
L 1.39268996 -2.09296998 1.39296004 -2.09365 0 P 0 
L 1.39296004 -2.09365 1.3933 -2.09431004 0 P 0 
L 1.3933 -2.09431004 1.39368996 -2.09493996 0 P 0 
L 1.39368996 -2.09493996 1.39411998 -2.09553996 0 P 0 
L 1.39411998 -2.09553996 1.39468996 -2.09618002 0 P 0 
L 1.39468996 -2.09618002 1.3953 -2.09678002 0 P 0 
L 1.3953 -2.09678002 1.39596004 -2.09731998 0 P 0 
L 1.39596004 -2.09731998 1.39666998 -2.0978 0 P 0 
L 1.39666998 -2.0978 1.39673996 -2.09783996 0 P 0 
L 1.39673996 -2.09783996 1.39741004 -2.09821998 0 P 0 
L 1.39741004 -2.09821998 1.39748996 -2.09825 0 P 0 
L 1.39748996 -2.09825 1.39818996 -2.09856998 0 P 0 
L 1.39818996 -2.09856998 1.39898996 -2.09886004 0 P 0 
L 1.39898996 -2.09886004 1.39906998 -2.09888002 0 P 0 
L 1.39906998 -2.09888002 1.40043996 -2.09888002 0 P 0 
L 1.40043996 -2.09888002 1.40033996 -2.09923002 0 P 0 
L 1.40033996 -2.09923002 1.40041998 -2.09925 0 P 0 
L 1.40041998 -2.09925 1.40186004 -2.09953002 0 P 0 
L 1.40186004 -2.09953002 1.40331004 -2.09971004 0 P 0 
L 1.40331004 -2.09971004 1.40478002 -2.09978002 0 P 0 
L 1.40478002 -2.09978002 1.40625 -2.09975 0 P 0 
L 1.40625 -2.09975 1.41096004 -2.09931004 0 P 0 
L 1.41096004 -2.09931004 1.41556998 -2.09855 0 P 0 
L 1.41556998 -2.09855 1.41791998 -2.09813002 0 P 0 
L 1.41791998 -2.09813002 1.41995 -2.09791004 0 P 0 
L 1.41995 -2.09791004 1.4201 -2.0979 0 P 0 
L 1.4201 -2.0979 1.41941004 -2.10078002 0 P 0 
L 1.41941004 -2.10078002 1.41761004 -2.10745 0 P 0 
L 1.41761004 -2.10745 1.41391004 -2.12025 0 P 0 
L 1.41391004 -2.12025 1.41215 -2.12626998 0 P 0 
L 1.41215 -2.12626998 1.40655 -2.12725 0 P 0 
L 1.40655 -2.12725 1.40046004 -2.12808002 0 P 0 
L 1.40046004 -2.12808002 1.39438002 -2.12845 0 P 0 
L 1.15303002 -2.08283002 1.20788996 -2.08283002 0 P 0 
L 1.15398996 -2.08183002 1.20795 -2.08183002 0 P 0 
L 1.15483002 -2.08083002 1.208 -2.08083002 0 P 0 
L 1.15555 -2.07983002 1.20805 -2.07983002 0 P 0 
L 1.15621998 -2.07883002 1.2081 -2.07883002 0 P 0 
L 1.15681998 -2.07783002 1.20816004 -2.07783002 0 P 0 
L 1.15733002 -2.07683002 1.20821004 -2.07683002 0 P 0 
L 1.15778996 -2.07583002 1.20826004 -2.07583002 0 P 0 
L 1.15818002 -2.07483002 1.20831004 -2.07483002 0 P 0 
L 1.15853996 -2.07383002 1.20836998 -2.07383002 0 P 0 
L 1.15881998 -2.07283002 1.20841998 -2.07283002 0 P 0 
L 1.1591 -2.07183002 1.20846998 -2.07183002 0 P 0 
L 1.15938002 -2.07083002 1.20853002 -2.07083002 0 P 0 
L 1.1596 -2.06983002 1.20858002 -2.06983002 0 P 0 
L 1.15981004 -2.06883002 1.20863996 -2.06883002 0 P 0 
L 1.16001004 -2.06783002 1.20868996 -2.06783002 0 P 0 
L 1.1602 -2.06683002 1.20875 -2.06683002 0 P 0 
L 1.16033996 -2.06583002 1.2088 -2.06583002 0 P 0 
L 1.16048996 -2.06483002 1.20886004 -2.06483002 0 P 0 
L 1.16063996 -2.06383002 1.20891998 -2.06383002 0 P 0 
L 1.16078002 -2.06283002 1.20896998 -2.06283002 0 P 0 
L 1.16088996 -2.06183002 1.20903002 -2.06183002 0 P 0 
L 1.16098996 -2.06083002 1.20908002 -2.06083002 0 P 0 
L 1.16108996 -2.05983002 1.20913996 -2.05983002 0 P 0 
L 1.16118002 -2.05883002 1.20918996 -2.05883002 0 P 0 
L 1.16128002 -2.05783002 1.20925 -2.05783002 0 P 0 
L 1.16133996 -2.05683002 1.2093 -2.05683002 0 P 0 
L 1.1614 -2.05583002 1.20936004 -2.05583002 0 P 0 
L 1.16146004 -2.05483002 1.20941004 -2.05483002 0 P 0 
L 1.16151998 -2.05383002 1.20946998 -2.05383002 0 P 0 
L 1.16158002 -2.05283002 1.20951998 -2.05283002 0 P 0 
L 1.16163996 -2.05183002 1.20958002 -2.05183002 0 P 0 
L 1.1617 -2.05083002 1.20963996 -2.05083002 0 P 0 
L 1.16175 -2.04983002 1.2097 -2.04983002 0 P 0 
L 1.16181004 -2.04883002 1.20975 -2.04883002 0 P 0 
L 1.16186998 -2.04783002 1.20981004 -2.04783002 0 P 0 
L 1.16193002 -2.04683002 1.20986998 -2.04683002 0 P 0 
L 1.16198996 -2.04583002 1.20993002 -2.04583002 0 P 0 
L 1.16205 -2.04483002 1.20998996 -2.04483002 0 P 0 
L 1.16211004 -2.04383002 1.21005 -2.04383002 0 P 0 
L 1.16215 -2.04283002 1.2101 -2.04283002 0 P 0 
L 1.1622 -2.04183002 1.21016004 -2.04183002 0 P 0 
L 1.16225 -2.04083002 1.21021998 -2.04083002 0 P 0 
L 1.16228996 -2.03983002 1.21028002 -2.03983002 0 P 0 
L 1.16233996 -2.03883002 1.21033996 -2.03883002 0 P 0 
L 1.16238002 -2.03783002 1.2104 -2.03783002 0 P 0 
L 1.16243002 -2.03683002 1.21046004 -2.03683002 0 P 0 
L 1.16246998 -2.03583002 1.21051004 -2.03583002 0 P 0 
L 1.16251998 -2.03483002 1.21056998 -2.03483002 0 P 0 
L 1.16256998 -2.03383002 1.21063996 -2.03383002 0 P 0 
L 1.16261004 -2.03283002 1.2107 -2.03283002 0 P 0 
L 1.16266004 -2.03183002 1.21076004 -2.03183002 0 P 0 
L 1.1627 -2.03083002 1.21083002 -2.03083002 0 P 0 
L 1.16015 -1.97631004 1.17066004 -1.97631004 0 P 0 
L 1.15961998 -1.97531004 1.17026004 -1.97531004 0 P 0 
L 1.1591 -1.97431004 1.16986998 -1.97431004 0 P 0 
L 1.15856998 -1.97331004 1.16946998 -1.97331004 0 P 0 
L 1.15803996 -1.97231004 1.16903002 -1.97231004 0 P 0 
L 1.15746998 -1.97131004 1.16858996 -1.97131004 0 P 0 
L 1.1569 -1.97031004 1.16815 -1.97031004 0 P 0 
L 1.15631998 -1.96931004 1.16771004 -1.96931004 0 P 0 
L 1.15573996 -1.96831004 1.16726998 -1.96831004 0 P 0 
L 1.15516004 -1.96731004 1.16681998 -1.96731004 0 P 0 
L 1.15458996 -1.96631004 1.16638002 -1.96631004 0 P 0 
L 1.15398002 -1.96531004 1.16593996 -1.96531004 0 P 0 
L 1.1533 -1.96431004 1.16548996 -1.96431004 0 P 0 
L 1.15261998 -1.96331004 1.16503002 -1.96331004 0 P 0 
L 1.15193996 -1.96231004 1.16448002 -1.96231004 0 P 0 
L 1.15126004 -1.96131004 1.16393002 -1.96131004 0 P 0 
L 1.15058002 -1.96031004 1.16338002 -1.96031004 0 P 0 
L 1.1499 -1.95931004 1.16283002 -1.95931004 0 P 0 
L 1.1491 -1.95831004 1.16228996 -1.95831004 0 P 0 
L 1.14831004 -1.95731004 1.16173996 -1.95731004 0 P 0 
L 1.14751004 -1.95631004 1.16118996 -1.95631004 0 P 0 
L 1.14671004 -1.95531004 1.16063996 -1.95531004 0 P 0 
L 1.14591998 -1.95431004 1.16008996 -1.95431004 0 P 0 
L 1.14511998 -1.95331004 1.15943996 -1.95331004 0 P 0 
L 1.1442 -1.95231004 1.15878002 -1.95231004 0 P 0 
L 1.14326998 -1.95131004 1.15811004 -1.95131004 0 P 0 
L 1.14233996 -1.95031004 1.15745 -1.95031004 0 P 0 
L 1.14141004 -1.94931004 1.15678002 -1.94931004 0 P 0 
L 1.14048996 -1.94831004 1.15611998 -1.94831004 0 P 0 
L 1.1395 -1.94731004 1.15545 -1.94731004 0 P 0 
L 1.13843002 -1.94631004 1.15478996 -1.94631004 0 P 0 
L 1.13736004 -1.94531004 1.15411998 -1.94531004 0 P 0 
L 1.13628996 -1.94431004 1.15333002 -1.94431004 0 P 0 
L 1.13521004 -1.94331004 1.15253002 -1.94331004 0 P 0 
L 1.13413996 -1.94231004 1.15173996 -1.94231004 0 P 0 
L 1.13306998 -1.94131004 1.15093996 -1.94131004 0 P 0 
L 1.132 -1.94031004 1.15013996 -1.94031004 0 P 0 
L 1.13081004 -1.93931004 1.14935 -1.93931004 0 P 0 
L 1.12958002 -1.93831004 1.14855 -1.93831004 0 P 0 
L 1.12833996 -1.93731004 1.14775 -1.93731004 0 P 0 
L 1.1271 -1.93631004 1.14688996 -1.93631004 0 P 0 
L 1.12586004 -1.93531004 1.14593996 -1.93531004 0 P 0 
L 1.12461998 -1.93431004 1.14498996 -1.93431004 0 P 0 
L 1.12338002 -1.93331004 1.14405 -1.93331004 0 P 0 
L 1.12203002 -1.93231004 1.1431 -1.93231004 0 P 0 
L 1.1206 -1.93131004 1.14216004 -1.93131004 0 P 0 
L 1.11916004 -1.93031004 1.14121004 -1.93031004 0 P 0 
L 1.11771998 -1.92931004 1.14026998 -1.92931004 0 P 0 
L 1.11628996 -1.92831004 1.13931998 -1.92831004 0 P 0 
L 1.11483996 -1.92731004 1.13838002 -1.92731004 0 P 0 
L 1.11338996 -1.92631004 1.13743002 -1.92631004 0 P 0 
L 1.11171998 -1.92531004 1.13648996 -1.92531004 0 P 0 
L 1.11005 -1.92431004 1.13538002 -1.92431004 0 P 0 
L 1.10838002 -1.92331004 1.13426998 -1.92331004 0 P 0 
L 1.1067 -1.92231004 1.13315 -1.92231004 0 P 0 
L 1.10503002 -1.92131004 1.13203002 -1.92131004 0 P 0 
L 1.10336004 -1.92031004 1.13091998 -1.92031004 0 P 0 
L 1.1015 -1.91931004 1.1298 -1.91931004 0 P 0 
L 1.09955 -1.91831004 1.12868002 -1.91831004 0 P 0 
L 1.16275 -2.02983002 1.21088996 -2.02983002 0 P 0 
L 1.16278996 -2.02883002 1.21095 -2.02883002 0 P 0 
L 1.16283996 -2.02783002 1.21101004 -2.02783002 0 P 0 
L 1.16226998 -2.02683002 1.21108002 -2.02683002 0 P 0 
L 1.16153996 -2.02583002 1.21113996 -2.02583002 0 P 0 
L 1.15846004 -2.02483002 1.2112 -2.02483002 0 P 0 
L 1.10036004 -2.00383002 1.21255 -2.00383002 0 P 0 
L 1.10226004 -2.00283002 1.2126 -2.00283002 0 P 0 
L 1.10433996 -2.00183002 1.21266998 -2.00183002 0 P 0 
L 1.1065 -2.00083002 1.21273002 -2.00083002 0 P 0 
L 1.10886998 -1.99983002 1.21278996 -1.99983002 0 P 0 
L 1.11138002 -1.99883002 1.21285 -1.99883002 0 P 0 
L 1.11436998 -1.99783002 1.21288002 -1.99783002 0 P 0 
L 1.11748996 -1.99683002 1.21255 -1.99683002 0 P 0 
L 1.12061998 -1.99583002 1.2089 -1.99583002 0 P 0 
L 1.12433996 -1.99483002 1.2036 -1.99483002 0 P 0 
L 1.12863996 -1.99383002 1.19728002 -1.99383002 0 P 0 
L 1.13295 -1.99283002 1.19096998 -1.99283002 0 P 0 
L 1.13985 -1.99183002 1.18111998 -1.99183002 0 P 0 
L 1.14948002 -1.99083002 1.1651 -1.99083002 0 P 0 
L 1.24218002 -2.08316004 1.29143996 -2.08316004 0 P 0 
L 1.24223002 -2.08216004 1.29151004 -2.08216004 0 P 0 
L 1.24228002 -2.08116004 1.29158996 -2.08116004 0 P 0 
L 1.24233996 -2.08016004 1.29166004 -2.08016004 0 P 0 
L 1.24238996 -2.07916004 1.29173002 -2.07916004 0 P 0 
L 1.24245 -2.07816004 1.29181004 -2.07816004 0 P 0 
L 1.2425 -2.07716004 1.29188002 -2.07716004 0 P 0 
L 1.24256004 -2.07616004 1.29195 -2.07616004 0 P 0 
L 1.24261004 -2.07516004 1.29203002 -2.07516004 0 P 0 
L 1.24266998 -2.07416004 1.2921 -2.07416004 0 P 0 
L 1.24271998 -2.07316004 1.29216998 -2.07316004 0 P 0 
L 1.24278002 -2.07216004 1.29223996 -2.07216004 0 P 0 
L 1.24283002 -2.07116004 1.29231998 -2.07116004 0 P 0 
L 1.24288002 -2.07016004 1.29238996 -2.07016004 0 P 0 
L 1.24293002 -2.06916004 1.29246004 -2.06916004 0 P 0 
L 1.24296998 -2.06816004 1.29253002 -2.06816004 0 P 0 
L 1.24301998 -2.06716004 1.29261004 -2.06716004 0 P 0 
L 1.24306004 -2.06616004 1.2927 -2.06616004 0 P 0 
L 1.24311004 -2.06516004 1.29281004 -2.06516004 0 P 0 
L 1.24315 -2.06416004 1.29291998 -2.06416004 0 P 0 
L 1.2432 -2.06316004 1.29303002 -2.06316004 0 P 0 
L 1.24323996 -2.06216004 1.29315 -2.06216004 0 P 0 
L 1.24328996 -2.06116004 1.29331998 -2.06116004 0 P 0 
L 1.24333002 -2.06016004 1.2935 -2.06016004 0 P 0 
L 1.24338002 -2.05916004 1.29366998 -2.05916004 0 P 0 
L 1.24341998 -2.05816004 1.29385 -2.05816004 0 P 0 
L 1.24346998 -2.05716004 1.29408996 -2.05716004 0 P 0 
L 1.24351004 -2.05616004 1.29433996 -2.05616004 0 P 0 
L 1.24355 -2.05516004 1.29458996 -2.05516004 0 P 0 
L 1.2436 -2.05416004 1.29485 -2.05416004 0 P 0 
L 1.24363996 -2.05316004 1.29516998 -2.05316004 0 P 0 
L 1.24368996 -2.05216004 1.29551998 -2.05216004 0 P 0 
L 1.24373002 -2.05116004 1.29586004 -2.05116004 0 P 0 
L 1.24378002 -2.05016004 1.29621004 -2.05016004 0 P 0 
L 1.24383002 -2.04916004 1.29663996 -2.04916004 0 P 0 
L 1.24386998 -2.04816004 1.29708002 -2.04816004 0 P 0 
L 1.24391004 -2.04716004 1.29753002 -2.04716004 0 P 0 
L 1.24396004 -2.04616004 1.29796998 -2.04616004 0 P 0 
L 1.244 -2.04516004 1.29851004 -2.04516004 0 P 0 
L 1.24405 -2.04416004 1.2991 -2.04416004 0 P 0 
L 1.24408996 -2.04316004 1.29975 -2.04316004 0 P 0 
L 1.24413996 -2.04216004 1.3005 -2.04216004 0 P 0 
L 1.24418002 -2.04116004 1.30131998 -2.04116004 0 P 0 
L 1.24423002 -2.04016004 1.30223002 -2.04016004 0 P 0 
L 1.24426998 -2.03916004 1.30326998 -2.03916004 0 P 0 
L 1.24431998 -2.03816004 1.30446004 -2.03816004 0 P 0 
L 1.24436004 -2.03716004 1.30581998 -2.03716004 0 P 0 
L 1.24441004 -2.03616004 1.30738002 -2.03616004 0 P 0 
L 1.24445 -2.03516004 1.30923002 -2.03516004 0 P 0 
L 1.24448996 -2.03416004 1.31156004 -2.03416004 0 P 0 
L 1.24453996 -2.03316004 1.31478996 -2.03316004 0 P 0 
L 1.24458996 -2.03216004 1.32013002 -2.03216004 0 P 0 
L 1.24461998 -2.03116004 1.33481004 -2.03116004 0 P 0 
L 1.24463996 -2.03016004 1.33478002 -2.03016004 0 P 0 
L 1.24466004 -2.02916004 1.33473996 -2.02916004 0 P 0 
L 1.24468002 -2.02816004 1.33471004 -2.02816004 0 P 0 
L 1.2447 -2.02716004 1.33468002 -2.02716004 0 P 0 
L 1.24471998 -2.02616004 1.33463996 -2.02616004 0 P 0 
L 1.24473996 -2.02516004 1.3346 -2.02516004 0 P 0 
L 1.24476004 -2.02416004 1.33456998 -2.02416004 0 P 0 
L 1.24478002 -2.02316004 1.33453002 -2.02316004 0 P 0 
L 1.2448 -2.02216004 1.3345 -2.02216004 0 P 0 
L 1.24481998 -2.02116004 1.33446998 -2.02116004 0 P 0 
L 1.24483996 -2.02016004 1.33443002 -2.02016004 0 P 0 
L 1.24486004 -2.01916004 1.3344 -2.01916004 0 P 0 
L 1.24488002 -2.01816004 1.33436004 -2.01816004 0 P 0 
L 1.2449 -2.01716004 1.33433002 -2.01716004 0 P 0 
L 1.24491998 -2.01616004 1.33428996 -2.01616004 0 P 0 
L 1.24493996 -2.01516004 1.33426004 -2.01516004 0 P 0 
L 1.24496004 -2.01416004 1.33421998 -2.01416004 0 P 0 
L 1.24498002 -2.01316004 1.33418996 -2.01316004 0 P 0 
L 1.245 -2.01216004 1.33415 -2.01216004 0 P 0 
L 1.24501998 -2.01116004 1.33411998 -2.01116004 0 P 0 
L 1.24503996 -2.01016004 1.33408002 -2.01016004 0 P 0 
L 1.24506004 -2.00916004 1.33403996 -2.00916004 0 P 0 
L 1.24508002 -2.00816004 1.334 -2.00816004 0 P 0 
L 1.2451 -2.00716004 1.33396004 -2.00716004 0 P 0 
L 1.24511998 -2.00616004 1.33393002 -2.00616004 0 P 0 
L 1.24513996 -2.00516004 1.29098996 -2.00516004 0 P 0 
L 1.24513996 -2.00416004 1.29033002 -2.00416004 0 P 0 
L 1.24513996 -2.00316004 1.29005 -2.00316004 0 P 0 
L 1.24513996 -2.00216004 1.29005 -2.00216004 0 P 0 
L 1.24513996 -2.00116004 1.29005 -2.00116004 0 P 0 
L 1.24515 -2.00016004 1.29005 -2.00016004 0 P 0 
L 1.24515 -1.99916004 1.29005 -1.99916004 0 P 0 
L 1.24515 -1.99816004 1.29005 -1.99816004 0 P 0 
L 1.24515 -1.99716004 1.29005 -1.99716004 0 P 0 
L 1.24515 -1.99616004 1.29005 -1.99616004 0 P 0 
L 1.24515 -1.99516004 1.29005 -1.99516004 0 P 0 
L 1.16085 -2.02753002 1.1601 -2.04393002 0 P 0 
L 1.1601 -2.04393002 1.15928996 -2.05771998 0 P 0 
L 1.15928996 -2.05771998 1.15883996 -2.06228002 0 P 0 
L 1.15883996 -2.06228002 1.15818002 -2.06681998 0 P 0 
L 1.15818002 -2.06681998 1.15751004 -2.07006998 0 P 0 
L 1.15751004 -2.07006998 1.15661004 -2.07328996 0 P 0 
L 1.15661004 -2.07328996 1.15616004 -2.07453996 0 P 0 
L 1.15616004 -2.07453996 1.15563002 -2.07576998 0 P 0 
L 1.15563002 -2.07576998 1.15501998 -2.07696004 0 P 0 
L 1.15501998 -2.07696004 1.15433002 -2.0781 0 P 0 
L 1.15433002 -2.0781 1.1534 -2.07941998 0 P 0 
L 1.1534 -2.07941998 1.15236004 -2.08066004 0 P 0 
L 1.15236004 -2.08066004 1.15123002 -2.08181998 0 P 0 
L 1.15123002 -2.08181998 1.15001004 -2.08286998 0 P 0 
L 1.15001004 -2.08286998 1.14871004 -2.08383002 0 P 0 
L 1.14871004 -2.08383002 1.14733002 -2.08468002 0 P 0 
L 1.14733002 -2.08468002 1.14591004 -2.0854 0 P 0 
L 1.14591004 -2.0854 1.14443996 -2.086 0 P 0 
L 1.14443996 -2.086 1.14291004 -2.08648002 0 P 0 
L 1.14291004 -2.08648002 1.14136004 -2.08683002 0 P 0 
L 1.14136004 -2.08683002 1.13976998 -2.08703996 0 P 0 
L 1.13976998 -2.08703996 1.13816004 -2.08713002 0 P 0 
L 1.13816004 -2.08713002 1.13656998 -2.08708002 0 P 0 
L 1.13656998 -2.08708002 1.13498996 -2.0869 0 P 0 
L 1.13498996 -2.0869 1.13341998 -2.08658996 0 P 0 
L 1.13341998 -2.08658996 1.13188996 -2.08615 0 P 0 
L 1.13188996 -2.08615 1.1304 -2.08558996 0 P 0 
L 1.1304 -2.08558996 1.12895 -2.08488996 0 P 0 
L 1.12895 -2.08488996 1.12756998 -2.08408002 0 P 0 
L 1.12756998 -2.08408002 1.12625 -2.08315 0 P 0 
L 1.12625 -2.08315 1.12501004 -2.08211998 0 P 0 
L 1.12501004 -2.08211998 1.12386004 -2.081 0 P 0 
L 1.12386004 -2.081 1.12281004 -2.07978002 0 P 0 
L 1.12281004 -2.07978002 1.12183996 -2.07846998 0 P 0 
L 1.12183996 -2.07846998 1.1211 -2.07726004 0 P 0 
L 1.1211 -2.07726004 1.12046998 -2.07598996 0 P 0 
L 1.12046998 -2.07598996 1.11996004 -2.07466998 0 P 0 
L 1.11996004 -2.07466998 1.11955 -2.07331004 0 P 0 
L 1.11955 -2.07331004 1.11926998 -2.07191004 0 P 0 
L 1.11926998 -2.07191004 1.11868002 -2.06693996 0 P 0 
L 1.11868002 -2.06693996 1.11848002 -2.06191004 0 P 0 
L 1.11848002 -2.06191004 1.11871004 -2.05668002 0 P 0 
L 1.11871004 -2.05668002 1.11936004 -2.05148002 0 P 0 
L 1.11936004 -2.05148002 1.11978996 -2.04936998 0 P 0 
L 1.11978996 -2.04936998 1.12036998 -2.0473 0 P 0 
L 1.12036998 -2.0473 1.12108996 -2.04528002 0 P 0 
L 1.12108996 -2.04528002 1.12196004 -2.04331998 0 P 0 
L 1.12196004 -2.04331998 1.1229 -2.04153996 0 P 0 
L 1.1229 -2.04153996 1.12396998 -2.03985 0 P 0 
L 1.12396998 -2.03985 1.12516998 -2.03823002 0 P 0 
L 1.12516998 -2.03823002 1.12735 -2.03573996 0 P 0 
L 1.12735 -2.03573996 1.12973002 -2.03345 0 P 0 
L 1.12973002 -2.03345 1.13223996 -2.03141998 0 P 0 
L 1.13223996 -2.03141998 1.13491998 -2.02961004 0 P 0 
L 1.13491998 -2.02961004 1.13611004 -2.02893002 0 P 0 
L 1.13611004 -2.02893002 1.13735 -2.02833996 0 P 0 
L 1.13735 -2.02833996 1.13861998 -2.02781998 0 P 0 
L 1.13861998 -2.02781998 1.13993996 -2.0274 0 P 0 
L 1.13993996 -2.0274 1.14191004 -2.02693002 0 P 0 
L 1.14191004 -2.02693002 1.14391004 -2.02663002 0 P 0 
L 1.14391004 -2.02663002 1.14935 -2.02626004 0 P 0 
L 1.14935 -2.02626004 1.15471004 -2.0263 0 P 0 
L 1.15471004 -2.0263 1.15591004 -2.02638996 0 P 0 
L 1.15591004 -2.02638996 1.1571 -2.02656998 0 P 0 
L 1.1571 -2.02656998 1.15828002 -2.02683996 0 P 0 
L 1.15828002 -2.02683996 1.16085 -2.02753002 0 P 0 
L 1.13876998 -2.14783002 1.20233002 -2.14783002 0 P 0 
L 1.14236998 -2.14683002 1.20266004 -2.14683002 0 P 0 
L 1.14481004 -2.14583002 1.20296004 -2.14583002 0 P 0 
L 1.1467 -2.14483002 1.20325 -2.14483002 0 P 0 
L 1.14826004 -2.14383002 1.20353002 -2.14383002 0 P 0 
L 1.1496 -2.14283002 1.20373996 -2.14283002 0 P 0 
L 1.15078996 -2.14183002 1.20395 -2.14183002 0 P 0 
L 1.15186004 -2.14083002 1.20415 -2.14083002 0 P 0 
L 1.15278996 -2.13983002 1.20431998 -2.13983002 0 P 0 
L 1.15361998 -2.13883002 1.20446004 -2.13883002 0 P 0 
L 1.15436004 -2.13783002 1.20458002 -2.13783002 0 P 0 
L 1.155 -2.13683002 1.20466998 -2.13683002 0 P 0 
L 1.15556998 -2.13583002 1.20475 -2.13583002 0 P 0 
L 1.15608996 -2.13483002 1.20481998 -2.13483002 0 P 0 
L 1.15653996 -2.13383002 1.20488996 -2.13383002 0 P 0 
L 1.15691004 -2.13283002 1.20496004 -2.13283002 0 P 0 
L 1.15723996 -2.13183002 1.20503002 -2.13183002 0 P 0 
L 1.15751998 -2.13083002 1.2051 -2.13083002 0 P 0 
L 1.15773002 -2.12983002 1.20516004 -2.12983002 0 P 0 
L 1.15793002 -2.12883002 1.20523002 -2.12883002 0 P 0 
L 1.15806004 -2.12783002 1.2053 -2.12783002 0 P 0 
L 1.15816998 -2.12683002 1.20536998 -2.12683002 0 P 0 
L 1.15821004 -2.12583002 1.20543996 -2.12583002 0 P 0 
L 1.11716004 -2.12483002 1.12726004 -2.12483002 0 P 0 
L 1.15823996 -2.12483002 1.20551004 -2.12483002 0 P 0 
L 1.10911998 -2.12383002 1.1352 -2.12383002 0 P 0 
L 1.15821998 -2.12383002 1.20556998 -2.12383002 0 P 0 
L 1.10468996 -2.12283002 1.14018996 -2.12283002 0 P 0 
L 1.1582 -2.12283002 1.20563996 -2.12283002 0 P 0 
L 1.10131004 -2.12183002 1.14366998 -2.12183002 0 P 0 
L 1.15818002 -2.12183002 1.2057 -2.12183002 0 P 0 
L 1.15808996 -2.12083002 1.20576004 -2.12083002 0 P 0 
L 1.15781004 -2.11983002 1.20583002 -2.11983002 0 P 0 
L 1.15721004 -2.11883002 1.20588002 -2.11883002 0 P 0 
L 1.14146004 -2.08883002 1.20758002 -2.08883002 0 P 0 
L 1.14525 -2.08783002 1.20763002 -2.08783002 0 P 0 
L 1.14751004 -2.08683002 1.20768002 -2.08683002 0 P 0 
L 1.14928002 -2.08583002 1.20773002 -2.08583002 0 P 0 
L 1.15073002 -2.08483002 1.20778996 -2.08483002 0 P 0 
L 1.15196004 -2.08383002 1.20783996 -2.08383002 0 P 0 
L 1.13818996 -2.08913002 1.13826998 -2.08913002 0 P 0 
L 1.13826998 -2.08913002 1.13988002 -2.08903996 0 P 0 
L 1.13988002 -2.08903996 1.13996004 -2.08903996 0 P 0 
L 1.13996004 -2.08903996 1.14001004 -2.08903002 0 P 0 
L 1.14001004 -2.08903002 1.14005 -2.08901998 0 P 0 
L 1.14005 -2.08901998 1.14163002 -2.08881004 0 P 0 
L 1.14163002 -2.08881004 1.14166998 -2.0888 0 P 0 
L 1.14166998 -2.0888 1.14171004 -2.0888 0 P 0 
L 1.14171004 -2.0888 1.14178996 -2.08878002 0 P 0 
L 1.14178996 -2.08878002 1.14335 -2.08843002 0 P 0 
L 1.14335 -2.08843002 1.14351004 -2.08838996 0 P 0 
L 1.14351004 -2.08838996 1.14503002 -2.08791004 0 P 0 
L 1.14503002 -2.08791004 1.14511004 -2.08788996 0 P 0 
L 1.14511004 -2.08788996 1.14515 -2.08786998 0 P 0 
L 1.14515 -2.08786998 1.14518996 -2.08786004 0 P 0 
L 1.14518996 -2.08786004 1.14666004 -2.08725 0 P 0 
L 1.14666004 -2.08725 1.14673996 -2.08721998 0 P 0 
L 1.14673996 -2.08721998 1.14678002 -2.0872 0 P 0 
L 1.14678002 -2.0872 1.14681998 -2.08718996 0 P 0 
L 1.14681998 -2.08718996 1.14823996 -2.08646998 0 P 0 
L 1.14823996 -2.08646998 1.14826998 -2.08645 0 P 0 
L 1.14826998 -2.08645 1.14835 -2.08641004 0 P 0 
L 1.14835 -2.08641004 1.14838002 -2.08638002 0 P 0 
L 1.14838002 -2.08638002 1.14976004 -2.08553002 0 P 0 
L 1.14976004 -2.08553002 1.14978996 -2.08551004 0 P 0 
L 1.14978996 -2.08551004 1.14983002 -2.08548996 0 P 0 
L 1.14983002 -2.08548996 1.14988996 -2.08543996 0 P 0 
L 1.14988996 -2.08543996 1.1512 -2.08448996 0 P 0 
L 1.1512 -2.08448996 1.15126004 -2.08443996 0 P 0 
L 1.15126004 -2.08443996 1.15128996 -2.08441004 0 P 0 
L 1.15128996 -2.08441004 1.15131998 -2.08438996 0 P 0 
L 1.15131998 -2.08438996 1.15253996 -2.08333002 0 P 0 
L 1.15253996 -2.08333002 1.15256998 -2.0833 0 P 0 
L 1.15256998 -2.0833 1.1526 -2.08328002 0 P 0 
L 1.1526 -2.08328002 1.15263002 -2.08323996 0 P 0 
L 1.15263002 -2.08323996 1.15266004 -2.08321998 0 P 0 
L 1.15266004 -2.08321998 1.15378996 -2.08206004 0 P 0 
L 1.15378996 -2.08206004 1.15376004 -2.08203996 0 P 0 
L 1.15376004 -2.08203996 1.15381998 -2.08203996 0 P 0 
L 1.15381998 -2.08203996 1.15383996 -2.082 0 P 0 
L 1.15383996 -2.082 1.15386998 -2.08196998 0 P 0 
L 1.15386998 -2.08196998 1.1539 -2.08195 0 P 0 
L 1.1539 -2.08195 1.15493002 -2.08071004 0 P 0 
L 1.15493002 -2.08071004 1.15493002 -2.0807 0 P 0 
L 1.15493002 -2.0807 1.15496004 -2.08066998 0 P 0 
L 1.15496004 -2.08066998 1.15498002 -2.08063996 0 P 0 
L 1.15498002 -2.08063996 1.15501004 -2.08061004 0 P 0 
L 1.15501004 -2.08061004 1.15503002 -2.08058002 0 P 0 
L 1.15503002 -2.08058002 1.15596004 -2.07926004 0 P 0 
L 1.15596004 -2.07926004 1.15603996 -2.07913996 0 P 0 
L 1.15603996 -2.07913996 1.15673002 -2.07798996 0 P 0 
L 1.15673002 -2.07798996 1.15676998 -2.07793002 0 P 0 
L 1.15676998 -2.07793002 1.15678996 -2.07786998 0 P 0 
L 1.15678996 -2.07786998 1.15741004 -2.07668996 0 P 0 
L 1.15741004 -2.07668996 1.15743996 -2.07663002 0 P 0 
L 1.15743996 -2.07663002 1.15746004 -2.07656998 0 P 0 
L 1.15746004 -2.07656998 1.15746998 -2.07656998 0 P 0 
L 1.15746998 -2.07656998 1.158 -2.07533996 0 P 0 
L 1.158 -2.07533996 1.15801004 -2.07531004 0 P 0 
L 1.15801004 -2.07531004 1.15803002 -2.07528002 0 P 0 
L 1.15803002 -2.07528002 1.15805 -2.07521998 0 P 0 
L 1.15805 -2.07521998 1.15848996 -2.07396004 0 P 0 
L 1.15848996 -2.07396004 1.15841004 -2.07393002 0 P 0 
L 1.15841004 -2.07393002 1.15851004 -2.07393002 0 P 0 
L 1.15851004 -2.07393002 1.15851998 -2.0739 0 P 0 
L 1.15851998 -2.0739 1.15853002 -2.07386004 0 P 0 
L 1.15853002 -2.07386004 1.15853996 -2.07383002 0 P 0 
L 1.15853996 -2.07383002 1.15943996 -2.07061004 0 P 0 
L 1.15943996 -2.07061004 1.15945 -2.07058002 0 P 0 
L 1.15945 -2.07058002 1.15946004 -2.07053996 0 P 0 
L 1.15946004 -2.07053996 1.15946998 -2.07051004 0 P 0 
L 1.15946998 -2.07051004 1.15946998 -2.07046998 0 P 0 
L 1.15946998 -2.07046998 1.16013996 -2.06723002 0 P 0 
L 1.16013996 -2.06723002 1.16013996 -2.0672 0 P 0 
L 1.16013996 -2.0672 1.16016004 -2.06713996 0 P 0 
L 1.16016004 -2.06713996 1.16016004 -2.06711004 0 P 0 
L 1.16016004 -2.06711004 1.16081998 -2.06256004 0 P 0 
L 1.16081998 -2.06256004 1.16081998 -2.06253996 0 P 0 
L 1.16081998 -2.06253996 1.16083002 -2.0625 0 P 0 
L 1.16083002 -2.0625 1.16083002 -2.06246998 0 P 0 
L 1.16083002 -2.06246998 1.16126998 -2.05791004 0 P 0 
L 1.16126998 -2.05791004 1.16128002 -2.0579 0 P 0 
L 1.16128002 -2.0579 1.16128002 -2.05783996 0 P 0 
L 1.16128002 -2.05783996 1.1621 -2.04405 0 P 0 
L 1.1621 -2.04405 1.1621 -2.04401998 0 P 0 
L 1.1621 -2.04401998 1.16285 -2.02761998 0 P 0 
L 1.16285 -2.02761998 1.16136998 -2.0256 0 P 0 
L 1.16136998 -2.0256 1.15878996 -2.02491004 0 P 0 
L 1.15878996 -2.02491004 1.15878002 -2.0249 0 P 0 
L 1.15878002 -2.0249 1.15871998 -2.02488996 0 P 0 
L 1.15871998 -2.02488996 1.15755 -2.02461998 0 P 0 
L 1.15755 -2.02461998 1.15746998 -2.0246 0 P 0 
L 1.15746998 -2.0246 1.1574 -2.0246 0 P 0 
L 1.1574 -2.0246 1.15621004 -2.02441004 0 P 0 
L 1.15621004 -2.02441004 1.15616998 -2.02441004 0 P 0 
L 1.15616998 -2.02441004 1.1561 -2.0244 0 P 0 
L 1.1561 -2.0244 1.15606004 -2.02438996 0 P 0 
L 1.15606004 -2.02438996 1.15486004 -2.0243 0 P 0 
L 1.15486004 -2.0243 1.15471998 -2.0243 0 P 0 
L 1.15471998 -2.0243 1.14936004 -2.02426004 0 P 0 
L 1.14936004 -2.02426004 1.14928996 -2.02426004 0 P 0 
L 1.14928996 -2.02426004 1.14925 -2.02426998 0 P 0 
L 1.14925 -2.02426998 1.14921004 -2.02426998 0 P 0 
L 1.14921004 -2.02426998 1.14376998 -2.02463996 0 P 0 
L 1.14376998 -2.02463996 1.1437 -2.02463996 0 P 0 
L 1.1437 -2.02463996 1.14365 -2.02465 0 P 0 
L 1.14365 -2.02465 1.14361004 -2.02465 0 P 0 
L 1.14361004 -2.02465 1.14161998 -2.02495 0 P 0 
L 1.14161998 -2.02495 1.14161004 -2.02495 0 P 0 
L 1.14161004 -2.02495 1.14153002 -2.02496998 0 P 0 
L 1.14153002 -2.02496998 1.14148996 -2.02496998 0 P 0 
L 1.14148996 -2.02496998 1.14143996 -2.02498996 0 P 0 
L 1.14143996 -2.02498996 1.13946998 -2.02545 0 P 0 
L 1.13946998 -2.02545 1.13943996 -2.02546998 0 P 0 
L 1.13943996 -2.02546998 1.1394 -2.02546998 0 P 0 
L 1.1394 -2.02546998 1.13933002 -2.0255 0 P 0 
L 1.13933002 -2.0255 1.13801004 -2.02591998 0 P 0 
L 1.13801004 -2.02591998 1.13798002 -2.02593002 0 P 0 
L 1.13798002 -2.02593002 1.13793996 -2.02593996 0 P 0 
L 1.13793996 -2.02593996 1.13788002 -2.02596998 0 P 0 
L 1.13788002 -2.02596998 1.1366 -2.02648002 0 P 0 
L 1.1366 -2.02648002 1.13653996 -2.0265 0 P 0 
L 1.13653996 -2.0265 1.13648002 -2.02653002 0 P 0 
L 1.13648002 -2.02653002 1.13523996 -2.02713002 0 P 0 
L 1.13523996 -2.02713002 1.13518002 -2.02716004 0 P 0 
L 1.13518002 -2.02716004 1.13515 -2.02716998 0 P 0 
L 1.13515 -2.02716998 1.13511998 -2.02718996 0 P 0 
L 1.13511998 -2.02718996 1.13393002 -2.02786998 0 P 0 
L 1.13393002 -2.02786998 1.13388996 -2.02788996 0 P 0 
L 1.13388996 -2.02788996 1.1338 -2.02795 0 P 0 
L 1.1338 -2.02795 1.13111998 -2.02976004 0 P 0 
L 1.13111998 -2.02976004 1.13105 -2.02981004 0 P 0 
L 1.13105 -2.02981004 1.13101004 -2.02983996 0 P 0 
L 1.13101004 -2.02983996 1.13098002 -2.02986004 0 P 0 
L 1.13098002 -2.02986004 1.12846998 -2.03188996 0 P 0 
L 1.12846998 -2.03188996 1.12838002 -2.03198002 0 P 0 
L 1.12838002 -2.03198002 1.12833996 -2.03201004 0 P 0 
L 1.12833996 -2.03201004 1.12596004 -2.0343 0 P 0 
L 1.12596004 -2.0343 1.12593996 -2.03433002 0 P 0 
L 1.12593996 -2.03433002 1.1259 -2.03436004 0 P 0 
L 1.1259 -2.03436004 1.12588002 -2.03438996 0 P 0 
L 1.12588002 -2.03438996 1.12585 -2.03443002 0 P 0 
L 1.12585 -2.03443002 1.12366998 -2.03691004 0 P 0 
L 1.12366998 -2.03691004 1.12363996 -2.03695 0 P 0 
L 1.12363996 -2.03695 1.12361998 -2.03698002 0 P 0 
L 1.12361998 -2.03698002 1.12358996 -2.03701004 0 P 0 
L 1.12358996 -2.03701004 1.12356998 -2.03703996 0 P 0 
L 1.12356998 -2.03703996 1.12236998 -2.03865 0 P 0 
L 1.12236998 -2.03865 1.12233996 -2.03868996 0 P 0 
L 1.12233996 -2.03868996 1.12233002 -2.03871004 0 P 0 
L 1.12233002 -2.03871004 1.12228996 -2.03878002 0 P 0 
L 1.12228996 -2.03878002 1.12121004 -2.04046998 0 P 0 
L 1.12121004 -2.04046998 1.12118996 -2.0405 0 P 0 
L 1.12118996 -2.0405 1.12116998 -2.04053996 0 P 0 
L 1.12116998 -2.04053996 1.12115 -2.04056998 0 P 0 
L 1.12115 -2.04056998 1.12113996 -2.04061004 0 P 0 
L 1.12113996 -2.04061004 1.12018996 -2.04238002 0 P 0 
L 1.12018996 -2.04238002 1.12016004 -2.04245 0 P 0 
L 1.12016004 -2.04245 1.12013996 -2.04248002 0 P 0 
L 1.12013996 -2.04248002 1.12013002 -2.04251004 0 P 0 
L 1.12013002 -2.04251004 1.11926004 -2.04446998 0 P 0 
L 1.11926004 -2.04446998 1.11925 -2.0445 0 P 0 
L 1.11925 -2.0445 1.11923002 -2.04453996 0 P 0 
L 1.11923002 -2.04453996 1.11921998 -2.04458002 0 P 0 
L 1.11921998 -2.04458002 1.11921004 -2.04461004 0 P 0 
L 1.11921004 -2.04461004 1.11848002 -2.04663002 0 P 0 
L 1.11848002 -2.04663002 1.11846998 -2.04666004 0 P 0 
L 1.11846998 -2.04666004 1.11846004 -2.0467 0 P 0 
L 1.11846004 -2.0467 1.11843996 -2.04676998 0 P 0 
L 1.11843996 -2.04676998 1.11786004 -2.04883996 0 P 0 
L 1.11786004 -2.04883996 1.11785 -2.04886998 0 P 0 
L 1.11785 -2.04886998 1.11783996 -2.04891004 0 P 0 
L 1.11783996 -2.04891004 1.11783996 -2.04893996 0 P 0 
L 1.11783996 -2.04893996 1.11783002 -2.04896998 0 P 0 
L 1.11783002 -2.04896998 1.11783002 -2.04898002 0 P 0 
L 1.11783002 -2.04898002 1.1174 -2.05108002 0 P 0 
L 1.1174 -2.05108002 1.1174 -2.05111998 0 P 0 
L 1.1174 -2.05111998 1.11738996 -2.05116004 0 P 0 
L 1.11738996 -2.05116004 1.11738002 -2.05118996 0 P 0 
L 1.11738002 -2.05118996 1.11738002 -2.05123002 0 P 0 
L 1.11738002 -2.05123002 1.11673002 -2.05643002 0 P 0 
L 1.11673002 -2.05643002 1.11671998 -2.05646998 0 P 0 
L 1.11671998 -2.05646998 1.11671998 -2.05655 0 P 0 
L 1.11671998 -2.05655 1.11671004 -2.05658996 0 P 0 
L 1.11671004 -2.05658996 1.11648996 -2.06181998 0 P 0 
L 1.11648996 -2.06181998 1.11648002 -2.06186998 0 P 0 
L 1.11648002 -2.06186998 1.11648002 -2.06195 0 P 0 
L 1.11648002 -2.06195 1.11648996 -2.06198996 0 P 0 
L 1.11648996 -2.06198996 1.11668002 -2.06696998 0 P 0 
L 1.11668002 -2.06696998 1.11768002 -2.06696998 0 P 0 
L 1.11768002 -2.06696998 1.11668002 -2.06701004 0 P 0 
L 1.11668002 -2.06701004 1.11668002 -2.06713002 0 P 0 
L 1.11668002 -2.06713002 1.11668996 -2.06716998 0 P 0 
L 1.11668996 -2.06716998 1.11728002 -2.07215 0 P 0 
L 1.11728002 -2.07215 1.11728996 -2.07218996 0 P 0 
L 1.11728996 -2.07218996 1.11728996 -2.07223002 0 P 0 
L 1.11728996 -2.07223002 1.11731004 -2.07231004 0 P 0 
L 1.11731004 -2.07231004 1.11758996 -2.07371004 0 P 0 
L 1.11758996 -2.07371004 1.1176 -2.07375 0 P 0 
L 1.1176 -2.07375 1.11761004 -2.0738 0 P 0 
L 1.11761004 -2.0738 1.11761998 -2.07383996 0 P 0 
L 1.11761998 -2.07383996 1.11763996 -2.07388002 0 P 0 
L 1.11763996 -2.07388002 1.11803996 -2.07523996 0 P 0 
L 1.11803996 -2.07523996 1.11806004 -2.07531998 0 P 0 
L 1.11806004 -2.07531998 1.11808002 -2.07536004 0 P 0 
L 1.11808002 -2.07536004 1.11808996 -2.07541004 0 P 0 
L 1.11808996 -2.07541004 1.11861004 -2.07673002 0 P 0 
L 1.11861004 -2.07673002 1.11863996 -2.07681004 0 P 0 
L 1.11863996 -2.07681004 1.11866004 -2.07683996 0 P 0 
L 1.11866004 -2.07683996 1.11868002 -2.07688002 0 P 0 
L 1.11868002 -2.07688002 1.11931004 -2.07815 0 P 0 
L 1.11931004 -2.07815 1.11935 -2.07823002 0 P 0 
L 1.11935 -2.07823002 1.1194 -2.0783 0 P 0 
L 1.1194 -2.0783 1.12013996 -2.07951998 0 P 0 
L 1.12013996 -2.07951998 1.12021004 -2.07961998 0 P 0 
L 1.12021004 -2.07961998 1.12023002 -2.07965 0 P 0 
L 1.12023002 -2.07965 1.12023002 -2.07966004 0 P 0 
L 1.12023002 -2.07966004 1.1212 -2.08096998 0 P 0 
L 1.1212 -2.08096998 1.12123996 -2.08103002 0 P 0 
L 1.12123996 -2.08103002 1.12126998 -2.08106004 0 P 0 
L 1.12126998 -2.08106004 1.12128996 -2.08108996 0 P 0 
L 1.12128996 -2.08108996 1.12235 -2.08231004 0 P 0 
L 1.12235 -2.08231004 1.12238002 -2.08233996 0 P 0 
L 1.12238002 -2.08233996 1.1224 -2.08236998 0 P 0 
L 1.1224 -2.08236998 1.12246004 -2.08243002 0 P 0 
L 1.12246004 -2.08243002 1.12361004 -2.08355 0 P 0 
L 1.12361004 -2.08355 1.12366998 -2.08361004 0 P 0 
L 1.12366998 -2.08361004 1.1237 -2.08363002 0 P 0 
L 1.1237 -2.08363002 1.12373002 -2.08366004 0 P 0 
L 1.12373002 -2.08366004 1.12496998 -2.08468996 0 P 0 
L 1.12496998 -2.08468996 1.125 -2.08471004 0 P 0 
L 1.125 -2.08471004 1.12503002 -2.08473996 0 P 0 
L 1.12503002 -2.08473996 1.12506998 -2.08476004 0 P 0 
L 1.12506998 -2.08476004 1.1251 -2.08478996 0 P 0 
L 1.1251 -2.08478996 1.12641998 -2.08571004 0 P 0 
L 1.12641998 -2.08571004 1.12645 -2.08573002 0 P 0 
L 1.12645 -2.08573002 1.12648002 -2.08576004 0 P 0 
L 1.12648002 -2.08576004 1.12651004 -2.08578002 0 P 0 
L 1.12651004 -2.08578002 1.12655 -2.0858 0 P 0 
L 1.12655 -2.0858 1.12793996 -2.08661004 0 P 0 
L 1.12793996 -2.08661004 1.12801004 -2.08665 0 P 0 
L 1.12801004 -2.08665 1.12805 -2.08666998 0 P 0 
L 1.12805 -2.08666998 1.12808002 -2.08668996 0 P 0 
L 1.12808002 -2.08668996 1.12808996 -2.08668996 0 P 0 
L 1.12808996 -2.08668996 1.12953996 -2.08738996 0 P 0 
L 1.12953996 -2.08738996 1.12961998 -2.08743002 0 P 0 
L 1.12961998 -2.08743002 1.12965 -2.08743996 0 P 0 
L 1.12965 -2.08743996 1.1297 -2.08746004 0 P 0 
L 1.1297 -2.08746004 1.13118002 -2.08801998 0 P 0 
L 1.13118002 -2.08801998 1.13133996 -2.08808002 0 P 0 
L 1.13133996 -2.08808002 1.13286998 -2.08851004 0 P 0 
L 1.13286998 -2.08851004 1.13295 -2.08853996 0 P 0 
L 1.13295 -2.08853996 1.13303996 -2.08855 0 P 0 
L 1.13303996 -2.08855 1.1346 -2.08886004 0 P 0 
L 1.1346 -2.08886004 1.13471998 -2.08888996 0 P 0 
L 1.13471998 -2.08888996 1.13476004 -2.08888996 0 P 0 
L 1.13476004 -2.08888996 1.13633996 -2.08906998 0 P 0 
L 1.13633996 -2.08906998 1.13638996 -2.08908002 0 P 0 
L 1.13638996 -2.08908002 1.13651004 -2.08908002 0 P 0 
L 1.13651004 -2.08908002 1.1381 -2.08913002 0 P 0 
L 1.1381 -2.08913002 1.13818996 -2.08913002 0 P 0 
L 1.31623996 -1.98923996 1.3135 -1.98988002 0 P 0 
L 1.3135 -1.98988002 1.31078996 -1.99071004 0 P 0 
L 1.31078996 -1.99071004 1.30813002 -1.99175 0 P 0 
L 1.30813002 -1.99175 1.30553996 -1.99296998 0 P 0 
L 1.30553996 -1.99296998 1.30308996 -1.99431998 0 P 0 
L 1.30308996 -1.99431998 1.30073996 -1.99585 0 P 0 
L 1.30073996 -1.99585 1.29863996 -1.99746004 0 P 0 
L 1.29863996 -1.99746004 1.29666004 -1.99923996 0 P 0 
L 1.29666004 -1.99923996 1.29205 -2.00375 0 P 0 
L 1.29205 -2.00375 1.29205 -1.99243996 0 P 0 
L 1.29205 -1.99243996 1.24316004 -1.99243996 0 P 0 
L 1.24316004 -1.99243996 1.24313996 -2.00521004 0 P 0 
L 1.24313996 -2.00521004 1.24261004 -2.03151004 0 P 0 
L 1.24261004 -2.03151004 1.24086998 -2.07046004 0 P 0 
L 1.24086998 -2.07046004 1.23873996 -2.10921004 0 P 0 
L 1.23873996 -2.10921004 1.23811998 -2.11641998 0 P 0 
L 1.23811998 -2.11641998 1.23711998 -2.12361998 0 P 0 
L 1.23711998 -2.12361998 1.23655 -2.12716004 0 P 0 
L 1.23655 -2.12716004 1.29205 -2.12716004 0 P 0 
L 1.29205 -2.12716004 1.29206998 -2.11766004 0 P 0 
L 1.29206998 -2.11766004 1.29238996 -2.10283996 0 P 0 
L 1.29238996 -2.10283996 1.29336004 -2.08431004 0 P 0 
L 1.29336004 -2.08431004 1.29463996 -2.06673002 0 P 0 
L 1.29463996 -2.06673002 1.29511004 -2.06253002 0 P 0 
L 1.29511004 -2.06253002 1.29583996 -2.05836004 0 P 0 
L 1.29583996 -2.05836004 1.29683002 -2.05446998 0 P 0 
L 1.29683002 -2.05446998 1.29813996 -2.05068996 0 P 0 
L 1.29813996 -2.05068996 1.29978002 -2.04701998 0 P 0 
L 1.29978002 -2.04701998 1.30056998 -2.04556998 0 P 0 
L 1.30056998 -2.04556998 1.30146998 -2.04418996 0 P 0 
L 1.30146998 -2.04418996 1.30246998 -2.04288002 0 P 0 
L 1.30246998 -2.04288002 1.30356998 -2.04165 0 P 0 
L 1.30356998 -2.04165 1.30475 -2.0405 0 P 0 
L 1.30475 -2.0405 1.30603996 -2.03945 0 P 0 
L 1.30603996 -2.03945 1.30773996 -2.03826004 0 P 0 
L 1.30773996 -2.03826004 1.30953002 -2.03723002 0 P 0 
L 1.30953002 -2.03723002 1.31141004 -2.03635 0 P 0 
L 1.31141004 -2.03635 1.31335 -2.03563002 0 P 0 
L 1.31335 -2.03563002 1.31535 -2.03508002 0 P 0 
L 1.31535 -2.03508002 1.31973996 -2.03423002 0 P 0 
L 1.31973996 -2.03423002 1.32416004 -2.03366998 0 P 0 
L 1.32416004 -2.03366998 1.32863002 -2.0334 0 P 0 
L 1.32863002 -2.0334 1.33688002 -2.03318002 0 P 0 
L 1.33688002 -2.03318002 1.33613002 -2.01151004 0 P 0 
L 1.33613002 -2.01151004 1.33581004 -2.00315 0 P 0 
L 1.33581004 -2.00315 1.33543996 -1.99596004 0 P 0 
L 1.33543996 -1.99596004 1.33508002 -1.98971004 0 P 0 
L 1.33508002 -1.98971004 1.33503996 -1.98945 0 P 0 
L 1.33503996 -1.98945 1.335 -1.98931998 0 P 0 
L 1.335 -1.98931998 1.33496004 -1.9892 0 P 0 
L 1.33496004 -1.9892 1.3349 -1.98908002 0 P 0 
L 1.3349 -1.98908002 1.33483996 -1.98896998 0 P 0 
L 1.33483996 -1.98896998 1.33476998 -1.98886004 0 P 0 
L 1.33476998 -1.98886004 1.33468996 -1.98876004 0 P 0 
L 1.33468996 -1.98876004 1.3346 -1.98866998 0 P 0 
L 1.3346 -1.98866998 1.33451004 -1.98858996 0 P 0 
L 1.33451004 -1.98858996 1.3344 -1.98851998 0 P 0 
L 1.3344 -1.98851998 1.3343 -1.98845 0 P 0 
L 1.3343 -1.98845 1.33418002 -1.98838996 0 P 0 
L 1.33418002 -1.98838996 1.33406998 -1.98833996 0 P 0 
L 1.33406998 -1.98833996 1.33395 -1.9883 0 P 0 
L 1.33395 -1.9883 1.33383002 -1.98828002 0 P 0 
L 1.33383002 -1.98828002 1.3337 -1.98826004 0 P 0 
L 1.3337 -1.98826004 1.33356998 -1.98825 0 P 0 
L 1.33356998 -1.98825 1.32756998 -1.98823002 0 P 0 
L 1.32756998 -1.98823002 1.32135 -1.98853996 0 P 0 
L 1.32135 -1.98853996 1.31878996 -1.98881998 0 P 0 
L 1.31878996 -1.98881998 1.31623996 -1.98923996 0 P 0 
L 1.2389 -2.12516004 1.29006004 -2.12516004 0 P 0 
L 1.23906998 -2.12416004 1.29006004 -2.12416004 0 P 0 
L 1.23921004 -2.12316004 1.29006004 -2.12316004 0 P 0 
L 1.23933996 -2.12216004 1.29006004 -2.12216004 0 P 0 
L 1.23948996 -2.12116004 1.29006004 -2.12116004 0 P 0 
L 1.23961998 -2.12016004 1.29006998 -2.12016004 0 P 0 
L 1.23976004 -2.11916004 1.29006998 -2.11916004 0 P 0 
L 1.2399 -2.11816004 1.29006998 -2.11816004 0 P 0 
L 1.24003996 -2.11716004 1.29008002 -2.11716004 0 P 0 
L 1.24015 -2.11616004 1.2901 -2.11616004 0 P 0 
L 1.24023996 -2.11516004 1.29011998 -2.11516004 0 P 0 
L 1.24033002 -2.11416004 1.29013996 -2.11416004 0 P 0 
L 1.24041004 -2.11316004 1.29016004 -2.11316004 0 P 0 
L 1.24048996 -2.11216004 1.29018996 -2.11216004 0 P 0 
L 1.24058002 -2.11116004 1.29021004 -2.11116004 0 P 0 
L 1.24066998 -2.11016004 1.29023002 -2.11016004 0 P 0 
L 1.24075 -2.10916004 1.29025 -2.10916004 0 P 0 
L 1.2408 -2.10816004 1.29026998 -2.10816004 0 P 0 
L 1.24086004 -2.10716004 1.29028996 -2.10716004 0 P 0 
L 1.24091004 -2.10616004 1.29031998 -2.10616004 0 P 0 
L 1.24096998 -2.10516004 1.29033996 -2.10516004 0 P 0 
L 1.24101998 -2.10416004 1.29036004 -2.10416004 0 P 0 
L 1.24108002 -2.10316004 1.29038002 -2.10316004 0 P 0 
L 1.24113002 -2.10216004 1.29041998 -2.10216004 0 P 0 
L 1.24118002 -2.10116004 1.29046998 -2.10116004 0 P 0 
L 1.24123996 -2.10016004 1.29053002 -2.10016004 0 P 0 
L 1.24128996 -2.09916004 1.29058002 -2.09916004 0 P 0 
L 1.24135 -2.09816004 1.29063002 -2.09816004 0 P 0 
L 1.2414 -2.09716004 1.29068002 -2.09716004 0 P 0 
L 1.24146004 -2.09616004 1.29073996 -2.09616004 0 P 0 
L 1.24151004 -2.09516004 1.29078996 -2.09516004 0 P 0 
L 1.24156998 -2.09416004 1.29083996 -2.09416004 0 P 0 
L 1.24161998 -2.09316004 1.2909 -2.09316004 0 P 0 
L 1.24168002 -2.09216004 1.29095 -2.09216004 0 P 0 
L 1.24173002 -2.09116004 1.291 -2.09116004 0 P 0 
L 1.24178996 -2.09016004 1.29105 -2.09016004 0 P 0 
L 1.24183996 -2.08916004 1.2911 -2.08916004 0 P 0 
L 1.2419 -2.08816004 1.29116004 -2.08816004 0 P 0 
L 1.24196004 -2.08716004 1.29121004 -2.08716004 0 P 0 
L 1.24201004 -2.08616004 1.29126998 -2.08616004 0 P 0 
L 1.24206998 -2.08516004 1.29131998 -2.08516004 0 P 0 
L 1.24211998 -2.08416004 1.29136998 -2.08416004 0 P 0 
L 1.2389 -2.12516004 1.2391 -2.12393002 0 P 0 
L 1.2391 -2.12393002 1.2391 -2.1239 0 P 0 
L 1.2391 -2.1239 1.24011004 -2.11665 0 P 0 
L 1.24011004 -2.11665 1.24073002 -2.10935 0 P 0 
L 1.24073002 -2.10935 1.24073996 -2.10931998 0 P 0 
L 1.24073996 -2.10931998 1.24286004 -2.07056004 0 P 0 
L 1.24286004 -2.07056004 1.24461004 -2.03158002 0 P 0 
L 1.24461004 -2.03158002 1.24513996 -2.00523002 0 P 0 
L 1.24513996 -2.00523002 1.24515 -1.99443996 0 P 0 
L 1.24515 -1.99443996 1.29005 -1.99443996 0 P 0 
L 1.29005 -1.99443996 1.29005 -2.00375 0 P 0 
L 1.29005 -2.00375 1.29128002 -2.0056 0 P 0 
L 1.29128002 -2.0056 1.29345 -2.00518002 0 P 0 
L 1.29345 -2.00518002 1.29803002 -2.0007 0 P 0 
L 1.29803002 -2.0007 1.29991998 -1.999 0 P 0 
L 1.29991998 -1.999 1.30188996 -1.99748996 0 P 0 
L 1.30188996 -1.99748996 1.30411998 -1.99603996 0 P 0 
L 1.30411998 -1.99603996 1.30645 -1.99475 0 P 0 
L 1.30645 -1.99475 1.30891998 -1.99358996 0 P 0 
L 1.30891998 -1.99358996 1.31145 -1.9926 0 P 0 
L 1.31145 -1.9926 1.31401998 -1.99181004 0 P 0 
L 1.31401998 -1.99181004 1.31663996 -1.9912 0 P 0 
L 1.31663996 -1.9912 1.31906004 -1.9908 0 P 0 
L 1.31906004 -1.9908 1.32151004 -1.99053002 0 P 0 
L 1.32151004 -1.99053002 1.32761998 -1.99023002 0 P 0 
L 1.32761998 -1.99023002 1.3331 -1.99025 0 P 0 
L 1.3331 -1.99025 1.33345 -1.99608002 0 P 0 
L 1.33345 -1.99608002 1.33381004 -2.00323002 0 P 0 
L 1.33381004 -2.00323002 1.33413002 -2.01158996 0 P 0 
L 1.33413002 -2.01158996 1.33413002 -2.0116 0 P 0 
L 1.33413002 -2.0116 1.33481998 -2.03123002 0 P 0 
L 1.33481998 -2.03123002 1.32853996 -2.0314 0 P 0 
L 1.32853996 -2.0314 1.32398002 -2.03166998 0 P 0 
L 1.32398002 -2.03166998 1.31941998 -2.03225 0 P 0 
L 1.31941998 -2.03225 1.31488996 -2.03313002 0 P 0 
L 1.31488996 -2.03313002 1.31273996 -2.03373002 0 P 0 
L 1.31273996 -2.03373002 1.31063996 -2.0345 0 P 0 
L 1.31063996 -2.0345 1.3086 -2.03545 0 P 0 
L 1.3086 -2.03545 1.30666004 -2.03656998 0 P 0 
L 1.30666004 -2.03656998 1.30658996 -2.03661998 0 P 0 
L 1.30658996 -2.03661998 1.30483002 -2.03786004 0 P 0 
L 1.30483002 -2.03786004 1.30341998 -2.03901004 0 P 0 
L 1.30341998 -2.03901004 1.30336998 -2.03906004 0 P 0 
L 1.30336998 -2.03906004 1.30211998 -2.04026004 0 P 0 
L 1.30211998 -2.04026004 1.30093002 -2.0416 0 P 0 
L 1.30093002 -2.0416 1.29983002 -2.04303996 0 P 0 
L 1.29983002 -2.04303996 1.29978996 -2.0431 0 P 0 
L 1.29978996 -2.0431 1.29885 -2.04453996 0 P 0 
L 1.29885 -2.04453996 1.29798996 -2.04613002 0 P 0 
L 1.29798996 -2.04613002 1.29631998 -2.04986998 0 P 0 
L 1.29631998 -2.04986998 1.29628002 -2.04995 0 P 0 
L 1.29628002 -2.04995 1.29625 -2.05003002 0 P 0 
L 1.29625 -2.05003002 1.29491998 -2.0539 0 P 0 
L 1.29491998 -2.0539 1.29388996 -2.05793996 0 P 0 
L 1.29388996 -2.05793996 1.29386998 -2.05801998 0 P 0 
L 1.29386998 -2.05801998 1.29313996 -2.06221004 0 P 0 
L 1.29313996 -2.06221004 1.29313002 -2.06223996 0 P 0 
L 1.29313002 -2.06223996 1.29311998 -2.0623 0 P 0 
L 1.29311998 -2.0623 1.29265 -2.06655 0 P 0 
L 1.29265 -2.06655 1.29136998 -2.08418996 0 P 0 
L 1.29136998 -2.08418996 1.29038996 -2.10276998 0 P 0 
L 1.29038996 -2.10276998 1.29006998 -2.11763002 0 P 0 
L 1.29006998 -2.11763002 1.29006004 -2.12516004 0 P 0 
L 1.29006004 -2.12516004 1.2389 -2.12516004 0 P 0 
L 1.09846998 -2.00483002 1.21248002 -2.00483002 0 P 0 
L 1.09838002 -2.12083002 1.14708002 -2.12083002 0 P 0 
L 1.11933002 -2.18283002 1.15161998 -2.18283002 0 P 0 
L 1.11001998 -2.18183002 1.15838002 -2.18183002 0 P 0 
L 1.10246998 -2.18083002 1.16333996 -2.18083002 0 P 0 
L 1.04061004 -1.89731004 1.09978002 -1.89731004 0 P 0 
L 1.03565 -1.89631004 1.09821004 -1.89631004 0 P 0 
L 1.03068996 -1.89531004 1.09661004 -1.89531004 0 P 0 
L 1.02573002 -1.89431004 1.09475 -1.89431004 0 P 0 
L 1.019 -1.89331004 1.09288002 -1.89331004 0 P 0 
L 1.01163996 -1.89231004 1.09101998 -1.89231004 0 P 0 
L 0.99518996 -1.89131004 1.08916004 -1.89131004 0 P 0 
L 0.87011998 -1.88331004 1.07278996 -1.88331004 0 P 0 
L 0.86963996 -1.88231004 1.07053002 -1.88231004 0 P 0 
L 0.86916004 -1.88131004 1.06828002 -1.88131004 0 P 0 
L 0.86863002 -1.88031004 1.06603002 -1.88031004 0 P 0 
L 0.86806998 -1.87931004 1.06351004 -1.87931004 0 P 0 
L 0.8675 -1.87831004 1.06076998 -1.87831004 0 P 0 
L 0.86693002 -1.87731004 1.05803996 -1.87731004 0 P 0 
L 0.86631004 -1.87631004 1.05531004 -1.87631004 0 P 0 
L 0.86563996 -1.87531004 1.05256998 -1.87531004 0 P 0 
L 0.86498002 -1.87431004 1.04983996 -1.87431004 0 P 0 
L 0.86431998 -1.87331004 1.0471 -1.87331004 0 P 0 
L 0.86356004 -1.87231004 1.04376004 -1.87231004 0 P 0 
L 0.86278996 -1.87131004 1.04041998 -1.87131004 0 P 0 
L 0.86203002 -1.87031004 1.03708002 -1.87031004 0 P 0 
L 0.86118996 -1.86931004 1.03373996 -1.86931004 0 P 0 
L 0.8603 -1.86831004 1.0304 -1.86831004 0 P 0 
L 0.85941004 -1.86731004 1.02656998 -1.86731004 0 P 0 
L 0.8585 -1.86631004 1.02231998 -1.86631004 0 P 0 
L 0.85756998 -1.86531004 1.01806998 -1.86531004 0 P 0 
L 0.85663002 -1.86431004 1.01381998 -1.86431004 0 P 0 
L 0.85568996 -1.86331004 1.00931998 -1.86331004 0 P 0 
L 0.85481004 -1.86231004 1.00335 -1.86231004 0 P 0 
L 0.85916998 -1.86131004 0.99738002 -1.86131004 0 P 0 
L 0.86716998 -1.86031004 0.99141998 -1.86031004 0 P 0 
L 0.87476998 -1.89731004 0.89943002 -1.89731004 0 P 0 
L 0.87453996 -1.89631004 0.90426004 -1.89631004 0 P 0 
L 0.87431004 -1.89531004 0.9097 -1.89531004 0 P 0 
L 0.87406998 -1.89431004 0.91608002 -1.89431004 0 P 0 
L 0.87383002 -1.89331004 0.92246004 -1.89331004 0 P 0 
L 0.87355 -1.89231004 0.93086004 -1.89231004 0 P 0 
L 0.87323002 -1.89131004 0.95553002 -1.89131004 0 P 0 
L 0.87291004 -1.89031004 1.08728996 -1.89031004 0 P 0 
L 0.87258996 -1.88931004 1.08543002 -1.88931004 0 P 0 
L 0.87223002 -1.88831004 1.08356998 -1.88831004 0 P 0 
L 0.87183002 -1.88731004 1.0817 -1.88731004 0 P 0 
L 0.87143002 -1.88631004 1.07955 -1.88631004 0 P 0 
L 0.87103002 -1.88531004 1.07728996 -1.88531004 0 P 0 
L 0.8706 -1.88431004 1.07503996 -1.88431004 0 P 0 
L 0.87525 -1.85931004 0.98545 -1.85931004 0 P 0 
L 0.88421004 -1.85831004 0.97621004 -1.85831004 0 P 0 
L 0.89393002 -1.85731004 0.96606998 -1.85731004 0 P 0 
L 0.9106 -1.85631004 0.95203002 -1.85631004 0 P 0 
L 1.08716004 -1.91231004 1.12151004 -1.91231004 0 P 0 
L 1.08486004 -1.91131004 1.12018996 -1.91131004 0 P 0 
L 1.08256004 -1.91031004 1.11886004 -1.91031004 0 P 0 
L 1.08023002 -1.90931004 1.11753996 -1.90931004 0 P 0 
L 1.07738002 -1.90831004 1.11621004 -1.90831004 0 P 0 
L 1.07453002 -1.90731004 1.11488996 -1.90731004 0 P 0 
L 1.07168996 -1.90631004 1.11356998 -1.90631004 0 P 0 
L 1.06883996 -1.90531004 1.11223996 -1.90531004 0 P 0 
L 1.066 -1.90431004 1.11076998 -1.90431004 0 P 0 
L 1.06315 -1.90331004 1.1092 -1.90331004 0 P 0 
L 1.0599 -1.90231004 1.10763002 -1.90231004 0 P 0 
L 1.05611998 -1.90131004 1.10606004 -1.90131004 0 P 0 
L 1.05235 -1.90031004 1.10448996 -1.90031004 0 P 0 
L 1.04856998 -1.89931004 1.10291998 -1.89931004 0 P 0 
L 1.04478996 -1.89831004 1.10135 -1.89831004 0 P 0 
L 0.98815 -2.08316004 1.03726998 -2.08316004 0 P 0 
L 0.98818002 -2.08216004 1.03731004 -2.08216004 0 P 0 
L 0.98821998 -2.08116004 1.03735 -2.08116004 0 P 0 
L 0.98825 -2.08016004 1.03738996 -2.08016004 0 P 0 
L 0.98828002 -2.07916004 1.03743002 -2.07916004 0 P 0 
L 0.98831998 -2.07816004 1.03746998 -2.07816004 0 P 0 
L 0.98835 -2.07716004 1.03751004 -2.07716004 0 P 0 
L 0.98838002 -2.07616004 1.03755 -2.07616004 0 P 0 
L 0.98841998 -2.07516004 1.03758002 -2.07516004 0 P 0 
L 0.98845 -2.07416004 1.03761004 -2.07416004 0 P 0 
L 0.98848002 -2.07316004 1.03763996 -2.07316004 0 P 0 
L 0.98851004 -2.07216004 1.03768002 -2.07216004 0 P 0 
L 0.98855 -2.07116004 1.03771004 -2.07116004 0 P 0 
L 0.98858002 -2.07016004 1.03773996 -2.07016004 0 P 0 
L 0.98858996 -2.06916004 1.03776998 -2.06916004 0 P 0 
L 0.98858996 -2.06816004 1.0378 -2.06816004 0 P 0 
L 0.98858996 -2.06716004 1.03783002 -2.06716004 0 P 0 
L 0.98858002 -2.06616004 1.03786004 -2.06616004 0 P 0 
L 0.98856998 -2.06516004 1.0379 -2.06516004 0 P 0 
L 0.98856998 -2.06416004 1.03793002 -2.06416004 0 P 0 
L 0.98856998 -2.06316004 1.03796004 -2.06316004 0 P 0 
L 0.98856004 -2.06216004 1.03798996 -2.06216004 0 P 0 
L 0.98855 -2.06116004 1.03801998 -2.06116004 0 P 0 
L 0.98855 -2.06016004 1.03805 -2.06016004 0 P 0 
L 0.98853996 -2.05916004 1.03808002 -2.05916004 0 P 0 
L 0.98853996 -2.05816004 1.0381 -2.05816004 0 P 0 
L 0.98853002 -2.05716004 1.03811998 -2.05716004 0 P 0 
L 0.98848002 -2.05616004 1.03815 -2.05616004 0 P 0 
L 0.98841004 -2.05516004 1.03818002 -2.05516004 0 P 0 
L 0.98835 -2.05416004 1.0382 -2.05416004 0 P 0 
L 0.98828002 -2.05316004 1.03821998 -2.05316004 0 P 0 
L 0.98821004 -2.05216004 1.03825 -2.05216004 0 P 0 
L 0.98815 -2.05116004 1.03826998 -2.05116004 0 P 0 
L 0.98808996 -2.05016004 1.03828996 -2.05016004 0 P 0 
L 0.98801998 -2.04916004 1.03831998 -2.04916004 0 P 0 
L 0.98796004 -2.04816004 1.03833996 -2.04816004 0 P 0 
L 0.98788996 -2.04716004 1.03836004 -2.04716004 0 P 0 
L 0.98783002 -2.04616004 1.03838996 -2.04616004 0 P 0 
L 0.98768996 -2.04516004 1.0384 -2.04516004 0 P 0 
L 0.98756004 -2.04416004 1.03841004 -2.04416004 0 P 0 
L 0.98738002 -2.04316004 1.03841998 -2.04316004 0 P 0 
L 0.98716004 -2.04216004 1.03843002 -2.04216004 0 P 0 
L 0.98691998 -2.04116004 1.03843996 -2.04116004 0 P 0 
L 0.98661998 -2.04016004 1.03845 -2.04016004 0 P 0 
L 0.98631998 -2.03916004 1.03846004 -2.03916004 0 P 0 
L 0.98593996 -2.03816004 1.03846998 -2.03816004 0 P 0 
L 0.98546998 -2.03716004 1.03848002 -2.03716004 0 P 0 
L 0.98491004 -2.03616004 1.03846998 -2.03616004 0 P 0 
L 0.98425 -2.03516004 1.03846004 -2.03516004 0 P 0 
L 0.98346004 -2.03416004 1.03846004 -2.03416004 0 P 0 
L 0.98251998 -2.03316004 1.03843996 -2.03316004 0 P 0 
L 0.98138002 -2.03216004 1.03843002 -2.03216004 0 P 0 
L 0.97998996 -2.03116004 1.03841998 -2.03116004 0 P 0 
L 0.97813996 -2.03016004 1.03841004 -2.03016004 0 P 0 
L 0.97491004 -2.02916004 1.0384 -2.02916004 0 P 0 
L 0.94763996 -2.00716004 1.03293996 -2.00716004 0 P 0 
L 0.94978996 -2.00616004 1.03231998 -2.00616004 0 P 0 
L 0.95081004 -2.00516004 1.0317 -2.00516004 0 P 0 
L 0.95183002 -2.00416004 1.03098002 -2.00416004 0 P 0 
L 0.95285 -2.00316004 1.03023002 -2.00316004 0 P 0 
L 0.95388996 -2.00216004 1.02936004 -2.00216004 0 P 0 
L 0.95498002 -2.00116004 1.02841998 -2.00116004 0 P 0 
L 0.95621998 -2.00016004 1.02738996 -2.00016004 0 P 0 
L 0.95761998 -1.99916004 1.0262 -1.99916004 0 P 0 
L 0.9592 -1.99816004 1.02486004 -1.99816004 0 P 0 
L 0.96083996 -1.99716004 1.02335 -1.99716004 0 P 0 
L 0.9627 -1.99616004 1.02161004 -1.99616004 0 P 0 
L 0.96468996 -1.99516004 1.01951998 -1.99516004 0 P 0 
L 0.96685 -1.99416004 1.01683002 -1.99416004 0 P 0 
L 0.96936998 -1.99316004 1.01378002 -1.99316004 0 P 0 
L 0.97236998 -1.99216004 1.00981004 -1.99216004 0 P 0 
L 0.97676004 -1.99116004 1.00456998 -1.99116004 0 P 0 
L 1.06713996 -2.08283002 1.12288002 -2.08283002 0 P 0 
L 1.06698996 -2.08183002 1.12193996 -2.08183002 0 P 0 
L 1.06686004 -2.08083002 1.12108996 -2.08083002 0 P 0 
L 1.06673996 -2.07983002 1.12036004 -2.07983002 0 P 0 
L 1.06661998 -2.07883002 1.11971998 -2.07883002 0 P 0 
L 1.06653002 -2.07783002 1.11916004 -2.07783002 0 P 0 
L 1.06648002 -2.07683002 1.11866004 -2.07683002 0 P 0 
L 1.06641998 -2.07583002 1.11826004 -2.07583002 0 P 0 
L 1.06636998 -2.07483002 1.11791998 -2.07483002 0 P 0 
L 1.06631998 -2.07383002 1.11761998 -2.07383002 0 P 0 
L 1.06626004 -2.07283002 1.11741998 -2.07283002 0 P 0 
L 1.06621004 -2.07183002 1.11723996 -2.07183002 0 P 0 
L 1.06616004 -2.07083002 1.11711998 -2.07083002 0 P 0 
L 1.06616004 -2.06983002 1.11701004 -2.06983002 0 P 0 
L 1.06616004 -2.06883002 1.11688996 -2.06883002 0 P 0 
L 1.06616998 -2.06783002 1.11676998 -2.06783002 0 P 0 
L 1.06618002 -2.06683002 1.11666998 -2.06683002 0 P 0 
L 1.06618996 -2.06583002 1.11663002 -2.06583002 0 P 0 
L 1.0662 -2.06483002 1.11658996 -2.06483002 0 P 0 
L 1.06621004 -2.06383002 1.11656004 -2.06383002 0 P 0 
L 1.06623002 -2.06283002 1.11651998 -2.06283002 0 P 0 
L 1.06631004 -2.06183002 1.11648996 -2.06183002 0 P 0 
L 1.06638002 -2.06083002 1.11653002 -2.06083002 0 P 0 
L 1.06645 -2.05983002 1.11656998 -2.05983002 0 P 0 
L 1.06651998 -2.05883002 1.11661998 -2.05883002 0 P 0 
L 1.06658996 -2.05783002 1.11666004 -2.05783002 0 P 0 
L 1.06666998 -2.05683002 1.11671004 -2.05683002 0 P 0 
L 1.06673996 -2.05583002 1.11681004 -2.05583002 0 P 0 
L 1.06686004 -2.05483002 1.11693002 -2.05483002 0 P 0 
L 1.067 -2.05383002 1.11705 -2.05383002 0 P 0 
L 1.06713996 -2.05283002 1.11718002 -2.05283002 0 P 0 
L 1.06728002 -2.05183002 1.11731004 -2.05183002 0 P 0 
L 1.06741998 -2.05083002 1.11746004 -2.05083002 0 P 0 
L 1.06756004 -2.04983002 1.11766004 -2.04983002 0 P 0 
L 1.0677 -2.04883002 1.11786004 -2.04883002 0 P 0 
L 1.06786004 -2.04783002 1.11813996 -2.04783002 0 P 0 
L 1.06806998 -2.04683002 1.11841998 -2.04683002 0 P 0 
L 1.06828002 -2.04583002 1.11876998 -2.04583002 0 P 0 
L 1.06848996 -2.04483002 1.11913002 -2.04483002 0 P 0 
L 1.06871004 -2.04383002 1.11955 -2.04383002 0 P 0 
L 1.06898996 -2.04283002 1.11998996 -2.04283002 0 P 0 
L 1.06928002 -2.04183002 1.12048002 -2.04183002 0 P 0 
L 1.06956004 -2.04083002 1.12101004 -2.04083002 0 P 0 
L 1.06985 -2.03983002 1.12161998 -2.03983002 0 P 0 
L 1.07021004 -2.03883002 1.12225 -2.03883002 0 P 0 
L 1.07056998 -2.03783002 1.12298002 -2.03783002 0 P 0 
L 1.07093002 -2.03683002 1.12373996 -2.03683002 0 P 0 
L 1.07128996 -2.03583002 1.12461998 -2.03583002 0 P 0 
L 1.07173002 -2.03483002 1.12548996 -2.03483002 0 P 0 
L 1.07216998 -2.03383002 1.12646004 -2.03383002 0 P 0 
L 1.07261998 -2.03283002 1.12748996 -2.03283002 0 P 0 
L 1.07308002 -2.03183002 1.12855 -2.03183002 0 P 0 
L 1.07361998 -2.03083002 1.12978996 -2.03083002 0 P 0 
L 1.09761004 -1.91731004 1.12756998 -1.91731004 0 P 0 
L 1.09566004 -1.91631004 1.12645 -1.91631004 0 P 0 
L 1.09371004 -1.91531004 1.12533002 -1.91531004 0 P 0 
L 1.09176004 -1.91431004 1.12416004 -1.91431004 0 P 0 
L 1.08946004 -1.91331004 1.12283996 -1.91331004 0 P 0 
L 1.07415 -2.02983002 1.13101998 -2.02983002 0 P 0 
L 1.07468996 -2.02883002 1.13248996 -2.02883002 0 P 0 
L 1.07528996 -2.02783002 1.134 -2.02783002 0 P 0 
L 1.07591998 -2.02683002 1.13586004 -2.02683002 0 P 0 
L 1.07656004 -2.02583002 1.13828996 -2.02583002 0 P 0 
L 1.07721004 -2.02483002 1.14243002 -2.02483002 0 P 0 
L 1.07795 -2.02383002 1.21126998 -2.02383002 0 P 0 
L 1.07868002 -2.02283002 1.21133002 -2.02283002 0 P 0 
L 1.07941998 -2.02183002 1.2114 -2.02183002 0 P 0 
L 1.08021004 -2.02083002 1.21146004 -2.02083002 0 P 0 
L 1.08103996 -2.01983002 1.21153002 -2.01983002 0 P 0 
L 1.08186998 -2.01883002 1.2116 -2.01883002 0 P 0 
L 1.08273002 -2.01783002 1.21166004 -2.01783002 0 P 0 
L 1.08366998 -2.01683002 1.21173002 -2.01683002 0 P 0 
L 1.0846 -2.01583002 1.2118 -2.01583002 0 P 0 
L 1.08555 -2.01483002 1.21186004 -2.01483002 0 P 0 
L 1.08661004 -2.01383002 1.21193002 -2.01383002 0 P 0 
L 1.08766998 -2.01283002 1.21198996 -2.01283002 0 P 0 
L 1.08873002 -2.01183002 1.21205 -2.01183002 0 P 0 
L 1.0898 -2.01083002 1.21211998 -2.01083002 0 P 0 
L 1.09098996 -2.00983002 1.21218002 -2.00983002 0 P 0 
L 1.09225 -2.00883002 1.21223996 -2.00883002 0 P 0 
L 1.09358996 -2.00783002 1.2123 -2.00783002 0 P 0 
L 1.09506998 -2.00683002 1.21236004 -2.00683002 0 P 0 
L 1.09668996 -2.00583002 1.21241998 -2.00583002 0 P 0 
L 0.98546998 -2.12516004 1.03548996 -2.12516004 0 P 0 
L 0.98558996 -2.12416004 1.03553996 -2.12416004 0 P 0 
L 0.9857 -2.12316004 1.03558002 -2.12316004 0 P 0 
L 0.98581004 -2.12216004 1.03561998 -2.12216004 0 P 0 
L 0.98591004 -2.12116004 1.03566998 -2.12116004 0 P 0 
L 0.98598996 -2.12016004 1.03571004 -2.12016004 0 P 0 
L 0.98608002 -2.11916004 1.03575 -2.11916004 0 P 0 
L 0.98616998 -2.11816004 1.0358 -2.11816004 0 P 0 
L 0.98625 -2.11716004 1.03583996 -2.11716004 0 P 0 
L 0.98633996 -2.11616004 1.03588002 -2.11616004 0 P 0 
L 0.98641998 -2.11516004 1.03593002 -2.11516004 0 P 0 
L 0.98651004 -2.11416004 1.03596998 -2.11416004 0 P 0 
L 0.9866 -2.11316004 1.03601004 -2.11316004 0 P 0 
L 0.98668002 -2.11216004 1.03605 -2.11216004 0 P 0 
L 0.98676998 -2.11116004 1.0361 -2.11116004 0 P 0 
L 0.98685 -2.11016004 1.03613996 -2.11016004 0 P 0 
L 0.98693996 -2.10916004 1.03618002 -2.10916004 0 P 0 
L 0.987 -2.10816004 1.03623002 -2.10816004 0 P 0 
L 0.98705 -2.10716004 1.03626998 -2.10716004 0 P 0 
L 0.9871 -2.10616004 1.03631004 -2.10616004 0 P 0 
L 0.98716004 -2.10516004 1.03636004 -2.10516004 0 P 0 
L 0.9872 -2.10416004 1.0364 -2.10416004 0 P 0 
L 0.98725 -2.10316004 1.03643996 -2.10316004 0 P 0 
L 0.98731004 -2.10216004 1.03648002 -2.10216004 0 P 0 
L 0.98735 -2.10116004 1.03653002 -2.10116004 0 P 0 
L 0.9874 -2.10016004 1.03656998 -2.10016004 0 P 0 
L 0.98746004 -2.09916004 1.03661004 -2.09916004 0 P 0 
L 0.98751004 -2.09816004 1.03666004 -2.09816004 0 P 0 
L 0.98755 -2.09716004 1.0367 -2.09716004 0 P 0 
L 0.9876 -2.09616004 1.03673996 -2.09616004 0 P 0 
L 0.98766004 -2.09516004 1.03678996 -2.09516004 0 P 0 
L 0.9877 -2.09416004 1.03683002 -2.09416004 0 P 0 
L 0.98775 -2.09316004 1.03686998 -2.09316004 0 P 0 
L 0.98781004 -2.09216004 1.03691998 -2.09216004 0 P 0 
L 0.98785 -2.09116004 1.03696004 -2.09116004 0 P 0 
L 0.9879 -2.09016004 1.037 -2.09016004 0 P 0 
L 0.98796004 -2.08916004 1.03703996 -2.08916004 0 P 0 
L 0.98798996 -2.08816004 1.03706998 -2.08816004 0 P 0 
L 0.98801998 -2.08716004 1.03711004 -2.08716004 0 P 0 
L 0.98805 -2.08616004 1.03715 -2.08616004 0 P 0 
L 0.98808996 -2.08516004 1.03718996 -2.08516004 0 P 0 
L 0.98811998 -2.08416004 1.03723002 -2.08416004 0 P 0 
L 1.08216998 -2.15683002 1.19803996 -2.15683002 0 P 0 
L 1.0821 -2.15583002 1.19861004 -2.15583002 0 P 0 
L 1.08201998 -2.15483002 1.19918002 -2.15483002 0 P 0 
L 1.08195 -2.15383002 1.1997 -2.15383002 0 P 0 
L 1.08188996 -2.15283002 1.20018002 -2.15283002 0 P 0 
L 1.08183002 -2.15183002 1.20066004 -2.15183002 0 P 0 
L 1.08176998 -2.15083002 1.20113996 -2.15083002 0 P 0 
L 1.08171998 -2.14983002 1.20153996 -2.14983002 0 P 0 
L 1.08166004 -2.14883002 1.20193002 -2.14883002 0 P 0 
L 1.0816 -2.14783002 1.11538996 -2.14783002 0 P 0 
L 1.08155 -2.14683002 1.10903002 -2.14683002 0 P 0 
L 1.0815 -2.14583002 1.10415 -2.14583002 0 P 0 
L 1.08146004 -2.14483002 1.09953002 -2.14483002 0 P 0 
L 1.08141004 -2.14383002 1.09563996 -2.14383002 0 P 0 
L 1.08136004 -2.14283002 1.09183996 -2.14283002 0 P 0 
L 1.08131004 -2.14183002 1.08821004 -2.14183002 0 P 0 
L 1.08133002 -2.14083002 1.08471998 -2.14083002 0 P 0 
L 1.09586998 -2.11983002 1.14965 -2.11983002 0 P 0 
L 1.09361998 -2.11883002 1.15221998 -2.11883002 0 P 0 
L 1.09158996 -2.11783002 1.20595 -2.11783002 0 P 0 
L 1.08988002 -2.11683002 1.20601004 -2.11683002 0 P 0 
L 1.08823996 -2.11583002 1.20606998 -2.11583002 0 P 0 
L 1.08678996 -2.11483002 1.20613002 -2.11483002 0 P 0 
L 1.08541004 -2.11383002 1.20618996 -2.11383002 0 P 0 
L 1.08416998 -2.11283002 1.20625 -2.11283002 0 P 0 
L 1.08295 -2.11183002 1.20631004 -2.11183002 0 P 0 
L 1.08188002 -2.11083002 1.20638002 -2.11083002 0 P 0 
L 1.08081998 -2.10983002 1.20643996 -2.10983002 0 P 0 
L 1.07986004 -2.10883002 1.2065 -2.10883002 0 P 0 
L 1.07895 -2.10783002 1.20656004 -2.10783002 0 P 0 
L 1.07803002 -2.10683002 1.20661998 -2.10683002 0 P 0 
L 1.07723996 -2.10583002 1.20666998 -2.10583002 0 P 0 
L 1.07646004 -2.10483002 1.20671998 -2.10483002 0 P 0 
L 1.07568002 -2.10383002 1.20678002 -2.10383002 0 P 0 
L 1.075 -2.10283002 1.20683002 -2.10283002 0 P 0 
L 1.07433002 -2.10183002 1.20688002 -2.10183002 0 P 0 
L 1.07366998 -2.10083002 1.20693996 -2.10083002 0 P 0 
L 1.07308996 -2.09983002 1.20698996 -2.09983002 0 P 0 
L 1.07253002 -2.09883002 1.20705 -2.09883002 0 P 0 
L 1.07198002 -2.09783002 1.2071 -2.09783002 0 P 0 
L 1.07146998 -2.09683002 1.20715 -2.09683002 0 P 0 
L 1.07101998 -2.09583002 1.2072 -2.09583002 0 P 0 
L 1.07056998 -2.09483002 1.20726004 -2.09483002 0 P 0 
L 1.07013002 -2.09383002 1.20731004 -2.09383002 0 P 0 
L 1.06976998 -2.09283002 1.20736004 -2.09283002 0 P 0 
L 1.06941998 -2.09183002 1.20741998 -2.09183002 0 P 0 
L 1.06906004 -2.09083002 1.20746998 -2.09083002 0 P 0 
L 1.06876004 -2.08983002 1.20753002 -2.08983002 0 P 0 
L 1.06848996 -2.08883002 1.13443002 -2.08883002 0 P 0 
L 1.06821998 -2.08783002 1.13068002 -2.08783002 0 P 0 
L 1.06795 -2.08683002 1.12836998 -2.08683002 0 P 0 
L 1.06771998 -2.08583002 1.1266 -2.08583002 0 P 0 
L 1.06753002 -2.08483002 1.12516004 -2.08483002 0 P 0 
L 1.06733002 -2.08383002 1.12393996 -2.08383002 0 P 0 
L 0.90273996 -1.85456998 0.89068996 -1.85558002 0 P 0 
L 0.89068996 -1.85558002 0.87421004 -1.85741998 0 P 0 
L 0.87421004 -1.85741998 0.85783002 -1.85946998 0 P 0 
L 0.85783002 -1.85946998 0.85526998 -1.8599 0 P 0 
L 0.85526998 -1.8599 0.85276004 -1.86055 0 P 0 
L 0.85276004 -1.86055 0.85255 -1.86063996 0 P 0 
L 0.85255 -1.86063996 0.85248996 -1.86068996 0 P 0 
L 0.85248996 -1.86068996 0.85243002 -1.86073002 0 P 0 
L 0.85243002 -1.86073002 0.85238002 -1.86078002 0 P 0 
L 0.85238002 -1.86078002 0.85233002 -1.86083996 0 P 0 
L 0.85233002 -1.86083996 0.85225 -1.86096004 0 P 0 
L 0.85225 -1.86096004 0.85218002 -1.8611 0 P 0 
L 0.85218002 -1.8611 0.85216004 -1.86116998 0 P 0 
L 0.85216004 -1.86116998 0.85215 -1.86123996 0 P 0 
L 0.85215 -1.86123996 0.85213996 -1.86136998 0 P 0 
L 0.85213996 -1.86136998 0.85213002 -1.86148996 0 P 0 
L 0.85213002 -1.86148996 0.85213996 -1.86161998 0 P 0 
L 0.85213996 -1.86161998 0.85215 -1.86173996 0 P 0 
L 0.85215 -1.86173996 0.85218002 -1.86186998 0 P 0 
L 0.85218002 -1.86186998 0.85221004 -1.86198996 0 P 0 
L 0.85221004 -1.86198996 0.85225 -1.8621 0 P 0 
L 0.85225 -1.8621 0.85231004 -1.86221998 0 P 0 
L 0.85231004 -1.86221998 0.85236998 -1.86233002 0 P 0 
L 0.85236998 -1.86233002 0.85281998 -1.863 0 P 0 
L 0.85281998 -1.863 0.8533 -1.86363996 0 P 0 
L 0.8533 -1.86363996 0.85383002 -1.86425 0 P 0 
L 0.85383002 -1.86425 0.85736004 -1.86801998 0 P 0 
L 0.85736004 -1.86801998 0.86013002 -1.87113002 0 P 0 
L 0.86013002 -1.87113002 0.86266004 -1.87443002 0 P 0 
L 0.86266004 -1.87443002 0.86501004 -1.87798996 0 P 0 
L 0.86501004 -1.87798996 0.86711998 -1.88171004 0 P 0 
L 0.86711998 -1.88171004 0.86896998 -1.88553996 0 P 0 
L 0.86896998 -1.88553996 0.87055 -1.8895 0 P 0 
L 0.87055 -1.8895 0.8718 -1.89343002 0 P 0 
L 0.8718 -1.89343002 0.87276004 -1.89745 0 P 0 
L 0.87276004 -1.89745 0.87371004 -1.90195 0 P 0 
L 0.87371004 -1.90195 0.87383002 -1.90236004 0 P 0 
L 0.87383002 -1.90236004 0.87396998 -1.90276004 0 P 0 
L 0.87396998 -1.90276004 0.87416004 -1.90313996 0 P 0 
L 0.87416004 -1.90313996 0.87436998 -1.90351004 0 P 0 
L 0.87436998 -1.90351004 0.87443002 -1.9036 0 P 0 
L 0.87443002 -1.9036 0.87456998 -1.90376004 0 P 0 
L 0.87456998 -1.90376004 0.87465 -1.90381998 0 P 0 
L 0.87465 -1.90381998 0.87473002 -1.90388996 0 P 0 
L 0.87473002 -1.90388996 0.87481998 -1.90393996 0 P 0 
L 0.87481998 -1.90393996 0.87491998 -1.90398996 0 P 0 
L 0.87491998 -1.90398996 0.87501004 -1.90403002 0 P 0 
L 0.87501004 -1.90403002 0.87521004 -1.90408996 0 P 0 
L 0.87521004 -1.90408996 0.87531998 -1.9041 0 P 0 
L 0.87531998 -1.9041 0.87573002 -1.90413002 0 P 0 
L 0.87573002 -1.90413002 0.87613996 -1.90411998 0 P 0 
L 0.87613996 -1.90411998 0.87653996 -1.90408002 0 P 0 
L 0.87653996 -1.90408002 0.87695 -1.90401004 0 P 0 
L 0.87695 -1.90401004 0.90756004 -1.89766998 0 P 0 
L 0.90756004 -1.89766998 0.92603996 -1.89478002 0 P 0 
L 0.92603996 -1.89478002 0.93486004 -1.89393996 0 P 0 
L 0.93486004 -1.89393996 0.94371004 -1.8935 0 P 0 
L 0.94371004 -1.8935 0.97045 -1.89308002 0 P 0 
L 0.97045 -1.89308002 0.99468996 -1.89328996 0 P 0 
L 0.99468996 -1.89328996 1.01021004 -1.89413996 0 P 0 
L 1.01021004 -1.89413996 1.0241 -1.89601998 0 P 0 
L 1.0241 -1.89601998 1.04188002 -1.89961004 0 P 0 
L 1.04188002 -1.89961004 1.06095 -1.90466004 0 P 0 
L 1.06095 -1.90466004 1.07963996 -1.91123002 0 P 0 
L 1.07963996 -1.91123002 1.09093996 -1.91613002 0 P 0 
L 1.09093996 -1.91613002 1.10186998 -1.92175 0 P 0 
L 1.10186998 -1.92175 1.11243996 -1.92806998 0 P 0 
L 1.11243996 -1.92806998 1.12163002 -1.93446998 0 P 0 
L 1.12163002 -1.93446998 1.13033002 -1.94148996 0 P 0 
L 1.13033002 -1.94148996 1.1385 -1.94911004 0 P 0 
L 1.1385 -1.94911004 1.14358996 -1.9546 0 P 0 
L 1.14358996 -1.9546 1.14825 -1.96045 0 P 0 
L 1.14825 -1.96045 1.15246998 -1.96663002 0 P 0 
L 1.15246998 -1.96663002 1.15623002 -1.97316004 0 P 0 
L 1.15623002 -1.97316004 1.15895 -1.97831004 0 P 0 
L 1.15895 -1.97831004 1.17358996 -1.97831004 0 P 0 
L 1.17358996 -1.97831004 1.17135 -1.9726 0 P 0 
L 1.17135 -1.9726 1.16696004 -1.96266998 0 P 0 
L 1.16696004 -1.96266998 1.16171998 -1.95313002 0 P 0 
L 1.16171998 -1.95313002 1.1557 -1.94406998 0 P 0 
L 1.1557 -1.94406998 1.14885 -1.93548002 0 P 0 
L 1.14885 -1.93548002 1.13778996 -1.92378002 0 P 0 
L 1.13778996 -1.92378002 1.12576998 -1.91301998 0 P 0 
L 1.12576998 -1.91301998 1.11283996 -1.90326004 0 P 0 
L 1.11283996 -1.90326004 1.09783002 -1.89368996 0 P 0 
L 1.09783002 -1.89368996 1.08213002 -1.88526998 0 P 0 
L 1.08213002 -1.88526998 1.06576998 -1.87801004 0 P 0 
L 1.06576998 -1.87801004 1.04776004 -1.87141998 0 P 0 
L 1.04776004 -1.87141998 1.02938002 -1.86591998 0 P 0 
L 1.02938002 -1.86591998 1.01058002 -1.8615 0 P 0 
L 1.01058002 -1.8615 0.98441998 -1.85711004 0 P 0 
L 0.98441998 -1.85711004 0.95781004 -1.85448996 0 P 0 
L 0.95781004 -1.85448996 0.93061004 -1.85366004 0 P 0 
L 0.93061004 -1.85366004 0.90273996 -1.85456998 0 P 0 
L 1.16015 -1.97631004 1.15798002 -1.97218996 0 P 0 
L 1.15798002 -1.97218996 1.15796004 -1.97216004 0 P 0 
L 1.15796004 -1.97216004 1.15416004 -1.96556998 0 P 0 
L 1.15416004 -1.96556998 1.15411998 -1.96551004 0 P 0 
L 1.15411998 -1.96551004 1.14986004 -1.95926004 0 P 0 
L 1.14986004 -1.95926004 1.14981998 -1.95921004 0 P 0 
L 1.14981998 -1.95921004 1.14511004 -1.9533 0 P 0 
L 1.14511004 -1.9533 1.13991998 -1.9477 0 P 0 
L 1.13991998 -1.9477 1.13986004 -1.94765 0 P 0 
L 1.13986004 -1.94765 1.13163996 -1.93998002 0 P 0 
L 1.13163996 -1.93998002 1.12283002 -1.93286004 0 P 0 
L 1.12283002 -1.93286004 1.11351998 -1.92638996 0 P 0 
L 1.11351998 -1.92638996 1.10283996 -1.92 0 P 0 
L 1.10283996 -1.92 1.0918 -1.91433002 0 P 0 
L 1.0918 -1.91433002 1.08036998 -1.90936004 0 P 0 
L 1.08036998 -1.90936004 1.06153002 -1.90273996 0 P 0 
L 1.06153002 -1.90273996 1.06146004 -1.90273002 0 P 0 
L 1.06146004 -1.90273002 1.04233002 -1.89766004 0 P 0 
L 1.04233002 -1.89766004 1.02443002 -1.89405 0 P 0 
L 1.02443002 -1.89405 1.0104 -1.89213996 0 P 0 
L 1.0104 -1.89213996 0.99475 -1.89128996 0 P 0 
L 0.99475 -1.89128996 0.97045 -1.89108002 0 P 0 
L 0.97045 -1.89108002 0.94365 -1.8915 0 P 0 
L 0.94365 -1.8915 0.94361998 -1.8915 0 P 0 
L 0.94361998 -1.8915 0.93471998 -1.89195 0 P 0 
L 0.93471998 -1.89195 0.92578996 -1.89278996 0 P 0 
L 0.92578996 -1.89278996 0.9072 -1.89571004 0 P 0 
L 0.9072 -1.89571004 0.87656998 -1.90203996 0 P 0 
L 0.87656998 -1.90203996 0.87626998 -1.9021 0 P 0 
L 0.87626998 -1.9021 0.87601998 -1.90211998 0 P 0 
L 0.87601998 -1.90211998 0.87588996 -1.90213002 0 P 0 
L 0.87588996 -1.90213002 0.87583002 -1.90198996 0 P 0 
L 0.87583002 -1.90198996 0.87573002 -1.90175 0 P 0 
L 0.87573002 -1.90175 0.87566004 -1.90146998 0 P 0 
L 0.87566004 -1.90146998 0.87471004 -1.89701004 0 P 0 
L 0.87471004 -1.89701004 0.8747 -1.89698996 0 P 0 
L 0.8747 -1.89698996 0.87373002 -1.89288996 0 P 0 
L 0.87373002 -1.89288996 0.87243002 -1.88881998 0 P 0 
L 0.87243002 -1.88881998 0.8724 -1.88876004 0 P 0 
L 0.8724 -1.88876004 0.8708 -1.88473996 0 P 0 
L 0.8708 -1.88473996 0.8689 -1.88078002 0 P 0 
L 0.8689 -1.88078002 0.86671998 -1.87693996 0 P 0 
L 0.86671998 -1.87693996 0.86428996 -1.87326004 0 P 0 
L 0.86428996 -1.87326004 0.86166998 -1.86985 0 P 0 
L 0.86166998 -1.86985 0.85883996 -1.86668002 0 P 0 
L 0.85883996 -1.86668002 0.85883002 -1.86666004 0 P 0 
L 0.85883002 -1.86666004 0.85531998 -1.86291004 0 P 0 
L 0.85531998 -1.86291004 0.85486004 -1.86238002 0 P 0 
L 0.85486004 -1.86238002 0.85466004 -1.86211998 0 P 0 
L 0.85466004 -1.86211998 0.8557 -1.86186004 0 P 0 
L 0.8557 -1.86186004 0.85811998 -1.86145 0 P 0 
L 0.85811998 -1.86145 0.87443996 -1.85941004 0 P 0 
L 0.87443996 -1.85941004 0.89088996 -1.85756998 0 P 0 
L 0.89088996 -1.85756998 0.90286004 -1.85656998 0 P 0 
L 0.90286004 -1.85656998 0.93061004 -1.85566004 0 P 0 
L 0.93061004 -1.85566004 0.95768002 -1.85648996 0 P 0 
L 0.95768002 -1.85648996 0.98416004 -1.8591 0 P 0 
L 0.98416004 -1.8591 1.01018996 -1.86346004 0 P 0 
L 1.01018996 -1.86346004 1.02886004 -1.86785 0 P 0 
L 1.02886004 -1.86785 1.04711998 -1.87331998 0 P 0 
L 1.04711998 -1.87331998 1.06501004 -1.87986004 0 P 0 
L 1.06501004 -1.87986004 1.08125 -1.88706998 0 P 0 
L 1.08125 -1.88706998 1.09681004 -1.89541998 0 P 0 
L 1.09681004 -1.89541998 1.1117 -1.9049 0 P 0 
L 1.1117 -1.9049 1.1245 -1.91456998 0 P 0 
L 1.1245 -1.91456998 1.13638996 -1.92521004 0 P 0 
L 1.13638996 -1.92521004 1.14733996 -1.93678996 0 P 0 
L 1.14733996 -1.93678996 1.15408002 -1.94525 0 P 0 
L 1.15408002 -1.94525 1.16001004 -1.95416998 0 P 0 
L 1.16001004 -1.95416998 1.16516004 -1.96355 0 P 0 
L 1.16516004 -1.96355 1.1695 -1.97336998 0 P 0 
L 1.1695 -1.97336998 1.17066004 -1.97631004 0 P 0 
L 1.17066004 -1.97631004 1.16015 -1.97631004 0 P 0 
L 0.87563002 -1.90131004 0.8801 -1.90131004 0 P 0 
L 0.87541004 -1.90031004 0.88493996 -1.90031004 0 P 0 
L 0.8752 -1.89931004 0.88976998 -1.89931004 0 P 0 
L 0.87498996 -1.89831004 0.8946 -1.89831004 0 P 0 
L 0.89423002 -2.08316004 0.94355 -2.08316004 0 P 0 
L 0.89428996 -2.08216004 0.9436 -2.08216004 0 P 0 
L 0.89435 -2.08116004 0.94365 -2.08116004 0 P 0 
L 0.89441004 -2.08016004 0.9437 -2.08016004 0 P 0 
L 0.89446004 -2.07916004 0.94375 -2.07916004 0 P 0 
L 0.89451998 -2.07816004 0.94378996 -2.07816004 0 P 0 
L 0.89458002 -2.07716004 0.94383996 -2.07716004 0 P 0 
L 0.89463996 -2.07616004 0.94388996 -2.07616004 0 P 0 
L 0.8947 -2.07516004 0.94393996 -2.07516004 0 P 0 
L 0.89475 -2.07416004 0.94398002 -2.07416004 0 P 0 
L 0.89481004 -2.07316004 0.94403002 -2.07316004 0 P 0 
L 0.89486998 -2.07216004 0.94408002 -2.07216004 0 P 0 
L 0.89493002 -2.07116004 0.94415 -2.07116004 0 P 0 
L 0.89498996 -2.07016004 0.94426004 -2.07016004 0 P 0 
L 0.89505 -2.06916004 0.94436998 -2.06916004 0 P 0 
L 0.8951 -2.06816004 0.94448002 -2.06816004 0 P 0 
L 0.89516004 -2.06716004 0.94458996 -2.06716004 0 P 0 
L 0.89521998 -2.06616004 0.9447 -2.06616004 0 P 0 
L 0.89526998 -2.06516004 0.94481004 -2.06516004 0 P 0 
L 0.89531004 -2.06416004 0.94491998 -2.06416004 0 P 0 
L 0.89535 -2.06316004 0.94503002 -2.06316004 0 P 0 
L 0.8954 -2.06216004 0.94513996 -2.06216004 0 P 0 
L 0.89543996 -2.06116004 0.94531998 -2.06116004 0 P 0 
L 0.89548996 -2.06016004 0.94551004 -2.06016004 0 P 0 
L 0.89553002 -2.05916004 0.9457 -2.05916004 0 P 0 
L 0.89558002 -2.05816004 0.94588996 -2.05816004 0 P 0 
L 0.89561998 -2.05716004 0.94608002 -2.05716004 0 P 0 
L 0.89566998 -2.05616004 0.94626998 -2.05616004 0 P 0 
L 0.89571004 -2.05516004 0.94646998 -2.05516004 0 P 0 
L 0.89575 -2.05416004 0.94666004 -2.05416004 0 P 0 
L 0.8958 -2.05316004 0.94685 -2.05316004 0 P 0 
L 0.89583996 -2.05216004 0.94708002 -2.05216004 0 P 0 
L 0.89588996 -2.05116004 0.94735 -2.05116004 0 P 0 
L 0.89593996 -2.05016004 0.94761998 -2.05016004 0 P 0 
L 0.89598002 -2.04916004 0.9479 -2.04916004 0 P 0 
L 0.89601998 -2.04816004 0.94825 -2.04816004 0 P 0 
L 0.89606998 -2.04716004 0.94858996 -2.04716004 0 P 0 
L 0.89611004 -2.04616004 0.94893002 -2.04616004 0 P 0 
L 0.89616004 -2.04516004 0.94935 -2.04516004 0 P 0 
L 0.8962 -2.04416004 0.94976998 -2.04416004 0 P 0 
L 0.89625 -2.04316004 0.9502 -2.04316004 0 P 0 
L 0.89628002 -2.04216004 0.95068996 -2.04216004 0 P 0 
L 0.89631004 -2.04116004 0.95118996 -2.04116004 0 P 0 
L 0.89633996 -2.04016004 0.95168996 -2.04016004 0 P 0 
L 0.89638002 -2.03916004 0.95228002 -2.03916004 0 P 0 
L 0.89641004 -2.03816004 0.95291004 -2.03816004 0 P 0 
L 0.89643996 -2.03716004 0.95363002 -2.03716004 0 P 0 
L 0.89646998 -2.03616004 0.95445 -2.03616004 0 P 0 
L 0.89651004 -2.03516004 0.95535 -2.03516004 0 P 0 
L 0.89653996 -2.03416004 0.95636998 -2.03416004 0 P 0 
L 0.89656998 -2.03316004 0.95756998 -2.03316004 0 P 0 
L 0.8966 -2.03216004 0.95893996 -2.03216004 0 P 0 
L 0.89663996 -2.03116004 0.96055 -2.03116004 0 P 0 
L 0.89666998 -2.03016004 0.96278002 -2.03016004 0 P 0 
L 0.8967 -2.02916004 0.96676004 -2.02916004 0 P 0 
L 0.89673996 -2.02816004 1.03838996 -2.02816004 0 P 0 
L 0.89676998 -2.02716004 1.03838002 -2.02716004 0 P 0 
L 0.8968 -2.02616004 1.03833996 -2.02616004 0 P 0 
L 0.89683996 -2.02516004 1.03828996 -2.02516004 0 P 0 
L 0.89686998 -2.02416004 1.03823002 -2.02416004 0 P 0 
L 0.8969 -2.02316004 1.03816004 -2.02316004 0 P 0 
L 0.89693996 -2.02216004 1.0381 -2.02216004 0 P 0 
L 0.89696998 -2.02116004 1.03803996 -2.02116004 0 P 0 
L 0.897 -2.02016004 1.0379 -2.02016004 0 P 0 
L 0.89703002 -2.01916004 1.03773996 -2.01916004 0 P 0 
L 0.89706004 -2.01816004 1.03751998 -2.01816004 0 P 0 
L 0.89708996 -2.01716004 1.03728002 -2.01716004 0 P 0 
L 0.89711998 -2.01616004 1.03698996 -2.01616004 0 P 0 
L 0.89713996 -2.01516004 1.03668002 -2.01516004 0 P 0 
L 0.89716998 -2.01416004 1.03631004 -2.01416004 0 P 0 
L 0.8972 -2.01316004 1.03591998 -2.01316004 0 P 0 
L 0.89721998 -2.01216004 1.03548996 -2.01216004 0 P 0 
L 0.89725 -2.01116004 1.03505 -2.01116004 0 P 0 
L 0.89726998 -2.01016004 1.03458002 -2.01016004 0 P 0 
L 0.8973 -2.00916004 1.03405 -2.00916004 0 P 0 
L 0.89733002 -2.00816004 1.03351998 -2.00816004 0 P 0 
L 0.89736004 -2.00716004 0.94676004 -2.00716004 0 P 0 
L 0.89738002 -2.00616004 0.9461 -2.00616004 0 P 0 
L 0.89741004 -2.00516004 0.94563996 -2.00516004 0 P 0 
L 0.89743996 -2.00416004 0.94563996 -2.00416004 0 P 0 
L 0.89746004 -2.00316004 0.94563996 -2.00316004 0 P 0 
L 0.89748996 -2.00216004 0.94563996 -2.00216004 0 P 0 
L 0.89751004 -2.00116004 0.94563996 -2.00116004 0 P 0 
L 0.89753996 -2.00016004 0.94563996 -2.00016004 0 P 0 
L 0.89756998 -1.99916004 0.94563996 -1.99916004 0 P 0 
L 0.8976 -1.99816004 0.94563996 -1.99816004 0 P 0 
L 0.89761998 -1.99716004 0.94563996 -1.99716004 0 P 0 
L 0.89765 -1.99616004 0.94563996 -1.99616004 0 P 0 
L 0.89768002 -1.99516004 0.94563996 -1.99516004 0 P 0 
L 0.97546998 -1.98933996 0.97236998 -1.99006004 0 P 0 
L 0.97236998 -1.99006004 0.96931998 -1.99103002 0 P 0 
L 0.96931998 -1.99103002 0.96603002 -1.99233002 0 P 0 
L 0.96603002 -1.99233002 0.96281004 -1.99383002 0 P 0 
L 0.96281004 -1.99383002 0.95976004 -1.99546998 0 P 0 
L 0.95976004 -1.99546998 0.95681004 -1.99728996 0 P 0 
L 0.95681004 -1.99728996 0.95521004 -1.99841004 0 P 0 
L 0.95521004 -1.99841004 0.95368996 -1.99963002 0 P 0 
L 0.95368996 -1.99963002 0.95223996 -2.00095 0 P 0 
L 0.95223996 -2.00095 0.94763996 -2.00546998 0 P 0 
L 0.94763996 -2.00546998 0.94763996 -1.99243996 0 P 0 
L 0.94763996 -1.99243996 0.89575 -1.99243996 0 P 0 
L 0.89575 -1.99243996 0.89505 -2.01878002 0 P 0 
L 0.89505 -2.01878002 0.89423996 -2.04316004 0 P 0 
L 0.89423996 -2.04316004 0.89321998 -2.0661 0 P 0 
L 0.89321998 -2.0661 0.89198996 -2.08728996 0 P 0 
L 0.89198996 -2.08728996 0.89055 -2.1063 0 P 0 
L 0.89055 -2.1063 0.88993996 -2.11358002 0 P 0 
L 0.88993996 -2.11358002 0.88943002 -2.11988002 0 P 0 
L 0.88943002 -2.11988002 0.88898996 -2.12533996 0 P 0 
L 0.88898996 -2.12533996 0.88896004 -2.12613002 0 P 0 
L 0.88896004 -2.12613002 0.88896998 -2.12621004 0 P 0 
L 0.88896998 -2.12621004 0.88898002 -2.12625 0 P 0 
L 0.88898002 -2.12625 0.88898996 -2.12628002 0 P 0 
L 0.88898996 -2.12628002 0.88901998 -2.12636004 0 P 0 
L 0.88901998 -2.12636004 0.88903996 -2.12638996 0 P 0 
L 0.88903996 -2.12638996 0.88906998 -2.12641998 0 P 0 
L 0.88906998 -2.12641998 0.88908996 -2.12645 0 P 0 
L 0.88908996 -2.12645 0.88911998 -2.12646998 0 P 0 
L 0.88911998 -2.12646998 0.88915 -2.1265 0 P 0 
L 0.88915 -2.1265 0.88921004 -2.12653996 0 P 0 
L 0.88921004 -2.12653996 0.88925 -2.12655 0 P 0 
L 0.88925 -2.12655 0.88928002 -2.12656004 0 P 0 
L 0.88928002 -2.12656004 0.88931998 -2.12658002 0 P 0 
L 0.88931998 -2.12658002 0.8894 -2.12658002 0 P 0 
L 0.8894 -2.12658002 0.89648002 -2.12686998 0 P 0 
L 0.89648002 -2.12686998 0.90518996 -2.1271 0 P 0 
L 0.90518996 -2.1271 0.9165 -2.12716004 0 P 0 
L 0.9165 -2.12716004 0.94403996 -2.12716004 0 P 0 
L 0.94403996 -2.12716004 0.94468996 -2.10135 0 P 0 
L 0.94468996 -2.10135 0.9461 -2.07171998 0 P 0 
L 0.9461 -2.07171998 0.94713002 -2.06233002 0 P 0 
L 0.94713002 -2.06233002 0.9489 -2.05308002 0 P 0 
L 0.9489 -2.05308002 0.94975 -2.04995 0 P 0 
L 0.94975 -2.04995 0.9508 -2.04688996 0 P 0 
L 0.9508 -2.04688996 0.95205 -2.0439 0 P 0 
L 0.95205 -2.0439 0.95351004 -2.041 0 P 0 
L 0.95351004 -2.041 0.9544 -2.03951004 0 P 0 
L 0.9544 -2.03951004 0.95541998 -2.03811004 0 P 0 
L 0.95541998 -2.03811004 0.95655 -2.03678996 0 P 0 
L 0.95655 -2.03678996 0.95778996 -2.03556998 0 P 0 
L 0.95778996 -2.03556998 0.95911998 -2.03446998 0 P 0 
L 0.95911998 -2.03446998 0.96056998 -2.03346998 0 P 0 
L 0.96056998 -2.03346998 0.96151004 -2.03291004 0 P 0 
L 0.96151004 -2.03291004 0.96248996 -2.03243002 0 P 0 
L 0.96248996 -2.03243002 0.96351004 -2.03201998 0 P 0 
L 0.96351004 -2.03201998 0.96455 -2.03168996 0 P 0 
L 0.96455 -2.03168996 0.96613002 -2.0313 0 P 0 
L 0.96613002 -2.0313 0.96773002 -2.03101998 0 P 0 
L 0.96773002 -2.03101998 0.96935 -2.03086004 0 P 0 
L 0.96935 -2.03086004 0.97095 -2.03081004 0 P 0 
L 0.97095 -2.03081004 0.97255 -2.03086998 0 P 0 
L 0.97255 -2.03086998 0.97413002 -2.03105 0 P 0 
L 0.97413002 -2.03105 0.97513002 -2.03123996 0 P 0 
L 0.97513002 -2.03123996 0.9761 -2.03151004 0 P 0 
L 0.9761 -2.03151004 0.97706004 -2.03186004 0 P 0 
L 0.97706004 -2.03186004 0.97796998 -2.0323 0 P 0 
L 0.97796998 -2.0323 0.97885 -2.0328 0 P 0 
L 0.97885 -2.0328 0.97968002 -2.03336998 0 P 0 
L 0.97968002 -2.03336998 0.98046998 -2.03398996 0 P 0 
L 0.98046998 -2.03398996 0.98121998 -2.03468002 0 P 0 
L 0.98121998 -2.03468002 0.98191004 -2.03541998 0 P 0 
L 0.98191004 -2.03541998 0.98253996 -2.0362 0 P 0 
L 0.98253996 -2.0362 0.9831 -2.03703002 0 P 0 
L 0.9831 -2.03703002 0.9836 -2.03788996 0 P 0 
L 0.9836 -2.03788996 0.98403996 -2.0388 0 P 0 
L 0.98403996 -2.0388 0.9844 -2.03973996 0 P 0 
L 0.9844 -2.03973996 0.98505 -2.04188996 0 P 0 
L 0.98505 -2.04188996 0.98553002 -2.04408002 0 P 0 
L 0.98553002 -2.04408002 0.98583002 -2.0463 0 P 0 
L 0.98583002 -2.0463 0.98653002 -2.05705 0 P 0 
L 0.98653002 -2.05705 0.9866 -2.06961004 0 P 0 
L 0.9866 -2.06961004 0.98596004 -2.08908002 0 P 0 
L 0.98596004 -2.08908002 0.98498002 -2.10858002 0 P 0 
L 0.98498002 -2.10858002 0.98388002 -2.12146998 0 P 0 
L 0.98388002 -2.12146998 0.98323002 -2.12716004 0 P 0 
L 0.98323002 -2.12716004 1.03741004 -2.12716004 0 P 0 
L 1.03741004 -2.12716004 1.03896004 -2.09103002 0 P 0 
L 1.03896004 -2.09103002 1.03956004 -2.0759 0 P 0 
L 1.03956004 -2.0759 1.04005 -2.06025 0 P 0 
L 1.04005 -2.06025 1.04038996 -2.04626004 0 P 0 
L 1.04038996 -2.04626004 1.04048002 -2.03698996 0 P 0 
L 1.04048002 -2.03698996 1.04036998 -2.02651998 0 P 0 
L 1.04036998 -2.02651998 1.04003996 -2.02096998 0 P 0 
L 1.04003996 -2.02096998 1.03975 -2.01895 0 P 0 
L 1.03975 -2.01895 1.0393 -2.01693996 0 P 0 
L 1.0393 -2.01693996 1.03868996 -2.01483996 0 P 0 
L 1.03868996 -2.01483996 1.03793996 -2.01278002 0 P 0 
L 1.03793996 -2.01278002 1.03658996 -2.00968002 0 P 0 
L 1.03658996 -2.00968002 1.03501004 -2.00668996 0 P 0 
L 1.03501004 -2.00668996 1.0332 -2.0038 0 P 0 
L 1.0332 -2.0038 1.03186998 -2.002 0 P 0 
L 1.03186998 -2.002 1.0304 -2.0003 0 P 0 
L 1.0304 -2.0003 1.0288 -1.99873002 0 P 0 
L 1.0288 -1.99873002 1.02708002 -1.99728996 0 P 0 
L 1.02708002 -1.99728996 1.02518002 -1.99593002 0 P 0 
L 1.02518002 -1.99593002 1.02318002 -1.99471998 0 P 0 
L 1.02318002 -1.99471998 1.0211 -1.99365 0 P 0 
L 1.0211 -1.99365 1.01893002 -1.99273996 0 P 0 
L 1.01893002 -1.99273996 1.01358996 -1.99098996 0 P 0 
L 1.01358996 -1.99098996 1.0081 -1.98971004 0 P 0 
L 1.0081 -1.98971004 1.00428996 -1.98908996 0 P 0 
L 1.00428996 -1.98908996 1.00043996 -1.98868002 0 P 0 
L 1.00043996 -1.98868002 0.99138002 -1.98826004 0 P 0 
L 0.99138002 -1.98826004 0.98251998 -1.98846998 0 P 0 
L 0.98251998 -1.98846998 0.97898996 -1.98878996 0 P 0 
L 0.97898996 -1.98878996 0.97546998 -1.98933996 0 P 0 
L 0.91651004 -2.12516004 0.94208996 -2.12516004 0 P 0 
L 0.8911 -2.12416004 0.94211004 -2.12416004 0 P 0 
L 0.89118002 -2.12316004 0.94213996 -2.12316004 0 P 0 
L 0.89125 -2.12216004 0.94216004 -2.12216004 0 P 0 
L 0.89133002 -2.12116004 0.94218996 -2.12116004 0 P 0 
L 0.89141004 -2.12016004 0.94221004 -2.12016004 0 P 0 
L 0.89148996 -2.11916004 0.94223996 -2.11916004 0 P 0 
L 0.89156998 -2.11816004 0.94226998 -2.11816004 0 P 0 
L 0.89166004 -2.11716004 0.94228996 -2.11716004 0 P 0 
L 0.89173996 -2.11616004 0.94231004 -2.11616004 0 P 0 
L 0.89181998 -2.11516004 0.94233996 -2.11516004 0 P 0 
L 0.8919 -2.11416004 0.94236004 -2.11416004 0 P 0 
L 0.89198002 -2.11316004 0.94238996 -2.11316004 0 P 0 
L 0.89206998 -2.11216004 0.94241998 -2.11216004 0 P 0 
L 0.89215 -2.11116004 0.94243996 -2.11116004 0 P 0 
L 0.89223002 -2.11016004 0.94246998 -2.11016004 0 P 0 
L 0.89231998 -2.10916004 0.94248996 -2.10916004 0 P 0 
L 0.8924 -2.10816004 0.94251998 -2.10816004 0 P 0 
L 0.89248002 -2.10716004 0.94255 -2.10716004 0 P 0 
L 0.89256998 -2.10616004 0.94256998 -2.10616004 0 P 0 
L 0.89263996 -2.10516004 0.94258996 -2.10516004 0 P 0 
L 0.89271004 -2.10416004 0.94261998 -2.10416004 0 P 0 
L 0.89278996 -2.10316004 0.94263996 -2.10316004 0 P 0 
L 0.89286998 -2.10216004 0.94266998 -2.10216004 0 P 0 
L 0.89293996 -2.10116004 0.9427 -2.10116004 0 P 0 
L 0.89301998 -2.10016004 0.94275 -2.10016004 0 P 0 
L 0.89308996 -2.09916004 0.94278996 -2.09916004 0 P 0 
L 0.89316998 -2.09816004 0.94283996 -2.09816004 0 P 0 
L 0.89325 -2.09716004 0.94288996 -2.09716004 0 P 0 
L 0.89331998 -2.09616004 0.94293996 -2.09616004 0 P 0 
L 0.8934 -2.09516004 0.94298002 -2.09516004 0 P 0 
L 0.89346998 -2.09416004 0.94303002 -2.09416004 0 P 0 
L 0.89355 -2.09316004 0.94308002 -2.09316004 0 P 0 
L 0.89361998 -2.09216004 0.94313002 -2.09216004 0 P 0 
L 0.8937 -2.09116004 0.94318002 -2.09116004 0 P 0 
L 0.89378002 -2.09016004 0.94321998 -2.09016004 0 P 0 
L 0.89385 -2.08916004 0.94326998 -2.08916004 0 P 0 
L 0.89393002 -2.08816004 0.94331998 -2.08816004 0 P 0 
L 0.894 -2.08716004 0.94336004 -2.08716004 0 P 0 
L 0.89406004 -2.08616004 0.94341004 -2.08616004 0 P 0 
L 0.89411998 -2.08516004 0.94346004 -2.08516004 0 P 0 
L 0.89418002 -2.08416004 0.94351004 -2.08416004 0 P 0 
L 0.91651004 -2.12516004 0.90521998 -2.1251 0 P 0 
L 0.90521998 -2.1251 0.89655 -2.12486998 0 P 0 
L 0.89655 -2.12486998 0.89106004 -2.12465 0 P 0 
L 0.89106004 -2.12465 0.89141998 -2.12003996 0 P 0 
L 0.89141998 -2.12003996 0.89193996 -2.11373996 0 P 0 
L 0.89193996 -2.11373996 0.89253996 -2.10645 0 P 0 
L 0.89253996 -2.10645 0.89398002 -2.08741998 0 P 0 
L 0.89398002 -2.08741998 0.89521998 -2.06621998 0 P 0 
L 0.89521998 -2.06621998 0.89521998 -2.06618996 0 P 0 
L 0.89521998 -2.06618996 0.89623996 -2.04323002 0 P 0 
L 0.89623996 -2.04323002 0.89703996 -2.01883002 0 P 0 
L 0.89703996 -2.01883002 0.8977 -1.99443996 0 P 0 
L 0.8977 -1.99443996 0.94563996 -1.99443996 0 P 0 
L 0.94563996 -1.99443996 0.94563996 -2.00546998 0 P 0 
L 0.94563996 -2.00546998 0.94686004 -2.00731004 0 P 0 
L 0.94686004 -2.00731004 0.94903002 -2.00688996 0 P 0 
L 0.94903002 -2.00688996 0.95361998 -2.00241004 0 P 0 
L 0.95361998 -2.00241004 0.95498996 -2.00115 0 P 0 
L 0.95498996 -2.00115 0.95641998 -2.00001004 0 P 0 
L 0.95641998 -2.00001004 0.9579 -1.99896004 0 P 0 
L 0.9579 -1.99896004 0.96076004 -1.9972 0 P 0 
L 0.96076004 -1.9972 0.9637 -1.99561998 0 P 0 
L 0.9637 -1.99561998 0.96683002 -1.99416998 0 P 0 
L 0.96683002 -1.99416998 0.96998996 -1.99291998 0 P 0 
L 0.96998996 -1.99291998 0.9729 -1.99198996 0 P 0 
L 0.9729 -1.99198996 0.97586004 -1.9913 0 P 0 
L 0.97586004 -1.9913 0.97923002 -1.99076998 0 P 0 
L 0.97923002 -1.99076998 0.98263002 -1.99046998 0 P 0 
L 0.98263002 -1.99046998 0.99136004 -1.99026004 0 P 0 
L 0.99136004 -1.99026004 1.00028996 -1.99066998 0 P 0 
L 1.00028996 -1.99066998 1.00403002 -1.99108002 0 P 0 
L 1.00403002 -1.99108002 1.00771004 -1.99166998 0 P 0 
L 1.00771004 -1.99166998 1.01305 -1.99291998 0 P 0 
L 1.01305 -1.99291998 1.01823002 -1.99461998 0 P 0 
L 1.01823002 -1.99461998 1.02026004 -1.99546998 0 P 0 
L 1.02026004 -1.99546998 1.02221004 -1.99646998 0 P 0 
L 1.02221004 -1.99646998 1.02408002 -1.9976 0 P 0 
L 1.02408002 -1.9976 1.02585 -1.99886998 0 P 0 
L 1.02585 -1.99886998 1.02746004 -2.00021004 0 P 0 
L 1.02746004 -2.00021004 1.02893996 -2.00166998 0 P 0 
L 1.02893996 -2.00166998 1.03031004 -2.00325 0 P 0 
L 1.03031004 -2.00325 1.03155 -2.00493002 0 P 0 
L 1.03155 -2.00493002 1.03326998 -2.00768002 0 P 0 
L 1.03326998 -2.00768002 1.03478002 -2.01055 0 P 0 
L 1.03478002 -2.01055 1.03608002 -2.01351998 0 P 0 
L 1.03608002 -2.01351998 1.03678996 -2.01546998 0 P 0 
L 1.03678996 -2.01546998 1.03736004 -2.01743002 0 P 0 
L 1.03736004 -2.01743002 1.03778002 -2.0193 0 P 0 
L 1.03778002 -2.0193 1.03805 -2.02116998 0 P 0 
L 1.03805 -2.02116998 1.03836998 -2.02658996 0 P 0 
L 1.03836998 -2.02658996 1.03848002 -2.03698996 0 P 0 
L 1.03848002 -2.03698996 1.03838996 -2.04623002 0 P 0 
L 1.03838996 -2.04623002 1.03805 -2.06018996 0 P 0 
L 1.03805 -2.06018996 1.03756004 -2.07583002 0 P 0 
L 1.03756004 -2.07583002 1.03696998 -2.09095 0 P 0 
L 1.03696998 -2.09095 1.03548996 -2.12516004 0 P 0 
L 1.03548996 -2.12516004 0.98546998 -2.12516004 0 P 0 
L 0.98546998 -2.12516004 0.98586998 -2.12166004 0 P 0 
L 0.98586998 -2.12166004 0.98696998 -2.10871998 0 P 0 
L 0.98696998 -2.10871998 0.98796004 -2.08916004 0 P 0 
L 0.98796004 -2.08916004 0.9886 -2.06963002 0 P 0 
L 0.9886 -2.06963002 0.98853002 -2.05698002 0 P 0 
L 0.98853002 -2.05698002 0.98781998 -2.0461 0 P 0 
L 0.98781998 -2.0461 0.9875 -2.04373002 0 P 0 
L 0.9875 -2.04373002 0.98748002 -2.04365 0 P 0 
L 0.98748002 -2.04365 0.98698996 -2.04138996 0 P 0 
L 0.98698996 -2.04138996 0.9863 -2.03908002 0 P 0 
L 0.9863 -2.03908002 0.98588002 -2.038 0 P 0 
L 0.98588002 -2.038 0.98538002 -2.03696004 0 P 0 
L 0.98538002 -2.03696004 0.9848 -2.03596004 0 P 0 
L 0.9848 -2.03596004 0.98413996 -2.03501004 0 P 0 
L 0.98413996 -2.03501004 0.98341998 -2.03411004 0 P 0 
L 0.98341998 -2.03411004 0.98336998 -2.03405 0 P 0 
L 0.98336998 -2.03405 0.98263002 -2.03326004 0 P 0 
L 0.98263002 -2.03326004 0.98176998 -2.03246998 0 P 0 
L 0.98176998 -2.03246998 0.98086998 -2.03175 0 P 0 
L 0.98086998 -2.03175 0.97991004 -2.0311 0 P 0 
L 0.97991004 -2.0311 0.9789 -2.03051998 0 P 0 
L 0.9789 -2.03051998 0.97783002 -2.03001998 0 P 0 
L 0.97783002 -2.03001998 0.97673002 -2.02961004 0 P 0 
L 0.97673002 -2.02961004 0.97663996 -2.02958002 0 P 0 
L 0.97663996 -2.02958002 0.97558996 -2.02928996 0 P 0 
L 0.97558996 -2.02928996 0.97443002 -2.02906998 0 P 0 
L 0.97443002 -2.02906998 0.9727 -2.02888002 0 P 0 
L 0.9727 -2.02888002 0.97261998 -2.02886998 0 P 0 
L 0.97261998 -2.02886998 0.97096004 -2.02881004 0 P 0 
L 0.97096004 -2.02881004 0.96921004 -2.02886004 0 P 0 
L 0.96921004 -2.02886004 0.96745 -2.02903996 0 P 0 
L 0.96745 -2.02903996 0.96571004 -2.02933996 0 P 0 
L 0.96571004 -2.02933996 0.964 -2.02976004 0 P 0 
L 0.964 -2.02976004 0.96283002 -2.03013996 0 P 0 
L 0.96283002 -2.03013996 0.96168002 -2.0306 0 P 0 
L 0.96168002 -2.0306 0.96056998 -2.03115 0 P 0 
L 0.96056998 -2.03115 0.95948996 -2.03178002 0 P 0 
L 0.95948996 -2.03178002 0.95791004 -2.03286998 0 P 0 
L 0.95791004 -2.03286998 0.95645 -2.03408996 0 P 0 
L 0.95645 -2.03408996 0.95508996 -2.03541998 0 P 0 
L 0.95508996 -2.03541998 0.95383996 -2.03686998 0 P 0 
L 0.95383996 -2.03686998 0.9538 -2.03693002 0 P 0 
L 0.9538 -2.03693002 0.95273002 -2.03841004 0 P 0 
L 0.95273002 -2.03841004 0.95175 -2.04003996 0 P 0 
L 0.95175 -2.04003996 0.95023002 -2.04306004 0 P 0 
L 0.95023002 -2.04306004 0.94896004 -2.04611004 0 P 0 
L 0.94896004 -2.04611004 0.94893002 -2.04616998 0 P 0 
L 0.94893002 -2.04616998 0.94783002 -2.04936004 0 P 0 
L 0.94783002 -2.04936004 0.94695 -2.05263002 0 P 0 
L 0.94695 -2.05263002 0.94515 -2.06203002 0 P 0 
L 0.94515 -2.06203002 0.9441 -2.07156004 0 P 0 
L 0.9441 -2.07156004 0.9427 -2.10128002 0 P 0 
L 0.9427 -2.10128002 0.94208996 -2.12516004 0 P 0 
L 0.94208996 -2.12516004 0.91651004 -2.12516004 0 P 0 
L 0.93143002 -2.21261998 1.00578996 -2.21261998 0 P 0 
L 0.94051004 -2.21161998 1.00803002 -2.21161998 0 P 0 
L 0.94941998 -2.21061998 1.01026004 -2.21061998 0 P 0 
L 0.9555 -2.20961998 1.0125 -2.20961998 0 P 0 
L 0.96158002 -2.20861998 1.01473996 -2.20861998 0 P 0 
L 0.96766004 -2.20761998 1.01696998 -2.20761998 0 P 0 
L 0.97373002 -2.20661998 1.01921004 -2.20661998 0 P 0 
L 0.97981004 -2.20561998 1.02145 -2.20561998 0 P 0 
L 0.98498996 -2.20461998 1.02368996 -2.20461998 0 P 0 
L 0.98973996 -2.20361998 1.02591998 -2.20361998 0 P 0 
L 0.99448996 -2.20261998 1.02816004 -2.20261998 0 P 0 
L 0.99923996 -2.20161998 1.0304 -2.20161998 0 P 0 
L 1.00398996 -2.20061998 1.03243996 -2.20061998 0 P 0 
L 1.00875 -2.19961998 1.0344 -2.19961998 0 P 0 
L 1.01348996 -2.19861998 1.03636998 -2.19861998 0 P 0 
L 1.0178 -2.19761998 1.03833996 -2.19761998 0 P 0 
L 1.02168996 -2.19661998 1.04031004 -2.19661998 0 P 0 
L 1.02558002 -2.19561998 1.04228002 -2.19561998 0 P 0 
L 1.02946998 -2.19461998 1.04415 -2.19461998 0 P 0 
L 1.03336004 -2.19361998 1.04596998 -2.19361998 0 P 0 
L 1.03725 -2.19261998 1.04778996 -2.19261998 0 P 0 
L 1.04113996 -2.19161998 1.0496 -2.19161998 0 P 0 
L 1.14356998 -1.98926998 1.13261004 -1.99086004 0 P 0 
L 1.13261004 -1.99086004 1.12165 -1.9934 0 P 0 
L 1.12165 -1.9934 1.11125 -1.99673002 0 P 0 
L 1.11125 -1.99673002 1.10658002 -1.99858996 0 P 0 
L 1.10658002 -1.99858996 1.10198996 -2.00071004 0 P 0 
L 1.10198996 -2.00071004 1.09653002 -2.00358996 0 P 0 
L 1.09653002 -2.00358996 1.09436998 -2.00488996 0 P 0 
L 1.09436998 -2.00488996 1.09226004 -2.00631004 0 P 0 
L 1.09226004 -2.00631004 1.09028002 -2.00781004 0 P 0 
L 1.09028002 -2.00781004 1.08836998 -2.00941998 0 P 0 
L 1.08836998 -2.00941998 1.08405 -2.0135 0 P 0 
L 1.08405 -2.0135 1.08096998 -2.01678996 0 P 0 
L 1.08096998 -2.01678996 1.07808002 -2.02026998 0 P 0 
L 1.07808002 -2.02026998 1.0754 -2.02393002 0 P 0 
L 1.0754 -2.02393002 1.07313996 -2.02748002 0 P 0 
L 1.07313996 -2.02748002 1.07116004 -2.03118996 0 P 0 
L 1.07116004 -2.03118996 1.06943996 -2.03505 0 P 0 
L 1.06943996 -2.03505 1.06795 -2.03918996 0 P 0 
L 1.06795 -2.03918996 1.06673996 -2.04343996 0 P 0 
L 1.06673996 -2.04343996 1.06583002 -2.04778002 0 P 0 
L 1.06583002 -2.04778002 1.06476998 -2.05538996 0 P 0 
L 1.06476998 -2.05538996 1.06421004 -2.06306004 0 P 0 
L 1.06421004 -2.06306004 1.06415 -2.07076004 0 P 0 
L 1.06415 -2.07076004 1.06456998 -2.0785 0 P 0 
L 1.06456998 -2.0785 1.06508996 -2.08276004 0 P 0 
L 1.06508996 -2.08276004 1.06591004 -2.08696004 0 P 0 
L 1.06591004 -2.08696004 1.06703002 -2.09108002 0 P 0 
L 1.06703002 -2.09108002 1.06833002 -2.09473002 0 P 0 
L 1.06833002 -2.09473002 1.06991998 -2.09823996 0 P 0 
L 1.06991998 -2.09823996 1.0718 -2.10161998 0 P 0 
L 1.0718 -2.10161998 1.07398002 -2.10491998 0 P 0 
L 1.07398002 -2.10491998 1.07641998 -2.10803002 0 P 0 
L 1.07641998 -2.10803002 1.07908996 -2.11095 0 P 0 
L 1.07908996 -2.11095 1.08175 -2.11345 0 P 0 
L 1.08175 -2.11345 1.08458996 -2.11573996 0 P 0 
L 1.08458996 -2.11573996 1.08758996 -2.1178 0 P 0 
L 1.08758996 -2.1178 1.09073002 -2.11963996 0 P 0 
L 1.09073002 -2.11963996 1.094 -2.12123996 0 P 0 
L 1.094 -2.12123996 1.0986 -2.12306998 0 P 0 
L 1.0986 -2.12306998 1.10331004 -2.12456004 0 P 0 
L 1.10331004 -2.12456004 1.10811004 -2.12568996 0 P 0 
L 1.10811004 -2.12568996 1.11298002 -2.12646998 0 P 0 
L 1.11298002 -2.12646998 1.1182 -2.12693002 0 P 0 
L 1.1182 -2.12693002 1.12343996 -2.12703002 0 P 0 
L 1.12343996 -2.12703002 1.12866998 -2.12676004 0 P 0 
L 1.12866998 -2.12676004 1.13388002 -2.12613002 0 P 0 
L 1.13388002 -2.12613002 1.14086004 -2.12473996 0 P 0 
L 1.14086004 -2.12473996 1.1477 -2.12273996 0 P 0 
L 1.1477 -2.12273996 1.15433996 -2.12015 0 P 0 
L 1.15433996 -2.12015 1.1545 -2.12008996 0 P 0 
L 1.1545 -2.12008996 1.15466004 -2.12003996 0 P 0 
L 1.15466004 -2.12003996 1.15483002 -2.12001004 0 P 0 
L 1.15483002 -2.12001004 1.15498996 -2.11998996 0 P 0 
L 1.15498996 -2.11998996 1.15533002 -2.11998996 0 P 0 
L 1.15533002 -2.11998996 1.15538996 -2.12 0 P 0 
L 1.15538996 -2.12 1.15545 -2.12001998 0 P 0 
L 1.15545 -2.12001998 1.15551004 -2.12003002 0 P 0 
L 1.15551004 -2.12003002 1.15556004 -2.12006004 0 P 0 
L 1.15556004 -2.12006004 1.15561004 -2.12008002 0 P 0 
L 1.15561004 -2.12008002 1.15566004 -2.12011004 0 P 0 
L 1.15566004 -2.12011004 1.15571004 -2.12015 0 P 0 
L 1.15571004 -2.12015 1.15575 -2.12018996 0 P 0 
L 1.15575 -2.12018996 1.15578996 -2.12023996 0 P 0 
L 1.15578996 -2.12023996 1.15583002 -2.12028002 0 P 0 
L 1.15583002 -2.12028002 1.15586004 -2.12033996 0 P 0 
L 1.15586004 -2.12033996 1.15588002 -2.12038996 0 P 0 
L 1.15588002 -2.12038996 1.15591004 -2.12043996 0 P 0 
L 1.15591004 -2.12043996 1.15601998 -2.12076004 0 P 0 
L 1.15601998 -2.12076004 1.1561 -2.12108002 0 P 0 
L 1.1561 -2.12108002 1.15616004 -2.12141998 0 P 0 
L 1.15616004 -2.12141998 1.15618002 -2.12175 0 P 0 
L 1.15618002 -2.12175 1.15623996 -2.12505 0 P 0 
L 1.15623996 -2.12505 1.15616004 -2.12688002 0 P 0 
L 1.15616004 -2.12688002 1.15593002 -2.12871004 0 P 0 
L 1.15593002 -2.12871004 1.15553996 -2.13051998 0 P 0 
L 1.15553996 -2.13051998 1.15516004 -2.1318 0 P 0 
L 1.15516004 -2.1318 1.1547 -2.13305 0 P 0 
L 1.1547 -2.13305 1.15415 -2.13426004 0 P 0 
L 1.15415 -2.13426004 1.15351004 -2.13545 0 P 0 
L 1.15351004 -2.13545 1.15278996 -2.1366 0 P 0 
L 1.15278996 -2.1366 1.15198002 -2.13768996 0 P 0 
L 1.15198002 -2.13768996 1.15111004 -2.13873002 0 P 0 
L 1.15111004 -2.13873002 1.15016004 -2.13971004 0 P 0 
L 1.15016004 -2.13971004 1.14876004 -2.14096004 0 P 0 
L 1.14876004 -2.14096004 1.14726004 -2.1421 0 P 0 
L 1.14726004 -2.1421 1.14566998 -2.14311004 0 P 0 
L 1.14566998 -2.14311004 1.144 -2.144 0 P 0 
L 1.144 -2.144 1.14226004 -2.14476004 0 P 0 
L 1.14226004 -2.14476004 1.14046004 -2.14536998 0 P 0 
L 1.14046004 -2.14536998 1.13863002 -2.14583002 0 P 0 
L 1.13863002 -2.14583002 1.13676004 -2.14613996 0 P 0 
L 1.13676004 -2.14613996 1.13041998 -2.14663996 0 P 0 
L 1.13041998 -2.14663996 1.12403996 -2.1466 0 P 0 
L 1.12403996 -2.1466 1.11621998 -2.14593996 0 P 0 
L 1.11621998 -2.14593996 1.10843996 -2.14471004 0 P 0 
L 1.10843996 -2.14471004 1.09946998 -2.14276998 0 P 0 
L 1.09946998 -2.14276998 1.0905 -2.14041004 0 P 0 
L 1.0905 -2.14041004 1.07963996 -2.13728996 0 P 0 
L 1.07963996 -2.13728996 1.07936004 -2.1401 0 P 0 
L 1.07936004 -2.1401 1.07931004 -2.14103996 0 P 0 
L 1.07931004 -2.14103996 1.07931998 -2.14198002 0 P 0 
L 1.07931998 -2.14198002 1.07956998 -2.14735 0 P 0 
L 1.07956998 -2.14735 1.07993996 -2.15375 0 P 0 
L 1.07993996 -2.15375 1.08045 -2.16081998 0 P 0 
L 1.08045 -2.16081998 1.08181004 -2.17873002 0 P 0 
L 1.08181004 -2.17873002 1.08996004 -2.18061004 0 P 0 
L 1.08996004 -2.18061004 1.09951004 -2.18246004 0 P 0 
L 1.09951004 -2.18246004 1.11243996 -2.18416998 0 P 0 
L 1.11243996 -2.18416998 1.1254 -2.18543002 0 P 0 
L 1.1254 -2.18543002 1.13508002 -2.18583002 0 P 0 
L 1.13508002 -2.18583002 1.14765 -2.18528996 0 P 0 
L 1.14765 -2.18528996 1.15368002 -2.18461004 0 P 0 
L 1.15368002 -2.18461004 1.15971004 -2.18363996 0 P 0 
L 1.15971004 -2.18363996 1.16521004 -2.18248002 0 P 0 
L 1.16521004 -2.18248002 1.17063996 -2.18103002 0 P 0 
L 1.17063996 -2.18103002 1.17528996 -2.17946998 0 P 0 
L 1.17528996 -2.17946998 1.17978002 -2.17753996 0 P 0 
L 1.17978002 -2.17753996 1.18216998 -2.1763 0 P 0 
L 1.18216998 -2.1763 1.18446004 -2.17488996 0 P 0 
L 1.18446004 -2.17488996 1.18663996 -2.17331004 0 P 0 
L 1.18663996 -2.17331004 1.18871004 -2.17156004 0 P 0 
L 1.18871004 -2.17156004 1.19161004 -2.16871998 0 P 0 
L 1.19161004 -2.16871998 1.19431004 -2.16568996 0 P 0 
L 1.19431004 -2.16568996 1.19678996 -2.16246998 0 P 0 
L 1.19678996 -2.16246998 1.19908996 -2.15901998 0 P 0 
L 1.19908996 -2.15901998 1.20113996 -2.15543996 0 P 0 
L 1.20113996 -2.15543996 1.20295 -2.15171004 0 P 0 
L 1.20295 -2.15171004 1.20435 -2.14815 0 P 0 
L 1.20435 -2.14815 1.20543996 -2.14448996 0 P 0 
L 1.20543996 -2.14448996 1.20621004 -2.14073996 0 P 0 
L 1.20621004 -2.14073996 1.20651998 -2.13855 0 P 0 
L 1.20651998 -2.13855 1.20671998 -2.13633996 0 P 0 
L 1.20671998 -2.13633996 1.20761998 -2.12321004 0 P 0 
L 1.20761998 -2.12321004 1.20858002 -2.10753996 0 P 0 
L 1.20858002 -2.10753996 1.20951004 -2.09021998 0 P 0 
L 1.20951004 -2.09021998 1.21048002 -2.07166004 0 P 0 
L 1.21048002 -2.07166004 1.21156004 -2.05228002 0 P 0 
L 1.21156004 -2.05228002 1.21258002 -2.03478996 0 P 0 
L 1.21258002 -2.03478996 1.21333002 -2.02286004 0 P 0 
L 1.21333002 -2.02286004 1.21393996 -2.01373996 0 P 0 
L 1.21393996 -2.01373996 1.21443996 -2.00568996 0 P 0 
L 1.21443996 -2.00568996 1.21485 -1.99883996 0 P 0 
L 1.21485 -1.99883996 1.2149 -1.99721004 0 P 0 
L 1.2149 -1.99721004 1.21488996 -1.99703996 0 P 0 
L 1.21488996 -1.99703996 1.21486998 -1.99686004 0 P 0 
L 1.21486998 -1.99686004 1.21483996 -1.99668996 0 P 0 
L 1.21483996 -1.99668996 1.21478996 -1.99653002 0 P 0 
L 1.21478996 -1.99653002 1.21473002 -1.99636998 0 P 0 
L 1.21473002 -1.99636998 1.21466004 -1.99621004 0 P 0 
L 1.21466004 -1.99621004 1.21458002 -1.99606004 0 P 0 
L 1.21458002 -1.99606004 1.21448002 -1.99591004 0 P 0 
L 1.21448002 -1.99591004 1.21433002 -1.99571998 0 P 0 
L 1.21433002 -1.99571998 1.21416998 -1.99553996 0 P 0 
L 1.21416998 -1.99553996 1.21398996 -1.99538002 0 P 0 
L 1.21398996 -1.99538002 1.21378996 -1.99523996 0 P 0 
L 1.21378996 -1.99523996 1.21358002 -1.99511004 0 P 0 
L 1.21358002 -1.99511004 1.21336004 -1.995 0 P 0 
L 1.21336004 -1.995 1.21261004 -1.99468996 0 P 0 
L 1.21261004 -1.99468996 1.21183996 -1.99443996 0 P 0 
L 1.21183996 -1.99443996 1.21105 -1.99423002 0 P 0 
L 1.21105 -1.99423002 1.20593996 -1.99318002 0 P 0 
L 1.20593996 -1.99318002 1.18996998 -1.99065 0 P 0 
L 1.18996998 -1.99065 1.17318996 -1.98908002 0 P 0 
L 1.17318996 -1.98908002 1.15718996 -1.98858002 0 P 0 
L 1.15718996 -1.98858002 1.1504 -1.98876004 0 P 0 
L 1.1504 -1.98876004 1.14356998 -1.98926998 0 P 0 
L 1.04503996 -2.19061998 1.05141998 -2.19061998 0 P 0 
L 1.04893002 -2.18961998 1.05323002 -2.18961998 0 P 0 
L 1.05263002 -2.18861998 1.05503996 -2.18861998 0 P 0 
L 1.05628996 -2.18761998 1.05676004 -2.18761998 0 P 0 
L 1.09645 -2.17983002 1.16738002 -2.17983002 0 P 0 
L 1.09126004 -2.17883002 1.17091004 -2.17883002 0 P 0 
L 1.0868 -2.17783002 1.17386998 -2.17783002 0 P 0 
L 1.08368002 -2.17683002 1.17636004 -2.17683002 0 P 0 
L 1.0836 -2.17583002 1.1787 -2.17583002 0 P 0 
L 1.08351998 -2.17483002 1.18066998 -2.17483002 0 P 0 
L 1.08345 -2.17383002 1.18236998 -2.17383002 0 P 0 
L 1.08336998 -2.17283002 1.1839 -2.17283002 0 P 0 
L 1.08328996 -2.17183002 1.18526998 -2.17183002 0 P 0 
L 1.08321998 -2.17083002 1.18646998 -2.17083002 0 P 0 
L 1.08313996 -2.16983002 1.18761998 -2.16983002 0 P 0 
L 1.08306998 -2.16883002 1.18863996 -2.16883002 0 P 0 
L 1.08298996 -2.16783002 1.18966004 -2.16783002 0 P 0 
L 1.08291998 -2.16683002 1.19061004 -2.16683002 0 P 0 
L 1.08283996 -2.16583002 1.1915 -2.16583002 0 P 0 
L 1.08276004 -2.16483002 1.19238996 -2.16483002 0 P 0 
L 1.08268996 -2.16383002 1.19321004 -2.16383002 0 P 0 
L 1.08261004 -2.16283002 1.19398002 -2.16283002 0 P 0 
L 1.08253002 -2.16183002 1.19476004 -2.16183002 0 P 0 
L 1.08246004 -2.16083002 1.19548002 -2.16083002 0 P 0 
L 1.08238002 -2.15983002 1.19613996 -2.15983002 0 P 0 
L 1.08231004 -2.15883002 1.19681004 -2.15883002 0 P 0 
L 1.08223996 -2.15783002 1.19746004 -2.15783002 0 P 0 
L 1.13506998 -2.18383002 1.12553002 -2.18343996 0 P 0 
L 1.12553002 -2.18343996 1.11266004 -2.18218002 0 P 0 
L 1.11266004 -2.18218002 1.09983002 -2.18048002 0 P 0 
L 1.09983002 -2.18048002 1.09036998 -2.17866004 0 P 0 
L 1.09036998 -2.17866004 1.0837 -2.17711004 0 P 0 
L 1.0837 -2.17711004 1.08245 -2.16066998 0 P 0 
L 1.08245 -2.16066998 1.08193996 -2.15361998 0 P 0 
L 1.08193996 -2.15361998 1.08156998 -2.14726004 0 P 0 
L 1.08156998 -2.14726004 1.08131998 -2.14191004 0 P 0 
L 1.08131998 -2.14191004 1.08131004 -2.14108996 0 P 0 
L 1.08131004 -2.14108996 1.08136004 -2.14026004 0 P 0 
L 1.08136004 -2.14026004 1.0814 -2.13986998 0 P 0 
L 1.0814 -2.13986998 1.08996004 -2.14233002 0 P 0 
L 1.08996004 -2.14233002 1.08996998 -2.14233996 0 P 0 
L 1.08996998 -2.14233996 1.08998996 -2.14233996 0 P 0 
L 1.08998996 -2.14233996 1.099 -2.14471998 0 P 0 
L 1.099 -2.14471998 1.10806998 -2.14668002 0 P 0 
L 1.10806998 -2.14668002 1.11598002 -2.14791998 0 P 0 
L 1.11598002 -2.14791998 1.12395 -2.1486 0 P 0 
L 1.12395 -2.1486 1.13048996 -2.14863996 0 P 0 
L 1.13048996 -2.14863996 1.137 -2.14811998 0 P 0 
L 1.137 -2.14811998 1.13903002 -2.14778996 0 P 0 
L 1.13903002 -2.14778996 1.14103002 -2.14728996 0 P 0 
L 1.14103002 -2.14728996 1.14298002 -2.14661998 0 P 0 
L 1.14298002 -2.14661998 1.14486998 -2.14581004 0 P 0 
L 1.14486998 -2.14581004 1.14668002 -2.14483996 0 P 0 
L 1.14668002 -2.14483996 1.1484 -2.14373996 0 P 0 
L 1.1484 -2.14373996 1.15003002 -2.1425 0 P 0 
L 1.15003002 -2.1425 1.15155 -2.14115 0 P 0 
L 1.15155 -2.14115 1.1526 -2.14006998 0 P 0 
L 1.1526 -2.14006998 1.15263996 -2.14001998 0 P 0 
L 1.15263996 -2.14001998 1.15356004 -2.13893002 0 P 0 
L 1.15356004 -2.13893002 1.15443996 -2.13771998 0 P 0 
L 1.15443996 -2.13771998 1.15523002 -2.13646004 0 P 0 
L 1.15523002 -2.13646004 1.15593996 -2.13515 0 P 0 
L 1.15593996 -2.13515 1.15655 -2.13381004 0 P 0 
L 1.15655 -2.13381004 1.15706004 -2.13243002 0 P 0 
L 1.15706004 -2.13243002 1.15748002 -2.13101004 0 P 0 
L 1.15748002 -2.13101004 1.1579 -2.12905 0 P 0 
L 1.1579 -2.12905 1.15816004 -2.12706004 0 P 0 
L 1.15816004 -2.12706004 1.15825 -2.12506998 0 P 0 
L 1.15825 -2.12506998 1.15818002 -2.12165 0 P 0 
L 1.15818002 -2.12165 1.15813996 -2.12118002 0 P 0 
L 1.15813996 -2.12118002 1.15813002 -2.1211 0 P 0 
L 1.15813002 -2.1211 1.15806004 -2.12068002 0 P 0 
L 1.15806004 -2.12068002 1.15793996 -2.12018996 0 P 0 
L 1.15793996 -2.12018996 1.15778002 -2.11973002 0 P 0 
L 1.15778002 -2.11973002 1.1577 -2.11953002 0 P 0 
L 1.1577 -2.11953002 1.15758996 -2.11933002 0 P 0 
L 1.15758996 -2.11933002 1.15746998 -2.11913996 0 P 0 
L 1.15746998 -2.11913996 1.15733002 -2.11895 0 P 0 
L 1.15733002 -2.11895 1.15716998 -2.11878002 0 P 0 
L 1.15716998 -2.11878002 1.157 -2.11863002 0 P 0 
L 1.157 -2.11863002 1.15681998 -2.11848996 0 P 0 
L 1.15681998 -2.11848996 1.15663002 -2.11836004 0 P 0 
L 1.15663002 -2.11836004 1.15641998 -2.11825 0 P 0 
L 1.15641998 -2.11825 1.15621004 -2.11816004 0 P 0 
L 1.15621004 -2.11816004 1.15598996 -2.11808996 0 P 0 
L 1.15598996 -2.11808996 1.15576998 -2.11803996 0 P 0 
L 1.15576998 -2.11803996 1.15553002 -2.118 0 P 0 
L 1.15553002 -2.118 1.15518002 -2.11798002 0 P 0 
L 1.15518002 -2.11798002 1.15483996 -2.11798996 0 P 0 
L 1.15483996 -2.11798996 1.15451004 -2.11803002 0 P 0 
L 1.15451004 -2.11803002 1.15418002 -2.1181 0 P 0 
L 1.15418002 -2.1181 1.15386004 -2.1182 0 P 0 
L 1.15386004 -2.1182 1.15361004 -2.11828996 0 P 0 
L 1.15361004 -2.11828996 1.14705 -2.12083996 0 P 0 
L 1.14705 -2.12083996 1.14038996 -2.12278996 0 P 0 
L 1.14038996 -2.12278996 1.13356004 -2.12416004 0 P 0 
L 1.13356004 -2.12416004 1.1285 -2.12476998 0 P 0 
L 1.1285 -2.12476998 1.12341004 -2.12501998 0 P 0 
L 1.12341004 -2.12501998 1.11831004 -2.12493002 0 P 0 
L 1.11831004 -2.12493002 1.11323002 -2.12448996 0 P 0 
L 1.11323002 -2.12448996 1.10848996 -2.12373002 0 P 0 
L 1.10848996 -2.12373002 1.10383996 -2.12263002 0 P 0 
L 1.10383996 -2.12263002 1.09926998 -2.12118996 0 P 0 
L 1.09926998 -2.12118996 1.09481004 -2.11941004 0 P 0 
L 1.09481004 -2.11941004 1.09168002 -2.11788002 0 P 0 
L 1.09168002 -2.11788002 1.08866004 -2.11611998 0 P 0 
L 1.08866004 -2.11611998 1.08578002 -2.11413002 0 P 0 
L 1.08578002 -2.11413002 1.08306998 -2.11193996 0 P 0 
L 1.08306998 -2.11193996 1.08051998 -2.10955 0 P 0 
L 1.08051998 -2.10955 1.07793996 -2.10673002 0 P 0 
L 1.07793996 -2.10673002 1.07561004 -2.10373996 0 P 0 
L 1.07561004 -2.10373996 1.07351004 -2.10058002 0 P 0 
L 1.07351004 -2.10058002 1.07171004 -2.09733996 0 P 0 
L 1.07171004 -2.09733996 1.07018002 -2.09396998 0 P 0 
L 1.07018002 -2.09396998 1.06893996 -2.09048002 0 P 0 
L 1.06893996 -2.09048002 1.06786004 -2.0865 0 P 0 
L 1.06786004 -2.0865 1.06706004 -2.08243996 0 P 0 
L 1.06706004 -2.08243996 1.06656004 -2.07833002 0 P 0 
L 1.06656004 -2.07833002 1.06615 -2.07071004 0 P 0 
L 1.06615 -2.07071004 1.06621004 -2.06313996 0 P 0 
L 1.06621004 -2.06313996 1.06675 -2.0556 0 P 0 
L 1.06675 -2.0556 1.0678 -2.04813002 0 P 0 
L 1.0678 -2.04813002 1.06868996 -2.04391998 0 P 0 
L 1.06868996 -2.04391998 1.06985 -2.03981004 0 P 0 
L 1.06985 -2.03981004 1.0713 -2.03578996 0 P 0 
L 1.0713 -2.03578996 1.07296004 -2.03206998 0 P 0 
L 1.07296004 -2.03206998 1.07486998 -2.02848996 0 P 0 
L 1.07486998 -2.02848996 1.07705 -2.02506004 0 P 0 
L 1.07705 -2.02506004 1.07966004 -2.0215 0 P 0 
L 1.07966004 -2.0215 1.08246998 -2.01811004 0 P 0 
L 1.08246998 -2.01811004 1.08546998 -2.01491004 0 P 0 
L 1.08546998 -2.01491004 1.0897 -2.01091004 0 P 0 
L 1.0897 -2.01091004 1.09153002 -2.00936998 0 P 0 
L 1.09153002 -2.00936998 1.09341998 -2.00793996 0 P 0 
L 1.09341998 -2.00793996 1.09545 -2.00658002 0 P 0 
L 1.09545 -2.00658002 1.09751004 -2.00533996 0 P 0 
L 1.09751004 -2.00533996 1.10288002 -2.0025 0 P 0 
L 1.10288002 -2.0025 1.10736998 -2.00043002 0 P 0 
L 1.10736998 -2.00043002 1.11193002 -1.99861004 0 P 0 
L 1.11193002 -1.99861004 1.12218002 -1.99533002 0 P 0 
L 1.12218002 -1.99533002 1.13298002 -1.99281998 0 P 0 
L 1.13298002 -1.99281998 1.14378996 -1.99126004 0 P 0 
L 1.14378996 -1.99126004 1.1505 -1.99075 0 P 0 
L 1.1505 -1.99075 1.15718002 -1.99058996 0 P 0 
L 1.15718002 -1.99058996 1.17306998 -1.99108002 0 P 0 
L 1.17306998 -1.99108002 1.18971998 -1.99263002 0 P 0 
L 1.18971998 -1.99263002 1.20558002 -1.99515 0 P 0 
L 1.20558002 -1.99515 1.21058996 -1.99618002 0 P 0 
L 1.21058996 -1.99618002 1.21126998 -1.99636004 0 P 0 
L 1.21126998 -1.99636004 1.21191998 -1.99656998 0 P 0 
L 1.21191998 -1.99656998 1.21253002 -1.99681998 0 P 0 
L 1.21253002 -1.99681998 1.21261004 -1.99686004 0 P 0 
L 1.21261004 -1.99686004 1.21266004 -1.99688996 0 P 0 
L 1.21266004 -1.99688996 1.21271998 -1.99693002 0 P 0 
L 1.21271998 -1.99693002 1.21281998 -1.99703002 0 P 0 
L 1.21281998 -1.99703002 1.21286004 -1.99708996 0 P 0 
L 1.21286004 -1.99708996 1.21288002 -1.99711004 0 P 0 
L 1.21288002 -1.99711004 1.21288002 -1.99711998 0 P 0 
L 1.21288002 -1.99711998 1.21288996 -1.99715 0 P 0 
L 1.21288996 -1.99715 1.2129 -1.99716998 0 P 0 
L 1.2129 -1.99716998 1.2129 -1.99721998 0 P 0 
L 1.2129 -1.99721998 1.21285 -1.99875 0 P 0 
L 1.21285 -1.99875 1.21243996 -2.00556998 0 P 0 
L 1.21243996 -2.00556998 1.21193996 -2.01361004 0 P 0 
L 1.21193996 -2.01361004 1.21133996 -2.02273002 0 P 0 
L 1.21133996 -2.02273002 1.21133996 -2.02273996 0 P 0 
L 1.21133996 -2.02273996 1.21058996 -2.03468002 0 P 0 
L 1.21058996 -2.03468002 1.20956004 -2.05216998 0 P 0 
L 1.20956004 -2.05216998 1.20848996 -2.07156004 0 P 0 
L 1.20848996 -2.07156004 1.20848996 -2.07156998 0 P 0 
L 1.20848996 -2.07156998 1.20751004 -2.09011004 0 P 0 
L 1.20751004 -2.09011004 1.20658996 -2.10743996 0 P 0 
L 1.20658996 -2.10743996 1.20561998 -2.12308996 0 P 0 
L 1.20561998 -2.12308996 1.20473002 -2.13618996 0 P 0 
L 1.20473002 -2.13618996 1.20453002 -2.13831998 0 P 0 
L 1.20453002 -2.13831998 1.20423996 -2.14041004 0 P 0 
L 1.20423996 -2.14041004 1.2035 -2.144 0 P 0 
L 1.2035 -2.144 1.20246004 -2.1475 0 P 0 
L 1.20246004 -2.1475 1.20111998 -2.1509 0 P 0 
L 1.20111998 -2.1509 1.19936998 -2.1545 0 P 0 
L 1.19936998 -2.1545 1.19738002 -2.15796998 0 P 0 
L 1.19738002 -2.15796998 1.19516004 -2.1613 0 P 0 
L 1.19516004 -2.1613 1.19276998 -2.16441004 0 P 0 
L 1.19276998 -2.16441004 1.19016004 -2.16733996 0 P 0 
L 1.19016004 -2.16733996 1.18736004 -2.17008002 0 P 0 
L 1.18736004 -2.17008002 1.1854 -2.17173996 0 P 0 
L 1.1854 -2.17173996 1.18335 -2.17323002 0 P 0 
L 1.18335 -2.17323002 1.18118002 -2.17456004 0 P 0 
L 1.18118002 -2.17456004 1.17893002 -2.17573002 0 P 0 
L 1.17893002 -2.17573002 1.17456998 -2.1776 0 P 0 
L 1.17456998 -2.1776 1.17006998 -2.17911998 0 P 0 
L 1.17006998 -2.17911998 1.16473996 -2.18053002 0 P 0 
L 1.16473996 -2.18053002 1.15935 -2.18166998 0 P 0 
L 1.15935 -2.18166998 1.15341998 -2.18263002 0 P 0 
L 1.15341998 -2.18263002 1.1475 -2.18328996 0 P 0 
L 1.1475 -2.18328996 1.13506998 -2.18383002 0 P 0 
L 0.90491998 -2.21461998 1.00131004 -2.21461998 0 P 0 
L 0.92235 -2.21361998 1.00355 -2.21361998 0 P 0 
L 0.76925 -1.8965 0.85586998 -1.8965 0 P 0 
L 0.76958996 -1.8955 0.85556004 -1.8955 0 P 0 
L 0.76995 -1.8945 0.85521004 -1.8945 0 P 0 
L 0.77031004 -1.8935 0.85486004 -1.8935 0 P 0 
L 0.77071004 -1.8925 0.85443996 -1.8925 0 P 0 
L 0.77115 -1.8915 0.85401004 -1.8915 0 P 0 
L 0.7716 -1.8905 0.85355 -1.8905 0 P 0 
L 0.77206004 -1.8895 0.85303002 -1.8895 0 P 0 
L 0.7726 -1.8885 0.85251004 -1.8885 0 P 0 
L 0.77313996 -1.8875 0.85198996 -1.8875 0 P 0 
L 0.77368996 -1.8865 0.85138002 -1.8865 0 P 0 
L 0.77433002 -1.8855 0.85073996 -1.8855 0 P 0 
L 0.77496004 -1.8845 0.85011004 -1.8845 0 P 0 
L 0.77561998 -1.8835 0.84943002 -1.8835 0 P 0 
L 0.77636004 -1.8825 0.84866998 -1.8825 0 P 0 
L 0.77711004 -1.8815 0.84791004 -1.8815 0 P 0 
L 0.7779 -1.8805 0.84713002 -1.8805 0 P 0 
L 0.77876998 -1.8795 0.84623002 -1.8795 0 P 0 
L 0.77963996 -1.8785 0.84533002 -1.8785 0 P 0 
L 0.7806 -1.8775 0.8444 -1.8775 0 P 0 
L 0.78161004 -1.8765 0.84335 -1.8765 0 P 0 
L 0.78265 -1.8755 0.84228996 -1.8755 0 P 0 
L 0.78381998 -1.8745 0.84108996 -1.8745 0 P 0 
L 0.78498996 -1.8735 0.83986998 -1.8735 0 P 0 
L 0.78635 -1.8725 0.83848002 -1.8725 0 P 0 
L 0.78773002 -1.8715 0.83706004 -1.8715 0 P 0 
L 0.78933002 -1.8705 0.83541998 -1.8705 0 P 0 
L 0.791 -1.8695 0.83366004 -1.8695 0 P 0 
L 0.793 -1.8685 0.83171998 -1.8685 0 P 0 
L 0.79525 -1.8675 0.82941998 -1.8675 0 P 0 
L 0.79791998 -1.8665 0.82671004 -1.8665 0 P 0 
L 0.80143996 -1.8655 0.82328996 -1.8655 0 P 0 
L 0.80705 -1.8645 0.81776004 -1.8645 0 P 0 
L 0.74543002 -1.89661998 0.75033002 -1.89661998 0 P 0 
L 0.74751004 -1.89561998 0.75058996 -1.89561998 0 P 0 
L 0.74958996 -1.89461998 0.75086004 -1.89461998 0 P 0 
L 0.76733996 -1.9125 0.85751998 -1.9125 0 P 0 
L 0.76728996 -1.9115 0.85756004 -1.9115 0 P 0 
L 0.76723996 -1.9105 0.85758996 -1.9105 0 P 0 
L 0.76721998 -1.9095 0.85763002 -1.9095 0 P 0 
L 0.76725 -1.9085 0.85761004 -1.9085 0 P 0 
L 0.76728002 -1.9075 0.85756998 -1.9075 0 P 0 
L 0.76731004 -1.9065 0.85753002 -1.9065 0 P 0 
L 0.76741998 -1.9055 0.85748996 -1.9055 0 P 0 
L 0.76753996 -1.9045 0.85738002 -1.9045 0 P 0 
L 0.76766004 -1.9035 0.85726004 -1.9035 0 P 0 
L 0.76781998 -1.9025 0.85713996 -1.9025 0 P 0 
L 0.76801998 -1.9015 0.85701004 -1.9015 0 P 0 
L 0.76821004 -1.9005 0.85683002 -1.9005 0 P 0 
L 0.76841998 -1.8995 0.85661998 -1.8995 0 P 0 
L 0.7687 -1.8985 0.85641004 -1.8985 0 P 0 
L 0.76896998 -1.8975 0.85613996 -1.8975 0 P 0 
L 0.76751004 -2.08325 0.8416 -2.08325 0 P 0 
L 0.76761998 -2.08225 0.84161998 -2.08225 0 P 0 
L 0.76773996 -2.08125 0.84166998 -2.08125 0 P 0 
L 0.76786004 -2.08025 0.84171998 -2.08025 0 P 0 
L 0.76796998 -2.07925 0.84176998 -2.07925 0 P 0 
L 0.76808002 -2.07825 0.84181004 -2.07825 0 P 0 
L 0.76818002 -2.07725 0.84186004 -2.07725 0 P 0 
L 0.76828996 -2.07625 0.8419 -2.07625 0 P 0 
L 0.76838996 -2.07525 0.84195 -2.07525 0 P 0 
L 0.76848996 -2.07425 0.842 -2.07425 0 P 0 
L 0.7686 -2.07325 0.84205 -2.07325 0 P 0 
L 0.7687 -2.07225 0.84208996 -2.07225 0 P 0 
L 0.7688 -2.07125 0.84213996 -2.07125 0 P 0 
L 0.7689 -2.07025 0.84218002 -2.07025 0 P 0 
L 0.76901004 -2.06925 0.84223002 -2.06925 0 P 0 
L 0.76911004 -2.06825 0.84228002 -2.06825 0 P 0 
L 0.76921004 -2.06725 0.84233002 -2.06725 0 P 0 
L 0.76931998 -2.06625 0.84236998 -2.06625 0 P 0 
L 0.76941998 -2.06525 0.84241998 -2.06525 0 P 0 
L 0.76948996 -2.06425 0.84246004 -2.06425 0 P 0 
L 0.76956004 -2.06325 0.84251004 -2.06325 0 P 0 
L 0.76963002 -2.06225 0.84256004 -2.06225 0 P 0 
L 0.7697 -2.06125 0.8426 -2.06125 0 P 0 
L 0.76976998 -2.06025 0.84265 -2.06025 0 P 0 
L 0.76983996 -2.05925 0.8427 -2.05925 0 P 0 
L 0.76991004 -2.05825 0.84273996 -2.05825 0 P 0 
L 0.76996998 -2.05725 0.84278996 -2.05725 0 P 0 
L 0.77001004 -2.05625 0.84283996 -2.05625 0 P 0 
L 0.77003996 -2.05525 0.84288002 -2.05525 0 P 0 
L 0.77008002 -2.05425 0.84295 -2.05425 0 P 0 
L 0.77011998 -2.05325 0.84303996 -2.05325 0 P 0 
L 0.77016004 -2.05225 0.84311998 -2.05225 0 P 0 
L 0.77018996 -2.05125 0.84321004 -2.05125 0 P 0 
L 0.77023002 -2.05025 0.8433 -2.05025 0 P 0 
L 0.77026998 -2.04925 0.84338002 -2.04925 0 P 0 
L 0.77031004 -2.04825 0.84346998 -2.04825 0 P 0 
L 0.77033996 -2.04725 0.84356004 -2.04725 0 P 0 
L 0.77038002 -2.04625 0.84363996 -2.04625 0 P 0 
L 0.77041004 -2.04525 0.84373002 -2.04525 0 P 0 
L 0.77043996 -2.04425 0.84381004 -2.04425 0 P 0 
L 0.77046004 -2.04325 0.8439 -2.04325 0 P 0 
L 0.77048002 -2.04225 0.84398996 -2.04225 0 P 0 
L 0.77051004 -2.04125 0.84406998 -2.04125 0 P 0 
L 0.77053002 -2.04025 0.84416004 -2.04025 0 P 0 
L 0.77055 -2.03925 0.84425 -2.03925 0 P 0 
L 0.77058002 -2.03825 0.84433002 -2.03825 0 P 0 
L 0.7706 -2.03725 0.84441998 -2.03725 0 P 0 
L 0.77061998 -2.03625 0.84451004 -2.03625 0 P 0 
L 0.77065 -2.03525 0.84458996 -2.03525 0 P 0 
L 0.77066998 -2.03425 0.84468002 -2.03425 0 P 0 
L 0.7707 -2.03325 0.84476998 -2.03325 0 P 0 
L 0.77071998 -2.03225 0.84485 -2.03225 0 P 0 
L 0.77073002 -2.03125 0.84493996 -2.03125 0 P 0 
L 0.77073996 -2.03025 0.84503002 -2.03025 0 P 0 
L 0.79986004 -1.8638 0.79643996 -1.86486998 0 P 0 
L 0.79643996 -1.86486998 0.79311998 -1.86621004 0 P 0 
L 0.79311998 -1.86621004 0.78991004 -1.86781004 0 P 0 
L 0.78991004 -1.86781004 0.78683996 -1.86966998 0 P 0 
L 0.78683996 -1.86966998 0.78391998 -1.87178002 0 P 0 
L 0.78391998 -1.87178002 0.78111998 -1.87416998 0 P 0 
L 0.78111998 -1.87416998 0.7785 -1.87676004 0 P 0 
L 0.7785 -1.87676004 0.77608002 -1.87953996 0 P 0 
L 0.77608002 -1.87953996 0.77386998 -1.8825 0 P 0 
L 0.77386998 -1.8825 0.77188002 -1.88561998 0 P 0 
L 0.77188002 -1.88561998 0.77013996 -1.88886004 0 P 0 
L 0.77013996 -1.88886004 0.76863996 -1.89221004 0 P 0 
L 0.76863996 -1.89221004 0.7674 -1.89566998 0 P 0 
L 0.7674 -1.89566998 0.76643002 -1.89921004 0 P 0 
L 0.76643002 -1.89921004 0.76571004 -1.90283996 0 P 0 
L 0.76571004 -1.90283996 0.76531004 -1.90636004 0 P 0 
L 0.76531004 -1.90636004 0.7652 -1.90991004 0 P 0 
L 0.7652 -1.90991004 0.76538996 -1.91345 0 P 0 
L 0.76538996 -1.91345 0.76586998 -1.91696998 0 P 0 
L 0.76586998 -1.91696998 0.76663996 -1.92046004 0 P 0 
L 0.76663996 -1.92046004 0.76803002 -1.92493996 0 P 0 
L 0.76803002 -1.92493996 0.76978002 -1.9293 0 P 0 
L 0.76978002 -1.9293 0.77106998 -1.93193996 0 P 0 
L 0.77106998 -1.93193996 0.77253002 -1.93448002 0 P 0 
L 0.77253002 -1.93448002 0.77416004 -1.93693996 0 P 0 
L 0.77416004 -1.93693996 0.77593002 -1.93923002 0 P 0 
L 0.77593002 -1.93923002 0.77783996 -1.94141004 0 P 0 
L 0.77783996 -1.94141004 0.77988996 -1.94345 0 P 0 
L 0.77988996 -1.94345 0.78216004 -1.94545 0 P 0 
L 0.78216004 -1.94545 0.78453996 -1.9473 0 P 0 
L 0.78453996 -1.9473 0.78703002 -1.94901998 0 P 0 
L 0.78703002 -1.94901998 0.79016998 -1.95088002 0 P 0 
L 0.79016998 -1.95088002 0.79343996 -1.95248996 0 P 0 
L 0.79343996 -1.95248996 0.79683002 -1.95383996 0 P 0 
L 0.79683002 -1.95383996 0.80031998 -1.95491998 0 P 0 
L 0.80031998 -1.95491998 0.80391004 -1.95573996 0 P 0 
L 0.80391004 -1.95573996 0.80751998 -1.95626004 0 P 0 
L 0.80751998 -1.95626004 0.81116004 -1.9565 0 P 0 
L 0.81116004 -1.9565 0.81481004 -1.95646004 0 P 0 
L 0.81481004 -1.95646004 0.81843996 -1.95613002 0 P 0 
L 0.81843996 -1.95613002 0.82205 -1.95551004 0 P 0 
L 0.82205 -1.95551004 0.82561998 -1.95461004 0 P 0 
L 0.82561998 -1.95461004 0.82911004 -1.95345 0 P 0 
L 0.82911004 -1.95345 0.83248996 -1.95201004 0 P 0 
L 0.83248996 -1.95201004 0.83576004 -1.95031998 0 P 0 
L 0.83576004 -1.95031998 0.83891998 -1.94836004 0 P 0 
L 0.83891998 -1.94836004 0.84191998 -1.94616998 0 P 0 
L 0.84191998 -1.94616998 0.84475 -1.94375 0 P 0 
L 0.84475 -1.94375 0.84738996 -1.94113996 0 P 0 
L 0.84738996 -1.94113996 0.84983002 -1.93833996 0 P 0 
L 0.84983002 -1.93833996 0.85206998 -1.93533996 0 P 0 
L 0.85206998 -1.93533996 0.8536 -1.93291998 0 P 0 
L 0.8536 -1.93291998 0.85496004 -1.93041004 0 P 0 
L 0.85496004 -1.93041004 0.85613996 -1.9278 0 P 0 
L 0.85613996 -1.9278 0.85711998 -1.92511004 0 P 0 
L 0.85711998 -1.92511004 0.85823002 -1.92123002 0 P 0 
L 0.85823002 -1.92123002 0.85901998 -1.91726998 0 P 0 
L 0.85901998 -1.91726998 0.85948996 -1.91323996 0 P 0 
L 0.85948996 -1.91323996 0.85963996 -1.90918002 0 P 0 
L 0.85963996 -1.90918002 0.85946998 -1.90513002 0 P 0 
L 0.85946998 -1.90513002 0.85898002 -1.9011 0 P 0 
L 0.85898002 -1.9011 0.85841998 -1.89826004 0 P 0 
L 0.85841998 -1.89826004 0.85766004 -1.89546004 0 P 0 
L 0.85766004 -1.89546004 0.85671004 -1.89273002 0 P 0 
L 0.85671004 -1.89273002 0.85556998 -1.89006004 0 P 0 
L 0.85556998 -1.89006004 0.85361998 -1.88631004 0 P 0 
L 0.85361998 -1.88631004 0.85136004 -1.88273996 0 P 0 
L 0.85136004 -1.88273996 0.84881004 -1.87938002 0 P 0 
L 0.84881004 -1.87938002 0.84596998 -1.87623002 0 P 0 
L 0.84596998 -1.87623002 0.84355 -1.87393996 0 P 0 
L 0.84355 -1.87393996 0.84096998 -1.87181998 0 P 0 
L 0.84096998 -1.87181998 0.83826004 -1.86988996 0 P 0 
L 0.83826004 -1.86988996 0.83541004 -1.86815 0 P 0 
L 0.83541004 -1.86815 0.83243996 -1.86661004 0 P 0 
L 0.83243996 -1.86661004 0.82938996 -1.86531004 0 P 0 
L 0.82938996 -1.86531004 0.82625 -1.86423002 0 P 0 
L 0.82625 -1.86423002 0.82303996 -1.86336004 0 P 0 
L 0.82303996 -1.86336004 0.81978002 -1.86273002 0 P 0 
L 0.81978002 -1.86273002 0.81646998 -1.86233002 0 P 0 
L 0.81646998 -1.86233002 0.81228996 -1.86215 0 P 0 
L 0.81228996 -1.86215 0.80811004 -1.86233996 0 P 0 
L 0.80811004 -1.86233996 0.80396004 -1.86288996 0 P 0 
L 0.80396004 -1.86288996 0.79986004 -1.8638 0 P 0 
L 0.80308996 -1.9535 0.82186004 -1.9535 0 P 0 
L 0.79926004 -1.9525 0.82563996 -1.9525 0 P 0 
L 0.79636004 -1.9515 0.82856998 -1.9515 0 P 0 
L 0.79393002 -1.9505 0.83093996 -1.9505 0 P 0 
L 0.7919 -1.9495 0.83298996 -1.9495 0 P 0 
L 0.79008002 -1.9485 0.8349 -1.9485 0 P 0 
L 0.78838996 -1.9475 0.83651004 -1.9475 0 P 0 
L 0.7869 -1.9465 0.83806998 -1.9465 0 P 0 
L 0.78548002 -1.9455 0.83943996 -1.9455 0 P 0 
L 0.7842 -1.9445 0.84078996 -1.9445 0 P 0 
L 0.78298002 -1.9435 0.84196998 -1.9435 0 P 0 
L 0.78183996 -1.9425 0.84313996 -1.9425 0 P 0 
L 0.78076998 -1.9415 0.84418996 -1.9415 0 P 0 
L 0.77976004 -1.9405 0.8452 -1.9405 0 P 0 
L 0.77883002 -1.9395 0.84616998 -1.9395 0 P 0 
L 0.77793996 -1.9385 0.84703996 -1.9385 0 P 0 
L 0.77711998 -1.9375 0.84791004 -1.9375 0 P 0 
L 0.77635 -1.9365 0.84871004 -1.9365 0 P 0 
L 0.77561004 -1.9355 0.84945 -1.9355 0 P 0 
L 0.77493996 -1.9345 0.8502 -1.9345 0 P 0 
L 0.77428002 -1.9335 0.85086998 -1.9335 0 P 0 
L 0.7737 -1.9325 0.8515 -1.9325 0 P 0 
L 0.77311998 -1.9315 0.8521 -1.9315 0 P 0 
L 0.77258996 -1.9305 0.85263996 -1.9305 0 P 0 
L 0.7721 -1.9295 0.85318002 -1.9295 0 P 0 
L 0.77161004 -1.9285 0.85363002 -1.9285 0 P 0 
L 0.77121004 -1.9275 0.85408002 -1.9275 0 P 0 
L 0.77081004 -1.9265 0.85448002 -1.9265 0 P 0 
L 0.77041004 -1.9255 0.85485 -1.9255 0 P 0 
L 0.77001004 -1.9245 0.85521998 -1.9245 0 P 0 
L 0.76968002 -1.9235 0.8555 -1.9235 0 P 0 
L 0.76936998 -1.9225 0.85578996 -1.9225 0 P 0 
L 0.76906004 -1.9215 0.85606998 -1.9215 0 P 0 
L 0.76875 -1.9205 0.85633002 -1.9205 0 P 0 
L 0.76848002 -1.9195 0.85653002 -1.9195 0 P 0 
L 0.76826004 -1.9185 0.85673002 -1.9185 0 P 0 
L 0.76803002 -1.9175 0.85693002 -1.9175 0 P 0 
L 0.76783002 -1.9165 0.85708996 -1.9165 0 P 0 
L 0.76768996 -1.9155 0.85721004 -1.9155 0 P 0 
L 0.76755 -1.9145 0.85733002 -1.9145 0 P 0 
L 0.76741998 -1.9135 0.85745 -1.9135 0 P 0 
L 0.81121004 -1.9545 0.80773002 -1.95426998 0 P 0 
L 0.80773002 -1.95426998 0.80426998 -1.95376998 0 P 0 
L 0.80426998 -1.95376998 0.80083996 -1.95298996 0 P 0 
L 0.80083996 -1.95298996 0.7975 -1.95195 0 P 0 
L 0.7975 -1.95195 0.79426004 -1.95066004 0 P 0 
L 0.79426004 -1.95066004 0.79111998 -1.94911998 0 P 0 
L 0.79111998 -1.94911998 0.78811004 -1.94733002 0 P 0 
L 0.78811004 -1.94733002 0.78573002 -1.94568996 0 P 0 
L 0.78573002 -1.94568996 0.78343996 -1.9439 0 P 0 
L 0.78343996 -1.9439 0.78126004 -1.94198996 0 P 0 
L 0.78126004 -1.94198996 0.7793 -1.94003996 0 P 0 
L 0.7793 -1.94003996 0.77746998 -1.93796004 0 P 0 
L 0.77746998 -1.93796004 0.77578996 -1.93576998 0 P 0 
L 0.77578996 -1.93576998 0.77423002 -1.93343002 0 P 0 
L 0.77423002 -1.93343002 0.77283996 -1.931 0 P 0 
L 0.77283996 -1.931 0.77161004 -1.92848996 0 P 0 
L 0.77161004 -1.92848996 0.76991998 -1.92426998 0 P 0 
L 0.76991998 -1.92426998 0.76858002 -1.91993996 0 P 0 
L 0.76858002 -1.91993996 0.76783996 -1.91661998 0 P 0 
L 0.76783996 -1.91661998 0.76738002 -1.91326998 0 P 0 
L 0.76738002 -1.91326998 0.76721004 -1.90988996 0 P 0 
L 0.76721004 -1.90988996 0.76731004 -1.90651004 0 P 0 
L 0.76731004 -1.90651004 0.7677 -1.90315 0 P 0 
L 0.7677 -1.90315 0.76838002 -1.89966998 0 P 0 
L 0.76838002 -1.89966998 0.76931004 -1.89626998 0 P 0 
L 0.76931004 -1.89626998 0.7705 -1.89296004 0 P 0 
L 0.7705 -1.89296004 0.77193996 -1.88973996 0 P 0 
L 0.77193996 -1.88973996 0.7736 -1.88663996 0 P 0 
L 0.7736 -1.88663996 0.77551004 -1.88363996 0 P 0 
L 0.77551004 -1.88363996 0.77763002 -1.8808 0 P 0 
L 0.77763002 -1.8808 0.77996004 -1.87813002 0 P 0 
L 0.77996004 -1.87813002 0.78246998 -1.87565 0 P 0 
L 0.78246998 -1.87565 0.78516004 -1.87336004 0 P 0 
L 0.78516004 -1.87336004 0.78795 -1.87133996 0 P 0 
L 0.78795 -1.87133996 0.79088002 -1.86956004 0 P 0 
L 0.79088002 -1.86956004 0.79393996 -1.86803002 0 P 0 
L 0.79393996 -1.86803002 0.79711004 -1.86675 0 P 0 
L 0.79711004 -1.86675 0.80038002 -1.86573002 0 P 0 
L 0.80038002 -1.86573002 0.80431004 -1.86486004 0 P 0 
L 0.80431004 -1.86486004 0.80828996 -1.86433996 0 P 0 
L 0.80828996 -1.86433996 0.8123 -1.86416004 0 P 0 
L 0.8123 -1.86416004 0.81631004 -1.86431998 0 P 0 
L 0.81631004 -1.86431998 0.81946998 -1.86471004 0 P 0 
L 0.81946998 -1.86471004 0.82258996 -1.86531004 0 P 0 
L 0.82258996 -1.86531004 0.82566004 -1.86613996 0 P 0 
L 0.82566004 -1.86613996 0.82866998 -1.86718002 0 P 0 
L 0.82866998 -1.86718002 0.83158996 -1.86843002 0 P 0 
L 0.83158996 -1.86843002 0.83443002 -1.86988996 0 P 0 
L 0.83443002 -1.86988996 0.83716004 -1.87156004 0 P 0 
L 0.83716004 -1.87156004 0.83976004 -1.87341004 0 P 0 
L 0.83976004 -1.87341004 0.84223002 -1.87543996 0 P 0 
L 0.84223002 -1.87543996 0.84453996 -1.87763002 0 P 0 
L 0.84453996 -1.87763002 0.84726998 -1.88065 0 P 0 
L 0.84726998 -1.88065 0.84971998 -1.88388002 0 P 0 
L 0.84971998 -1.88388002 0.85188996 -1.88731004 0 P 0 
L 0.85188996 -1.88731004 0.85376004 -1.89091004 0 P 0 
L 0.85376004 -1.89091004 0.85483996 -1.89345 0 P 0 
L 0.85483996 -1.89345 0.85575 -1.89605 0 P 0 
L 0.85575 -1.89605 0.85646998 -1.89871004 0 P 0 
L 0.85646998 -1.89871004 0.857 -1.90141004 0 P 0 
L 0.857 -1.90141004 0.85748002 -1.9053 0 P 0 
L 0.85748002 -1.9053 0.85763996 -1.90918996 0 P 0 
L 0.85763996 -1.90918996 0.8575 -1.91308002 0 P 0 
L 0.8575 -1.91308002 0.85703996 -1.91696004 0 P 0 
L 0.85703996 -1.91696004 0.85628002 -1.92076004 0 P 0 
L 0.85628002 -1.92076004 0.85521998 -1.92448996 0 P 0 
L 0.85521998 -1.92448996 0.85428002 -1.92705 0 P 0 
L 0.85428002 -1.92705 0.85316998 -1.92951998 0 P 0 
L 0.85316998 -1.92951998 0.85188002 -1.93191004 0 P 0 
L 0.85188002 -1.93191004 0.85041998 -1.9342 0 P 0 
L 0.85041998 -1.9342 0.84826998 -1.93708002 0 P 0 
L 0.84826998 -1.93708002 0.84593002 -1.93976998 0 P 0 
L 0.84593002 -1.93976998 0.8434 -1.94228002 0 P 0 
L 0.8434 -1.94228002 0.84068002 -1.9446 0 P 0 
L 0.84068002 -1.9446 0.8378 -1.9467 0 P 0 
L 0.8378 -1.9467 0.83476998 -1.94858002 0 P 0 
L 0.83476998 -1.94858002 0.83163996 -1.9502 0 P 0 
L 0.83163996 -1.9502 0.8284 -1.95158002 0 P 0 
L 0.8284 -1.95158002 0.82506004 -1.95268996 0 P 0 
L 0.82506004 -1.95268996 0.82163996 -1.95356004 0 P 0 
L 0.82163996 -1.95356004 0.81818002 -1.95413996 0 P 0 
L 0.81818002 -1.95413996 0.8147 -1.95446004 0 P 0 
L 0.8147 -1.95446004 0.81121004 -1.9545 0 P 0 
L 0.77075 -2.02925 0.84511004 -2.02925 0 P 0 
L 0.77076004 -2.02825 0.8452 -2.02825 0 P 0 
L 0.77076998 -2.02725 0.84528996 -2.02725 0 P 0 
L 0.77078002 -2.02625 0.84536998 -2.02625 0 P 0 
L 0.77078996 -2.02525 0.84548996 -2.02525 0 P 0 
L 0.7708 -2.02425 0.84561998 -2.02425 0 P 0 
L 0.77081004 -2.02325 0.84575 -2.02325 0 P 0 
L 0.77081998 -2.02225 0.84588002 -2.02225 0 P 0 
L 0.77083002 -2.02125 0.84601004 -2.02125 0 P 0 
L 0.77083996 -2.02025 0.84613996 -2.02025 0 P 0 
L 0.77085 -2.01925 0.84626004 -2.01925 0 P 0 
L 0.77085 -2.01825 0.84638996 -2.01825 0 P 0 
L 0.77085 -2.01725 0.84651998 -2.01725 0 P 0 
L 0.77086004 -2.01625 0.84663996 -2.01625 0 P 0 
L 0.77086004 -2.01525 0.84676998 -2.01525 0 P 0 
L 0.77086004 -2.01425 0.8469 -2.01425 0 P 0 
L 0.77086004 -2.01325 0.84703002 -2.01325 0 P 0 
L 0.77086004 -2.01225 0.84716004 -2.01225 0 P 0 
L 0.77086004 -2.01125 0.84728996 -2.01125 0 P 0 
L 0.77086004 -2.01025 0.84741004 -2.01025 0 P 0 
L 0.77086998 -2.00925 0.84753996 -2.00925 0 P 0 
L 0.77086998 -2.00825 0.84766998 -2.00825 0 P 0 
L 0.77086998 -2.00725 0.84778996 -2.00725 0 P 0 
L 0.77086998 -2.00625 0.84791998 -2.00625 0 P 0 
L 0.77086998 -2.00525 0.84805 -2.00525 0 P 0 
L 0.77086998 -2.00425 0.84818002 -2.00425 0 P 0 
L 0.77088002 -2.00325 0.84831004 -2.00325 0 P 0 
L 0.77088002 -2.00225 0.84843996 -2.00225 0 P 0 
L 0.77088002 -2.00125 0.84856004 -2.00125 0 P 0 
L 0.77088002 -2.00025 0.84868996 -2.00025 0 P 0 
L 0.77088002 -1.99925 0.84881998 -1.99925 0 P 0 
L 0.77088002 -1.99825 0.84896004 -1.99825 0 P 0 
L 0.77088002 -1.99725 0.84911004 -1.99725 0 P 0 
L 0.77088996 -1.99625 0.84926998 -1.99625 0 P 0 
L 0.77088996 -1.99525 0.84941998 -1.99525 0 P 0 
L 0.77088996 -1.99425 0.84956998 -1.99425 0 P 0 
L 0.77088996 -1.99325 0.84971998 -1.99325 0 P 0 
L 0.77088996 -1.99225 0.84986998 -1.99225 0 P 0 
L 0.77088996 -1.99125 0.85003002 -1.99125 0 P 0 
L 0.7709 -1.99025 0.85018002 -1.99025 0 P 0 
L 0.7709 -1.98925 0.85033002 -1.98925 0 P 0 
L 0.76885 -2.01878002 0.76871998 -2.03201998 0 P 0 
L 0.76871998 -2.03201998 0.7684 -2.04553996 0 P 0 
L 0.7684 -2.04553996 0.76796004 -2.05751004 0 P 0 
L 0.76796004 -2.05751004 0.76741004 -2.06523002 0 P 0 
L 0.76741004 -2.06523002 0.76596004 -2.07933996 0 P 0 
L 0.76596004 -2.07933996 0.7636 -2.09918002 0 P 0 
L 0.7636 -2.09918002 0.76116004 -2.119 0 P 0 
L 0.76116004 -2.119 0.76011998 -2.12526004 0 P 0 
L 0.76011998 -2.12526004 0.75948996 -2.12825 0 P 0 
L 0.75948996 -2.12825 0.84418002 -2.12825 0 P 0 
L 0.84418002 -2.12825 0.84361998 -2.10788002 0 P 0 
L 0.84361998 -2.10788002 0.8436 -2.08276004 0 P 0 
L 0.8436 -2.08276004 0.8449 -2.05491998 0 P 0 
L 0.8449 -2.05491998 0.84736004 -2.02641004 0 P 0 
L 0.84736004 -2.02641004 0.85083996 -1.99923002 0 P 0 
L 0.85083996 -1.99923002 0.85268996 -1.987 0 P 0 
L 0.85268996 -1.987 0.7689 -1.987 0 P 0 
L 0.7689 -1.987 0.76885 -2.01878002 0 P 0 
L 0.76195 -2.12625 0.84211998 -2.12625 0 P 0 
L 0.76213996 -2.12525 0.8421 -2.12525 0 P 0 
L 0.76231004 -2.12425 0.84206998 -2.12425 0 P 0 
L 0.76248002 -2.12325 0.84203996 -2.12325 0 P 0 
L 0.76263996 -2.12225 0.84201004 -2.12225 0 P 0 
L 0.76281004 -2.12125 0.84198996 -2.12125 0 P 0 
L 0.76296998 -2.12025 0.84196004 -2.12025 0 P 0 
L 0.76313996 -2.11925 0.84193002 -2.11925 0 P 0 
L 0.76326998 -2.11825 0.8419 -2.11825 0 P 0 
L 0.76338996 -2.11725 0.84188002 -2.11725 0 P 0 
L 0.76351004 -2.11625 0.84185 -2.11625 0 P 0 
L 0.76363996 -2.11525 0.84181998 -2.11525 0 P 0 
L 0.76376004 -2.11425 0.84178996 -2.11425 0 P 0 
L 0.76388002 -2.11325 0.84176998 -2.11325 0 P 0 
L 0.76401004 -2.11225 0.84173996 -2.11225 0 P 0 
L 0.76413002 -2.11125 0.84171004 -2.11125 0 P 0 
L 0.76425 -2.11025 0.84168002 -2.11025 0 P 0 
L 0.76438002 -2.10925 0.84166004 -2.10925 0 P 0 
L 0.7645 -2.10825 0.84163002 -2.10825 0 P 0 
L 0.76461998 -2.10725 0.84161998 -2.10725 0 P 0 
L 0.76475 -2.10625 0.84161998 -2.10625 0 P 0 
L 0.76486998 -2.10525 0.84161998 -2.10525 0 P 0 
L 0.76498996 -2.10425 0.84161998 -2.10425 0 P 0 
L 0.76511998 -2.10325 0.84161998 -2.10325 0 P 0 
L 0.76523996 -2.10225 0.84161998 -2.10225 0 P 0 
L 0.76536004 -2.10125 0.84161998 -2.10125 0 P 0 
L 0.76548996 -2.10025 0.84161998 -2.10025 0 P 0 
L 0.76561004 -2.09925 0.84161998 -2.09925 0 P 0 
L 0.76573002 -2.09825 0.84161004 -2.09825 0 P 0 
L 0.76583996 -2.09725 0.84161004 -2.09725 0 P 0 
L 0.76596998 -2.09625 0.84161004 -2.09625 0 P 0 
L 0.76608996 -2.09525 0.84161004 -2.09525 0 P 0 
L 0.7662 -2.09425 0.84161004 -2.09425 0 P 0 
L 0.76631998 -2.09325 0.84161004 -2.09325 0 P 0 
L 0.76643996 -2.09225 0.84161004 -2.09225 0 P 0 
L 0.76656004 -2.09125 0.84161004 -2.09125 0 P 0 
L 0.76668002 -2.09025 0.84161004 -2.09025 0 P 0 
L 0.76678996 -2.08925 0.84161004 -2.08925 0 P 0 
L 0.76691998 -2.08825 0.84161004 -2.08825 0 P 0 
L 0.76703002 -2.08725 0.84161004 -2.08725 0 P 0 
L 0.76715 -2.08625 0.8416 -2.08625 0 P 0 
L 0.76726998 -2.08525 0.8416 -2.08525 0 P 0 
L 0.76738996 -2.08425 0.8416 -2.08425 0 P 0 
L 0.76195 -2.12625 0.76208002 -2.12561998 0 P 0 
L 0.76208002 -2.12561998 0.76313996 -2.11928996 0 P 0 
L 0.76313996 -2.11928996 0.76558996 -2.09941998 0 P 0 
L 0.76558996 -2.09941998 0.76558996 -2.09941004 0 P 0 
L 0.76558996 -2.09941004 0.76793996 -2.07956004 0 P 0 
L 0.76793996 -2.07956004 0.7694 -2.0654 0 P 0 
L 0.7694 -2.0654 0.76941004 -2.06536004 0 P 0 
L 0.76941004 -2.06536004 0.76996004 -2.05761998 0 P 0 
L 0.76996004 -2.05761998 0.76996004 -2.05758996 0 P 0 
L 0.76996004 -2.05758996 0.7704 -2.0456 0 P 0 
L 0.7704 -2.0456 0.77071998 -2.03206004 0 P 0 
L 0.77071998 -2.03206004 0.77085 -2.01878002 0 P 0 
L 0.77085 -2.01878002 0.7709 -1.989 0 P 0 
L 0.7709 -1.989 0.85036004 -1.989 0 P 0 
L 0.85036004 -1.989 0.84886004 -1.99895 0 P 0 
L 0.84886004 -1.99895 0.84538002 -2.02618996 0 P 0 
L 0.84538002 -2.02618996 0.8429 -2.05478996 0 P 0 
L 0.8429 -2.05478996 0.8416 -2.08271004 0 P 0 
L 0.8416 -2.08271004 0.84161998 -2.10791004 0 P 0 
L 0.84161998 -2.10791004 0.84211998 -2.12625 0 P 0 
L 0.84211998 -2.12625 0.76195 -2.12625 0 P 0 
L 0.71628996 -1.91261998 0.74938002 -1.91261998 0 P 0 
L 0.71783002 -1.91161998 0.74933002 -1.91161998 0 P 0 
L 0.71953002 -1.91061998 0.74931004 -1.91061998 0 P 0 
L 0.72133002 -1.90961998 0.74928996 -1.90961998 0 P 0 
L 0.72313996 -1.90861998 0.74926998 -1.90861998 0 P 0 
L 0.72493996 -1.90761998 0.74928996 -1.90761998 0 P 0 
L 0.72673996 -1.90661998 0.74931998 -1.90661998 0 P 0 
L 0.72855 -1.90561998 0.74935 -1.90561998 0 P 0 
L 0.73035 -1.90461998 0.74938996 -1.90461998 0 P 0 
L 0.73215 -1.90361998 0.74946998 -1.90361998 0 P 0 
L 0.73396004 -1.90261998 0.74953996 -1.90261998 0 P 0 
L 0.73576004 -1.90161998 0.74961998 -1.90161998 0 P 0 
L 0.73756998 -1.90061998 0.74973996 -1.90061998 0 P 0 
L 0.73943002 -1.89961998 0.74986004 -1.89961998 0 P 0 
L 0.74141998 -1.89861998 0.74998996 -1.89861998 0 P 0 
L 0.74341004 -1.89761998 0.75015 -1.89761998 0 P 0 
L 0.59843002 -2.08361998 0.6754 -2.08361998 0 P 0 
L 0.59846004 -2.08261998 0.67538996 -2.08261998 0 P 0 
L 0.59848002 -2.08161998 0.67538002 -2.08161998 0 P 0 
L 0.59851004 -2.08061998 0.67538002 -2.08061998 0 P 0 
L 0.59853002 -2.07961998 0.67546004 -2.07961998 0 P 0 
L 0.59856004 -2.07861998 0.67553996 -2.07861998 0 P 0 
L 0.59861998 -2.07761998 0.67561004 -2.07761998 0 P 0 
L 0.5987 -2.07661998 0.67568996 -2.07661998 0 P 0 
L 0.59878002 -2.07561998 0.67576004 -2.07561998 0 P 0 
L 0.59885 -2.07461998 0.67583996 -2.07461998 0 P 0 
L 0.59893002 -2.07361998 0.67591998 -2.07361998 0 P 0 
L 0.59901004 -2.07261998 0.67598996 -2.07261998 0 P 0 
L 0.59908002 -2.07161998 0.67606998 -2.07161998 0 P 0 
L 0.59916004 -2.07061998 0.67613996 -2.07061998 0 P 0 
L 0.59923002 -2.06961998 0.67621004 -2.06961998 0 P 0 
L 0.59936004 -2.06861998 0.6763 -2.06861998 0 P 0 
L 0.59948996 -2.06761998 0.67645 -2.06761998 0 P 0 
L 0.59963002 -2.06661998 0.6766 -2.06661998 0 P 0 
L 0.59976998 -2.06561998 0.67676004 -2.06561998 0 P 0 
L 0.5999 -2.06461998 0.67691998 -2.06461998 0 P 0 
L 0.60003002 -2.06361998 0.67706998 -2.06361998 0 P 0 
L 0.60016998 -2.06261998 0.6773 -2.06261998 0 P 0 
L 0.60031004 -2.06161998 0.67753002 -2.06161998 0 P 0 
L 0.60051004 -2.06061998 0.67776004 -2.06061998 0 P 0 
L 0.60071004 -2.05961998 0.67798996 -2.05961998 0 P 0 
L 0.60091998 -2.05861998 0.67823002 -2.05861998 0 P 0 
L 0.60111998 -2.05761998 0.67853002 -2.05761998 0 P 0 
L 0.60133002 -2.05661998 0.67883996 -2.05661998 0 P 0 
L 0.60153996 -2.05561998 0.67913996 -2.05561998 0 P 0 
L 0.60173996 -2.05461998 0.67945 -2.05461998 0 P 0 
L 0.60195 -2.05361998 0.67975 -2.05361998 0 P 0 
L 0.60223002 -2.05261998 0.68006004 -2.05261998 0 P 0 
L 0.60251004 -2.05161998 0.68036004 -2.05161998 0 P 0 
L 0.60278996 -2.05061998 0.68066998 -2.05061998 0 P 0 
L 0.60306004 -2.04961998 0.68096998 -2.04961998 0 P 0 
L 0.60333996 -2.04861998 0.68135 -2.04861998 0 P 0 
L 0.60361998 -2.04761998 0.68173002 -2.04761998 0 P 0 
L 0.6039 -2.04661998 0.68211004 -2.04661998 0 P 0 
L 0.60418002 -2.04561998 0.68248996 -2.04561998 0 P 0 
L 0.60453002 -2.04461998 0.68288002 -2.04461998 0 P 0 
L 0.60488002 -2.04361998 0.68326004 -2.04361998 0 P 0 
L 0.60523002 -2.04261998 0.68363996 -2.04261998 0 P 0 
L 0.60556998 -2.04161998 0.68401998 -2.04161998 0 P 0 
L 0.60591998 -2.04061998 0.6844 -2.04061998 0 P 0 
L 0.60626998 -2.03961998 0.68486004 -2.03961998 0 P 0 
L 0.60661998 -2.03861998 0.68531998 -2.03861998 0 P 0 
L 0.60698996 -2.03761998 0.68578002 -2.03761998 0 P 0 
L 0.60743002 -2.03661998 0.68623996 -2.03661998 0 P 0 
L 0.60786004 -2.03561998 0.6867 -2.03561998 0 P 0 
L 0.60828996 -2.03461998 0.68716004 -2.03461998 0 P 0 
L 0.60873002 -2.03361998 0.68761998 -2.03361998 0 P 0 
L 0.60916004 -2.03261998 0.68808996 -2.03261998 0 P 0 
L 0.60958996 -2.03161998 0.68856998 -2.03161998 0 P 0 
L 0.61003002 -2.03061998 0.68911004 -2.03061998 0 P 0 
L 0.61046004 -2.02961998 0.68965 -2.02961998 0 P 0 
L 0.61088996 -2.02861998 0.69018996 -2.02861998 0 P 0 
L 0.61133002 -2.02761998 0.69073002 -2.02761998 0 P 0 
L 0.61176004 -2.02661998 0.69126998 -2.02661998 0 P 0 
L 0.6122 -2.02561998 0.69181004 -2.02561998 0 P 0 
L 0.61263002 -2.02461998 0.69235 -2.02461998 0 P 0 
L 0.61306004 -2.02361998 0.69288002 -2.02361998 0 P 0 
L 0.61348996 -2.02261998 0.69346998 -2.02261998 0 P 0 
L 0.61393002 -2.02161998 0.69408996 -2.02161998 0 P 0 
L 0.61436004 -2.02061998 0.6947 -2.02061998 0 P 0 
L 0.61478996 -2.01961998 0.69531998 -2.01961998 0 P 0 
L 0.61531004 -2.01861998 0.69593996 -2.01861998 0 P 0 
L 0.61583996 -2.01761998 0.69656004 -2.01761998 0 P 0 
L 0.61636004 -2.01661998 0.69718002 -2.01661998 0 P 0 
L 0.61688002 -2.01561998 0.69778996 -2.01561998 0 P 0 
L 0.6174 -2.01461998 0.69841998 -2.01461998 0 P 0 
L 0.61791998 -2.01361998 0.69911998 -2.01361998 0 P 0 
L 0.61843996 -2.01261998 0.69981998 -2.01261998 0 P 0 
L 0.61896004 -2.01161998 0.70051998 -2.01161998 0 P 0 
L 0.61948002 -2.01061998 0.70123002 -2.01061998 0 P 0 
L 0.62 -2.00961998 0.70193002 -2.00961998 0 P 0 
L 0.62051998 -2.00861998 0.70263002 -2.00861998 0 P 0 
L 0.62103996 -2.00761998 0.70333002 -2.00761998 0 P 0 
L 0.62163996 -2.00661998 0.70403996 -2.00661998 0 P 0 
L 0.62225 -2.00561998 0.70483002 -2.00561998 0 P 0 
L 0.62285 -2.00461998 0.70565 -2.00461998 0 P 0 
L 0.62346004 -2.00361998 0.70646004 -2.00361998 0 P 0 
L 0.62406004 -2.00261998 0.70726998 -2.00261998 0 P 0 
L 0.62466004 -2.00161998 0.70808996 -2.00161998 0 P 0 
L 0.62526998 -2.00061998 0.7089 -2.00061998 0 P 0 
L 0.62586998 -1.99961998 0.70971004 -1.99961998 0 P 0 
L 0.62648002 -1.99861998 0.71053002 -1.99861998 0 P 0 
L 0.62708002 -1.99761998 0.71133996 -1.99761998 0 P 0 
L 0.62768996 -1.99661998 0.71216004 -1.99661998 0 P 0 
L 0.62831998 -1.99561998 0.71296998 -1.99561998 0 P 0 
L 0.62901004 -1.99461998 0.71378996 -1.99461998 0 P 0 
L 0.62971004 -1.99361998 0.71466004 -1.99361998 0 P 0 
L 0.6304 -1.99261998 0.71561004 -1.99261998 0 P 0 
L 0.6311 -1.99161998 0.71656998 -1.99161998 0 P 0 
L 0.63178996 -1.99061998 0.71753002 -1.99061998 0 P 0 
L 0.63248996 -1.98961998 0.71848996 -1.98961998 0 P 0 
L 0.63318002 -1.98861998 0.71945 -1.98861998 0 P 0 
L 0.63388002 -1.98761998 0.72041004 -1.98761998 0 P 0 
L 0.63456998 -1.98661998 0.72136998 -1.98661998 0 P 0 
L 0.63526998 -1.98561998 0.72233002 -1.98561998 0 P 0 
L 0.63598002 -1.98461998 0.72328996 -1.98461998 0 P 0 
L 0.63678996 -1.98361998 0.72425 -1.98361998 0 P 0 
L 0.6376 -1.98261998 0.72521004 -1.98261998 0 P 0 
L 0.63841004 -1.98161998 0.72628002 -1.98161998 0 P 0 
L 0.63921998 -1.98061998 0.72738996 -1.98061998 0 P 0 
L 0.64003002 -1.97961998 0.7285 -1.97961998 0 P 0 
L 0.64083996 -1.97861998 0.72961004 -1.97861998 0 P 0 
L 0.64165 -1.97761998 0.73071004 -1.97761998 0 P 0 
L 0.64246004 -1.97661998 0.73181998 -1.97661998 0 P 0 
L 0.64326998 -1.97561998 0.73293002 -1.97561998 0 P 0 
L 0.64406998 -1.97461998 0.73403996 -1.97461998 0 P 0 
L 0.64488002 -1.97361998 0.73515 -1.97361998 0 P 0 
L 0.64568996 -1.97261998 0.73625 -1.97261998 0 P 0 
L 0.6465 -1.97161998 0.73736004 -1.97161998 0 P 0 
L 0.64731004 -1.97061998 0.73848002 -1.97061998 0 P 0 
L 0.64811998 -1.96961998 0.73973002 -1.96961998 0 P 0 
L 0.64893002 -1.96861998 0.74098996 -1.96861998 0 P 0 
L 0.64981004 -1.96761998 0.74225 -1.96761998 0 P 0 
L 0.65076004 -1.96661998 0.74351004 -1.96661998 0 P 0 
L 0.65171004 -1.96561998 0.74476998 -1.96561998 0 P 0 
L 0.65266998 -1.96461998 0.74603002 -1.96461998 0 P 0 
L 0.65361998 -1.96361998 0.74728996 -1.96361998 0 P 0 
L 0.65458002 -1.96261998 0.74855 -1.96261998 0 P 0 
L 0.65553002 -1.96161998 0.74981004 -1.96161998 0 P 0 
L 0.65648996 -1.96061998 0.75106004 -1.96061998 0 P 0 
L 0.65743996 -1.95961998 0.75233996 -1.95961998 0 P 0 
L 0.6584 -1.95861998 0.7537 -1.95861998 0 P 0 
L 0.65935 -1.95761998 0.75506004 -1.95761998 0 P 0 
L 0.66031004 -1.95661998 0.75641998 -1.95661998 0 P 0 
L 0.66126004 -1.95561998 0.75778996 -1.95561998 0 P 0 
L 0.66221004 -1.95461998 0.75916004 -1.95461998 0 P 0 
L 0.66316998 -1.95361998 0.76053996 -1.95361998 0 P 0 
L 0.66411998 -1.95261998 0.76193996 -1.95261998 0 P 0 
L 0.66523002 -1.95161998 0.76333996 -1.95161998 0 P 0 
L 0.66636004 -1.95061998 0.76406998 -1.95061998 0 P 0 
L 0.66746998 -1.94961998 0.76355 -1.94961998 0 P 0 
L 0.6686 -1.94861998 0.76291998 -1.94861998 0 P 0 
L 0.66971004 -1.94761998 0.76226998 -1.94761998 0 P 0 
L 0.67083996 -1.94661998 0.76161998 -1.94661998 0 P 0 
L 0.67196004 -1.94561998 0.76096998 -1.94561998 0 P 0 
L 0.67306998 -1.94461998 0.76033002 -1.94461998 0 P 0 
L 0.6742 -1.94361998 0.75968996 -1.94361998 0 P 0 
L 0.67531004 -1.94261998 0.75905 -1.94261998 0 P 0 
L 0.67643996 -1.94161998 0.75846004 -1.94161998 0 P 0 
L 0.67755 -1.94061998 0.75788996 -1.94061998 0 P 0 
L 0.67868002 -1.93961998 0.75731998 -1.93961998 0 P 0 
L 0.67978996 -1.93861998 0.75676998 -1.93861998 0 P 0 
L 0.68091998 -1.93761998 0.75626998 -1.93761998 0 P 0 
L 0.68221004 -1.93661998 0.75576998 -1.93661998 0 P 0 
L 0.68353002 -1.93561998 0.75528002 -1.93561998 0 P 0 
L 0.68483996 -1.93461998 0.75483996 -1.93461998 0 P 0 
L 0.68616004 -1.93361998 0.75441004 -1.93361998 0 P 0 
L 0.68746998 -1.93261998 0.75398002 -1.93261998 0 P 0 
L 0.68878002 -1.93161998 0.7536 -1.93161998 0 P 0 
L 0.6901 -1.93061998 0.75323996 -1.93061998 0 P 0 
L 0.69141004 -1.92961998 0.75286998 -1.92961998 0 P 0 
L 0.69271998 -1.92861998 0.75253996 -1.92861998 0 P 0 
L 0.69403002 -1.92761998 0.75223002 -1.92761998 0 P 0 
L 0.69535 -1.92661998 0.75193002 -1.92661998 0 P 0 
L 0.69666004 -1.92561998 0.75163002 -1.92561998 0 P 0 
L 0.69796998 -1.92461998 0.75138002 -1.92461998 0 P 0 
L 0.69936998 -1.92361998 0.75113996 -1.92361998 0 P 0 
L 0.70091004 -1.92261998 0.75088996 -1.92261998 0 P 0 
L 0.70243996 -1.92161998 0.75066004 -1.92161998 0 P 0 
L 0.70398002 -1.92061998 0.75046004 -1.92061998 0 P 0 
L 0.70551998 -1.91961998 0.75026004 -1.91961998 0 P 0 
L 0.70706004 -1.91861998 0.75006998 -1.91861998 0 P 0 
L 0.7086 -1.91761998 0.7499 -1.91761998 0 P 0 
L 0.71013996 -1.91661998 0.74976998 -1.91661998 0 P 0 
L 0.71166998 -1.91561998 0.74961998 -1.91561998 0 P 0 
L 0.71321004 -1.91461998 0.74951998 -1.91461998 0 P 0 
L 0.71475 -1.91361998 0.74945 -1.91361998 0 P 0 
L 0.61556998 -2.15661998 0.70655 -2.15661998 0 P 0 
L 0.61503002 -2.15561998 0.7056 -2.15561998 0 P 0 
L 0.61448996 -2.15461998 0.70465 -2.15461998 0 P 0 
L 0.61395 -2.15361998 0.7037 -2.15361998 0 P 0 
L 0.61341004 -2.15261998 0.70273996 -2.15261998 0 P 0 
L 0.61286998 -2.15161998 0.70178996 -2.15161998 0 P 0 
L 0.61233002 -2.15061998 0.70095 -2.15061998 0 P 0 
L 0.61188002 -2.14961998 0.70015 -2.14961998 0 P 0 
L 0.61143002 -2.14861998 0.69935 -2.14861998 0 P 0 
L 0.61098002 -2.14761998 0.69855 -2.14761998 0 P 0 
L 0.61053002 -2.14661998 0.69775 -2.14661998 0 P 0 
L 0.61008002 -2.14561998 0.69695 -2.14561998 0 P 0 
L 0.60963002 -2.14461998 0.69615 -2.14461998 0 P 0 
L 0.60918002 -2.14361998 0.69535 -2.14361998 0 P 0 
L 0.60873002 -2.14261998 0.69455 -2.14261998 0 P 0 
L 0.60831004 -2.14161998 0.69381998 -2.14161998 0 P 0 
L 0.60793996 -2.14061998 0.69315 -2.14061998 0 P 0 
L 0.60756998 -2.13961998 0.69248002 -2.13961998 0 P 0 
L 0.60721004 -2.13861998 0.69181004 -2.13861998 0 P 0 
L 0.60683996 -2.13761998 0.69115 -2.13761998 0 P 0 
L 0.60646998 -2.13661998 0.69048002 -2.13661998 0 P 0 
L 0.60611004 -2.13561998 0.68981004 -2.13561998 0 P 0 
L 0.60573996 -2.13461998 0.68918002 -2.13461998 0 P 0 
L 0.60538002 -2.13361998 0.68863002 -2.13361998 0 P 0 
L 0.60503996 -2.13261998 0.68808002 -2.13261998 0 P 0 
L 0.60476004 -2.13161998 0.68753002 -2.13161998 0 P 0 
L 0.60446998 -2.13061998 0.68698002 -2.13061998 0 P 0 
L 0.60418002 -2.12961998 0.68643002 -2.12961998 0 P 0 
L 0.6039 -2.12861998 0.68588002 -2.12861998 0 P 0 
L 0.60361004 -2.12761998 0.68533002 -2.12761998 0 P 0 
L 0.60331998 -2.12661998 0.68486004 -2.12661998 0 P 0 
L 0.60303002 -2.12561998 0.68441998 -2.12561998 0 P 0 
L 0.60275 -2.12461998 0.68396998 -2.12461998 0 P 0 
L 0.60246004 -2.12361998 0.68353002 -2.12361998 0 P 0 
L 0.60218002 -2.12261998 0.68308996 -2.12261998 0 P 0 
L 0.60188996 -2.12161998 0.68263996 -2.12161998 0 P 0 
L 0.60166998 -2.12061998 0.6822 -2.12061998 0 P 0 
L 0.60145 -2.11961998 0.68176004 -2.11961998 0 P 0 
L 0.60123002 -2.11861998 0.68138996 -2.11861998 0 P 0 
L 0.60101004 -2.11761998 0.68105 -2.11761998 0 P 0 
L 0.60078002 -2.11661998 0.68071004 -2.11661998 0 P 0 
L 0.6006 -2.11561998 0.68036004 -2.11561998 0 P 0 
L 0.60043002 -2.11461998 0.68001998 -2.11461998 0 P 0 
L 0.60025 -2.11361998 0.67968002 -2.11361998 0 P 0 
L 0.60008002 -2.11261998 0.67933002 -2.11261998 0 P 0 
L 0.59991004 -2.11161998 0.67898996 -2.11161998 0 P 0 
L 0.59976004 -2.11061998 0.6787 -2.11061998 0 P 0 
L 0.59963996 -2.10961998 0.67845 -2.10961998 0 P 0 
L 0.59951004 -2.10861998 0.6782 -2.10861998 0 P 0 
L 0.59938002 -2.10761998 0.67795 -2.10761998 0 P 0 
L 0.59925 -2.10661998 0.6777 -2.10661998 0 P 0 
L 0.59913002 -2.10561998 0.67746004 -2.10561998 0 P 0 
L 0.59905 -2.10461998 0.67721004 -2.10461998 0 P 0 
L 0.59896998 -2.10361998 0.67696004 -2.10361998 0 P 0 
L 0.59888002 -2.10261998 0.67671004 -2.10261998 0 P 0 
L 0.5988 -2.10161998 0.67653996 -2.10161998 0 P 0 
L 0.59871998 -2.10061998 0.67638002 -2.10061998 0 P 0 
L 0.59866998 -2.09961998 0.67621004 -2.09961998 0 P 0 
L 0.59863996 -2.09861998 0.67605 -2.09861998 0 P 0 
L 0.59861004 -2.09761998 0.67588996 -2.09761998 0 P 0 
L 0.59858996 -2.09661998 0.6758 -2.09661998 0 P 0 
L 0.59856004 -2.09561998 0.67571004 -2.09561998 0 P 0 
L 0.59853002 -2.09461998 0.67563002 -2.09461998 0 P 0 
L 0.5985 -2.09361998 0.67553996 -2.09361998 0 P 0 
L 0.59846998 -2.09261998 0.67546004 -2.09261998 0 P 0 
L 0.59843996 -2.09161998 0.67546004 -2.09161998 0 P 0 
L 0.59841998 -2.09061998 0.67545 -2.09061998 0 P 0 
L 0.59838002 -2.08961998 0.67543996 -2.08961998 0 P 0 
L 0.59836004 -2.08861998 0.67543002 -2.08861998 0 P 0 
L 0.59833002 -2.08761998 0.67543002 -2.08761998 0 P 0 
L 0.59835 -2.08661998 0.67541998 -2.08661998 0 P 0 
L 0.59836998 -2.08561998 0.67541004 -2.08561998 0 P 0 
L 0.5984 -2.08461998 0.67541004 -2.08461998 0 P 0 
L 0.80005 -2.25161998 0.85543996 -2.25161998 0 P 0 
L 0.78651998 -2.25061998 0.86596004 -2.25061998 0 P 0 
L 0.77878996 -2.24961998 0.87636004 -2.24961998 0 P 0 
L 0.77106004 -2.24861998 0.88285 -2.24861998 0 P 0 
L 0.76398996 -2.24761998 0.88933996 -2.24761998 0 P 0 
L 0.75891998 -2.24661998 0.89583996 -2.24661998 0 P 0 
L 0.73781004 -1.8982 0.71738996 -1.90951998 0 P 0 
L 0.71738996 -1.90951998 0.69766998 -1.92233996 0 P 0 
L 0.69766998 -1.92233996 0.67971004 -1.93601998 0 P 0 
L 0.67971004 -1.93601998 0.66278996 -1.95113002 0 P 0 
L 0.66278996 -1.95113002 0.64786998 -1.96675 0 P 0 
L 0.64786998 -1.96675 0.63423996 -1.98358996 0 P 0 
L 0.63423996 -1.98358996 0.62643996 -1.99483002 0 P 0 
L 0.62643996 -1.99483002 0.61933996 -2.00655 0 P 0 
L 0.61933996 -2.00655 0.61298996 -2.01873996 0 P 0 
L 0.61298996 -2.01873996 0.60503002 -2.03713002 0 P 0 
L 0.60503002 -2.03713002 0.60225 -2.04506004 0 P 0 
L 0.60225 -2.04506004 0.59998996 -2.05323002 0 P 0 
L 0.59998996 -2.05323002 0.59833996 -2.0612 0 P 0 
L 0.59833996 -2.0612 0.59725 -2.06928996 0 P 0 
L 0.59725 -2.06928996 0.59656998 -2.07833996 0 P 0 
L 0.59656998 -2.07833996 0.59633002 -2.0875 0 P 0 
L 0.59633002 -2.0875 0.59668996 -2.10036998 0 P 0 
L 0.59668996 -2.10036998 0.59715 -2.10596004 0 P 0 
L 0.59715 -2.10596004 0.59786004 -2.11151004 0 P 0 
L 0.59786004 -2.11151004 0.59878996 -2.11686998 0 P 0 
L 0.59878996 -2.11686998 0.59996998 -2.1222 0 P 0 
L 0.59996998 -2.1222 0.60326998 -2.13368996 0 P 0 
L 0.60326998 -2.13368996 0.60656998 -2.1427 0 P 0 
L 0.60656998 -2.1427 0.6105 -2.15143996 0 P 0 
L 0.6105 -2.15143996 0.61505 -2.15988002 0 P 0 
L 0.61505 -2.15988002 0.62023996 -2.16803996 0 P 0 
L 0.62023996 -2.16803996 0.62828996 -2.17873002 0 P 0 
L 0.62828996 -2.17873002 0.63718996 -2.18871004 0 P 0 
L 0.63718996 -2.18871004 0.64693002 -2.19795 0 P 0 
L 0.64693002 -2.19795 0.6582 -2.20701998 0 P 0 
L 0.6582 -2.20701998 0.67011004 -2.21518996 0 P 0 
L 0.67011004 -2.21518996 0.68261004 -2.22243002 0 P 0 
L 0.68261004 -2.22243002 0.69673996 -2.22936004 0 P 0 
L 0.69673996 -2.22936004 0.71123002 -2.23543996 0 P 0 
L 0.71123002 -2.23543996 0.72611998 -2.24066998 0 P 0 
L 0.72611998 -2.24066998 0.74536004 -2.24598996 0 P 0 
L 0.74536004 -2.24598996 0.76493002 -2.24985 0 P 0 
L 0.76493002 -2.24985 0.78671998 -2.25266998 0 P 0 
L 0.78671998 -2.25266998 0.80863002 -2.25425 0 P 0 
L 0.80863002 -2.25425 0.83146004 -2.25463002 0 P 0 
L 0.83146004 -2.25463002 0.85418002 -2.25375 0 P 0 
L 0.85418002 -2.25375 0.87641004 -2.25163996 0 P 0 
L 0.87641004 -2.25163996 0.89853002 -2.24823002 0 P 0 
L 0.89853002 -2.24823002 0.93045 -2.24101998 0 P 0 
L 0.93045 -2.24101998 0.96466004 -2.23063002 0 P 0 
L 0.96466004 -2.23063002 0.99911004 -2.2178 0 P 0 
L 0.99911004 -2.2178 1.03183002 -2.20318002 0 P 0 
L 1.03183002 -2.20318002 1.04391998 -2.19703002 0 P 0 
L 1.04391998 -2.19703002 1.05581004 -2.19048996 0 P 0 
L 1.05581004 -2.19048996 1.06676004 -2.18411998 0 P 0 
L 1.06676004 -2.18411998 1.06681004 -2.18408996 0 P 0 
L 1.06681004 -2.18408996 1.06685 -2.18405 0 P 0 
L 1.06685 -2.18405 1.0669 -2.18401004 0 P 0 
L 1.0669 -2.18401004 1.06693996 -2.18396998 0 P 0 
L 1.06693996 -2.18396998 1.06696998 -2.18391998 0 P 0 
L 1.06696998 -2.18391998 1.06701004 -2.18386998 0 P 0 
L 1.06701004 -2.18386998 1.06703002 -2.18381998 0 P 0 
L 1.06703002 -2.18381998 1.06706004 -2.18376004 0 P 0 
L 1.06706004 -2.18376004 1.06706998 -2.18371004 0 P 0 
L 1.06706998 -2.18371004 1.06708996 -2.18365 0 P 0 
L 1.06708996 -2.18365 1.06708996 -2.18358996 0 P 0 
L 1.06708996 -2.18358996 1.0671 -2.18353002 0 P 0 
L 1.0671 -2.18353002 1.0671 -2.18346998 0 P 0 
L 1.0671 -2.18346998 1.06708996 -2.18341004 0 P 0 
L 1.06708996 -2.18341004 1.06706998 -2.18336004 0 P 0 
L 1.06706998 -2.18336004 1.06706004 -2.1833 0 P 0 
L 1.06706004 -2.1833 1.06703002 -2.18323996 0 P 0 
L 1.06703002 -2.18323996 1.06701004 -2.18318996 0 P 0 
L 1.06701004 -2.18318996 1.06696998 -2.18313996 0 P 0 
L 1.06696998 -2.18313996 1.06693996 -2.18308996 0 P 0 
L 1.06693996 -2.18308996 1.06688002 -2.18303002 0 P 0 
L 1.06688002 -2.18303002 1.06678996 -2.18296998 0 P 0 
L 1.06678996 -2.18296998 1.06673002 -2.18295 0 P 0 
L 1.06673002 -2.18295 1.0667 -2.18295 0 P 0 
L 1.0667 -2.18295 1.06666004 -2.18293996 0 P 0 
L 1.06666004 -2.18293996 1.0666 -2.18293996 0 P 0 
L 1.0666 -2.18293996 1.06656998 -2.18295 0 P 0 
L 1.06656998 -2.18295 1.06653002 -2.18295 0 P 0 
L 1.06653002 -2.18295 1.06153002 -2.1842 0 P 0 
L 1.06153002 -2.1842 1.05583996 -2.18566998 0 P 0 
L 1.05583996 -2.18566998 1.04916998 -2.1875 0 P 0 
L 1.04916998 -2.1875 1.0153 -2.1962 0 P 0 
L 1.0153 -2.1962 0.9814 -2.20333996 0 P 0 
L 0.9814 -2.20333996 0.94881998 -2.2087 0 P 0 
L 0.94881998 -2.2087 0.9189 -2.21198996 0 P 0 
L 0.9189 -2.21198996 0.90113996 -2.21278996 0 P 0 
L 0.90113996 -2.21278996 0.87738002 -2.21265 0 P 0 
L 0.87738002 -2.21265 0.854 -2.21183002 0 P 0 
L 0.854 -2.21183002 0.83788996 -2.21033996 0 P 0 
L 0.83788996 -2.21033996 0.8174 -2.20693002 0 P 0 
L 0.8174 -2.20693002 0.79708996 -2.2023 0 P 0 
L 0.79708996 -2.2023 0.7769 -2.19641004 0 P 0 
L 0.7769 -2.19641004 0.76433002 -2.19183996 0 P 0 
L 0.76433002 -2.19183996 0.75208996 -2.18638002 0 P 0 
L 0.75208996 -2.18638002 0.74026998 -2.18006998 0 P 0 
L 0.74026998 -2.18006998 0.72886998 -2.17291004 0 P 0 
L 0.72886998 -2.17291004 0.71961998 -2.16603002 0 P 0 
L 0.71961998 -2.16603002 0.71098996 -2.15838996 0 P 0 
L 0.71098996 -2.15838996 0.70303002 -2.15003002 0 P 0 
L 0.70303002 -2.15003002 0.6958 -2.14098996 0 P 0 
L 0.6958 -2.14098996 0.69106998 -2.1339 0 P 0 
L 0.69106998 -2.1339 0.68696004 -2.12643002 0 P 0 
L 0.68696004 -2.12643002 0.68351004 -2.11863002 0 P 0 
L 0.68351004 -2.11863002 0.68073996 -2.11056004 0 P 0 
L 0.68073996 -2.11056004 0.67866004 -2.10218996 0 P 0 
L 0.67866004 -2.10218996 0.67788002 -2.09741998 0 P 0 
L 0.67788002 -2.09741998 0.67746004 -2.0926 0 P 0 
L 0.67746004 -2.0926 0.67738002 -2.08076004 0 P 0 
L 0.67738002 -2.08076004 0.67828002 -2.06891004 0 P 0 
L 0.67828002 -2.06891004 0.67903002 -2.06403996 0 P 0 
L 0.67903002 -2.06403996 0.68013002 -2.05923996 0 P 0 
L 0.68013002 -2.05923996 0.68288002 -2.05021998 0 P 0 
L 0.68288002 -2.05021998 0.68623996 -2.04141004 0 P 0 
L 0.68623996 -2.04141004 0.69018002 -2.03286004 0 P 0 
L 0.69018002 -2.03286004 0.69486004 -2.02418002 0 P 0 
L 0.69486004 -2.02418002 0.70003996 -2.0158 0 P 0 
L 0.70003996 -2.0158 0.70573002 -2.00768996 0 P 0 
L 0.70573002 -2.00768996 0.7158 -1.99531998 0 P 0 
L 0.7158 -1.99531998 0.72681004 -1.98385 0 P 0 
L 0.72681004 -1.98385 0.73971004 -1.9722 0 P 0 
L 0.73971004 -1.9722 0.7533 -1.9614 0 P 0 
L 0.7533 -1.9614 0.75753996 -1.95828002 0 P 0 
L 0.75753996 -1.95828002 0.76138002 -1.95548002 0 P 0 
L 0.76138002 -1.95548002 0.76463002 -1.95316004 0 P 0 
L 0.76463002 -1.95316004 0.76516004 -1.95281004 0 P 0 
L 0.76516004 -1.95281004 0.7657 -1.95248996 0 P 0 
L 0.7657 -1.95248996 0.76578002 -1.95243996 0 P 0 
L 0.76578002 -1.95243996 0.76586004 -1.95238002 0 P 0 
L 0.76586004 -1.95238002 0.76593002 -1.95231998 0 P 0 
L 0.76593002 -1.95231998 0.766 -1.95223996 0 P 0 
L 0.766 -1.95223996 0.76606004 -1.95216998 0 P 0 
L 0.76606004 -1.95216998 0.76616004 -1.95201004 0 P 0 
L 0.76616004 -1.95201004 0.7662 -1.95191998 0 P 0 
L 0.7662 -1.95191998 0.76626004 -1.95173996 0 P 0 
L 0.76626004 -1.95173996 0.76628002 -1.95163996 0 P 0 
L 0.76628002 -1.95163996 0.7663 -1.95143002 0 P 0 
L 0.7663 -1.95143002 0.7663 -1.95121004 0 P 0 
L 0.7663 -1.95121004 0.76628996 -1.951 0 P 0 
L 0.76628996 -1.951 0.76625 -1.95078996 0 P 0 
L 0.76625 -1.95078996 0.7662 -1.95058002 0 P 0 
L 0.7662 -1.95058002 0.76613002 -1.95036998 0 P 0 
L 0.76613002 -1.95036998 0.76583002 -1.94966998 0 P 0 
L 0.76583002 -1.94966998 0.76548996 -1.94896998 0 P 0 
L 0.76548996 -1.94896998 0.76508996 -1.9483 0 P 0 
L 0.76508996 -1.9483 0.76253002 -1.94436004 0 P 0 
L 0.76253002 -1.94436004 0.76056998 -1.94126998 0 P 0 
L 0.76056998 -1.94126998 0.75871998 -1.93806004 0 P 0 
L 0.75871998 -1.93806004 0.75716998 -1.93496998 0 P 0 
L 0.75716998 -1.93496998 0.7558 -1.93178002 0 P 0 
L 0.7558 -1.93178002 0.7546 -1.92853996 0 P 0 
L 0.7546 -1.92853996 0.75358996 -1.92521004 0 P 0 
L 0.75358996 -1.92521004 0.7527 -1.92161998 0 P 0 
L 0.7527 -1.92161998 0.75196998 -1.91796004 0 P 0 
L 0.75196998 -1.91796004 0.75155 -1.91496004 0 P 0 
L 0.75155 -1.91496004 0.75133002 -1.91193002 0 P 0 
L 0.75133002 -1.91193002 0.75126998 -1.9085 0 P 0 
L 0.75126998 -1.9085 0.75136004 -1.90506004 0 P 0 
L 0.75136004 -1.90506004 0.75161004 -1.90181998 0 P 0 
L 0.75161004 -1.90181998 0.752 -1.8986 0 P 0 
L 0.752 -1.8986 0.75228996 -1.89701998 0 P 0 
L 0.75228996 -1.89701998 0.75268996 -1.89546998 0 P 0 
L 0.75268996 -1.89546998 0.7532 -1.89395 0 P 0 
L 0.7532 -1.89395 0.75358996 -1.89281998 0 P 0 
L 0.75358996 -1.89281998 0.75373002 -1.89231998 0 P 0 
L 0.75373002 -1.89231998 0.75383996 -1.8918 0 P 0 
L 0.75383996 -1.8918 0.75391998 -1.89138996 0 P 0 
L 0.75391998 -1.89138996 0.75396998 -1.89098996 0 P 0 
L 0.75396998 -1.89098996 0.75396998 -1.89086004 0 P 0 
L 0.75396998 -1.89086004 0.75393996 -1.89076998 0 P 0 
L 0.75393996 -1.89076998 0.7539 -1.89071004 0 P 0 
L 0.7539 -1.89071004 0.75386004 -1.89066998 0 P 0 
L 0.75386004 -1.89066998 0.75381004 -1.89063002 0 P 0 
L 0.75381004 -1.89063002 0.75378996 -1.89061004 0 P 0 
L 0.75378996 -1.89061004 0.75373002 -1.89058996 0 P 0 
L 0.75373002 -1.89058996 0.75368002 -1.89056998 0 P 0 
L 0.75368002 -1.89056998 0.75356004 -1.89056998 0 P 0 
L 0.75356004 -1.89056998 0.75346998 -1.8906 0 P 0 
L 0.75346998 -1.8906 0.74898002 -1.8927 0 P 0 
L 0.74898002 -1.8927 0.74383002 -1.89518002 0 P 0 
L 0.74383002 -1.89518002 0.73781004 -1.8982 0 P 0 
L 0.69776998 -2.22761998 0.96701004 -2.22761998 0 P 0 
L 0.6957 -2.22661998 0.96968996 -2.22661998 0 P 0 
L 0.69366998 -2.22561998 0.97238002 -2.22561998 0 P 0 
L 0.69163002 -2.22461998 0.97506004 -2.22461998 0 P 0 
L 0.68958996 -2.22361998 0.97775 -2.22361998 0 P 0 
L 0.68756004 -2.22261998 0.98043002 -2.22261998 0 P 0 
L 0.68551998 -2.22161998 0.98311004 -2.22161998 0 P 0 
L 0.68348996 -2.22061998 0.9858 -2.22061998 0 P 0 
L 0.68176998 -2.21961998 0.98848002 -2.21961998 0 P 0 
L 0.68003996 -2.21861998 0.99116998 -2.21861998 0 P 0 
L 0.67831004 -2.21761998 0.99385 -2.21761998 0 P 0 
L 0.67658002 -2.21661998 0.99653996 -2.21661998 0 P 0 
L 0.67485 -2.21561998 0.99908002 -2.21561998 0 P 0 
L 0.67311998 -2.21461998 0.87665 -2.21461998 0 P 0 
L 0.6714 -2.21361998 0.85166004 -2.21361998 0 P 0 
L 0.6699 -2.21261998 0.84083002 -2.21261998 0 P 0 
L 0.66845 -2.21161998 0.8334 -2.21161998 0 P 0 
L 0.66698996 -2.21061998 0.8274 -2.21061998 0 P 0 
L 0.66553002 -2.20961998 0.82138996 -2.20961998 0 P 0 
L 0.66406998 -2.20861998 0.81583002 -2.20861998 0 P 0 
L 0.66261998 -2.20761998 0.81143996 -2.20761998 0 P 0 
L 0.66116004 -2.20661998 0.80706004 -2.20661998 0 P 0 
L 0.6597 -2.20561998 0.80266998 -2.20561998 0 P 0 
L 0.65841004 -2.20461998 0.79828996 -2.20461998 0 P 0 
L 0.65716998 -2.20361998 0.79448996 -2.20361998 0 P 0 
L 0.65593002 -2.20261998 0.79106004 -2.20261998 0 P 0 
L 0.65468996 -2.20161998 0.78763996 -2.20161998 0 P 0 
L 0.83143002 -2.25261998 0.80871998 -2.25225 0 P 0 
L 0.80871998 -2.25225 0.78691998 -2.25066998 0 P 0 
L 0.78691998 -2.25066998 0.76525 -2.24786998 0 P 0 
L 0.76525 -2.24786998 0.74581998 -2.24403996 0 P 0 
L 0.74581998 -2.24403996 0.72671004 -2.23876004 0 P 0 
L 0.72671004 -2.23876004 0.71196004 -2.23356998 0 P 0 
L 0.71196004 -2.23356998 0.69756998 -2.22753996 0 P 0 
L 0.69756998 -2.22753996 0.68355 -2.22066004 0 P 0 
L 0.68355 -2.22066004 0.67118002 -2.2135 0 P 0 
L 0.67118002 -2.2135 0.65938996 -2.20541004 0 P 0 
L 0.65938996 -2.20541004 0.64825 -2.19643996 0 P 0 
L 0.64825 -2.19643996 0.63861998 -2.18731998 0 P 0 
L 0.63861998 -2.18731998 0.62983002 -2.17746998 0 P 0 
L 0.62983002 -2.17746998 0.62188996 -2.1669 0 P 0 
L 0.62188996 -2.1669 0.61678002 -2.15886998 0 P 0 
L 0.61678002 -2.15886998 0.6123 -2.15056004 0 P 0 
L 0.6123 -2.15056004 0.60841998 -2.14193996 0 P 0 
L 0.60841998 -2.14193996 0.60516998 -2.13306998 0 P 0 
L 0.60516998 -2.13306998 0.60191004 -2.12171004 0 P 0 
L 0.60191004 -2.12171004 0.60075 -2.11648002 0 P 0 
L 0.60075 -2.11648002 0.59983996 -2.11121004 0 P 0 
L 0.59983996 -2.11121004 0.59913996 -2.10576004 0 P 0 
L 0.59913996 -2.10576004 0.59868996 -2.10026004 0 P 0 
L 0.59868996 -2.10026004 0.59833002 -2.0875 0 P 0 
L 0.59833002 -2.0875 0.59856998 -2.07843996 0 P 0 
L 0.59856998 -2.07843996 0.59923996 -2.0695 0 P 0 
L 0.59923996 -2.0695 0.60031998 -2.06153996 0 P 0 
L 0.60031998 -2.06153996 0.60193002 -2.05368996 0 P 0 
L 0.60193002 -2.05368996 0.60416004 -2.04566004 0 P 0 
L 0.60416004 -2.04566004 0.60688996 -2.03786004 0 P 0 
L 0.60688996 -2.03786004 0.6148 -2.01961004 0 P 0 
L 0.6148 -2.01961004 0.62108996 -2.00753002 0 P 0 
L 0.62108996 -2.00753002 0.62811998 -1.99591998 0 P 0 
L 0.62811998 -1.99591998 0.63583996 -1.98478996 0 P 0 
L 0.63583996 -1.98478996 0.64936998 -1.96808002 0 P 0 
L 0.64936998 -1.96808002 0.66418002 -1.95256998 0 P 0 
L 0.66418002 -1.95256998 0.68098002 -1.93756004 0 P 0 
L 0.68098002 -1.93756004 0.69881998 -1.92398002 0 P 0 
L 0.69881998 -1.92398002 0.71841998 -1.91123996 0 P 0 
L 0.71841998 -1.91123996 0.73875 -1.89996998 0 P 0 
L 0.73875 -1.89996998 0.74471004 -1.89696998 0 P 0 
L 0.74471004 -1.89696998 0.74983002 -1.89451004 0 P 0 
L 0.74983002 -1.89451004 0.7511 -1.89391004 0 P 0 
L 0.7511 -1.89391004 0.75076998 -1.89488996 0 P 0 
L 0.75076998 -1.89488996 0.75033996 -1.89658996 0 P 0 
L 0.75033996 -1.89658996 0.75003002 -1.8983 0 P 0 
L 0.75003002 -1.8983 0.74961998 -1.90161998 0 P 0 
L 0.74961998 -1.90161998 0.74936004 -1.90496004 0 P 0 
L 0.74936004 -1.90496004 0.74926998 -1.9085 0 P 0 
L 0.74926998 -1.9085 0.74933002 -1.91201998 0 P 0 
L 0.74933002 -1.91201998 0.74956004 -1.91516998 0 P 0 
L 0.74956004 -1.91516998 0.75 -1.91828996 0 P 0 
L 0.75 -1.91828996 0.75075 -1.92205 0 P 0 
L 0.75075 -1.92205 0.75166004 -1.92573996 0 P 0 
L 0.75166004 -1.92573996 0.7527 -1.92916998 0 P 0 
L 0.7527 -1.92916998 0.75393996 -1.93253002 0 P 0 
L 0.75393996 -1.93253002 0.75536004 -1.93581998 0 P 0 
L 0.75536004 -1.93581998 0.75696004 -1.939 0 P 0 
L 0.75696004 -1.939 0.75885 -1.94231004 0 P 0 
L 0.75885 -1.94231004 0.76083996 -1.94543996 0 P 0 
L 0.76083996 -1.94543996 0.76338996 -1.94933996 0 P 0 
L 0.76338996 -1.94933996 0.76371998 -1.94991998 0 P 0 
L 0.76371998 -1.94991998 0.76401004 -1.9505 0 P 0 
L 0.76401004 -1.9505 0.76423996 -1.95103002 0 P 0 
L 0.76423996 -1.95103002 0.76408996 -1.95111004 0 P 0 
L 0.76408996 -1.95111004 0.76348996 -1.95151004 0 P 0 
L 0.76348996 -1.95151004 0.76021004 -1.95386004 0 P 0 
L 0.76021004 -1.95386004 0.7602 -1.95386998 0 P 0 
L 0.7602 -1.95386998 0.75636998 -1.95666004 0 P 0 
L 0.75636998 -1.95666004 0.75636004 -1.95666998 0 P 0 
L 0.75636004 -1.95666998 0.75635 -1.95666998 0 P 0 
L 0.75635 -1.95666998 0.75208996 -1.95981004 0 P 0 
L 0.75208996 -1.95981004 0.73841004 -1.97066998 0 P 0 
L 0.73841004 -1.97066998 0.72541004 -1.98241004 0 P 0 
L 0.72541004 -1.98241004 0.7143 -1.994 0 P 0 
L 0.7143 -1.994 0.71425 -1.99406004 0 P 0 
L 0.71425 -1.99406004 0.70413996 -2.00648002 0 P 0 
L 0.70413996 -2.00648002 0.69836998 -2.01468996 0 P 0 
L 0.69836998 -2.01468996 0.69313002 -2.02318002 0 P 0 
L 0.69313002 -2.02318002 0.68838996 -2.03196004 0 P 0 
L 0.68838996 -2.03196004 0.68438996 -2.04063996 0 P 0 
L 0.68438996 -2.04063996 0.68098996 -2.04958002 0 P 0 
L 0.68098996 -2.04958002 0.6782 -2.05873002 0 P 0 
L 0.6782 -2.05873002 0.67706004 -2.06366004 0 P 0 
L 0.67706004 -2.06366004 0.67628996 -2.06866998 0 P 0 
L 0.67628996 -2.06866998 0.67538002 -2.08068996 0 P 0 
L 0.67538002 -2.08068996 0.67546004 -2.09268996 0 P 0 
L 0.67546004 -2.09268996 0.67588996 -2.09766998 0 P 0 
L 0.67588996 -2.09766998 0.6767 -2.10258996 0 P 0 
L 0.6767 -2.10258996 0.67881998 -2.11111998 0 P 0 
L 0.67881998 -2.11111998 0.68163996 -2.11936004 0 P 0 
L 0.68163996 -2.11936004 0.68516004 -2.12731998 0 P 0 
L 0.68516004 -2.12731998 0.68935 -2.13493996 0 P 0 
L 0.68935 -2.13493996 0.69418002 -2.14216998 0 P 0 
L 0.69418002 -2.14216998 0.70153002 -2.15135 0 P 0 
L 0.70153002 -2.15135 0.7096 -2.15983002 0 P 0 
L 0.7096 -2.15983002 0.71836004 -2.16758996 0 P 0 
L 0.71836004 -2.16758996 0.71843002 -2.16763996 0 P 0 
L 0.71843002 -2.16763996 0.72773996 -2.17456004 0 P 0 
L 0.72773996 -2.17456004 0.73926998 -2.1818 0 P 0 
L 0.73926998 -2.1818 0.75121004 -2.18818002 0 P 0 
L 0.75121004 -2.18818002 0.75128002 -2.18821004 0 P 0 
L 0.75128002 -2.18821004 0.76358002 -2.19368996 0 P 0 
L 0.76358002 -2.19368996 0.77628002 -2.19831004 0 P 0 
L 0.77628002 -2.19831004 0.79658996 -2.20423996 0 P 0 
L 0.79658996 -2.20423996 0.81701004 -2.20888996 0 P 0 
L 0.81701004 -2.20888996 0.83763996 -2.21233002 0 P 0 
L 0.83763996 -2.21233002 0.85388002 -2.21383002 0 P 0 
L 0.85388002 -2.21383002 0.87733996 -2.21465 0 P 0 
L 0.87733996 -2.21465 0.90118002 -2.21478996 0 P 0 
L 0.90118002 -2.21478996 0.91906004 -2.21398996 0 P 0 
L 0.91906004 -2.21398996 0.94908996 -2.21068002 0 P 0 
L 0.94908996 -2.21068002 0.98176998 -2.2053 0 P 0 
L 0.98176998 -2.2053 1.01575 -2.19815 0 P 0 
L 1.01575 -2.19815 1.04968002 -2.18943002 0 P 0 
L 1.04968002 -2.18943002 1.05633996 -2.18761004 0 P 0 
L 1.05633996 -2.18761004 1.05713996 -2.1874 0 P 0 
L 1.05713996 -2.1874 1.05483002 -2.18875 0 P 0 
L 1.05483002 -2.18875 1.04298996 -2.19526004 0 P 0 
L 1.04298996 -2.19526004 1.03096998 -2.20136998 0 P 0 
L 1.03096998 -2.20136998 0.99835 -2.21595 0 P 0 
L 0.99835 -2.21595 0.96401998 -2.22873996 0 P 0 
L 0.96401998 -2.22873996 0.92993996 -2.23908002 0 P 0 
L 0.92993996 -2.23908002 0.89816004 -2.24626004 0 P 0 
L 0.89816004 -2.24626004 0.87616004 -2.24965 0 P 0 
L 0.87616004 -2.24965 0.85405 -2.25176004 0 P 0 
L 0.85405 -2.25176004 0.83143002 -2.25261998 0 P 0 
L 0.65345 -2.20061998 0.78421004 -2.20061998 0 P 0 
L 0.65221004 -2.19961998 0.78078002 -2.19961998 0 P 0 
L 0.65096004 -2.19861998 0.77735 -2.19861998 0 P 0 
L 0.64971998 -2.19761998 0.77438996 -2.19761998 0 P 0 
L 0.64848002 -2.19661998 0.77163996 -2.19661998 0 P 0 
L 0.64738996 -2.19561998 0.76888996 -2.19561998 0 P 0 
L 0.64633996 -2.19461998 0.76613996 -2.19461998 0 P 0 
L 0.64528002 -2.19361998 0.76343002 -2.19361998 0 P 0 
L 0.64421998 -2.19261998 0.76118996 -2.19261998 0 P 0 
L 0.64316998 -2.19161998 0.75893996 -2.19161998 0 P 0 
L 0.64211004 -2.19061998 0.7567 -2.19061998 0 P 0 
L 0.64106004 -2.18961998 0.75446004 -2.18961998 0 P 0 
L 0.64 -2.18861998 0.75221004 -2.18861998 0 P 0 
L 0.63895 -2.18761998 0.75018002 -2.18761998 0 P 0 
L 0.63801004 -2.18661998 0.74831004 -2.18661998 0 P 0 
L 0.63711004 -2.18561998 0.74643002 -2.18561998 0 P 0 
L 0.63621998 -2.18461998 0.74456004 -2.18461998 0 P 0 
L 0.63533002 -2.18361998 0.74268002 -2.18361998 0 P 0 
L 0.63443996 -2.18261998 0.74081004 -2.18261998 0 P 0 
L 0.63353996 -2.18161998 0.73898996 -2.18161998 0 P 0 
L 0.63265 -2.18061998 0.73738996 -2.18061998 0 P 0 
L 0.63176004 -2.17961998 0.7358 -2.17961998 0 P 0 
L 0.63086998 -2.17861998 0.73421004 -2.17861998 0 P 0 
L 0.62996998 -2.17761998 0.73261998 -2.17761998 0 P 0 
L 0.6292 -2.17661998 0.73103002 -2.17661998 0 P 0 
L 0.62845 -2.17561998 0.72943996 -2.17561998 0 P 0 
L 0.6277 -2.17461998 0.72783996 -2.17461998 0 P 0 
L 0.62693996 -2.17361998 0.72648002 -2.17361998 0 P 0 
L 0.62618996 -2.17261998 0.72513996 -2.17261998 0 P 0 
L 0.62543996 -2.17161998 0.72378996 -2.17161998 0 P 0 
L 0.62468996 -2.17061998 0.72245 -2.17061998 0 P 0 
L 0.62393996 -2.16961998 0.7211 -2.16961998 0 P 0 
L 0.62318002 -2.16861998 0.71976004 -2.16861998 0 P 0 
L 0.62243996 -2.16761998 0.71841004 -2.16761998 0 P 0 
L 0.62171004 -2.16661998 0.71726998 -2.16661998 0 P 0 
L 0.62108002 -2.16561998 0.71613996 -2.16561998 0 P 0 
L 0.62043996 -2.16461998 0.71501004 -2.16461998 0 P 0 
L 0.61981004 -2.16361998 0.71388002 -2.16361998 0 P 0 
L 0.61916998 -2.16261998 0.71276004 -2.16261998 0 P 0 
L 0.61853002 -2.16161998 0.71163002 -2.16161998 0 P 0 
L 0.6179 -2.16061998 0.7105 -2.16061998 0 P 0 
L 0.61726004 -2.15961998 0.7094 -2.15961998 0 P 0 
L 0.61665 -2.15861998 0.70845 -2.15861998 0 P 0 
L 0.61611004 -2.15761998 0.7075 -2.15761998 0 P 0 
L 0.75383996 -2.24561998 0.901 -2.24561998 0 P 0 
L 0.74876998 -2.24461998 0.90541998 -2.24461998 0 P 0 
L 0.74431004 -2.24361998 0.90985 -2.24361998 0 P 0 
L 0.7407 -2.24261998 0.91426998 -2.24261998 0 P 0 
L 0.73708002 -2.24161998 0.9187 -2.24161998 0 P 0 
L 0.73346998 -2.24061998 0.92311998 -2.24061998 0 P 0 
L 0.72986004 -2.23961998 0.92753996 -2.23961998 0 P 0 
L 0.72633996 -2.23861998 0.93145 -2.23861998 0 P 0 
L 0.72348996 -2.23761998 0.93473996 -2.23761998 0 P 0 
L 0.72063996 -2.23661998 0.93803996 -2.23661998 0 P 0 
L 0.7178 -2.23561998 0.94133002 -2.23561998 0 P 0 
L 0.71495 -2.23461998 0.94461998 -2.23461998 0 P 0 
L 0.7121 -2.23361998 0.94791998 -2.23361998 0 P 0 
L 0.70968996 -2.23261998 0.95121004 -2.23261998 0 P 0 
L 0.70731004 -2.23161998 0.95451004 -2.23161998 0 P 0 
L 0.70491998 -2.23061998 0.9578 -2.23061998 0 P 0 
L 0.70253996 -2.22961998 0.9611 -2.22961998 0 P 0 
L 0.70015 -2.22861998 0.96431998 -2.22861998 0 P 0 
P 7.17716998 5.7874 20 P 0 0;4=22
P 7.17716998 0.23621998 20 P 0 0;4=22
P 0.22245 0.68898002 19 P 0 0;4=23
P 0.22245 5.11811004 19 P 0 0;4=23
P 12.68701998 5.15748002 19 P 0 0;4=23
P 12.68701998 0.72835 19 P 0 0;4=23
P 6.11811004 1.52756004 19 P 0 0;4=23
P 6.11811004 4.20473002 19 P 0 0;4=23
P 4.83268002 4.22441004 19 P 0 0;4=23
P 2.24606004 4.22441004 19 P 0 0;4=23
P 0.96063002 4.20473002 19 P 0 0;4=23
P 0.96063002 1.52756004 19 P 0 0;4=23
P 2.24606004 1.50786998 19 P 0 0;4=23
P 4.83268002 1.50786998 19 P 0 0;4=23
P 6.04921004 2.58268002 18 P 0 0;4=24
P 1.05905 2.58268002 28 P 0 0;4=25
P 12.12205 1.52756004 19 P 0 0;4=23
P 12.12205 4.20473002 19 P 0 0;4=23
P 10.83661998 4.22441004 19 P 0 0;4=23
P 8.25 4.22441004 19 P 0 0;4=23
P 6.96456998 4.20473002 19 P 0 0;4=23
P 6.96456998 1.52756004 19 P 0 0;4=23
P 8.25 1.50786998 19 P 0 0;4=23
P 10.83661998 1.50786998 19 P 0 0;4=23
P 12.05315 2.58268002 18 P 0 0;4=24
P 7.06298996 2.58268002 28 P 0 0;4=25
P 12.33465 5.69528002 15 P 0 0;4=26
P 3.58311004 4.91851004 10 P 0 0;4=27
P 2.72091004 4.91851004 10 P 0 0;4=27
P 9.58665 4.91851004 10 P 0 0;4=27
P 8.72445 4.91851004 10 P 0 0;4=27
P 2.41851004 4.91851004 10 P 0 0;4=27
P 1.55631004 4.91851004 10 P 0 0;4=27
P 8.42205 4.91851004 10 P 0 0;4=27
P 7.55985 4.91851004 10 P 0 0;4=27
P 0.22243996 1.79331004 13 P 0 0;4=28
P 0.22243996 4.67323002 13 P 0 0;4=28
P 12.687 1.83268002 13 P 0 0;4=28
P 12.687 4.7126 13 P 0 0;4=28
P 0.7687 5.62008002 9 P 0 0;4=29
P 1.47736004 5.62008002 9 P 0 0;4=29
L 0.0349 -2.3038 0.0349 -1.0038 5 P 0 
L 0.0349 -1.0038 4.5349 -1.0038 5 P 0 
L 4.5349 -1.0038 4.5349 -2.3038 5 P 0 
L 4.5349 -2.3038 0.0349 -2.3038 5 P 0 
L 0.0349 -1.6038 4.5349 -1.6038 5 P 0 
L 0.0349 -1.8038 4.5349 -1.8038 5 P 0 
L 2.4349 -2.1038 4.0349 -2.1038 5 P 0 
L 2.4349 -2.3038 2.4349 -1.8038 5 P 0 
L 3.2349 -2.1038 3.2349 -1.8038 5 P 0 
L 4.0349 -2.3038 4.0349 -1.8038 5 P 0 
L 0.0723999 -1.6844687 0.07906663 -1.69030079 2 P 0 ;0,5=30,7=0.000000
L 0.07906663 -1.69030079 0.08656654 -1.6938 2 P 0 ;0,5=30,7=0.000000
L 0.08656654 -1.6938 0.09323337 -1.6938 2 P 0 ;0,5=30,7=0.000000
L 0.09323337 -1.6938 0.0999001 -1.69030079 2 P 0 ;0,5=30,7=0.000000
L 0.0999001 -1.69030079 0.10490059 -1.6844687 2 P 0 ;0,5=30,7=0.000000
L 0.10490059 -1.6844687 0.1074 -1.67629951 2 P 0 ;0,5=30,7=0.000000
L 0.1074 -1.67629951 0.10573376 -1.66813455 2 P 0 ;0,5=30,7=0.000000
L 0.10573376 -1.66813455 0.10156644 -1.66113396 2 P 0 ;0,5=30,7=0.000000
L 0.10156644 -1.66113396 0.09406654 -1.65646614 2 P 0 ;0,5=30,7=0.000000
L 0.09406654 -1.65646614 0.08406713 -1.65413327 2 P 0 ;0,5=30,7=0.000000
L 0.08406713 -1.65413327 0.07823346 -1.64946762 2 P 0 ;0,5=30,7=0.000000
L 0.07823346 -1.64946762 0.07573248 -1.64130059 2 P 0 ;0,5=30,7=0.000000
L 0.07573248 -1.64130059 0.0774003 -1.63313356 2 P 0 ;0,5=30,7=0.000000
L 0.0774003 -1.63313356 0.08156614 -1.62730148 2 P 0 ;0,5=30,7=0.000000
L 0.08156614 -1.62730148 0.0873997 -1.6238 2 P 0 ;0,5=30,7=0.000000
L 0.0873997 -1.6238 0.09323337 -1.6238 2 P 0 ;0,5=30,7=0.000000
L 0.09323337 -1.6238 0.09906693 -1.62613287 2 P 0 ;0,5=30,7=0.000000
L 0.09906693 -1.62613287 0.10406742 -1.63196713 2 P 0 ;0,5=30,7=0.000000
L 0.1383999 -1.6938 0.1383999 -1.6238 2 P 0 ;0,5=30,7=0.000000
L 0.1734 -1.6238 0.1734 -1.6938 2 P 0 ;0,5=30,7=0.000000
L 0.1734 -1.65880108 0.1383999 -1.65880108 2 P 0 ;0,5=30,7=0.000000
L 0.23856683 -1.6938 0.20523307 -1.6938 2 P 0 ;0,5=30,7=0.000000
L 0.20523307 -1.6938 0.20523307 -1.6238 2 P 0 ;0,5=30,7=0.000000
L 0.20523307 -1.6238 0.23856683 -1.6238 2 P 0 ;0,5=30,7=0.000000
L 0.22523337 -1.65763258 0.20523307 -1.65763258 2 P 0 ;0,5=30,7=0.000000
L 0.30456683 -1.6938 0.27123307 -1.6938 2 P 0 ;0,5=30,7=0.000000
L 0.27123307 -1.6938 0.27123307 -1.6238 2 P 0 ;0,5=30,7=0.000000
L 0.27123307 -1.6238 0.30456683 -1.6238 2 P 0 ;0,5=30,7=0.000000
L 0.29123337 -1.65763258 0.27123307 -1.65763258 2 P 0 ;0,5=30,7=0.000000
L 0.35389921 -1.6238 0.35389921 -1.6938 2 P 0 ;0,5=30,7=0.000000
L 0.33473356 -1.6238 0.37306634 -1.6238 2 P 0 ;0,5=30,7=0.000000
L 0.09489921 -1.7188 0.09489921 -1.7888 2 P 0 ;0,5=31,7=0.000000
L 0.07573356 -1.7188 0.11406634 -1.7188 2 P 0 ;0,5=31,7=0.000000
L 0.1508998 -1.7188 0.17089862 -1.7188 2 P 0 ;0,5=31,7=0.000000
L 0.16089921 -1.7188 0.16089921 -1.7888 2 P 0 ;0,5=31,7=0.000000
L 0.1508998 -1.7888 0.17089862 -1.7888 2 P 0 ;0,5=31,7=0.000000
L 0.22689921 -1.7188 0.22689921 -1.7888 2 P 0 ;0,5=31,7=0.000000
L 0.20773356 -1.7188 0.24606634 -1.7188 2 P 0 ;0,5=31,7=0.000000
L 0.27623307 -1.7188 0.27623307 -1.7888 2 P 0 ;0,5=31,7=0.000000
L 0.27623307 -1.7888 0.30956683 -1.7888 2 P 0 ;0,5=31,7=0.000000
L 0.37556683 -1.7888 0.34223307 -1.7888 2 P 0 ;0,5=31,7=0.000000
L 0.34223307 -1.7888 0.34223307 -1.7188 2 P 0 ;0,5=31,7=0.000000
L 0.34223307 -1.7188 0.37556683 -1.7188 2 P 0 ;0,5=31,7=0.000000
L 0.36223337 -1.75263258 0.34223307 -1.75263258 2 P 0 ;0,5=31,7=0.000000
L 2.5438999 -1.96813563 2.5519 -1.97480089 2 P 0 ;0,5=32,7=0.000000
L 2.5519 -1.97480089 2.5608999 -1.9788 2 P 0 ;0,5=32,7=0.000000
L 2.5608999 -1.9788 2.5689 -1.9788 2 P 0 ;0,5=32,7=0.000000
L 2.5689 -1.9788 2.5769001 -1.97480089 2 P 0 ;0,5=32,7=0.000000
L 2.5769001 -1.97480089 2.58290069 -1.96813563 2 P 0 ;0,5=32,7=0.000000
L 2.58290069 -1.96813563 2.5859 -1.95879941 2 P 0 ;0,5=32,7=0.000000
L 2.5859 -1.95879941 2.58390049 -1.94946811 2 P 0 ;0,5=32,7=0.000000
L 2.58390049 -1.94946811 2.5788997 -1.94146732 2 P 0 ;0,5=32,7=0.000000
L 2.5788997 -1.94146732 2.5698998 -1.93613278 2 P 0 ;0,5=32,7=0.000000
L 2.5698998 -1.93613278 2.55790049 -1.93346663 2 P 0 ;0,5=32,7=0.000000
L 2.55790049 -1.93346663 2.5509002 -1.92813445 2 P 0 ;0,5=32,7=0.000000
L 2.5509002 -1.92813445 2.54789902 -1.91880069 2 P 0 ;0,5=32,7=0.000000
L 2.54789902 -1.91880069 2.54990039 -1.90946683 2 P 0 ;0,5=32,7=0.000000
L 2.54990039 -1.90946683 2.55489931 -1.90280167 2 P 0 ;0,5=32,7=0.000000
L 2.55489931 -1.90280167 2.5618997 -1.8988 2 P 0 ;0,5=32,7=0.000000
L 2.5618997 -1.8988 2.5689 -1.8988 2 P 0 ;0,5=32,7=0.000000
L 2.5689 -1.8988 2.57590039 -1.90146614 2 P 0 ;0,5=32,7=0.000000
L 2.57590039 -1.90146614 2.58190089 -1.90813386 2 P 0 ;0,5=32,7=0.000000
L 2.6648998 -1.90546772 2.65889931 -1.90146614 2 P 0 ;0,5=32,7=0.000000
L 2.65889931 -1.90146614 2.65190079 -1.8988 2 P 0 ;0,5=32,7=0.000000
L 2.65190079 -1.8988 2.64390069 -1.8988 2 P 0 ;0,5=32,7=0.000000
L 2.64390069 -1.8988 2.63489892 -1.90280167 2 P 0 ;0,5=32,7=0.000000
L 2.63489892 -1.90280167 2.62790039 -1.90946683 2 P 0 ;0,5=32,7=0.000000
L 2.62790039 -1.90946683 2.62289961 -1.91746762 2 P 0 ;0,5=32,7=0.000000
L 2.62289961 -1.91746762 2.61889862 -1.93080049 2 P 0 ;0,5=32,7=0.000000
L 2.61889862 -1.93080049 2.61789892 -1.94280039 2 P 0 ;0,5=32,7=0.000000
L 2.61789892 -1.94280039 2.6199003 -1.9548003 2 P 0 ;0,5=32,7=0.000000
L 2.6199003 -1.9548003 2.62289961 -1.96280098 2 P 0 ;0,5=32,7=0.000000
L 2.62289961 -1.96280098 2.6289002 -1.97080177 2 P 0 ;0,5=32,7=0.000000
L 2.6289002 -1.97080177 2.63590049 -1.97613396 2 P 0 ;0,5=32,7=0.000000
L 2.63590049 -1.97613396 2.64289902 -1.9788 2 P 0 ;0,5=32,7=0.000000
L 2.64289902 -1.9788 2.64989941 -1.9788 2 P 0 ;0,5=32,7=0.000000
L 2.64989941 -1.9788 2.6568997 -1.97613396 2 P 0 ;0,5=32,7=0.000000
L 2.6568997 -1.97613396 2.6629003 -1.97213484 2 P 0 ;0,5=32,7=0.000000
L 2.6629003 -1.97213484 2.66790098 -1.96680266 2 P 0 ;0,5=32,7=0.000000
L 2.69589892 -1.9788 2.72089902 -1.8988 2 P 0 ;0,5=32,7=0.000000
L 2.72089902 -1.8988 2.74590098 -1.9788 2 P 0 ;0,5=32,7=0.000000
L 2.73689931 -1.95080118 2.70489882 -1.95080118 2 P 0 ;0,5=32,7=0.000000
L 2.77889961 -1.8988 2.77889961 -1.9788 2 P 0 ;0,5=32,7=0.000000
L 2.77889961 -1.9788 2.8189003 -1.9788 2 P 0 ;0,5=32,7=0.000000
L 2.8969003 -1.9788 2.85689961 -1.9788 2 P 0 ;0,5=32,7=0.000000
L 2.85689961 -1.9788 2.85689961 -1.8988 2 P 0 ;0,5=32,7=0.000000
L 2.85689961 -1.8988 2.8969003 -1.8988 2 P 0 ;0,5=32,7=0.000000
L 2.8809 -1.93746575 2.85689961 -1.93746575 2 P 0 ;0,5=32,7=0.000000
L 3.03289902 -1.9788 3.03289902 -1.8988 2 P 0 ;0,5=32,7=0.000000
L 3.03289902 -1.8988 3.0208998 -1.91479911 2 P 0 ;0,5=32,7=0.000000
L 3.0208998 -1.9788 3.04489833 -1.9788 2 P 0 ;0,5=32,7=0.000000
L 3.11089902 -1.98146604 3.10889951 -1.98013297 2 P 0 ;0,5=32,7=0.000000
L 3.10889951 -1.98013297 3.10889951 -1.97746703 2 P 0 ;0,5=32,7=0.000000
L 3.10889951 -1.97746703 3.11089902 -1.97613396 2 P 0 ;0,5=32,7=0.000000
L 3.11089902 -1.97613396 3.11290039 -1.97746703 2 P 0 ;0,5=32,7=0.000000
L 3.11290039 -1.97746703 3.11290039 -1.98013297 2 P 0 ;0,5=32,7=0.000000
L 3.11290039 -1.98013297 3.11089902 -1.98146604 2 P 0 ;0,5=32,7=0.000000
L 3.11089902 -1.945469 3.10889951 -1.94413346 2 P 0 ;0,5=32,7=0.000000
L 3.10889951 -1.94413346 3.10889951 -1.94146732 2 P 0 ;0,5=32,7=0.000000
L 3.10889951 -1.94146732 3.11089902 -1.94013435 2 P 0 ;0,5=32,7=0.000000
L 3.11089902 -1.94013435 3.11290039 -1.94146732 2 P 0 ;0,5=32,7=0.000000
L 3.11290039 -1.94146732 3.11290039 -1.94413346 2 P 0 ;0,5=32,7=0.000000
L 3.11290039 -1.94413346 3.11089902 -1.945469 2 P 0 ;0,5=32,7=0.000000
L 3.18889902 -1.9788 3.18889902 -1.8988 2 P 0 ;0,5=32,7=0.000000
L 3.18889902 -1.8988 3.1768998 -1.91479911 2 P 0 ;0,5=32,7=0.000000
L 3.1768998 -1.9788 3.20089833 -1.9788 2 P 0 ;0,5=32,7=0.000000
L 2.5138999 -2.23313563 2.5219 -2.23980089 2 P 0 ;0,5=30,7=0.000000
L 2.5219 -2.23980089 2.5308999 -2.2438 2 P 0 ;0,5=30,7=0.000000
L 2.5308999 -2.2438 2.5389 -2.2438 2 P 0 ;0,5=30,7=0.000000
L 2.5389 -2.2438 2.5469001 -2.23980089 2 P 0 ;0,5=30,7=0.000000
L 2.5469001 -2.23980089 2.55290069 -2.23313563 2 P 0 ;0,5=30,7=0.000000
L 2.55290069 -2.23313563 2.5559 -2.22379941 2 P 0 ;0,5=30,7=0.000000
L 2.5559 -2.22379941 2.55390049 -2.21446811 2 P 0 ;0,5=30,7=0.000000
L 2.55390049 -2.21446811 2.5488997 -2.20646732 2 P 0 ;0,5=30,7=0.000000
L 2.5488997 -2.20646732 2.5398998 -2.20113278 2 P 0 ;0,5=30,7=0.000000
L 2.5398998 -2.20113278 2.52790049 -2.19846663 2 P 0 ;0,5=30,7=0.000000
L 2.52790049 -2.19846663 2.5209002 -2.19313445 2 P 0 ;0,5=30,7=0.000000
L 2.5209002 -2.19313445 2.51789902 -2.18380069 2 P 0 ;0,5=30,7=0.000000
L 2.51789902 -2.18380069 2.51990039 -2.17446683 2 P 0 ;0,5=30,7=0.000000
L 2.51990039 -2.17446683 2.52489931 -2.16780167 2 P 0 ;0,5=30,7=0.000000
L 2.52489931 -2.16780167 2.5318997 -2.1638 2 P 0 ;0,5=30,7=0.000000
L 2.5318997 -2.1638 2.5389 -2.1638 2 P 0 ;0,5=30,7=0.000000
L 2.5389 -2.1638 2.54590039 -2.16646614 2 P 0 ;0,5=30,7=0.000000
L 2.54590039 -2.16646614 2.55190089 -2.17313386 2 P 0 ;0,5=30,7=0.000000
L 2.5918999 -2.2438 2.5918999 -2.1638 2 P 0 ;0,5=30,7=0.000000
L 2.6339 -2.1638 2.6339 -2.2438 2 P 0 ;0,5=30,7=0.000000
L 2.6339 -2.20380128 2.5918999 -2.20380128 2 P 0 ;0,5=30,7=0.000000
L 2.7109003 -2.2438 2.67089961 -2.2438 2 P 0 ;0,5=30,7=0.000000
L 2.67089961 -2.2438 2.67089961 -2.1638 2 P 0 ;0,5=30,7=0.000000
L 2.67089961 -2.1638 2.7109003 -2.1638 2 P 0 ;0,5=30,7=0.000000
L 2.6949 -2.20246575 2.67089961 -2.20246575 2 P 0 ;0,5=30,7=0.000000
L 2.7889003 -2.2438 2.74889961 -2.2438 2 P 0 ;0,5=30,7=0.000000
L 2.74889961 -2.2438 2.74889961 -2.1638 2 P 0 ;0,5=30,7=0.000000
L 2.74889961 -2.1638 2.7889003 -2.1638 2 P 0 ;0,5=30,7=0.000000
L 2.7729 -2.20246575 2.74889961 -2.20246575 2 P 0 ;0,5=30,7=0.000000
L 2.84689902 -2.1638 2.84689902 -2.2438 2 P 0 ;0,5=30,7=0.000000
L 2.8239003 -2.1638 2.86989961 -2.1638 2 P 0 ;0,5=30,7=0.000000
L 3.29489961 -1.9238 3.29489961 -2.0038 2 P 0 ;0,5=33,7=0.000000
L 3.29489961 -2.0038 3.3349003 -2.0038 2 P 0 ;0,5=33,7=0.000000
L 3.36789892 -2.0038 3.39289902 -1.9238 2 P 0 ;0,5=33,7=0.000000
L 3.39289902 -1.9238 3.41790098 -2.0038 2 P 0 ;0,5=33,7=0.000000
L 3.40889931 -1.97580118 3.37689882 -1.97580118 2 P 0 ;0,5=33,7=0.000000
L 3.47089902 -2.0038 3.47089902 -1.96780039 2 P 0 ;0,5=33,7=0.000000
L 3.47089902 -1.96780039 3.45089961 -1.9238 2 P 0 ;0,5=33,7=0.000000
L 3.4909003 -1.9238 3.47089902 -1.96780039 2 P 0 ;0,5=33,7=0.000000
L 3.5689003 -2.0038 3.52889961 -2.0038 2 P 0 ;0,5=33,7=0.000000
L 3.52889961 -2.0038 3.52889961 -1.9238 2 P 0 ;0,5=33,7=0.000000
L 3.52889961 -1.9238 3.5689003 -1.9238 2 P 0 ;0,5=33,7=0.000000
L 3.5529 -1.96246575 3.52889961 -1.96246575 2 P 0 ;0,5=33,7=0.000000
L 3.60689961 -2.0038 3.60689961 -1.9238 2 P 0 ;0,5=33,7=0.000000
L 3.60689961 -1.9238 3.6318998 -1.9238 2 P 0 ;0,5=33,7=0.000000
L 3.6318998 -1.9238 3.6398999 -1.92780167 2 P 0 ;0,5=33,7=0.000000
L 3.6398999 -1.92780167 3.64490069 -1.93313386 2 P 0 ;0,5=33,7=0.000000
L 3.64490069 -1.93313386 3.6469003 -1.94380069 2 P 0 ;0,5=33,7=0.000000
L 3.6469003 -1.94380069 3.64490069 -1.95446752 2 P 0 ;0,5=33,7=0.000000
L 3.64490069 -1.95446752 3.6389001 -1.96113278 2 P 0 ;0,5=33,7=0.000000
L 3.6389001 -1.96113278 3.6318998 -1.96513435 2 P 0 ;0,5=33,7=0.000000
L 3.6318998 -1.96513435 3.60689961 -1.96513435 2 P 0 ;0,5=33,7=0.000000
L 3.6318998 -1.96513435 3.6469003 -2.0038 2 P 0 ;0,5=33,7=0.000000
L 3.33989902 -2.2538 3.33189892 -2.25246703 2 P 0 ;0,5=34,7=0.000000
L 3.33189892 -2.25246703 3.32490039 -2.24713484 2 P 0 ;0,5=34,7=0.000000
L 3.32490039 -2.24713484 3.3188999 -2.23913406 2 P 0 ;0,5=34,7=0.000000
L 3.3188999 -2.23913406 3.31489892 -2.2298003 2 P 0 ;0,5=34,7=0.000000
L 3.31489892 -2.2298003 3.31289931 -2.21913346 2 P 0 ;0,5=34,7=0.000000
L 3.31289931 -2.21913346 3.31289931 -2.20846663 2 P 0 ;0,5=34,7=0.000000
L 3.31289931 -2.20846663 3.31489892 -2.1977998 2 P 0 ;0,5=34,7=0.000000
L 3.31489892 -2.1977998 3.3188999 -2.18846604 2 P 0 ;0,5=34,7=0.000000
L 3.3188999 -2.18846604 3.32490039 -2.18046772 2 P 0 ;0,5=34,7=0.000000
L 3.32490039 -2.18046772 3.33189892 -2.17513307 2 P 0 ;0,5=34,7=0.000000
L 3.33189892 -2.17513307 3.33989902 -2.1738 2 P 0 ;0,5=34,7=0.000000
L 3.33989902 -2.1738 3.34789911 -2.17513307 2 P 0 ;0,5=34,7=0.000000
L 3.34789911 -2.17513307 3.35489951 -2.18046772 2 P 0 ;0,5=34,7=0.000000
L 3.35489951 -2.18046772 3.3609 -2.18846604 2 P 0 ;0,5=34,7=0.000000
L 3.3609 -2.18846604 3.36490098 -2.1977998 2 P 0 ;0,5=34,7=0.000000
L 3.36490098 -2.1977998 3.36690059 -2.20846663 2 P 0 ;0,5=34,7=0.000000
L 3.36690059 -2.20846663 3.36690059 -2.21913346 2 P 0 ;0,5=34,7=0.000000
L 3.36690059 -2.21913346 3.36490098 -2.2298003 2 P 0 ;0,5=34,7=0.000000
L 3.36490098 -2.2298003 3.3609 -2.23913406 2 P 0 ;0,5=34,7=0.000000
L 3.3609 -2.23913406 3.35489951 -2.24713484 2 P 0 ;0,5=34,7=0.000000
L 3.35489951 -2.24713484 3.34789911 -2.25246703 2 P 0 ;0,5=34,7=0.000000
L 3.34789911 -2.25246703 3.33989902 -2.2538 2 P 0 ;0,5=34,7=0.000000
L 3.39889941 -2.2538 3.39889941 -2.1738 2 P 0 ;0,5=34,7=0.000000
L 3.39889941 -2.1738 3.43690049 -2.1738 2 P 0 ;0,5=34,7=0.000000
L 3.4228998 -2.21246575 3.39889941 -2.21246575 2 P 0 ;0,5=34,7=0.000000
L 0.16489872 -1.0538 0.16489872 -1.1538 2 P 0 ;0,5=31,7=0.000000
L 0.13423376 -1.0538 0.19556614 -1.0538 2 P 0 ;0,5=31,7=0.000000
L 0.2588997 -1.0538 0.29089774 -1.0538 2 P 0 ;0,5=31,7=0.000000
L 0.27489872 -1.0538 0.27489872 -1.1538 2 P 0 ;0,5=31,7=0.000000
L 0.2588997 -1.1538 0.29089774 -1.1538 2 P 0 ;0,5=31,7=0.000000
L 0.38489872 -1.0538 0.38489872 -1.1538 2 P 0 ;0,5=31,7=0.000000
L 0.35423376 -1.0538 0.41556614 -1.0538 2 P 0 ;0,5=31,7=0.000000
L 0.46823287 -1.0538 0.46823287 -1.1538 2 P 0 ;0,5=31,7=0.000000
L 0.46823287 -1.1538 0.52156703 -1.1538 2 P 0 ;0,5=31,7=0.000000
L 0.63156703 -1.1538 0.57823287 -1.1538 2 P 0 ;0,5=31,7=0.000000
L 0.57823287 -1.1538 0.57823287 -1.0538 2 P 0 ;0,5=31,7=0.000000
L 0.57823287 -1.0538 0.63156703 -1.0538 2 P 0 ;0,5=31,7=0.000000
L 0.61023337 -1.10213219 0.57823287 -1.10213219 2 P 0 ;0,5=31,7=0.000000
L 4.18989892 -1.9538 4.21489902 -1.8738 2 P 0 ;0,5=35,7=0.000000
L 4.21489902 -1.8738 4.23990098 -1.9538 2 P 0 ;0,5=35,7=0.000000
L 4.23089931 -1.92580118 4.19889882 -1.92580118 2 P 0 ;0,5=35,7=0.000000
L 4.27289961 -1.9538 4.27289961 -1.8738 2 P 0 ;0,5=35,7=0.000000
L 4.27289961 -1.8738 4.2978998 -1.8738 2 P 0 ;0,5=35,7=0.000000
L 4.2978998 -1.8738 4.3058999 -1.87780167 2 P 0 ;0,5=35,7=0.000000
L 4.3058999 -1.87780167 4.31090069 -1.88313386 2 P 0 ;0,5=35,7=0.000000
L 4.31090069 -1.88313386 4.3129003 -1.89380069 2 P 0 ;0,5=35,7=0.000000
L 4.3129003 -1.89380069 4.31090069 -1.90446752 2 P 0 ;0,5=35,7=0.000000
L 4.31090069 -1.90446752 4.3049001 -1.91113278 2 P 0 ;0,5=35,7=0.000000
L 4.3049001 -1.91113278 4.2978998 -1.91513435 2 P 0 ;0,5=35,7=0.000000
L 4.2978998 -1.91513435 4.27289961 -1.91513435 2 P 0 ;0,5=35,7=0.000000
L 4.2978998 -1.91513435 4.3129003 -1.9538 2 P 0 ;0,5=35,7=0.000000
L 4.37089902 -1.8738 4.37089902 -1.9538 2 P 0 ;0,5=35,7=0.000000
L 4.3479003 -1.8738 4.39389961 -1.8738 2 P 0 ;0,5=35,7=0.000000
L 2.0244002 -1.74180266 2.01506663 -1.74930098 2 P 0 ;0,3,5=36,7=0.000000
L 2.01506663 -1.74930098 2.00456683 -1.7538 2 P 0 ;0,3,5=36,7=0.000000
L 2.00456683 -1.7538 1.99523327 -1.7538 2 P 0 ;0,3,5=36,7=0.000000
L 1.99523327 -1.7538 1.9858998 -1.74930098 2 P 0 ;0,3,5=36,7=0.000000
L 1.9858998 -1.74930098 1.97889921 -1.74180266 2 P 0 ;0,3,5=36,7=0.000000
L 1.97889921 -1.74180266 1.9753999 -1.73129941 2 P 0 ;0,3,5=36,7=0.000000
L 1.9753999 -1.73129941 1.97773278 -1.72080157 2 P 0 ;0,3,5=36,7=0.000000
L 1.97773278 -1.72080157 1.98356703 -1.71180079 2 P 0 ;0,3,5=36,7=0.000000
L 1.98356703 -1.71180079 1.99406693 -1.70579931 2 P 0 ;0,3,5=36,7=0.000000
L 1.99406693 -1.70579931 2.00806604 -1.7028 2 P 0 ;0,3,5=36,7=0.000000
L 2.00806604 -1.7028 2.01623307 -1.69680128 2 P 0 ;0,3,5=36,7=0.000000
L 2.01623307 -1.69680128 2.01973445 -1.68630069 2 P 0 ;0,3,5=36,7=0.000000
L 2.01973445 -1.68630069 2.01739951 -1.6758002 2 P 0 ;0,3,5=36,7=0.000000
L 2.01739951 -1.6758002 2.01156742 -1.66830187 2 P 0 ;0,3,5=36,7=0.000000
L 2.01156742 -1.66830187 2.00340039 -1.6638 2 P 0 ;0,3,5=36,7=0.000000
L 2.00340039 -1.6638 1.99523327 -1.6638 2 P 0 ;0,3,5=36,7=0.000000
L 1.99523327 -1.6638 1.98706624 -1.66679941 2 P 0 ;0,3,5=36,7=0.000000
L 1.98706624 -1.66679941 1.98006565 -1.67430059 2 P 0 ;0,3,5=36,7=0.000000
L 1.90990108 -1.7538 1.91923455 -1.75230039 2 P 0 ;0,3,5=36,7=0.000000
L 1.91923455 -1.75230039 1.92739951 -1.74630167 2 P 0 ;0,3,5=36,7=0.000000
L 1.92739951 -1.74630167 1.9344002 -1.73730079 2 P 0 ;0,3,5=36,7=0.000000
L 1.9344002 -1.73730079 1.93906791 -1.7268003 2 P 0 ;0,3,5=36,7=0.000000
L 1.93906791 -1.7268003 1.94140079 -1.7148001 2 P 0 ;0,3,5=36,7=0.000000
L 1.94140079 -1.7148001 1.94140079 -1.7028 2 P 0 ;0,3,5=36,7=0.000000
L 1.94140079 -1.7028 1.93906791 -1.6907998 2 P 0 ;0,3,5=36,7=0.000000
L 1.93906791 -1.6907998 1.9344002 -1.68029931 2 P 0 ;0,3,5=36,7=0.000000
L 1.9344002 -1.68029931 1.92739951 -1.67130118 2 P 0 ;0,3,5=36,7=0.000000
L 1.92739951 -1.67130118 1.91923455 -1.6652997 2 P 0 ;0,3,5=36,7=0.000000
L 1.91923455 -1.6652997 1.90990108 -1.6638 2 P 0 ;0,3,5=36,7=0.000000
L 1.90990108 -1.6638 1.90056762 -1.6652997 2 P 0 ;0,3,5=36,7=0.000000
L 1.90056762 -1.6652997 1.89240059 -1.67130118 2 P 0 ;0,3,5=36,7=0.000000
L 1.89240059 -1.67130118 1.8853999 -1.68029931 2 P 0 ;0,3,5=36,7=0.000000
L 1.8853999 -1.68029931 1.88073219 -1.6907998 2 P 0 ;0,3,5=36,7=0.000000
L 1.88073219 -1.6907998 1.87839931 -1.7028 2 P 0 ;0,3,5=36,7=0.000000
L 1.87839931 -1.7028 1.87839931 -1.7148001 2 P 0 ;0,3,5=36,7=0.000000
L 1.87839931 -1.7148001 1.88073219 -1.7268003 2 P 0 ;0,3,5=36,7=0.000000
L 1.88073219 -1.7268003 1.8853999 -1.73730079 2 P 0 ;0,3,5=36,7=0.000000
L 1.8853999 -1.73730079 1.89240059 -1.74630167 2 P 0 ;0,3,5=36,7=0.000000
L 1.89240059 -1.74630167 1.90056762 -1.75230039 2 P 0 ;0,3,5=36,7=0.000000
L 1.90056762 -1.75230039 1.90990108 -1.7538 2 P 0 ;0,3,5=36,7=0.000000
L 1.84323376 -1.6638 1.84323376 -1.7538 2 P 0 ;0,3,5=36,7=0.000000
L 1.84323376 -1.7538 1.79656634 -1.7538 2 P 0 ;0,3,5=36,7=0.000000
L 1.75556654 -1.7538 1.75556654 -1.6638 2 P 0 ;0,3,5=36,7=0.000000
L 1.75556654 -1.6638 1.73223396 -1.6638 2 P 0 ;0,3,5=36,7=0.000000
L 1.73223396 -1.6638 1.72290049 -1.66830187 2 P 0 ;0,3,5=36,7=0.000000
L 1.72290049 -1.66830187 1.7158998 -1.67430059 2 P 0 ;0,3,5=36,7=0.000000
L 1.7158998 -1.67430059 1.71006565 -1.68329862 2 P 0 ;0,3,5=36,7=0.000000
L 1.71006565 -1.68329862 1.7053999 -1.69380187 2 P 0 ;0,3,5=36,7=0.000000
L 1.7053999 -1.69380187 1.70423356 -1.70880138 2 P 0 ;0,3,5=36,7=0.000000
L 1.70423356 -1.70880138 1.7053999 -1.72380098 2 P 0 ;0,3,5=36,7=0.000000
L 1.7053999 -1.72380098 1.71006565 -1.73430148 2 P 0 ;0,3,5=36,7=0.000000
L 1.71006565 -1.73430148 1.7158998 -1.74330226 2 P 0 ;0,3,5=36,7=0.000000
L 1.7158998 -1.74330226 1.72290049 -1.74930098 2 P 0 ;0,3,5=36,7=0.000000
L 1.72290049 -1.74930098 1.73223396 -1.7538 2 P 0 ;0,3,5=36,7=0.000000
L 1.73223396 -1.7538 1.75556654 -1.7538 2 P 0 ;0,3,5=36,7=0.000000
L 1.61656634 -1.7538 1.66323376 -1.7538 2 P 0 ;0,3,5=36,7=0.000000
L 1.66323376 -1.7538 1.66323376 -1.6638 2 P 0 ;0,3,5=36,7=0.000000
L 1.66323376 -1.6638 1.61656634 -1.6638 2 P 0 ;0,3,5=36,7=0.000000
L 1.63523327 -1.70729902 1.66323376 -1.70729902 2 P 0 ;0,3,5=36,7=0.000000
L 1.57323376 -1.7538 1.57323376 -1.6638 2 P 0 ;0,3,5=36,7=0.000000
L 1.57323376 -1.6638 1.54406693 -1.6638 2 P 0 ;0,3,5=36,7=0.000000
L 1.54406693 -1.6638 1.53473346 -1.66830187 2 P 0 ;0,3,5=36,7=0.000000
L 1.53473346 -1.66830187 1.52889921 -1.67430059 2 P 0 ;0,3,5=36,7=0.000000
L 1.52889921 -1.67430059 1.52656634 -1.68630069 2 P 0 ;0,3,5=36,7=0.000000
L 1.52656634 -1.68630069 1.52889921 -1.69830089 2 P 0 ;0,3,5=36,7=0.000000
L 1.52889921 -1.69830089 1.5358998 -1.70579931 2 P 0 ;0,3,5=36,7=0.000000
L 1.5358998 -1.70579931 1.54406693 -1.71030108 2 P 0 ;0,3,5=36,7=0.000000
L 1.54406693 -1.71030108 1.57323376 -1.71030108 2 P 0 ;0,3,5=36,7=0.000000
L 1.54406693 -1.71030108 1.52656634 -1.7538 2 P 0 ;0,3,5=36,7=0.000000
L 1.40023435 -1.7538 1.40023435 -1.6638 2 P 0 ;0,3,5=36,7=0.000000
L 1.40023435 -1.6638 1.36990108 -1.73880049 2 P 0 ;0,3,5=36,7=0.000000
L 1.36990108 -1.73880049 1.33956575 -1.6638 2 P 0 ;0,3,5=36,7=0.000000
L 1.33956575 -1.6638 1.33956575 -1.7538 2 P 0 ;0,3,5=36,7=0.000000
L 1.30906791 -1.7538 1.27990108 -1.6638 2 P 0 ;0,3,5=36,7=0.000000
L 1.27990108 -1.6638 1.25073219 -1.7538 2 P 0 ;0,3,5=36,7=0.000000
L 1.26123415 -1.72230128 1.29856811 -1.72230128 2 P 0 ;0,3,5=36,7=0.000000
L 1.2144002 -1.74180266 1.20506663 -1.74930098 2 P 0 ;0,3,5=36,7=0.000000
L 1.20506663 -1.74930098 1.19456683 -1.7538 2 P 0 ;0,3,5=36,7=0.000000
L 1.19456683 -1.7538 1.18523327 -1.7538 2 P 0 ;0,3,5=36,7=0.000000
L 1.18523327 -1.7538 1.1758998 -1.74930098 2 P 0 ;0,3,5=36,7=0.000000
L 1.1758998 -1.74930098 1.16889921 -1.74180266 2 P 0 ;0,3,5=36,7=0.000000
L 1.16889921 -1.74180266 1.1653999 -1.73129941 2 P 0 ;0,3,5=36,7=0.000000
L 1.1653999 -1.73129941 1.16773278 -1.72080157 2 P 0 ;0,3,5=36,7=0.000000
L 1.16773278 -1.72080157 1.17356703 -1.71180079 2 P 0 ;0,3,5=36,7=0.000000
L 1.17356703 -1.71180079 1.18406693 -1.70579931 2 P 0 ;0,3,5=36,7=0.000000
L 1.18406693 -1.70579931 1.19806604 -1.7028 2 P 0 ;0,3,5=36,7=0.000000
L 1.19806604 -1.7028 1.20623307 -1.69680128 2 P 0 ;0,3,5=36,7=0.000000
L 1.20623307 -1.69680128 1.20973445 -1.68630069 2 P 0 ;0,3,5=36,7=0.000000
L 1.20973445 -1.68630069 1.20739951 -1.6758002 2 P 0 ;0,3,5=36,7=0.000000
L 1.20739951 -1.6758002 1.20156742 -1.66830187 2 P 0 ;0,3,5=36,7=0.000000
L 1.20156742 -1.66830187 1.19340039 -1.6638 2 P 0 ;0,3,5=36,7=0.000000
L 1.19340039 -1.6638 1.18523327 -1.6638 2 P 0 ;0,3,5=36,7=0.000000
L 1.18523327 -1.6638 1.17706624 -1.66679941 2 P 0 ;0,3,5=36,7=0.000000
L 1.17706624 -1.66679941 1.17006565 -1.67430059 2 P 0 ;0,3,5=36,7=0.000000
L 1.12556654 -1.7538 1.12556654 -1.6638 2 P 0 ;0,3,5=36,7=0.000000
L 1.08123415 -1.6638 1.12556654 -1.71930197 2 P 0 ;0,3,5=36,7=0.000000
L 1.07423356 -1.7538 1.10573317 -1.69380187 2 P 0 ;0,3,5=36,7=0.000000
L 0.92573317 -1.78379902 0.93739951 -1.76879951 2 P 0 ;0,3,5=36,7=0.000000
L 0.93739951 -1.76879951 0.94323376 -1.7538 2 P 0 ;0,3,5=36,7=0.000000
L 0.94323376 -1.7538 0.94323376 -1.69380187 2 P 0 ;0,3,5=36,7=0.000000
L 0.94323376 -1.69380187 0.93739951 -1.67879961 2 P 0 ;0,3,5=36,7=0.000000
L 0.93739951 -1.67879961 0.92573317 -1.6638 2 P 0 ;0,3,5=36,7=0.000000
L 0.82056762 -1.70579931 0.8158998 -1.7013003 2 P 0 ;0,3,5=36,7=0.000000
L 0.8158998 -1.7013003 0.81240059 -1.69380187 2 P 0 ;0,3,5=36,7=0.000000
L 0.81240059 -1.69380187 0.81006565 -1.68329862 2 P 0 ;0,3,5=36,7=0.000000
L 0.81006565 -1.68329862 0.81240059 -1.67430059 2 P 0 ;0,3,5=36,7=0.000000
L 0.81240059 -1.67430059 0.81706624 -1.66830187 2 P 0 ;0,3,5=36,7=0.000000
L 0.81706624 -1.66830187 0.82523327 -1.6638 2 P 0 ;0,3,5=36,7=0.000000
L 0.82523327 -1.6638 0.85673297 -1.6638 2 P 0 ;0,3,5=36,7=0.000000
L 0.85673297 -1.6638 0.85673297 -1.7538 2 P 0 ;0,3,5=36,7=0.000000
L 0.85673297 -1.7538 0.81823268 -1.7538 2 P 0 ;0,3,5=36,7=0.000000
L 0.81823268 -1.7538 0.81006565 -1.74780138 2 P 0 ;0,3,5=36,7=0.000000
L 0.81006565 -1.74780138 0.8053999 -1.73880049 2 P 0 ;0,3,5=36,7=0.000000
L 0.8053999 -1.73880049 0.80306713 -1.7283 2 P 0 ;0,3,5=36,7=0.000000
L 0.80306713 -1.7283 0.8053999 -1.71780226 2 P 0 ;0,3,5=36,7=0.000000
L 0.8053999 -1.71780226 0.81240059 -1.70880138 2 P 0 ;0,3,5=36,7=0.000000
L 0.81240059 -1.70880138 0.82056762 -1.70579931 2 P 0 ;0,3,5=36,7=0.000000
L 0.82056762 -1.70579931 0.85673297 -1.70579931 2 P 0 ;0,3,5=36,7=0.000000
L 0.73990108 -1.7538 0.74923455 -1.75230039 2 P 0 ;0,3,5=36,7=0.000000
L 0.74923455 -1.75230039 0.75739951 -1.74630167 2 P 0 ;0,3,5=36,7=0.000000
L 0.75739951 -1.74630167 0.7644002 -1.73730079 2 P 0 ;0,3,5=36,7=0.000000
L 0.7644002 -1.73730079 0.76906791 -1.7268003 2 P 0 ;0,3,5=36,7=0.000000
L 0.76906791 -1.7268003 0.77140079 -1.7148001 2 P 0 ;0,3,5=36,7=0.000000
L 0.77140079 -1.7148001 0.77140079 -1.7028 2 P 0 ;0,3,5=36,7=0.000000
L 0.77140079 -1.7028 0.76906791 -1.6907998 2 P 0 ;0,3,5=36,7=0.000000
L 0.76906791 -1.6907998 0.7644002 -1.68029931 2 P 0 ;0,3,5=36,7=0.000000
L 0.7644002 -1.68029931 0.75739951 -1.67130118 2 P 0 ;0,3,5=36,7=0.000000
L 0.75739951 -1.67130118 0.74923455 -1.6652997 2 P 0 ;0,3,5=36,7=0.000000
L 0.74923455 -1.6652997 0.73990108 -1.6638 2 P 0 ;0,3,5=36,7=0.000000
L 0.73990108 -1.6638 0.73056762 -1.6652997 2 P 0 ;0,3,5=36,7=0.000000
L 0.73056762 -1.6652997 0.72240059 -1.67130118 2 P 0 ;0,3,5=36,7=0.000000
L 0.72240059 -1.67130118 0.7153999 -1.68029931 2 P 0 ;0,3,5=36,7=0.000000
L 0.7153999 -1.68029931 0.71073219 -1.6907998 2 P 0 ;0,3,5=36,7=0.000000
L 0.71073219 -1.6907998 0.70839931 -1.7028 2 P 0 ;0,3,5=36,7=0.000000
L 0.70839931 -1.7028 0.70839931 -1.7148001 2 P 0 ;0,3,5=36,7=0.000000
L 0.70839931 -1.7148001 0.71073219 -1.7268003 2 P 0 ;0,3,5=36,7=0.000000
L 0.71073219 -1.7268003 0.7153999 -1.73730079 2 P 0 ;0,3,5=36,7=0.000000
L 0.7153999 -1.73730079 0.72240059 -1.74630167 2 P 0 ;0,3,5=36,7=0.000000
L 0.72240059 -1.74630167 0.73056762 -1.75230039 2 P 0 ;0,3,5=36,7=0.000000
L 0.73056762 -1.75230039 0.73990108 -1.7538 2 P 0 ;0,3,5=36,7=0.000000
L 0.64990108 -1.6638 0.64990108 -1.7538 2 P 0 ;0,3,5=36,7=0.000000
L 0.67673297 -1.6638 0.62306713 -1.6638 2 P 0 ;0,3,5=36,7=0.000000
L 0.55406693 -1.78379902 0.54240059 -1.76879951 2 P 0 ;0,3,5=36,7=0.000000
L 0.54240059 -1.76879951 0.53656634 -1.7538 2 P 0 ;0,3,5=36,7=0.000000
L 0.53656634 -1.7538 0.53656634 -1.69380187 2 P 0 ;0,3,5=36,7=0.000000
L 0.53656634 -1.69380187 0.54240059 -1.67879961 2 P 0 ;0,3,5=36,7=0.000000
L 0.54240059 -1.67879961 0.55406693 -1.6638 2 P 0 ;0,3,5=36,7=0.000000
L 3.06989892 -2.2538 3.06989892 -2.1638 2 P 0 ;0,5=37,7=0.000000
L 3.06989892 -2.1638 3.0558997 -2.18179892 2 P 0 ;0,5=37,7=0.000000
L 3.0558997 -2.2538 3.08389803 -2.2538 2 P 0 ;0,5=37,7=0.000000
L 3.64489892 -2.2538 3.64489892 -2.1638 2 P 0 ;0,5=37,7=0.000000
L 3.64489892 -2.1638 3.6308997 -2.18179892 2 P 0 ;0,5=37,7=0.000000
L 3.6308997 -2.2538 3.65889803 -2.2538 2 P 0 ;0,5=37,7=0.000000
L 3.72973337 -1.97380098 3.76006654 -1.97380098 2 P 0 ;0,5=38,7=0.000000
L 0.59099833 -1.36499882 0.5990003 -1.35750039 2 P 0 ;0,5=39,7=0.000000
L 0.5990003 -1.35750039 0.60499902 -1.34500315 2 P 0 ;0,5=39,7=0.000000
L 0.60499902 -1.34500315 0.60900187 -1.32749764 2 P 0 ;0,5=39,7=0.000000
L 0.60900187 -1.32749764 0.60499902 -1.31250089 2 P 0 ;0,5=39,7=0.000000
L 0.60499902 -1.31250089 0.59700079 -1.30250305 2 P 0 ;0,5=39,7=0.000000
L 0.59700079 -1.30250305 0.5830001 -1.295 2 P 0 ;0,5=39,7=0.000000
L 0.5830001 -1.295 0.52900059 -1.295 2 P 0 ;0,5=39,7=0.000000
L 0.52900059 -1.295 0.52900059 -1.445 2 P 0 ;0,5=39,7=0.000000
L 0.52900059 -1.445 0.59500118 -1.445 2 P 0 ;0,5=39,7=0.000000
L 0.59500118 -1.445 0.60900187 -1.43500217 2 P 0 ;0,5=39,7=0.000000
L 0.60900187 -1.43500217 0.6170001 -1.42000079 2 P 0 ;0,5=39,7=0.000000
L 0.6170001 -1.42000079 0.62099931 -1.4025 2 P 0 ;0,5=39,7=0.000000
L 0.62099931 -1.4025 0.6170001 -1.38500374 2 P 0 ;0,5=39,7=0.000000
L 0.6170001 -1.38500374 0.60499902 -1.37000236 2 P 0 ;0,5=39,7=0.000000
L 0.60499902 -1.37000236 0.59099833 -1.36499882 2 P 0 ;0,5=39,7=0.000000
L 0.59099833 -1.36499882 0.52900059 -1.36499882 2 P 0 ;0,5=39,7=0.000000
L 0.77100138 -1.445 0.77100138 -1.34500315 2 P 0 ;0,5=39,7=0.000000
L 0.77100138 -1.36249941 0.76299951 -1.35250148 2 P 0 ;0,5=39,7=0.000000
L 0.76299951 -1.35250148 0.75099833 -1.34750256 2 P 0 ;0,5=39,7=0.000000
L 0.75099833 -1.34750256 0.73700138 -1.34500315 2 P 0 ;0,5=39,7=0.000000
L 0.73700138 -1.34500315 0.72300069 -1.35000207 2 P 0 ;0,5=39,7=0.000000
L 0.72300069 -1.35000207 0.71099961 -1.3599999 2 P 0 ;0,5=39,7=0.000000
L 0.71099961 -1.3599999 0.70299764 -1.37500128 2 P 0 ;0,5=39,7=0.000000
L 0.70299764 -1.37500128 0.69899852 -1.39500157 2 P 0 ;0,5=39,7=0.000000
L 0.69899852 -1.39500157 0.70299764 -1.41500187 2 P 0 ;0,5=39,7=0.000000
L 0.70299764 -1.41500187 0.71099961 -1.43000325 2 P 0 ;0,5=39,7=0.000000
L 0.71099961 -1.43000325 0.72300069 -1.44000108 2 P 0 ;0,5=39,7=0.000000
L 0.72300069 -1.44000108 0.73700138 -1.445 2 P 0 ;0,5=39,7=0.000000
L 0.73700138 -1.445 0.75099833 -1.44250059 2 P 0 ;0,5=39,7=0.000000
L 0.75099833 -1.44250059 0.76299951 -1.43500217 2 P 0 ;0,5=39,7=0.000000
L 0.76299951 -1.43500217 0.77100138 -1.42500433 2 P 0 ;0,5=39,7=0.000000
L 0.86700039 -1.445 0.86700039 -1.34500315 2 P 0 ;0,5=39,7=0.000000
L 0.86700039 -1.36499882 0.87699833 -1.35500098 2 P 0 ;0,5=39,7=0.000000
L 0.87699833 -1.35500098 0.8869998 -1.34750256 2 P 0 ;0,5=39,7=0.000000
L 0.8869998 -1.34750256 0.90100049 -1.34500315 2 P 0 ;0,5=39,7=0.000000
L 0.90100049 -1.34500315 0.91099833 -1.34750256 2 P 0 ;0,5=39,7=0.000000
L 0.91099833 -1.34750256 0.92299951 -1.35500098 2 P 0 ;0,5=39,7=0.000000
L 1.02700039 -1.445 1.02700039 -1.34500315 2 P 0 ;0,5=39,7=0.000000
L 1.02700039 -1.36499882 1.03699833 -1.35500098 2 P 0 ;0,5=39,7=0.000000
L 1.03699833 -1.35500098 1.0469998 -1.34750256 2 P 0 ;0,5=39,7=0.000000
L 1.0469998 -1.34750256 1.06100049 -1.34500315 2 P 0 ;0,5=39,7=0.000000
L 1.06100049 -1.34500315 1.07099833 -1.34750256 2 P 0 ;0,5=39,7=0.000000
L 1.07099833 -1.34750256 1.08299951 -1.35500098 2 P 0 ;0,5=39,7=0.000000
L 1.18500089 -1.37750069 1.24900187 -1.37750069 2 P 0 ;0,5=39,7=0.000000
L 1.24900187 -1.37750069 1.24299951 -1.3599999 2 P 0 ;0,5=39,7=0.000000
L 1.24299951 -1.3599999 1.23300157 -1.35000207 2 P 0 ;0,5=39,7=0.000000
L 1.23300157 -1.35000207 1.21900089 -1.34500315 2 P 0 ;0,5=39,7=0.000000
L 1.21900089 -1.34500315 1.2050003 -1.34750256 2 P 0 ;0,5=39,7=0.000000
L 1.2050003 -1.34750256 1.19299911 -1.35500098 2 P 0 ;0,5=39,7=0.000000
L 1.19299911 -1.35500098 1.18500089 -1.37250177 2 P 0 ;0,5=39,7=0.000000
L 1.18500089 -1.37250177 1.18099803 -1.38750315 2 P 0 ;0,5=39,7=0.000000
L 1.18099803 -1.38750315 1.18099803 -1.4025 2 P 0 ;0,5=39,7=0.000000
L 1.18099803 -1.4025 1.18500089 -1.41750138 2 P 0 ;0,5=39,7=0.000000
L 1.18500089 -1.41750138 1.19499872 -1.43250276 2 P 0 ;0,5=39,7=0.000000
L 1.19499872 -1.43250276 1.2069998 -1.44250059 2 P 0 ;0,5=39,7=0.000000
L 1.2069998 -1.44250059 1.22100049 -1.445 2 P 0 ;0,5=39,7=0.000000
L 1.22100049 -1.445 1.23500118 -1.44000108 2 P 0 ;0,5=39,7=0.000000
L 1.23500118 -1.44000108 1.24900187 -1.42500433 2 P 0 ;0,5=39,7=0.000000
L 1.37499813 -1.445 1.37499813 -1.295 2 P 0 ;0,5=39,7=0.000000
L 1.50500089 -1.37750069 1.56900187 -1.37750069 2 P 0 ;0,5=39,7=0.000000
L 1.56900187 -1.37750069 1.56299951 -1.3599999 2 P 0 ;0,5=39,7=0.000000
L 1.56299951 -1.3599999 1.55300157 -1.35000207 2 P 0 ;0,5=39,7=0.000000
L 1.55300157 -1.35000207 1.53900089 -1.34500315 2 P 0 ;0,5=39,7=0.000000
L 1.53900089 -1.34500315 1.5250003 -1.34750256 2 P 0 ;0,5=39,7=0.000000
L 1.5250003 -1.34750256 1.51299911 -1.35500098 2 P 0 ;0,5=39,7=0.000000
L 1.51299911 -1.35500098 1.50500089 -1.37250177 2 P 0 ;0,5=39,7=0.000000
L 1.50500089 -1.37250177 1.50099803 -1.38750315 2 P 0 ;0,5=39,7=0.000000
L 1.50099803 -1.38750315 1.50099803 -1.4025 2 P 0 ;0,5=39,7=0.000000
L 1.50099803 -1.4025 1.50500089 -1.41750138 2 P 0 ;0,5=39,7=0.000000
L 1.50500089 -1.41750138 1.51499872 -1.43250276 2 P 0 ;0,5=39,7=0.000000
L 1.51499872 -1.43250276 1.5269998 -1.44250059 2 P 0 ;0,5=39,7=0.000000
L 1.5269998 -1.44250059 1.54100049 -1.445 2 P 0 ;0,5=39,7=0.000000
L 1.54100049 -1.445 1.55500118 -1.44000108 2 P 0 ;0,5=39,7=0.000000
L 1.55500118 -1.44000108 1.56900187 -1.42500433 2 P 0 ;0,5=39,7=0.000000
L 1.6529998 -1.48999951 1.66500089 -1.49499843 2 P 0 ;0,5=39,7=0.000000
L 1.66500089 -1.49499843 1.68100108 -1.48999951 2 P 0 ;0,5=39,7=0.000000
L 1.68100108 -1.48999951 1.69099902 -1.48000167 2 P 0 ;0,5=39,7=0.000000
L 1.69099902 -1.48000167 1.69900089 -1.4674997 2 P 0 ;0,5=39,7=0.000000
L 1.69900089 -1.4674997 1.71099833 -1.42750374 2 P 0 ;0,5=39,7=0.000000
L 1.71099833 -1.42750374 1.7370001 -1.34500315 2 P 0 ;0,5=39,7=0.000000
L 1.67299911 -1.34500315 1.71099833 -1.42750374 2 P 0 ;0,5=39,7=0.000000
L 1.82500089 -1.37750069 1.88900187 -1.37750069 2 P 0 ;0,5=39,7=0.000000
L 1.88900187 -1.37750069 1.88299951 -1.3599999 2 P 0 ;0,5=39,7=0.000000
L 1.88299951 -1.3599999 1.87300157 -1.35000207 2 P 0 ;0,5=39,7=0.000000
L 1.87300157 -1.35000207 1.85900089 -1.34500315 2 P 0 ;0,5=39,7=0.000000
L 1.85900089 -1.34500315 1.8450003 -1.34750256 2 P 0 ;0,5=39,7=0.000000
L 1.8450003 -1.34750256 1.83299911 -1.35500098 2 P 0 ;0,5=39,7=0.000000
L 1.83299911 -1.35500098 1.82500089 -1.37250177 2 P 0 ;0,5=39,7=0.000000
L 1.82500089 -1.37250177 1.82099803 -1.38750315 2 P 0 ;0,5=39,7=0.000000
L 1.82099803 -1.38750315 1.82099803 -1.4025 2 P 0 ;0,5=39,7=0.000000
L 1.82099803 -1.4025 1.82500089 -1.41750138 2 P 0 ;0,5=39,7=0.000000
L 1.82500089 -1.41750138 1.83499872 -1.43250276 2 P 0 ;0,5=39,7=0.000000
L 1.83499872 -1.43250276 1.8469998 -1.44250059 2 P 0 ;0,5=39,7=0.000000
L 1.8469998 -1.44250059 1.86100049 -1.445 2 P 0 ;0,5=39,7=0.000000
L 1.86100049 -1.445 1.87500118 -1.44000108 2 P 0 ;0,5=39,7=0.000000
L 1.87500118 -1.44000108 1.88900187 -1.42500433 2 P 0 ;0,5=39,7=0.000000
L 2.18699921 -1.37000236 2.22700167 -1.37000236 2 P 0 ;0,5=39,7=0.000000
L 2.22700167 -1.37000236 2.22700167 -1.41500187 2 P 0 ;0,5=39,7=0.000000
L 2.22700167 -1.41500187 2.21500059 -1.43000325 2 P 0 ;0,5=39,7=0.000000
L 2.21500059 -1.43000325 2.2009999 -1.44000108 2 P 0 ;0,5=39,7=0.000000
L 2.2009999 -1.44000108 2.18100049 -1.445 2 P 0 ;0,5=39,7=0.000000
L 2.18100049 -1.445 2.16100108 -1.44000108 2 P 0 ;0,5=39,7=0.000000
L 2.16100108 -1.44000108 2.14700039 -1.43000325 2 P 0 ;0,5=39,7=0.000000
L 2.14700039 -1.43000325 2.13499931 -1.41500187 2 P 0 ;0,5=39,7=0.000000
L 2.13499931 -1.41500187 2.12699734 -1.39750108 2 P 0 ;0,5=39,7=0.000000
L 2.12699734 -1.39750108 2.12299823 -1.37750069 2 P 0 ;0,5=39,7=0.000000
L 2.12299823 -1.37750069 2.12299823 -1.3599999 2 P 0 ;0,5=39,7=0.000000
L 2.12299823 -1.3599999 2.12699734 -1.34500315 2 P 0 ;0,5=39,7=0.000000
L 2.12699734 -1.34500315 2.13499931 -1.32749764 2 P 0 ;0,5=39,7=0.000000
L 2.13499931 -1.32749764 2.14700039 -1.31250089 2 P 0 ;0,5=39,7=0.000000
L 2.14700039 -1.31250089 2.15899783 -1.30250305 2 P 0 ;0,5=39,7=0.000000
L 2.15899783 -1.30250305 2.17499813 -1.295 2 P 0 ;0,5=39,7=0.000000
L 2.17499813 -1.295 2.18899882 -1.295 2 P 0 ;0,5=39,7=0.000000
L 2.18899882 -1.295 2.20499902 -1.29999902 2 P 0 ;0,5=39,7=0.000000
L 2.20499902 -1.29999902 2.2170001 -1.31000138 2 P 0 ;0,5=39,7=0.000000
L 2.29699892 -1.31999931 2.309 -1.30500246 2 P 0 ;0,5=39,7=0.000000
L 2.309 -1.30500246 2.32300069 -1.29749951 2 P 0 ;0,5=39,7=0.000000
L 2.32300069 -1.29749951 2.33900089 -1.295 2 P 0 ;0,5=39,7=0.000000
L 2.33900089 -1.295 2.3590003 -1.29999902 2 P 0 ;0,5=39,7=0.000000
L 2.3590003 -1.29999902 2.37300098 -1.31250089 2 P 0 ;0,5=39,7=0.000000
L 2.37300098 -1.31250089 2.3770001 -1.32749764 2 P 0 ;0,5=39,7=0.000000
L 2.3770001 -1.32749764 2.37500059 -1.34250364 2 P 0 ;0,5=39,7=0.000000
L 2.37500059 -1.34250364 2.36699862 -1.35500098 2 P 0 ;0,5=39,7=0.000000
L 2.36699862 -1.35500098 2.3269998 -1.3800002 2 P 0 ;0,5=39,7=0.000000
L 2.3269998 -1.3800002 2.309 -1.39750108 2 P 0 ;0,5=39,7=0.000000
L 2.309 -1.39750108 2.29699892 -1.42250482 2 P 0 ;0,5=39,7=0.000000
L 2.29699892 -1.42250482 2.2929998 -1.445 2 P 0 ;0,5=39,7=0.000000
L 2.2929998 -1.445 2.3770001 -1.445 2 P 0 ;0,5=39,7=0.000000
L 2.6129998 -1.42500433 2.629 -1.43750167 2 P 0 ;0,5=39,7=0.000000
L 2.629 -1.43750167 2.6469998 -1.445 2 P 0 ;0,5=39,7=0.000000
L 2.6469998 -1.445 2.6630001 -1.445 2 P 0 ;0,5=39,7=0.000000
L 2.6630001 -1.445 2.6790003 -1.43750167 2 P 0 ;0,5=39,7=0.000000
L 2.6790003 -1.43750167 2.69100138 -1.42500433 2 P 0 ;0,5=39,7=0.000000
L 2.69100138 -1.42500433 2.6970001 -1.40749892 2 P 0 ;0,5=39,7=0.000000
L 2.6970001 -1.40749892 2.69300098 -1.39000266 2 P 0 ;0,5=39,7=0.000000
L 2.69300098 -1.39000266 2.68299951 -1.37500128 2 P 0 ;0,5=39,7=0.000000
L 2.68299951 -1.37500128 2.66499961 -1.36499882 2 P 0 ;0,5=39,7=0.000000
L 2.66499961 -1.36499882 2.64100108 -1.3599999 2 P 0 ;0,5=39,7=0.000000
L 2.64100108 -1.3599999 2.62700039 -1.35000207 2 P 0 ;0,5=39,7=0.000000
L 2.62700039 -1.35000207 2.62099803 -1.33250118 2 P 0 ;0,5=39,7=0.000000
L 2.62099803 -1.33250118 2.62500089 -1.31500039 2 P 0 ;0,5=39,7=0.000000
L 2.62500089 -1.31500039 2.63499872 -1.30250305 2 P 0 ;0,5=39,7=0.000000
L 2.63499872 -1.30250305 2.64899941 -1.295 2 P 0 ;0,5=39,7=0.000000
L 2.64899941 -1.295 2.6630001 -1.295 2 P 0 ;0,5=39,7=0.000000
L 2.6630001 -1.295 2.67700079 -1.29999902 2 P 0 ;0,5=39,7=0.000000
L 2.67700079 -1.29999902 2.68900187 -1.31250089 2 P 0 ;0,5=39,7=0.000000
L 2.7729998 -1.445 2.8570001 -1.295 2 P 0 ;0,5=39,7=0.000000
L 2.7729998 -1.295 2.8570001 -1.445 2 P 0 ;0,5=39,7=0.000000
L 2.92299823 -1.445 2.92299823 -1.295 2 P 0 ;0,5=39,7=0.000000
L 2.92299823 -1.295 2.97499813 -1.42000079 2 P 0 ;0,5=39,7=0.000000
L 2.97499813 -1.42000079 3.02700167 -1.295 2 P 0 ;0,5=39,7=0.000000
L 3.02700167 -1.295 3.02700167 -1.445 2 P 0 ;0,5=39,7=0.000000
L 3.09699892 -1.31999931 3.109 -1.30500246 2 P 0 ;0,5=39,7=0.000000
L 3.109 -1.30500246 3.12300069 -1.29749951 2 P 0 ;0,5=39,7=0.000000
L 3.12300069 -1.29749951 3.13900089 -1.295 2 P 0 ;0,5=39,7=0.000000
L 3.13900089 -1.295 3.1590003 -1.29999902 2 P 0 ;0,5=39,7=0.000000
L 3.1590003 -1.29999902 3.17300098 -1.31250089 2 P 0 ;0,5=39,7=0.000000
L 3.17300098 -1.31250089 3.1770001 -1.32749764 2 P 0 ;0,5=39,7=0.000000
L 3.1770001 -1.32749764 3.17500059 -1.34250364 2 P 0 ;0,5=39,7=0.000000
L 3.17500059 -1.34250364 3.16699862 -1.35500098 2 P 0 ;0,5=39,7=0.000000
L 3.16699862 -1.35500098 3.1269998 -1.3800002 2 P 0 ;0,5=39,7=0.000000
L 3.1269998 -1.3800002 3.109 -1.39750108 2 P 0 ;0,5=39,7=0.000000
L 3.109 -1.39750108 3.09699892 -1.42250482 2 P 0 ;0,5=39,7=0.000000
L 3.09699892 -1.42250482 3.0929998 -1.445 2 P 0 ;0,5=39,7=0.000000
L 3.0929998 -1.445 3.1770001 -1.445 2 P 0 ;0,5=39,7=0.000000
L 3.269 -1.39500157 3.3209999 -1.39500157 2 P 0 ;0,5=39,7=0.000000
L 3.41499931 -1.445 3.41499931 -1.295 2 P 0 ;0,5=39,7=0.000000
L 3.41499931 -1.295 3.46499961 -1.295 2 P 0 ;0,5=39,7=0.000000
L 3.46499961 -1.295 3.4809999 -1.30250305 2 P 0 ;0,5=39,7=0.000000
L 3.4809999 -1.30250305 3.49100138 -1.31250089 2 P 0 ;0,5=39,7=0.000000
L 3.49100138 -1.31250089 3.49500059 -1.33250118 2 P 0 ;0,5=39,7=0.000000
L 3.49500059 -1.33250118 3.49100138 -1.35250148 2 P 0 ;0,5=39,7=0.000000
L 3.49100138 -1.35250148 3.4790003 -1.36499882 2 P 0 ;0,5=39,7=0.000000
L 3.4790003 -1.36499882 3.46499961 -1.37250177 2 P 0 ;0,5=39,7=0.000000
L 3.46499961 -1.37250177 3.41499931 -1.37250177 2 P 0 ;0,5=39,7=0.000000
L 3.46499961 -1.37250177 3.49500059 -1.445 2 P 0 ;0,5=39,7=0.000000
L 3.61499813 -1.34500315 3.61499813 -1.445 2 P 0 ;0,5=39,7=0.000000
L 3.61499813 -1.30500246 3.61099902 -1.30250305 2 P 0 ;0,5=39,7=0.000000
L 3.61099902 -1.30250305 3.61099902 -1.29749951 2 P 0 ;0,5=39,7=0.000000
L 3.61099902 -1.29749951 3.61499813 -1.295 2 P 0 ;0,5=39,7=0.000000
L 3.61499813 -1.295 3.61900089 -1.29749951 2 P 0 ;0,5=39,7=0.000000
L 3.61900089 -1.29749951 3.61900089 -1.30250305 2 P 0 ;0,5=39,7=0.000000
L 3.61900089 -1.30250305 3.61499813 -1.30500246 2 P 0 ;0,5=39,7=0.000000
L 3.74500089 -1.42750374 3.75499872 -1.43750167 2 P 0 ;0,5=39,7=0.000000
L 3.75499872 -1.43750167 3.76899941 -1.445 2 P 0 ;0,5=39,7=0.000000
L 3.76899941 -1.445 3.78100049 -1.445 2 P 0 ;0,5=39,7=0.000000
L 3.78100049 -1.445 3.79300157 -1.44000108 2 P 0 ;0,5=39,7=0.000000
L 3.79300157 -1.44000108 3.8009999 -1.43250276 2 P 0 ;0,5=39,7=0.000000
L 3.8009999 -1.43250276 3.80499902 -1.42250482 2 P 0 ;0,5=39,7=0.000000
L 3.80499902 -1.42250482 3.80299951 -1.40749892 2 P 0 ;0,5=39,7=0.000000
L 3.80299951 -1.40749892 3.79500118 -1.40000049 2 P 0 ;0,5=39,7=0.000000
L 3.79500118 -1.40000049 3.75899783 -1.38500374 2 P 0 ;0,5=39,7=0.000000
L 3.75899783 -1.38500374 3.75099961 -1.36749833 2 P 0 ;0,5=39,7=0.000000
L 3.75099961 -1.36749833 3.75499872 -1.35500098 2 P 0 ;0,5=39,7=0.000000
L 3.75499872 -1.35500098 3.76300069 -1.34750256 2 P 0 ;0,5=39,7=0.000000
L 3.76300069 -1.34750256 3.77499813 -1.34500315 2 P 0 ;0,5=39,7=0.000000
L 3.77499813 -1.34500315 3.78699921 -1.34750256 2 P 0 ;0,5=39,7=0.000000
L 3.78699921 -1.34750256 3.7990003 -1.35500098 2 P 0 ;0,5=39,7=0.000000
L 3.90500089 -1.37750069 3.96900187 -1.37750069 2 P 0 ;0,5=39,7=0.000000
L 3.96900187 -1.37750069 3.96299951 -1.3599999 2 P 0 ;0,5=39,7=0.000000
L 3.96299951 -1.3599999 3.95300157 -1.35000207 2 P 0 ;0,5=39,7=0.000000
L 3.95300157 -1.35000207 3.93900089 -1.34500315 2 P 0 ;0,5=39,7=0.000000
L 3.93900089 -1.34500315 3.9250003 -1.34750256 2 P 0 ;0,5=39,7=0.000000
L 3.9250003 -1.34750256 3.91299911 -1.35500098 2 P 0 ;0,5=39,7=0.000000
L 3.91299911 -1.35500098 3.90500089 -1.37250177 2 P 0 ;0,5=39,7=0.000000
L 3.90500089 -1.37250177 3.90099803 -1.38750315 2 P 0 ;0,5=39,7=0.000000
L 3.90099803 -1.38750315 3.90099803 -1.4025 2 P 0 ;0,5=39,7=0.000000
L 3.90099803 -1.4025 3.90500089 -1.41750138 2 P 0 ;0,5=39,7=0.000000
L 3.90500089 -1.41750138 3.91499872 -1.43250276 2 P 0 ;0,5=39,7=0.000000
L 3.91499872 -1.43250276 3.9269998 -1.44250059 2 P 0 ;0,5=39,7=0.000000
L 3.9269998 -1.44250059 3.94100049 -1.445 2 P 0 ;0,5=39,7=0.000000
L 3.94100049 -1.445 3.95500118 -1.44000108 2 P 0 ;0,5=39,7=0.000000
L 3.95500118 -1.44000108 3.96900187 -1.42500433 2 P 0 ;0,5=39,7=0.000000
L 4.06700039 -1.445 4.06700039 -1.34500315 2 P 0 ;0,5=39,7=0.000000
L 4.06700039 -1.36499882 4.07699833 -1.35500098 2 P 0 ;0,5=39,7=0.000000
L 4.07699833 -1.35500098 4.0869998 -1.34750256 2 P 0 ;0,5=39,7=0.000000
L 4.0869998 -1.34750256 4.10100049 -1.34500315 2 P 0 ;0,5=39,7=0.000000
L 4.10100049 -1.34500315 4.11099833 -1.34750256 2 P 0 ;0,5=39,7=0.000000
L 4.11099833 -1.34750256 4.12299951 -1.35500098 2 P 0 ;0,5=39,7=0.000000
L 4.16964783 -2.2038 4.21839813 -2.0478 2 P 0 ;0,5=40,7=0.000000
L 4.21839813 -2.0478 4.26715207 -2.2038 2 P 0 ;0,5=40,7=0.000000
L 4.24959862 -2.14920217 4.18719774 -2.14920217 2 P 0 ;0,5=40,7=0.000000
L 4.37939813 -2.2038 4.37939813 -2.0478 2 P 0 ;0,5=40,7=0.000000
L 4.37939813 -2.0478 4.35599961 -2.07899813 2 P 0 ;0,5=40,7=0.000000
L 4.35599961 -2.2038 4.40279675 -2.2038 2 P 0 ;0,5=40,7=0.000000
L 2.0009002 -0.9538 2.0009002 -0.8038 2 P 0 ;0,5=41,7=0.000000
L 2.0009002 -0.8038 2.04089902 -0.8038 2 P 0 ;0,5=41,7=0.000000
L 2.04089902 -0.8038 2.05689921 -0.81130305 2 P 0 ;0,5=41,7=0.000000
L 2.05689921 -0.81130305 2.0689003 -0.82130089 2 P 0 ;0,5=41,7=0.000000
L 2.0689003 -0.82130089 2.07890187 -0.83629764 2 P 0 ;0,5=41,7=0.000000
L 2.07890187 -0.83629764 2.0869001 -0.85380315 2 P 0 ;0,5=41,7=0.000000
L 2.0869001 -0.85380315 2.0888997 -0.87880236 2 P 0 ;0,5=41,7=0.000000
L 2.0888997 -0.87880236 2.0869001 -0.90380157 2 P 0 ;0,5=41,7=0.000000
L 2.0869001 -0.90380157 2.07890187 -0.92130246 2 P 0 ;0,5=41,7=0.000000
L 2.07890187 -0.92130246 2.0689003 -0.93630374 2 P 0 ;0,5=41,7=0.000000
L 2.0689003 -0.93630374 2.05689921 -0.94630167 2 P 0 ;0,5=41,7=0.000000
L 2.05689921 -0.94630167 2.04089902 -0.9538 2 P 0 ;0,5=41,7=0.000000
L 2.04089902 -0.9538 2.0009002 -0.9538 2 P 0 ;0,5=41,7=0.000000
L 2.15489783 -0.9538 2.20489813 -0.8038 2 P 0 ;0,5=41,7=0.000000
L 2.20489813 -0.8038 2.25490207 -0.9538 2 P 0 ;0,5=41,7=0.000000
L 2.23689862 -0.90130207 2.17289764 -0.90130207 2 P 0 ;0,5=41,7=0.000000
L 2.36489813 -0.8038 2.36489813 -0.9538 2 P 0 ;0,5=41,7=0.000000
L 2.31890059 -0.8038 2.41089931 -0.8038 2 P 0 ;0,5=41,7=0.000000
L 2.56490059 -0.9538 2.48489931 -0.9538 2 P 0 ;0,5=41,7=0.000000
L 2.48489931 -0.9538 2.48489931 -0.8038 2 P 0 ;0,5=41,7=0.000000
L 2.48489931 -0.8038 2.56490059 -0.8038 2 P 0 ;0,5=41,7=0.000000
L 2.5329001 -0.87629833 2.48489931 -0.87629833 2 P 0 ;0,5=41,7=0.000000
L 2.84489813 -0.9538 2.82889783 -0.95130059 2 P 0 ;0,5=41,7=0.000000
L 2.82889783 -0.95130059 2.81490089 -0.94130276 2 P 0 ;0,5=41,7=0.000000
L 2.81490089 -0.94130276 2.8028998 -0.92630138 2 P 0 ;0,5=41,7=0.000000
L 2.8028998 -0.92630138 2.79489783 -0.90880049 2 P 0 ;0,5=41,7=0.000000
L 2.79489783 -0.90880049 2.79089862 -0.8888002 2 P 0 ;0,5=41,7=0.000000
L 2.79089862 -0.8888002 2.79089862 -0.8687999 2 P 0 ;0,5=41,7=0.000000
L 2.79089862 -0.8687999 2.79489783 -0.84879961 2 P 0 ;0,5=41,7=0.000000
L 2.79489783 -0.84879961 2.8028998 -0.83129872 2 P 0 ;0,5=41,7=0.000000
L 2.8028998 -0.83129872 2.81490089 -0.81630197 2 P 0 ;0,5=41,7=0.000000
L 2.81490089 -0.81630197 2.82889783 -0.80629951 2 P 0 ;0,5=41,7=0.000000
L 2.82889783 -0.80629951 2.84489813 -0.8038 2 P 0 ;0,5=41,7=0.000000
L 2.84489813 -0.8038 2.86089833 -0.80629951 2 P 0 ;0,5=41,7=0.000000
L 2.86089833 -0.80629951 2.87489902 -0.81630197 2 P 0 ;0,5=41,7=0.000000
L 2.87489902 -0.81630197 2.8869001 -0.83129872 2 P 0 ;0,5=41,7=0.000000
L 2.8869001 -0.83129872 2.89490207 -0.84879961 2 P 0 ;0,5=41,7=0.000000
L 2.89490207 -0.84879961 2.89890128 -0.8687999 2 P 0 ;0,5=41,7=0.000000
L 2.89890128 -0.8687999 2.89890128 -0.8888002 2 P 0 ;0,5=41,7=0.000000
L 2.89890128 -0.8888002 2.89490207 -0.90880049 2 P 0 ;0,5=41,7=0.000000
L 2.89490207 -0.90880049 2.8869001 -0.92630138 2 P 0 ;0,5=41,7=0.000000
L 2.8869001 -0.92630138 2.87489902 -0.94130276 2 P 0 ;0,5=41,7=0.000000
L 2.87489902 -0.94130276 2.86089833 -0.95130059 2 P 0 ;0,5=41,7=0.000000
L 2.86089833 -0.95130059 2.84489813 -0.9538 2 P 0 ;0,5=41,7=0.000000
L 3.0488997 -0.81630197 3.03689862 -0.80879902 2 P 0 ;0,5=41,7=0.000000
L 3.03689862 -0.80879902 3.02290157 -0.8038 2 P 0 ;0,5=41,7=0.000000
L 3.02290157 -0.8038 3.00690138 -0.8038 2 P 0 ;0,5=41,7=0.000000
L 3.00690138 -0.8038 2.98889783 -0.81130305 2 P 0 ;0,5=41,7=0.000000
L 2.98889783 -0.81130305 2.97490089 -0.82380039 2 P 0 ;0,5=41,7=0.000000
L 2.97490089 -0.82380039 2.96489931 -0.83880177 2 P 0 ;0,5=41,7=0.000000
L 2.96489931 -0.83880177 2.95689734 -0.86380098 2 P 0 ;0,5=41,7=0.000000
L 2.95689734 -0.86380098 2.95489783 -0.88630069 2 P 0 ;0,5=41,7=0.000000
L 2.95489783 -0.88630069 2.95890059 -0.90880049 2 P 0 ;0,5=41,7=0.000000
L 2.95890059 -0.90880049 2.96489931 -0.92380187 2 P 0 ;0,5=41,7=0.000000
L 2.96489931 -0.92380187 2.97690039 -0.93880325 2 P 0 ;0,5=41,7=0.000000
L 2.97690039 -0.93880325 2.99090108 -0.94880108 2 P 0 ;0,5=41,7=0.000000
L 2.99090108 -0.94880108 3.00489813 -0.9538 2 P 0 ;0,5=41,7=0.000000
L 3.00489813 -0.9538 3.01889882 -0.9538 2 P 0 ;0,5=41,7=0.000000
L 3.01889882 -0.9538 3.03289951 -0.94880108 2 P 0 ;0,5=41,7=0.000000
L 3.03289951 -0.94880108 3.04490059 -0.94130276 2 P 0 ;0,5=41,7=0.000000
L 3.04490059 -0.94130276 3.05490207 -0.93130482 2 P 0 ;0,5=41,7=0.000000
L 3.16489813 -0.8038 3.16489813 -0.9538 2 P 0 ;0,5=41,7=0.000000
L 3.11890059 -0.8038 3.21089931 -0.8038 2 P 0 ;0,5=41,7=0.000000
L 3.28889852 -0.95879892 3.36090138 -0.8038 2 P 0 ;0,5=41,7=0.000000
L 3.44689892 -0.82879931 3.4589 -0.81380246 2 P 0 ;0,5=41,7=0.000000
L 3.4589 -0.81380246 3.47290069 -0.80629951 2 P 0 ;0,5=41,7=0.000000
L 3.47290069 -0.80629951 3.48890089 -0.8038 2 P 0 ;0,5=41,7=0.000000
L 3.48890089 -0.8038 3.5089003 -0.80879902 2 P 0 ;0,5=41,7=0.000000
L 3.5089003 -0.80879902 3.52290098 -0.82130089 2 P 0 ;0,5=41,7=0.000000
L 3.52290098 -0.82130089 3.5269001 -0.83629764 2 P 0 ;0,5=41,7=0.000000
L 3.5269001 -0.83629764 3.52490059 -0.85130364 2 P 0 ;0,5=41,7=0.000000
L 3.52490059 -0.85130364 3.51689862 -0.86380098 2 P 0 ;0,5=41,7=0.000000
L 3.51689862 -0.86380098 3.4768998 -0.8888002 2 P 0 ;0,5=41,7=0.000000
L 3.4768998 -0.8888002 3.4589 -0.90630108 2 P 0 ;0,5=41,7=0.000000
L 3.4589 -0.90630108 3.44689892 -0.93130482 2 P 0 ;0,5=41,7=0.000000
L 3.44689892 -0.93130482 3.4428998 -0.9538 2 P 0 ;0,5=41,7=0.000000
L 3.4428998 -0.9538 3.5269001 -0.9538 2 P 0 ;0,5=41,7=0.000000
L 3.64089902 -0.9538 3.64489813 -0.92130246 2 P 0 ;0,5=41,7=0.000000
L 3.64489813 -0.92130246 3.65090049 -0.89380374 2 P 0 ;0,5=41,7=0.000000
L 3.65090049 -0.89380374 3.65889882 -0.8687999 2 P 0 ;0,5=41,7=0.000000
L 3.65889882 -0.8687999 3.6689003 -0.84130118 2 P 0 ;0,5=41,7=0.000000
L 3.6689003 -0.84130118 3.68490059 -0.8038 2 P 0 ;0,5=41,7=0.000000
L 3.68490059 -0.8038 3.60489931 -0.8038 2 P 0 ;0,5=41,7=0.000000
L 3.76889852 -0.95879892 3.84090138 -0.8038 2 P 0 ;0,5=41,7=0.000000
L 3.92689892 -0.82879931 3.9389 -0.81380246 2 P 0 ;0,5=41,7=0.000000
L 3.9389 -0.81380246 3.95290069 -0.80629951 2 P 0 ;0,5=41,7=0.000000
L 3.95290069 -0.80629951 3.96890089 -0.8038 2 P 0 ;0,5=41,7=0.000000
L 3.96890089 -0.8038 3.9889003 -0.80879902 2 P 0 ;0,5=41,7=0.000000
L 3.9889003 -0.80879902 4.00290098 -0.82130089 2 P 0 ;0,5=41,7=0.000000
L 4.00290098 -0.82130089 4.0069001 -0.83629764 2 P 0 ;0,5=41,7=0.000000
L 4.0069001 -0.83629764 4.00490059 -0.85130364 2 P 0 ;0,5=41,7=0.000000
L 4.00490059 -0.85130364 3.99689862 -0.86380098 2 P 0 ;0,5=41,7=0.000000
L 3.99689862 -0.86380098 3.9568998 -0.8888002 2 P 0 ;0,5=41,7=0.000000
L 3.9568998 -0.8888002 3.9389 -0.90630108 2 P 0 ;0,5=41,7=0.000000
L 3.9389 -0.90630108 3.92689892 -0.93130482 2 P 0 ;0,5=41,7=0.000000
L 3.92689892 -0.93130482 3.9228998 -0.9538 2 P 0 ;0,5=41,7=0.000000
L 3.9228998 -0.9538 4.0069001 -0.9538 2 P 0 ;0,5=41,7=0.000000
L 4.12489813 -0.8038 4.10889783 -0.80879902 2 P 0 ;0,5=41,7=0.000000
L 4.10889783 -0.80879902 4.09690039 -0.82130089 2 P 0 ;0,5=41,7=0.000000
L 4.09690039 -0.82130089 4.08889852 -0.83629764 2 P 0 ;0,5=41,7=0.000000
L 4.08889852 -0.83629764 4.0828998 -0.85630256 2 P 0 ;0,5=41,7=0.000000
L 4.0828998 -0.85630256 4.0809002 -0.87880236 2 P 0 ;0,5=41,7=0.000000
L 4.0809002 -0.87880236 4.0828998 -0.90130207 2 P 0 ;0,5=41,7=0.000000
L 4.0828998 -0.90130207 4.08889852 -0.92130246 2 P 0 ;0,5=41,7=0.000000
L 4.08889852 -0.92130246 4.09690039 -0.93630374 2 P 0 ;0,5=41,7=0.000000
L 4.09690039 -0.93630374 4.10889783 -0.94880108 2 P 0 ;0,5=41,7=0.000000
L 4.10889783 -0.94880108 4.12489813 -0.9538 2 P 0 ;0,5=41,7=0.000000
L 4.12489813 -0.9538 4.14089833 -0.94880108 2 P 0 ;0,5=41,7=0.000000
L 4.14089833 -0.94880108 4.15289951 -0.93630374 2 P 0 ;0,5=41,7=0.000000
L 4.15289951 -0.93630374 4.16090138 -0.92130246 2 P 0 ;0,5=41,7=0.000000
L 4.16090138 -0.92130246 4.1669001 -0.90130207 2 P 0 ;0,5=41,7=0.000000
L 4.1669001 -0.90130207 4.1688997 -0.87880236 2 P 0 ;0,5=41,7=0.000000
L 4.1688997 -0.87880236 4.1669001 -0.85630256 2 P 0 ;0,5=41,7=0.000000
L 4.1669001 -0.85630256 4.16090138 -0.83629764 2 P 0 ;0,5=41,7=0.000000
L 4.16090138 -0.83629764 4.15289951 -0.82130089 2 P 0 ;0,5=41,7=0.000000
L 4.15289951 -0.82130089 4.14089833 -0.80879902 2 P 0 ;0,5=41,7=0.000000
L 4.14089833 -0.80879902 4.12489813 -0.8038 2 P 0 ;0,5=41,7=0.000000
L 4.28489813 -0.9538 4.28489813 -0.8038 2 P 0 ;0,5=41,7=0.000000
L 4.28489813 -0.8038 4.26089961 -0.83379823 2 P 0 ;0,5=41,7=0.000000
L 4.26089961 -0.9538 4.30889665 -0.9538 2 P 0 ;0,5=41,7=0.000000
L 4.44089902 -0.9538 4.44489813 -0.92130246 2 P 0 ;0,5=41,7=0.000000
L 4.44489813 -0.92130246 4.45090049 -0.89380374 2 P 0 ;0,5=41,7=0.000000
L 4.45090049 -0.89380374 4.45889882 -0.8687999 2 P 0 ;0,5=41,7=0.000000
L 4.45889882 -0.8687999 4.4689003 -0.84130118 2 P 0 ;0,5=41,7=0.000000
L 4.4689003 -0.84130118 4.48490059 -0.8038 2 P 0 ;0,5=41,7=0.000000
L 4.48490059 -0.8038 4.40489931 -0.8038 2 P 0 ;0,5=41,7=0.000000

### steps/drc/layers/bd-1-4/tools
SLOTS=NO
THICKNESS=0
USER_PARAMS=

TOOLS {
    NUM=1
    SHAPE=HOLE
    TYPE=PLATED
    TYPE2=STANDARD
    MIN_TOL=0
    MAX_TOL=0
    BIT=
    FINISH_SIZE=-9.84251968503937e-05
    DRILL_SIZE=8
    ORIG_SIZE=-1
    SLOT_LENGTH=0
}

### steps/drc/layers/bd-1-9/tools
SLOTS=NO
THICKNESS=0
USER_PARAMS=

TOOLS {
    NUM=1
    SHAPE=HOLE
    TYPE=PLATED
    TYPE2=STANDARD
    MIN_TOL=0
    MAX_TOL=0
    BIT=
    FINISH_SIZE=-9.84251968503937e-05
    DRILL_SIZE=8
    ORIG_SIZE=-1
    SLOT_LENGTH=0
}

### steps/drc/layers/bd-12-4/tools
SLOTS=NO
THICKNESS=0
USER_PARAMS=

TOOLS {
    NUM=1
    SHAPE=HOLE
    TYPE=PLATED
    TYPE2=STANDARD
    MIN_TOL=0
    MAX_TOL=0
    BIT=
    FINISH_SIZE=-9.84251968503937e-05
    DRILL_SIZE=8
    ORIG_SIZE=-1
    SLOT_LENGTH=0
}

### steps/drc/layers/bd-12-6/tools
SLOTS=NO
THICKNESS=0
USER_PARAMS=

TOOLS {
    NUM=1
    SHAPE=HOLE
    TYPE=PLATED
    TYPE2=STANDARD
    MIN_TOL=0
    MAX_TOL=0
    BIT=
    FINISH_SIZE=-9.84251968503937e-05
    DRILL_SIZE=8
    ORIG_SIZE=-1
    SLOT_LENGTH=0
}

### steps/drc/layers/drillo/tools
SLOTS=NO
THICKNESS=61.8
USER_PARAMS=

TOOLS {
    NUM=1
    SHAPE=HOLE
    TYPE=VIA
    TYPE2=STANDARD
    MIN_TOL=6
    MAX_TOL=2
    BIT=
    FINISH_SIZE=8
    DRILL_SIZE=8
    ORIG_SIZE=-1
    SLOT_LENGTH=0
}

TOOLS {
    NUM=2
    SHAPE=HOLE
    TYPE=VIA
    TYPE2=STANDARD
    MIN_TOL=6
    MAX_TOL=2
    BIT=
    FINISH_SIZE=10
    DRILL_SIZE=10
    ORIG_SIZE=-1
    SLOT_LENGTH=0
}

TOOLS {
    NUM=3
    SHAPE=HOLE
    TYPE=VIA
    TYPE2=STANDARD
    MIN_TOL=6
    MAX_TOL=2
    BIT=
    FINISH_SIZE=10
    DRILL_SIZE=10
    ORIG_SIZE=-1
    SLOT_LENGTH=0
}

TOOLS {
    NUM=4
    SHAPE=HOLE
    TYPE=PLATED
    TYPE2=STANDARD
    MIN_TOL=0
    MAX_TOL=0
    BIT=
    FINISH_SIZE=27.56003937007874
    DRILL_SIZE=27.56003937007874
    ORIG_SIZE=-1
    SLOT_LENGTH=0
}

TOOLS {
    NUM=5
    SHAPE=HOLE
    TYPE=PLATED
    TYPE2=STANDARD
    MIN_TOL=2.98996062992126
    MAX_TOL=2.98996062992126
    BIT=
    FINISH_SIZE=29.91998031496063
    DRILL_SIZE=29.91998031496063
    ORIG_SIZE=-1
    SLOT_LENGTH=0
}

TOOLS {
    NUM=6
    SHAPE=HOLE
    TYPE=NON_PLATED
    TYPE2=STANDARD
    MIN_TOL=2.01003937007874
    MAX_TOL=2.01003937007874
    BIT=
    FINISH_SIZE=39.37007874015748
    DRILL_SIZE=39.37007874015748
    ORIG_SIZE=-1
    SLOT_LENGTH=0
}

TOOLS {
    NUM=7
    SHAPE=HOLE
    TYPE=NON_PLATED
    TYPE2=STANDARD
    MIN_TOL=2.01003937007874
    MAX_TOL=2.01003937007874
    BIT=
    FINISH_SIZE=51.18001968503937
    DRILL_SIZE=51.18001968503937
    ORIG_SIZE=-1
    SLOT_LENGTH=0
}

TOOLS {
    NUM=8
    SHAPE=HOLE
    TYPE=PLATED
    TYPE2=STANDARD
    MIN_TOL=2.98996062992126
    MAX_TOL=2.98996062992126
    BIT=
    FINISH_SIZE=55.11998031496063
    DRILL_SIZE=55.11998031496063
    ORIG_SIZE=-1
    SLOT_LENGTH=0
}

TOOLS {
    NUM=9
    SHAPE=HOLE
    TYPE=NON_PLATED
    TYPE2=STANDARD
    MIN_TOL=2.01003937007874
    MAX_TOL=2.01003937007874
    BIT=
    FINISH_SIZE=92.51968503937007
    DRILL_SIZE=92.51968503937007
    ORIG_SIZE=-1
    SLOT_LENGTH=0
}

TOOLS {
    NUM=10
    SHAPE=HOLE
    TYPE=NON_PLATED
    TYPE2=STANDARD
    MIN_TOL=2.01003937007874
    MAX_TOL=2.01003937007874
    BIT=
    FINISH_SIZE=98.43001968503937
    DRILL_SIZE=98.43001968503937
    ORIG_SIZE=-1
    SLOT_LENGTH=0
}

TOOLS {
    NUM=11
    SHAPE=HOLE
    TYPE=NON_PLATED
    TYPE2=STANDARD
    MIN_TOL=2.01003937007874
    MAX_TOL=2.01003937007874
    BIT=
    FINISH_SIZE=118.1102362204724
    DRILL_SIZE=118.1102362204724
    ORIG_SIZE=-1
    SLOT_LENGTH=0
}

TOOLS {
    NUM=12
    SHAPE=HOLE
    TYPE=NON_PLATED
    TYPE2=STANDARD
    MIN_TOL=0
    MAX_TOL=3
    BIT=
    FINISH_SIZE=125
    DRILL_SIZE=125
    ORIG_SIZE=-1
    SLOT_LENGTH=0
}

TOOLS {
    NUM=13
    SHAPE=HOLE
    TYPE=NON_PLATED
    TYPE2=STANDARD
    MIN_TOL=2.01003937007874
    MAX_TOL=2.01003937007874
    BIT=
    FINISH_SIZE=129.9199803149606
    DRILL_SIZE=129.9199803149606
    ORIG_SIZE=-1
    SLOT_LENGTH=0
}

TOOLS {
    NUM=14
    SHAPE=HOLE
    TYPE=NON_PLATED
    TYPE2=STANDARD
    MIN_TOL=2.01003937007874
    MAX_TOL=2.01003937007874
    BIT=
    FINISH_SIZE=137.8
    DRILL_SIZE=137.8
    ORIG_SIZE=-1
    SLOT_LENGTH=0
}

TOOLS {
    NUM=15
    SHAPE=HOLE
    TYPE=NON_PLATED
    TYPE2=STANDARD
    MIN_TOL=5
    MAX_TOL=5
    BIT=
    FINISH_SIZE=137.8
    DRILL_SIZE=137.8
    ORIG_SIZE=-1
    SLOT_LENGTH=0
}

TOOLS {
    NUM=16
    SHAPE=HOLE
    TYPE=NON_PLATED
    TYPE2=STANDARD
    MIN_TOL=0
    MAX_TOL=2.98996062992126
    BIT=
    FINISH_SIZE=157.4803149606299
    DRILL_SIZE=157.4803149606299
    ORIG_SIZE=-1
    SLOT_LENGTH=0
}

TOOLS {
    NUM=17
    SHAPE=HOLE
    TYPE=NON_PLATED
    TYPE2=STANDARD
    MIN_TOL=0
    MAX_TOL=2.98996062992126
    BIT=
    FINISH_SIZE=177.1699803149606
    DRILL_SIZE=177.1699803149606
    ORIG_SIZE=-1
    SLOT_LENGTH=0
}

TOOLS {
    NUM=18
    SHAPE=HOLE
    TYPE=NON_PLATED
    TYPE2=STANDARD
    MIN_TOL=2.01003937007874
    MAX_TOL=2.01003937007874
    BIT=
    FINISH_SIZE=393.7
    DRILL_SIZE=393.7
    ORIG_SIZE=-1
    SLOT_LENGTH=0
}

TOOLS {
    NUM=19
    SHAPE=HOLE
    TYPE=PLATED
    TYPE2=STANDARD
    MIN_TOL=2.98996062992126
    MAX_TOL=2.98996062992126
    BIT=
    FINISH_SIZE=27.56003937007874
    DRILL_SIZE=27.56003937007874
    ORIG_SIZE=-1
    SLOT_LENGTH=0
}

### steps/drc/layers/rout/tools
SLOTS=NO
THICKNESS=0
USER_PARAMS=

TOOLS {
    NUM=1
    SHAPE=HOLE
    TYPE=NON_PLATED
    TYPE2=STANDARD
    MIN_TOL=0
    MAX_TOL=0
    BIT=
    FINISH_SIZE=-9.84251968503937e-05
    DRILL_SIZE=0
    ORIG_SIZE=-1
    SLOT_LENGTH=0
}

### symbols/8888-lcd/features
#
#Feature symbol names
#
$0 8888

#
#Layer features
#
P -0.00085315 -0.00489311 0 N 0 0

### symbols/8888/features
#
#Feature symbol names
#
$0 r16
$1 rect500x140

#
#Layer features
#
P 0 0 1 N 0 0
L -0.08669656 -0.04660522 -0.06156703 -0.04660522 0 P 0 
L -0.06856506 0.0494438 -0.04232215 0.0494438 0 P 0 
L -0.10721378 -0.03357913 -0.1032376 -0.01425482 0 P 0 
L -0.09703474 0.01666407 -0.09226329 0.04028278 0 P 0 
L -0.04009547 -0.03357913 -0.03564222 -0.01425482 0 P 0 
L -0.02864409 0.01666407 -0.02419075 0.03641782 0 P 0 
L -0.08065276 0.00335187 -0.05075177 0.00335187 0 P 0 
L 0.04054183 -0.04660522 0.06567136 -0.04660522 0 P 0 
L 0.05867333 0.0494438 0.08491614 0.0494438 0 P 0 
L 0.02002451 -0.03357913 0.02400079 -0.01425482 0 P 0 
L 0.03020374 0.01666407 0.0349752 0.04028278 0 P 0 
L 0.08714282 -0.03357913 0.09159616 -0.01425482 0 P 0 
L 0.09859439 0.01666407 0.10304764 0.03641782 0 P 0 
L 0.04658563 0.00335187 0.07648661 0.00335187 0 P 0 
L 0.16778022 -0.04660522 0.19290974 -0.04660522 0 P 0 
L 0.18591171 0.0494438 0.21215463 0.0494438 0 P 0 
L 0.14726299 -0.03357913 0.15123917 -0.01425482 0 P 0 
L 0.15744213 0.01666407 0.16221358 0.04028278 0 P 0 
L 0.2143813 -0.03357913 0.21883455 -0.01425482 0 P 0 
L 0.22583278 0.01666407 0.23028602 0.03641782 0 P 0 
L 0.17382402 0.00335187 0.2037251 0.00335187 0 P 0 
L -0.2045499 -0.04324528 -0.17942037 -0.04324528 0 P 0 
L -0.18641841 0.05280384 -0.16017559 0.05280384 0 P 0 
L -0.22506713 -0.03021919 -0.22109094 -0.01089488 0 P 0 
L -0.21488799 0.02002402 -0.21011663 0.04364262 0 P 0 
L -0.15794882 -0.03021919 -0.15349547 -0.01089488 0 P 0 
L -0.14649734 0.02002402 -0.142044 0.03977785 0 P 0 
L -0.198506 0.00671171 -0.16860502 0.00671171 0 P 0 

### symbols/b1_2-test/features
#
#Feature symbol names
#
$0 r39.37
$1 r236

#
#Layer features
#
L 0 0 0 0 1 N 0 
L 0 0 0 0 0 P 0 

### symbols/b1_2/features
#
#Feature symbol names
#
$0 r39.37
$1 r236

#
#Layer features
#
L 0 0 0 0 1 N 0 
L 0 0 0 0 0 P 0 

### symbols/b2-1-test/features
#
#Feature symbol names
#
$0 r236
$1 donut_r78.74x55.118

#
#Layer features
#
L 0 0 0 0 0 N 0 
L 0 0 0 0 1 P 0 

### symbols/b2-1/features
#
#Feature symbol names
#
$0 r236
$1 donut_r78.74x55.118

#
#Layer features
#
L 0 0 0 0 0 N 0 
L 0 0 0 0 1 P 0 

### symbols/b2/features
#
#Feature symbol names
#
$0 donut_r78.74x70.866

#
#Layer features
#
P 0 0 0 P 0 0

### symbols/hm8888/features
#
#Feature symbol names
#
$0 r20
$1 rect1560x180
$2 rect1600x220

#
#Layer features
#
P 0 0 2 N 0 0
P 0 0 1 P 0 0
L 0.72394961 0.06050925 0.68523573 0.06050925 0 N 0 
L 0.69601683 -0.0662249 0.6555877 -0.0662249 0 N 0 
L 0.75555787 0.04332185 0.74943219 0.01782382 0 N 0 
L 0.73987628 -0.02297293 0.73252549 -0.05413701 0 N 0 
L 0.65215728 0.04332185 0.64529665 0.01782382 0 N 0 
L 0.63451555 -0.02297293 0.62765482 -0.0490374 0 N 0 
L 0.71463868 -0.00540758 0.66857402 -0.00540758 0 N 0 
L 0.52792963 0.06050925 0.48921575 0.06050925 0 N 0 
L 0.49999685 -0.0662249 0.45956772 -0.0662249 0 N 0 
L 0.55953789 0.04332185 0.5534122 0.01782382 0 N 0 
L 0.5438563 -0.02297293 0.53650551 -0.05413701 0 N 0 
L 0.4561373 0.04332185 0.44927667 0.01782382 0 N 0 
L 0.43849547 -0.02297293 0.43163474 -0.0490374 0 N 0 
L 0.5186187 -0.00540758 0.47255404 -0.00540758 0 N 0 
L 0.33190965 0.06050925 0.29319577 0.06050925 0 N 0 
L 0.30397687 -0.0662249 0.26354774 -0.0662249 0 N 0 
L 0.36351791 0.04332185 0.35739222 0.01782382 0 N 0 
L 0.34783632 -0.02297293 0.34048553 -0.05413701 0 N 0 
L 0.26011732 0.04332185 0.25325659 0.01782382 0 N 0 
L 0.24247549 -0.02297293 0.23561476 -0.0490374 0 N 0 
L 0.32259872 -0.00540758 0.27653406 -0.00540758 0 N 0 
L 0.13588967 0.06050925 0.09717569 0.06050925 0 N 0 
L 0.10795689 -0.0662249 0.06752776 -0.0662249 0 N 0 
L 0.16749793 0.04332185 0.16137224 0.01782382 0 N 0 
L 0.15181624 -0.02297293 0.14446555 -0.05413701 0 N 0 
L 0.06409724 0.04332185 0.05723661 0.01782382 0 N 0 
L 0.04645551 -0.02297293 0.03959478 -0.0490374 0 N 0 
L 0.12657874 -0.00540758 0.08051407 -0.00540758 0 N 0 
L -0.33011093 0.06291014 -0.28451496 -0.06381988 0 N 0 
L -0.28451496 -0.06381988 -0.238919 0.06291014 0 N 0 
L -0.37570699 -0.06381988 -0.33011093 0.06291014 0 N 0 
L -0.238919 0.06291014 -0.19332303 -0.06381988 0 N 0 
L -0.43435039 0.06050925 -0.47306437 0.06050925 0 N 0 
L -0.46228327 -0.0662249 -0.5027123 -0.0662249 0 N 0 
L -0.40274213 0.04332185 -0.40886782 0.01782382 0 N 0 
L -0.41842372 -0.02297293 -0.42577451 -0.05413701 0 N 0 
L -0.50614272 0.04332185 -0.51300335 0.01782382 0 N 0 
L -0.52378455 -0.02297293 -0.53064528 -0.0490374 0 N 0 
L -0.44366132 -0.00540758 -0.48972598 -0.00540758 0 N 0 
L -0.63037037 0.06050925 -0.66908435 0.06050925 0 N 0 
L -0.65830325 -0.0662249 -0.69873228 -0.0662249 0 N 0 
L -0.59876211 0.04332185 -0.6048878 0.01782382 0 N 0 
L -0.6144437 -0.02297293 -0.62179449 -0.05413701 0 N 0 
L -0.7021627 0.04332185 -0.70902333 0.01782382 0 N 0 
L -0.71980453 -0.02297293 -0.72666526 -0.0490374 0 N 0 
L -0.6396813 -0.00540758 -0.68574596 -0.00540758 0 N 0 
L -0.06013032 0.06050925 -0.09884429 0.06050925 0 N 0 
L -0.08806309 -0.0662249 -0.12849222 -0.0662249 0 N 0 
L -0.02852205 0.04332185 -0.03464774 0.01782382 0 N 0 
L -0.04420374 -0.02297293 -0.05155443 -0.05413701 0 N 0 
L -0.13192274 0.04332185 -0.13878337 0.01782382 0 N 0 
L -0.14956447 -0.02297293 -0.1564252 -0.0490374 0 N 0 
L -0.06944124 -0.00540758 -0.11550591 -0.00540758 0 N 0 

### symbols/msro-old/features
#
#Feature symbol names
#
$0 r6
$1 r6.5
$2 r10
$3 r55
$4 r70
$5 r130
$6 r131
$7 r170
$8 r199
$9 s69.25
$10 s74.5
$11 s104
$12 s200

#
#Layer features
#
L 0 0 1.3 0 12 P 0 
L 1.4 0.000375 1.39875 0.016 2 N 0 
L 1.39875 0.016 1.395125 0.03125 2 N 0 
L 1.395125 0.03125 1.389125 0.04575 2 N 0 
L 1.389125 0.04575 1.380875 0.059125 2 N 0 
L 1.380875 0.059125 1.37075 0.071125 2 N 0 
L 1.37075 0.071125 1.35875 0.08125 2 N 0 
L 1.35875 0.08125 1.345375 0.0895 2 N 0 
L 1.345375 0.0895 1.330875 0.0955 2 N 0 
L 1.330875 0.0955 1.315625 0.099125 2 N 0 
L 1.315625 0.099125 1.3 0.100375 2 N 0 
L 1.3 0.100375 1.284375 0.099125 2 N 0 
L 1.284375 0.099125 1.269125 0.0955 2 N 0 
L 1.269125 0.0955 1.254625 0.0895 2 N 0 
L 1.254625 0.0895 1.24125 0.08125 2 N 0 
L 1.24125 0.08125 1.22925 0.071125 2 N 0 
L 1.22925 0.071125 1.219125 0.059125 2 N 0 
L 1.219125 0.059125 1.210875 0.04575 2 N 0 
L 1.210875 0.04575 1.204875 0.03125 2 N 0 
L 1.204875 0.03125 1.20125 0.016 2 N 0 
L 1.20125 0.016 1.2 0.000375 2 N 0 
L 1.2 0.000375 1.20125 -0.0155 2 N 0 
L 1.20125 -0.0155 1.204875 -0.03075 2 N 0 
L 1.204875 -0.03075 1.210875 -0.04525 2 N 0 
L 1.210875 -0.04525 1.219125 -0.058625 2 N 0 
L 1.219125 -0.058625 1.22925 -0.070625 2 N 0 
L 1.22925 -0.070625 1.24125 -0.08075 2 N 0 
L 1.24125 -0.08075 1.254625 -0.089 2 N 0 
L 1.254625 -0.089 1.269125 -0.095 2 N 0 
L 1.269125 -0.095 1.284375 -0.098625 2 N 0 
L 1.284375 -0.098625 1.3 -0.099875 2 N 0 
L 1.3 -0.099875 1.315625 -0.098625 2 N 0 
L 1.315625 -0.098625 1.330875 -0.095 2 N 0 
L 1.330875 -0.095 1.345375 -0.089 2 N 0 
L 1.345375 -0.089 1.35875 -0.08075 2 N 0 
L 1.35875 -0.08075 1.37075 -0.070625 2 N 0 
L 1.37075 -0.070625 1.380875 -0.058625 2 N 0 
L 1.380875 -0.058625 1.389125 -0.04525 2 N 0 
L 1.389125 -0.04525 1.395125 -0.03075 2 N 0 
L 1.395125 -0.03075 1.39875 -0.0155 2 N 0 
L 1.39875 -0.0155 1.4 0.000375 2 N 0 
L 1.3 0.000375 1.3 0.000375 8 N 0 
L 0.9 0.000375 0.9 0.000375 3 N 0 
L 0.8 0.000375 0.8 0.000375 3 N 0 
L 0.7 0.000375 0.7 0.000375 3 N 0 
L 0.6 0.000375 0.6 0.000375 3 N 0 
L 0.5 0.000375 0.5 0.000375 3 N 0 
L 0.4 0.000375 0.4 0.000375 3 N 0 
L 0.1 0.000375 0.09875 0.016 2 N 0 
L 0.09875 0.016 0.095125 0.03125 2 N 0 
L 0.095125 0.03125 0.089125 0.04575 2 N 0 
L 0.089125 0.04575 0.080875 0.059125 2 N 0 
L 0.080875 0.059125 0.07075 0.071125 2 N 0 
L 0.07075 0.071125 0.05875 0.08125 2 N 0 
L 0.05875 0.08125 0.045375 0.0895 2 N 0 
L 0.045375 0.0895 0.030875 0.0955 2 N 0 
L 0.030875 0.0955 0.015625 0.099125 2 N 0 
L 0.015625 0.099125 0 0.100375 2 N 0 
L 0 0.100375 -0.015625 0.099125 2 N 0 
L -0.015625 0.099125 -0.030875 0.0955 2 N 0 
L -0.030875 0.0955 -0.045375 0.0895 2 N 0 
L -0.045375 0.0895 -0.05875 0.08125 2 N 0 
L -0.05875 0.08125 -0.07075 0.071125 2 N 0 
L -0.07075 0.071125 -0.080875 0.059125 2 N 0 
L -0.080875 0.059125 -0.089125 0.04575 2 N 0 
L -0.089125 0.04575 -0.095125 0.03125 2 N 0 
L -0.095125 0.03125 -0.09875 0.016 2 N 0 
L -0.09875 0.016 -0.1 0.000375 2 N 0 
L -0.1 0.000375 -0.09875 -0.0155 2 N 0 
L -0.09875 -0.0155 -0.095125 -0.03075 2 N 0 
L -0.095125 -0.03075 -0.089125 -0.04525 2 N 0 
L -0.089125 -0.04525 -0.080875 -0.058625 2 N 0 
L -0.080875 -0.058625 -0.07075 -0.070625 2 N 0 
L -0.07075 -0.070625 -0.05875 -0.08075 2 N 0 
L -0.05875 -0.08075 -0.045375 -0.089 2 N 0 
L -0.045375 -0.089 -0.030875 -0.095 2 N 0 
L -0.030875 -0.095 -0.015625 -0.098625 2 N 0 
L -0.015625 -0.098625 0 -0.099875 2 N 0 
L 0 -0.099875 0.015625 -0.098625 2 N 0 
L 0.015625 -0.098625 0.030875 -0.095 2 N 0 
L 0.030875 -0.095 0.045375 -0.089 2 N 0 
L 0.045375 -0.089 0.05875 -0.08075 2 N 0 
L 0.05875 -0.08075 0.07075 -0.070625 2 N 0 
L 0.07075 -0.070625 0.080875 -0.058625 2 N 0 
L 0.080875 -0.058625 0.089125 -0.04525 2 N 0 
L 0.089125 -0.04525 0.095125 -0.03075 2 N 0 
L 0.095125 -0.03075 0.09875 -0.0155 2 N 0 
L 0.09875 -0.0155 0.1 0.000375 2 N 0 
L 0 0.000375 0 0.000375 8 N 0 
L 1.3 0.000375 1.3 0.000375 6 N 0 
L 0.9 0.000375 0.9 0.000375 3 N 0 
L 0.8 0.000375 0.8 0.000375 3 N 0 
L 0.7 0.000375 0.7 0.000375 3 N 0 
L 0.6 0.000375 0.6 0.000375 3 N 0 
L 0.5 0.000375 0.5 0.000375 3 N 0 
L 0.4 0.000375 0.4 0.000375 3 N 0 
L 0 0.000375 0 0.000375 6 N 0 
L 0.55 0.050375 0.55 -0.049875 2 N 0 
L 0.65 -0.049875 0.65 0.050375 2 N 0 
L 0.75 0.050375 0.75 -0.049875 2 N 0 
L 0.8 0.000375 0.9 0.000375 0 N 0 
L 0.5 0.000375 0.4 0.000375 0 N 0 
L 0.28925 -0.039875 0.28925 0.040375 1 N 0 
L 0.27775 -0.039875 0.27775 0.040875 1 N 0 
L 0.26625 -0.039875 0.26625 0.040875 1 N 0 
L 0.25475 -0.039875 0.25475 0.040875 1 N 0 
L 0.24325 -0.039875 0.24325 0.040875 1 N 0 
L 1.01075 -0.039875 1.01075 0.040375 1 N 0 
L 0 0.000375 0 0.000375 7 P 0 
L 1.3 0.000375 1.3 0.000375 7 P 0 
L 0 0.000375 0 0.000375 5 N 0 
L 1.3 0.000375 1.3 0.000375 5 N 0 
L 0.38825 -0.003125 0.498375 -0.003125 10 P 0 
L 0.59875 0.0025 0.59875 -0.00275 9 P 0 
L 0.69975 0.006625 0.69975 -0.00675 9 P 0 
L 0.817125 -0.00875 0.891625 -0.00875 11 P 0 
L 0.4 0 0.4 0 4 N 0 
L 0.6 0 0.6 0 4 N 0 
L 0.8 0 0.8 0 4 N 0 
L 0.5 0 0.5 0 4 N 0 
L 0.7 0 0.7 0 4 N 0 
L 0.9 0 0.9 0 4 N 0 
L 0.4 0 0.5 0 0 N 0 
L 0.8 0 0.9 0 0 N 0 

### symbols/msro/features
#
#Feature symbol names
#
$0 r6
$1 r6.5
$2 r10
$3 r55
$4 r70
$5 r130
$6 r131
$7 r170
$8 r199
$9 s69.25
$10 s74.5
$11 s104
$12 s200

#
#Layer features
#
L 0 0 1.3 0 12 P 0 
L 1.4 0.000375 1.39875 0.016 2 N 0 
L 1.39875 0.016 1.395125 0.03125 2 N 0 
L 1.395125 0.03125 1.389125 0.04575 2 N 0 
L 1.389125 0.04575 1.380875 0.059125 2 N 0 
L 1.380875 0.059125 1.37075 0.071125 2 N 0 
L 1.37075 0.071125 1.35875 0.08125 2 N 0 
L 1.35875 0.08125 1.345375 0.0895 2 N 0 
L 1.345375 0.0895 1.330875 0.0955 2 N 0 
L 1.330875 0.0955 1.315625 0.099125 2 N 0 
L 1.315625 0.099125 1.3 0.100375 2 N 0 
L 1.3 0.100375 1.284375 0.099125 2 N 0 
L 1.284375 0.099125 1.269125 0.0955 2 N 0 
L 1.269125 0.0955 1.254625 0.0895 2 N 0 
L 1.254625 0.0895 1.24125 0.08125 2 N 0 
L 1.24125 0.08125 1.22925 0.071125 2 N 0 
L 1.22925 0.071125 1.219125 0.059125 2 N 0 
L 1.219125 0.059125 1.210875 0.04575 2 N 0 
L 1.210875 0.04575 1.204875 0.03125 2 N 0 
L 1.204875 0.03125 1.20125 0.016 2 N 0 
L 1.20125 0.016 1.2 0.000375 2 N 0 
L 1.2 0.000375 1.20125 -0.0155 2 N 0 
L 1.20125 -0.0155 1.204875 -0.03075 2 N 0 
L 1.204875 -0.03075 1.210875 -0.04525 2 N 0 
L 1.210875 -0.04525 1.219125 -0.058625 2 N 0 
L 1.219125 -0.058625 1.22925 -0.070625 2 N 0 
L 1.22925 -0.070625 1.24125 -0.08075 2 N 0 
L 1.24125 -0.08075 1.254625 -0.089 2 N 0 
L 1.254625 -0.089 1.269125 -0.095 2 N 0 
L 1.269125 -0.095 1.284375 -0.098625 2 N 0 
L 1.284375 -0.098625 1.3 -0.099875 2 N 0 
L 1.3 -0.099875 1.315625 -0.098625 2 N 0 
L 1.315625 -0.098625 1.330875 -0.095 2 N 0 
L 1.330875 -0.095 1.345375 -0.089 2 N 0 
L 1.345375 -0.089 1.35875 -0.08075 2 N 0 
L 1.35875 -0.08075 1.37075 -0.070625 2 N 0 
L 1.37075 -0.070625 1.380875 -0.058625 2 N 0 
L 1.380875 -0.058625 1.389125 -0.04525 2 N 0 
L 1.389125 -0.04525 1.395125 -0.03075 2 N 0 
L 1.395125 -0.03075 1.39875 -0.0155 2 N 0 
L 1.39875 -0.0155 1.4 0.000375 2 N 0 
L 1.3 0.000375 1.3 0.000375 8 N 0 
L 0.9 0.000375 0.9 0.000375 3 N 0 
L 0.8 0.000375 0.8 0.000375 3 N 0 
L 0.7 0.000375 0.7 0.000375 3 N 0 
L 0.6 0.000375 0.6 0.000375 3 N 0 
L 0.5 0.000375 0.5 0.000375 3 N 0 
L 0.4 0.000375 0.4 0.000375 3 N 0 
L 0.1 0.000375 0.09875 0.016 2 N 0 
L 0.09875 0.016 0.095125 0.03125 2 N 0 
L 0.095125 0.03125 0.089125 0.04575 2 N 0 
L 0.089125 0.04575 0.080875 0.059125 2 N 0 
L 0.080875 0.059125 0.07075 0.071125 2 N 0 
L 0.07075 0.071125 0.05875 0.08125 2 N 0 
L 0.05875 0.08125 0.045375 0.0895 2 N 0 
L 0.045375 0.0895 0.030875 0.0955 2 N 0 
L 0.030875 0.0955 0.015625 0.099125 2 N 0 
L 0.015625 0.099125 0 0.100375 2 N 0 
L 0 0.100375 -0.015625 0.099125 2 N 0 
L -0.015625 0.099125 -0.030875 0.0955 2 N 0 
L -0.030875 0.0955 -0.045375 0.0895 2 N 0 
L -0.045375 0.0895 -0.05875 0.08125 2 N 0 
L -0.05875 0.08125 -0.07075 0.071125 2 N 0 
L -0.07075 0.071125 -0.080875 0.059125 2 N 0 
L -0.080875 0.059125 -0.089125 0.04575 2 N 0 
L -0.089125 0.04575 -0.095125 0.03125 2 N 0 
L -0.095125 0.03125 -0.09875 0.016 2 N 0 
L -0.09875 0.016 -0.1 0.000375 2 N 0 
L -0.1 0.000375 -0.09875 -0.0155 2 N 0 
L -0.09875 -0.0155 -0.095125 -0.03075 2 N 0 
L -0.095125 -0.03075 -0.089125 -0.04525 2 N 0 
L -0.089125 -0.04525 -0.080875 -0.058625 2 N 0 
L -0.080875 -0.058625 -0.07075 -0.070625 2 N 0 
L -0.07075 -0.070625 -0.05875 -0.08075 2 N 0 
L -0.05875 -0.08075 -0.045375 -0.089 2 N 0 
L -0.045375 -0.089 -0.030875 -0.095 2 N 0 
L -0.030875 -0.095 -0.015625 -0.098625 2 N 0 
L -0.015625 -0.098625 0 -0.099875 2 N 0 
L 0 -0.099875 0.015625 -0.098625 2 N 0 
L 0.015625 -0.098625 0.030875 -0.095 2 N 0 
L 0.030875 -0.095 0.045375 -0.089 2 N 0 
L 0.045375 -0.089 0.05875 -0.08075 2 N 0 
L 0.05875 -0.08075 0.07075 -0.070625 2 N 0 
L 0.07075 -0.070625 0.080875 -0.058625 2 N 0 
L 0.080875 -0.058625 0.089125 -0.04525 2 N 0 
L 0.089125 -0.04525 0.095125 -0.03075 2 N 0 
L 0.095125 -0.03075 0.09875 -0.0155 2 N 0 
L 0.09875 -0.0155 0.1 0.000375 2 N 0 
L 0 0.000375 0 0.000375 8 N 0 
L 1.3 0.000375 1.3 0.000375 6 N 0 
L 0.9 0.000375 0.9 0.000375 3 N 0 
L 0.8 0.000375 0.8 0.000375 3 N 0 
L 0.7 0.000375 0.7 0.000375 3 N 0 
L 0.6 0.000375 0.6 0.000375 3 N 0 
L 0.5 0.000375 0.5 0.000375 3 N 0 
L 0.4 0.000375 0.4 0.000375 3 N 0 
L 0 0.000375 0 0.000375 6 N 0 
L 0.55 0.050375 0.55 -0.049875 2 N 0 
L 0.65 -0.049875 0.65 0.050375 2 N 0 
L 0.75 0.050375 0.75 -0.049875 2 N 0 
L 0.8 0.000375 0.9 0.000375 0 N 0 
L 0.5 0.000375 0.4 0.000375 0 N 0 
L 0.28925 -0.039875 0.28925 0.040375 1 N 0 
L 0.27775 -0.039875 0.27775 0.040875 1 N 0 
L 0.26625 -0.039875 0.26625 0.040875 1 N 0 
L 0.25475 -0.039875 0.25475 0.040875 1 N 0 
L 0.24325 -0.039875 0.24325 0.040875 1 N 0 
L 1.01075 -0.039875 1.01075 0.040375 1 N 0 
L 0 0.000375 0 0.000375 7 P 0 
L 1.3 0.000375 1.3 0.000375 7 P 0 
L 0 0.000375 0 0.000375 5 N 0 
L 1.3 0.000375 1.3 0.000375 5 N 0 
L 0.38825 -0.003125 0.498375 -0.003125 10 P 0 
L 0.59875 0.0025 0.59875 -0.00275 9 P 0 
L 0.69975 0.006625 0.69975 -0.00675 9 P 0 
L 0.817125 -0.00875 0.891625 -0.00875 11 P 0 
L 0.4 0 0.4 0 4 N 0 
L 0.6 0 0.6 0 4 N 0 
L 0.8 0 0.8 0 4 N 0 
L 0.5 0 0.5 0 4 N 0 
L 0.7 0 0.7 0 4 N 0 
L 0.9 0 0.9 0 4 N 0 
L 0.4 0 0.5 0 0 N 0 
L 0.8 0 0.9 0 0 N 0 

### symbols/msro_y-old/features
#
#Feature symbol names
#
$0 r6
$1 r10
$2 r22
$3 r50
$4 r70
$5 r80
$6 r130
$7 r131
$8 r135
$9 r170
$10 r199
$11 s4.75
$12 s5.75
$13 s6.75
$14 s69.25
$15 s200
$16 rect200x100

#
#Layer features
#
L 0 -0.17064616 0 -1.13284882 15 P 0 
L 0.000375 -1.4 0.016 -1.39875 1 N 0 
L 0.016 -1.39875 0.03125 -1.395125 1 N 0 
L 0.03125 -1.395125 0.04575 -1.389125 1 N 0 
L 0.04575 -1.389125 0.059125 -1.380875 1 N 0 
L 0.059125 -1.380875 0.071125 -1.37075 1 N 0 
L 0.071125 -1.37075 0.08125 -1.35875 1 N 0 
L 0.08125 -1.35875 0.0895 -1.345375 1 N 0 
L 0.0895 -1.345375 0.0955 -1.330875 1 N 0 
L 0.0955 -1.330875 0.099125 -1.315625 1 N 0 
L 0.099125 -1.315625 0.100375 -1.3 1 N 0 
L 0.100375 -1.3 0.099125 -1.284375 1 N 0 
L 0.099125 -1.284375 0.0955 -1.269125 1 N 0 
L 0.0955 -1.269125 0.0895 -1.254625 1 N 0 
L 0.0895 -1.254625 0.08125 -1.24125 1 N 0 
L 0.08125 -1.24125 0.071125 -1.22925 1 N 0 
L 0.071125 -1.22925 0.059125 -1.219125 1 N 0 
L 0.059125 -1.219125 0.04575 -1.210875 1 N 0 
L 0.04575 -1.210875 0.03125 -1.204875 1 N 0 
L 0.03125 -1.204875 0.016 -1.20125 1 N 0 
L 0.016 -1.20125 0.000375 -1.2 1 N 0 
L 0.000375 -1.2 -0.0155 -1.20125 1 N 0 
L -0.0155 -1.20125 -0.03075 -1.204875 1 N 0 
L -0.03075 -1.204875 -0.04525 -1.210875 1 N 0 
L -0.04525 -1.210875 -0.058625 -1.219125 1 N 0 
L -0.058625 -1.219125 -0.070625 -1.22925 1 N 0 
L -0.070625 -1.22925 -0.08075 -1.24125 1 N 0 
L -0.08075 -1.24125 -0.089 -1.254625 1 N 0 
L -0.089 -1.254625 -0.095 -1.269125 1 N 0 
L -0.095 -1.269125 -0.098625 -1.284375 1 N 0 
L -0.098625 -1.284375 -0.099875 -1.3 1 N 0 
L -0.099875 -1.3 -0.098625 -1.315625 1 N 0 
L -0.098625 -1.315625 -0.095 -1.330875 1 N 0 
L -0.095 -1.330875 -0.089 -1.345375 1 N 0 
L -0.089 -1.345375 -0.08075 -1.35875 1 N 0 
L -0.08075 -1.35875 -0.070625 -1.37075 1 N 0 
L -0.070625 -1.37075 -0.058625 -1.380875 1 N 0 
L -0.058625 -1.380875 -0.04525 -1.389125 1 N 0 
L -0.04525 -1.389125 -0.03075 -1.395125 1 N 0 
L -0.03075 -1.395125 -0.0155 -1.39875 1 N 0 
L -0.0155 -1.39875 0.000375 -1.4 1 N 0 
L 0.000375 -1.3 0.000375 -1.3 10 N 0 
L 0.000375 -0.9 0.000375 -0.9 4 N 0 
L 0.000375 -0.8 0.000375 -0.8 4 N 0 
L 0.000375 -0.7 0.000375 -0.7 4 N 0 
L 0.000375 -0.6 0.000375 -0.6 4 N 0 
L 0.000375 -0.5 0.000375 -0.5 4 N 0 
L 0.000375 -0.4 0.000375 -0.4 4 N 0 
L 0.000375 -0.1 0.016 -0.09875 1 N 0 
L 0.016 -0.09875 0.03125 -0.095125 1 N 0 
L 0.03125 -0.095125 0.04575 -0.089125 1 N 0 
L 0.04575 -0.089125 0.059125 -0.080875 1 N 0 
L 0.059125 -0.080875 0.071125 -0.07075 1 N 0 
L 0.071125 -0.07075 0.08125 -0.05875 1 N 0 
L 0.08125 -0.05875 0.0895 -0.045375 1 N 0 
L 0.0895 -0.045375 0.0955 -0.030875 1 N 0 
L 0.0955 -0.030875 0.099125 -0.015625 1 N 0 
L 0.099125 -0.015625 0.100375 0 1 N 0 
L 0.100375 0 0.099125 0.015625 1 N 0 
L 0.099125 0.015625 0.0955 0.030875 1 N 0 
L 0.0955 0.030875 0.0895 0.045375 1 N 0 
L 0.0895 0.045375 0.08125 0.05875 1 N 0 
L 0.08125 0.05875 0.071125 0.07075 1 N 0 
L 0.071125 0.07075 0.059125 0.080875 1 N 0 
L 0.059125 0.080875 0.04575 0.089125 1 N 0 
L 0.04575 0.089125 0.03125 0.095125 1 N 0 
L 0.03125 0.095125 0.016 0.09875 1 N 0 
L 0.016 0.09875 0.000375 0.1 1 N 0 
L 0.000375 0.1 -0.0155 0.09875 1 N 0 
L -0.0155 0.09875 -0.03075 0.095125 1 N 0 
L -0.03075 0.095125 -0.04525 0.089125 1 N 0 
L -0.04525 0.089125 -0.058625 0.080875 1 N 0 
L -0.058625 0.080875 -0.070625 0.07075 1 N 0 
L -0.070625 0.07075 -0.08075 0.05875 1 N 0 
L -0.08075 0.05875 -0.089 0.045375 1 N 0 
L -0.089 0.045375 -0.095 0.030875 1 N 0 
L -0.095 0.030875 -0.098625 0.015625 1 N 0 
L -0.098625 0.015625 -0.099875 0 1 N 0 
L -0.099875 0 -0.098625 -0.015625 1 N 0 
L -0.098625 -0.015625 -0.095 -0.030875 1 N 0 
L -0.095 -0.030875 -0.089 -0.045375 1 N 0 
L -0.089 -0.045375 -0.08075 -0.05875 1 N 0 
L -0.08075 -0.05875 -0.070625 -0.07075 1 N 0 
L -0.070625 -0.07075 -0.058625 -0.080875 1 N 0 
L -0.058625 -0.080875 -0.04525 -0.089125 1 N 0 
L -0.04525 -0.089125 -0.03075 -0.095125 1 N 0 
L -0.03075 -0.095125 -0.0155 -0.09875 1 N 0 
L -0.0155 -0.09875 0.000375 -0.1 1 N 0 
L 0.000375 -0.9 0.000375 -0.9 4 N 0 
L 0.000375 -0.8 0.000375 -0.8 4 N 0 
L 0.000375 -0.7 0.000375 -0.7 4 N 0 
L 0.000375 -0.6 0.000375 -0.6 4 N 0 
L 0.000375 -0.5 0.000375 -0.5 4 N 0 
L 0.000375 -0.4 0.000375 -0.4 4 N 0 
L 0.000375 0 0.000375 0 7 N 0 
L 0.09665512 -0.55 -0.09664144 -0.55 13 N 0 
L -0.09711289 -0.65 0.09712894 -0.65 12 N 0 
L 0.09760285 -0.75 -0.09771909 -0.75 11 N 0 
L 0.000375 -0.8 0.000375 -0.9 0 N 0 
L 0.000375 -0.5 0.000375 -0.4 0 N 0 
L -0.09671142 -0.28925 0.09675354 -0.28925 13 N 0 
L -0.09671152 -0.27775 0.09664006 -0.27775 13 N 0 
L -0.09671152 -0.26625 0.09664006 -0.26625 13 N 0 
L -0.09671152 -0.25475 0.09664006 -0.25475 13 N 0 
L -0.09659803 -0.24325 0.09664006 -0.24325 13 N 0 
L -0.09673287 -1.01075 0.09668602 -1.01075 13 N 0 
L 0.000375 -1.3 0.000375 -1.3 9 P 0 
L 0.000375 0 0.000375 0 6 N 0 
L 0.000375 -1.3 0.000375 -1.3 6 N 0 
L 0.0025 -0.59875 -0.00275 -0.59875 14 P 0 
L 0 -0.4 0 -0.4 5 N 0 
L 0 -0.6 0 -0.6 5 N 0 
L 0 -0.8 0 -0.8 5 N 0 
L 0 -0.5 0 -0.5 3 N 0 
L 0 -0.7 0 -0.7 3 N 0 
L 0 -0.9 0 -0.9 3 N 0 
L 0 -0.4 0 -0.5 0 N 0 
L 0 -0.8 0 -0.9 0 N 0 
P 0.000375 -0.021 16 N 0 0
L 0.000375 0 0.000375 0 10 N 0 
L 0.000375 0 0.000375 0 7 N 0 
L 0.000375 0 0.000375 0 9 P 0 
L 0.000375 0 0.000375 0 6 N 0 
P 0 -1.279 16 N 0 0
L 0.000375 -1.4 0.016 -1.39875 1 N 0 
L 0.016 -1.39875 0.03125 -1.395125 1 N 0 
L 0.03125 -1.395125 0.04575 -1.389125 1 N 0 
L 0.04575 -1.389125 0.059125 -1.380875 1 N 0 
L 0.059125 -1.380875 0.071125 -1.37075 1 N 0 
L 0.071125 -1.37075 0.08125 -1.35875 1 N 0 
L 0.08125 -1.35875 0.0895 -1.345375 1 N 0 
L 0.0895 -1.345375 0.0955 -1.330875 1 N 0 
L 0.0955 -1.330875 0.099125 -1.315625 1 N 0 
L 0.099125 -1.315625 0.100375 -1.3 1 N 0 
L 0.100375 -1.3 0.099125 -1.284375 1 N 0 
L 0.099125 -1.284375 0.0955 -1.269125 1 N 0 
L 0.0955 -1.269125 0.0895 -1.254625 1 N 0 
L 0.0895 -1.254625 0.08125 -1.24125 1 N 0 
L 0.08125 -1.24125 0.071125 -1.22925 1 N 0 
L 0.071125 -1.22925 0.059125 -1.219125 1 N 0 
L 0.059125 -1.219125 0.04575 -1.210875 1 N 0 
L 0.04575 -1.210875 0.03125 -1.204875 1 N 0 
L 0.03125 -1.204875 0.016 -1.20125 1 N 0 
L 0.016 -1.20125 0.000375 -1.2 1 N 0 
L 0.000375 -1.2 -0.0155 -1.20125 1 N 0 
L -0.0155 -1.20125 -0.03075 -1.204875 1 N 0 
L -0.03075 -1.204875 -0.04525 -1.210875 1 N 0 
L -0.04525 -1.210875 -0.058625 -1.219125 1 N 0 
L -0.058625 -1.219125 -0.070625 -1.22925 1 N 0 
L -0.070625 -1.22925 -0.08075 -1.24125 1 N 0 
L -0.08075 -1.24125 -0.089 -1.254625 1 N 0 
L -0.089 -1.254625 -0.095 -1.269125 1 N 0 
L -0.095 -1.269125 -0.098625 -1.284375 1 N 0 
L -0.098625 -1.284375 -0.099875 -1.3 1 N 0 
L -0.099875 -1.3 -0.098625 -1.315625 1 N 0 
L -0.098625 -1.315625 -0.095 -1.330875 1 N 0 
L -0.095 -1.330875 -0.089 -1.345375 1 N 0 
L -0.089 -1.345375 -0.08075 -1.35875 1 N 0 
L -0.08075 -1.35875 -0.070625 -1.37075 1 N 0 
L -0.070625 -1.37075 -0.058625 -1.380875 1 N 0 
L -0.058625 -1.380875 -0.04525 -1.389125 1 N 0 
L -0.04525 -1.389125 -0.03075 -1.395125 1 N 0 
L -0.03075 -1.395125 -0.0155 -1.39875 1 N 0 
L -0.0155 -1.39875 0.000375 -1.4 1 N 0 
L 0.000375 -1.3 0.000375 -1.3 7 N 0 
L 0.000375 -1.3 0.000375 -1.3 9 P 0 
L 0.000375 -1.3 0.000375 -1.3 6 N 0 
P 0.000375 0 8 P 0 0
P 0.000375 -1.3 8 P 0 0
P 0.07 -0.4 2 N 0 1
P 0.07 -0.44 2 N 0 1
P 0.07 -0.48 2 N 0 1
P 0.07 -0.52 2 N 0 1
P 0.07 -0.56 2 N 0 1
P 0.07 -0.6 2 N 0 1
P 0.07 -0.64 2 N 0 1
P 0.07 -0.68 2 N 0 1
P 0.07 -0.72 2 N 0 1
P 0.07 -0.76 2 N 0 1
P 0.07 -0.8 2 N 0 1
P 0.07 -0.84 2 N 0 1
P 0.07 -0.88 2 N 0 1
P 0.07 -0.92 2 N 0 1
P 0.07 -0.96 2 N 0 1
P 0.07 -1 2 N 0 1

### symbols/msro_y/features
#
#Feature symbol names
#
$0 r6
$1 r10
$2 r22
$3 r50
$4 r70
$5 r80
$6 r130
$7 r131
$8 r135
$9 r170
$10 r199
$11 s4.75
$12 s5.75
$13 s6.75
$14 s69.25
$15 s200
$16 rect200x100

#
#Layer features
#
L 0 -0.17064616 0 -1.13284882 15 P 0 
L 0.000375 -1.4 0.016 -1.39875 1 N 0 
L 0.016 -1.39875 0.03125 -1.395125 1 N 0 
L 0.03125 -1.395125 0.04575 -1.389125 1 N 0 
L 0.04575 -1.389125 0.059125 -1.380875 1 N 0 
L 0.059125 -1.380875 0.071125 -1.37075 1 N 0 
L 0.071125 -1.37075 0.08125 -1.35875 1 N 0 
L 0.08125 -1.35875 0.0895 -1.345375 1 N 0 
L 0.0895 -1.345375 0.0955 -1.330875 1 N 0 
L 0.0955 -1.330875 0.099125 -1.315625 1 N 0 
L 0.099125 -1.315625 0.100375 -1.3 1 N 0 
L 0.100375 -1.3 0.099125 -1.284375 1 N 0 
L 0.099125 -1.284375 0.0955 -1.269125 1 N 0 
L 0.0955 -1.269125 0.0895 -1.254625 1 N 0 
L 0.0895 -1.254625 0.08125 -1.24125 1 N 0 
L 0.08125 -1.24125 0.071125 -1.22925 1 N 0 
L 0.071125 -1.22925 0.059125 -1.219125 1 N 0 
L 0.059125 -1.219125 0.04575 -1.210875 1 N 0 
L 0.04575 -1.210875 0.03125 -1.204875 1 N 0 
L 0.03125 -1.204875 0.016 -1.20125 1 N 0 
L 0.016 -1.20125 0.000375 -1.2 1 N 0 
L 0.000375 -1.2 -0.0155 -1.20125 1 N 0 
L -0.0155 -1.20125 -0.03075 -1.204875 1 N 0 
L -0.03075 -1.204875 -0.04525 -1.210875 1 N 0 
L -0.04525 -1.210875 -0.058625 -1.219125 1 N 0 
L -0.058625 -1.219125 -0.070625 -1.22925 1 N 0 
L -0.070625 -1.22925 -0.08075 -1.24125 1 N 0 
L -0.08075 -1.24125 -0.089 -1.254625 1 N 0 
L -0.089 -1.254625 -0.095 -1.269125 1 N 0 
L -0.095 -1.269125 -0.098625 -1.284375 1 N 0 
L -0.098625 -1.284375 -0.099875 -1.3 1 N 0 
L -0.099875 -1.3 -0.098625 -1.315625 1 N 0 
L -0.098625 -1.315625 -0.095 -1.330875 1 N 0 
L -0.095 -1.330875 -0.089 -1.345375 1 N 0 
L -0.089 -1.345375 -0.08075 -1.35875 1 N 0 
L -0.08075 -1.35875 -0.070625 -1.37075 1 N 0 
L -0.070625 -1.37075 -0.058625 -1.380875 1 N 0 
L -0.058625 -1.380875 -0.04525 -1.389125 1 N 0 
L -0.04525 -1.389125 -0.03075 -1.395125 1 N 0 
L -0.03075 -1.395125 -0.0155 -1.39875 1 N 0 
L -0.0155 -1.39875 0.000375 -1.4 1 N 0 
L 0.000375 -1.3 0.000375 -1.3 10 N 0 
L 0.000375 -0.9 0.000375 -0.9 4 N 0 
L 0.000375 -0.8 0.000375 -0.8 4 N 0 
L 0.000375 -0.7 0.000375 -0.7 4 N 0 
L 0.000375 -0.6 0.000375 -0.6 4 N 0 
L 0.000375 -0.5 0.000375 -0.5 4 N 0 
L 0.000375 -0.4 0.000375 -0.4 4 N 0 
L 0.000375 -0.1 0.016 -0.09875 1 N 0 
L 0.016 -0.09875 0.03125 -0.095125 1 N 0 
L 0.03125 -0.095125 0.04575 -0.089125 1 N 0 
L 0.04575 -0.089125 0.059125 -0.080875 1 N 0 
L 0.059125 -0.080875 0.071125 -0.07075 1 N 0 
L 0.071125 -0.07075 0.08125 -0.05875 1 N 0 
L 0.08125 -0.05875 0.0895 -0.045375 1 N 0 
L 0.0895 -0.045375 0.0955 -0.030875 1 N 0 
L 0.0955 -0.030875 0.099125 -0.015625 1 N 0 
L 0.099125 -0.015625 0.100375 0 1 N 0 
L 0.100375 0 0.099125 0.015625 1 N 0 
L 0.099125 0.015625 0.0955 0.030875 1 N 0 
L 0.0955 0.030875 0.0895 0.045375 1 N 0 
L 0.0895 0.045375 0.08125 0.05875 1 N 0 
L 0.08125 0.05875 0.071125 0.07075 1 N 0 
L 0.071125 0.07075 0.059125 0.080875 1 N 0 
L 0.059125 0.080875 0.04575 0.089125 1 N 0 
L 0.04575 0.089125 0.03125 0.095125 1 N 0 
L 0.03125 0.095125 0.016 0.09875 1 N 0 
L 0.016 0.09875 0.000375 0.1 1 N 0 
L 0.000375 0.1 -0.0155 0.09875 1 N 0 
L -0.0155 0.09875 -0.03075 0.095125 1 N 0 
L -0.03075 0.095125 -0.04525 0.089125 1 N 0 
L -0.04525 0.089125 -0.058625 0.080875 1 N 0 
L -0.058625 0.080875 -0.070625 0.07075 1 N 0 
L -0.070625 0.07075 -0.08075 0.05875 1 N 0 
L -0.08075 0.05875 -0.089 0.045375 1 N 0 
L -0.089 0.045375 -0.095 0.030875 1 N 0 
L -0.095 0.030875 -0.098625 0.015625 1 N 0 
L -0.098625 0.015625 -0.099875 0 1 N 0 
L -0.099875 0 -0.098625 -0.015625 1 N 0 
L -0.098625 -0.015625 -0.095 -0.030875 1 N 0 
L -0.095 -0.030875 -0.089 -0.045375 1 N 0 
L -0.089 -0.045375 -0.08075 -0.05875 1 N 0 
L -0.08075 -0.05875 -0.070625 -0.07075 1 N 0 
L -0.070625 -0.07075 -0.058625 -0.080875 1 N 0 
L -0.058625 -0.080875 -0.04525 -0.089125 1 N 0 
L -0.04525 -0.089125 -0.03075 -0.095125 1 N 0 
L -0.03075 -0.095125 -0.0155 -0.09875 1 N 0 
L -0.0155 -0.09875 0.000375 -0.1 1 N 0 
L 0.000375 -0.9 0.000375 -0.9 4 N 0 
L 0.000375 -0.8 0.000375 -0.8 4 N 0 
L 0.000375 -0.7 0.000375 -0.7 4 N 0 
L 0.000375 -0.6 0.000375 -0.6 4 N 0 
L 0.000375 -0.5 0.000375 -0.5 4 N 0 
L 0.000375 -0.4 0.000375 -0.4 4 N 0 
L 0.000375 0 0.000375 0 7 N 0 
L 0.09665512 -0.55 -0.09664144 -0.55 13 N 0 
L -0.09711289 -0.65 0.09712894 -0.65 12 N 0 
L 0.09760285 -0.75 -0.09771909 -0.75 11 N 0 
L 0.000375 -0.8 0.000375 -0.9 0 N 0 
L 0.000375 -0.5 0.000375 -0.4 0 N 0 
L -0.09671142 -0.28925 0.09675354 -0.28925 13 N 0 
L -0.09671152 -0.27775 0.09664006 -0.27775 13 N 0 
L -0.09671152 -0.26625 0.09664006 -0.26625 13 N 0 
L -0.09671152 -0.25475 0.09664006 -0.25475 13 N 0 
L -0.09659803 -0.24325 0.09664006 -0.24325 13 N 0 
L -0.09673287 -1.01075 0.09668602 -1.01075 13 N 0 
L 0.000375 -1.3 0.000375 -1.3 9 P 0 
L 0.000375 0 0.000375 0 6 N 0 
L 0.000375 -1.3 0.000375 -1.3 6 N 0 
L 0.0025 -0.59875 -0.00275 -0.59875 14 P 0 
L 0 -0.4 0 -0.4 5 N 0 
L 0 -0.6 0 -0.6 5 N 0 
L 0 -0.8 0 -0.8 5 N 0 
L 0 -0.5 0 -0.5 3 N 0 
L 0 -0.7 0 -0.7 3 N 0 
L 0 -0.9 0 -0.9 3 N 0 
L 0 -0.4 0 -0.5 0 N 0 
L 0 -0.8 0 -0.9 0 N 0 
P 0.000375 -0.021 16 N 0 0
L 0.000375 0 0.000375 0 10 N 0 
L 0.000375 0 0.000375 0 7 N 0 
L 0.000375 0 0.000375 0 9 P 0 
L 0.000375 0 0.000375 0 6 N 0 
P 0 -1.279 16 N 0 0
L 0.000375 -1.4 0.016 -1.39875 1 N 0 
L 0.016 -1.39875 0.03125 -1.395125 1 N 0 
L 0.03125 -1.395125 0.04575 -1.389125 1 N 0 
L 0.04575 -1.389125 0.059125 -1.380875 1 N 0 
L 0.059125 -1.380875 0.071125 -1.37075 1 N 0 
L 0.071125 -1.37075 0.08125 -1.35875 1 N 0 
L 0.08125 -1.35875 0.0895 -1.345375 1 N 0 
L 0.0895 -1.345375 0.0955 -1.330875 1 N 0 
L 0.0955 -1.330875 0.099125 -1.315625 1 N 0 
L 0.099125 -1.315625 0.100375 -1.3 1 N 0 
L 0.100375 -1.3 0.099125 -1.284375 1 N 0 
L 0.099125 -1.284375 0.0955 -1.269125 1 N 0 
L 0.0955 -1.269125 0.0895 -1.254625 1 N 0 
L 0.0895 -1.254625 0.08125 -1.24125 1 N 0 
L 0.08125 -1.24125 0.071125 -1.22925 1 N 0 
L 0.071125 -1.22925 0.059125 -1.219125 1 N 0 
L 0.059125 -1.219125 0.04575 -1.210875 1 N 0 
L 0.04575 -1.210875 0.03125 -1.204875 1 N 0 
L 0.03125 -1.204875 0.016 -1.20125 1 N 0 
L 0.016 -1.20125 0.000375 -1.2 1 N 0 
L 0.000375 -1.2 -0.0155 -1.20125 1 N 0 
L -0.0155 -1.20125 -0.03075 -1.204875 1 N 0 
L -0.03075 -1.204875 -0.04525 -1.210875 1 N 0 
L -0.04525 -1.210875 -0.058625 -1.219125 1 N 0 
L -0.058625 -1.219125 -0.070625 -1.22925 1 N 0 
L -0.070625 -1.22925 -0.08075 -1.24125 1 N 0 
L -0.08075 -1.24125 -0.089 -1.254625 1 N 0 
L -0.089 -1.254625 -0.095 -1.269125 1 N 0 
L -0.095 -1.269125 -0.098625 -1.284375 1 N 0 
L -0.098625 -1.284375 -0.099875 -1.3 1 N 0 
L -0.099875 -1.3 -0.098625 -1.315625 1 N 0 
L -0.098625 -1.315625 -0.095 -1.330875 1 N 0 
L -0.095 -1.330875 -0.089 -1.345375 1 N 0 
L -0.089 -1.345375 -0.08075 -1.35875 1 N 0 
L -0.08075 -1.35875 -0.070625 -1.37075 1 N 0 
L -0.070625 -1.37075 -0.058625 -1.380875 1 N 0 
L -0.058625 -1.380875 -0.04525 -1.389125 1 N 0 
L -0.04525 -1.389125 -0.03075 -1.395125 1 N 0 
L -0.03075 -1.395125 -0.0155 -1.39875 1 N 0 
L -0.0155 -1.39875 0.000375 -1.4 1 N 0 
L 0.000375 -1.3 0.000375 -1.3 7 N 0 
L 0.000375 -1.3 0.000375 -1.3 9 P 0 
L 0.000375 -1.3 0.000375 -1.3 6 N 0 
P 0.000375 0 8 P 0 0
P 0.000375 -1.3 8 P 0 0
P 0.07 -0.4 2 N 0 1
P 0.07 -0.44 2 N 0 1
P 0.07 -0.48 2 N 0 1
P 0.07 -0.52 2 N 0 1
P 0.07 -0.56 2 N 0 1
P 0.07 -0.6 2 N 0 1
P 0.07 -0.64 2 N 0 1
P 0.07 -0.68 2 N 0 1
P 0.07 -0.72 2 N 0 1
P 0.07 -0.76 2 N 0 1
P 0.07 -0.8 2 N 0 1
P 0.07 -0.84 2 N 0 1
P 0.07 -0.88 2 N 0 1
P 0.07 -0.92 2 N 0 1
P 0.07 -0.96 2 N 0 1
P 0.07 -1 2 N 0 1

### symbols/p-nut-old/features
#
#Feature symbol names
#
$0 r28
$1 r140
$2 s300
$3 s350

#
#Layer features
#
P 0.0044221 0.0022111 3 P 0 0
P 0.0044221 0.0022111 2 N 0 0
P 0.0044221 0.0022111 1 P 0 0
L 0.0044221 0.0022111 0.0044221 0.0022111 0 N 0 

### symbols/p-nut/features
#
#Feature symbol names
#
$0 r15
$1 r28
$2 s300

#
#Layer features
#
L 0 0 0 0 2 P 0 
L 0 0 0 0 1 N 0 
L 0.0425 0 0.0415 0.0075 0 N 0 
L 0.0415 0.0075 0.0395 0.0145 0 N 0 
L 0.0395 0.0145 0.036 0.0215 0 N 0 
L 0.036 0.0215 0.032 0.0275 0 N 0 
L 0.032 0.0275 0.026 0.033 0 N 0 
L 0.026 0.033 0.02 0.037 0 N 0 
L 0.02 0.037 0.013 0.04 0 N 0 
L 0.013 0.04 0.0055 0.042 0 N 0 
L 0.0055 0.042 -0.0015 0.042 0 N 0 
L -0.0015 0.042 -0.009 0.041 0 N 0 
L -0.009 0.041 -0.0165 0.039 0 N 0 
L -0.0165 0.039 -0.023 0.035 0 N 0 
L -0.023 0.035 -0.029 0.0305 0 N 0 
L -0.029 0.0305 -0.034 0.0245 0 N 0 
L -0.034 0.0245 -0.038 0.018 0 N 0 
L -0.038 0.018 -0.0405 0.011 0 N 0 
L -0.0405 0.011 -0.042 0.0035 0 N 0 
L -0.042 0.0035 -0.042 -0.0035 0 N 0 
L -0.042 -0.0035 -0.0405 -0.011 0 N 0 
L -0.0405 -0.011 -0.038 -0.018 0 N 0 
L -0.038 -0.018 -0.034 -0.0245 0 N 0 
L -0.034 -0.0245 -0.029 -0.0305 0 N 0 
L -0.029 -0.0305 -0.023 -0.035 0 N 0 
L -0.023 -0.035 -0.0165 -0.039 0 N 0 
L -0.0165 -0.039 -0.009 -0.041 0 N 0 
L -0.009 -0.041 -0.0015 -0.042 0 N 0 
L -0.0015 -0.042 0.0055 -0.042 0 N 0 
L 0.0055 -0.042 0.013 -0.04 0 N 0 
L 0.013 -0.04 0.02 -0.037 0 N 0 
L 0.02 -0.037 0.026 -0.033 0 N 0 
L 0.026 -0.033 0.032 -0.0275 0 N 0 
L 0.032 -0.0275 0.036 -0.0215 0 N 0 
L 0.036 -0.0215 0.0395 -0.0145 0 N 0 
L 0.0395 -0.0145 0.0415 -0.0075 0 N 0 
L 0.0415 -0.0075 0.042 0 0 N 0 
L 0.042 0 0.0425 0 0 N 0 

### symbols/pke-bot-old/features
#
#Feature symbol names
#
$0 r196.85
$1 rect354.331x354.331

#
#Layer features
#
P 0 0 1 P 0 0
P 0 0 0 N 0 0

### symbols/pke-bot/features
#
#Feature symbol names
#
$0 r196.85
$1 rect354.331x354.331

#
#Layer features
#
P 0 0 1 P 0 0
P 0 0 0 N 0 0

### symbols/pke-top-old/features
#
#Feature symbol names
#
$0 r59.055
$1 rect354.331x354.331

#
#Layer features
#
P 0 0 1 P 0 0
P 0 0 0 N 0 0

### symbols/pke-top/features
#
#Feature symbol names
#
$0 r59.055
$1 rect354.331x354.331

#
#Layer features
#
P 0 0 1 P 0 0
P 0 0 0 N 0 0

### symbols/reg_lb/features
#
#Feature symbol names
#
$0 r40

#
#Layer features
#
L 0 0 0.79 0 0 P 0 
L 0 0 0 0.79 0 P 0 

### symbols/reg_lt/features
#
#Feature symbol names
#
$0 r40

#
#Layer features
#
L 0 0 0.79 0 0 P 0 
L 0 0 0 -0.79 0 P 0 

### symbols/reg_rb/features
#
#Feature symbol names
#
$0 r40

#
#Layer features
#
L 0 0 -0.79 0 0 P 0 
L 0 0 0 0.79 0 P 0 

### symbols/reg_rt/features
#
#Feature symbol names
#
$0 r40

#
#Layer features
#
L 0 0 -0.79 0 0 P 0 
L 0 0 0 -0.79 0 P 0 

### symbols/seal_new/features
#
#Layer features
#
S P 0
OB -0.196850393701 0 I
OS -0.196850393701 0.275590551181
OS 2.283464566929 0.275590551181
OS 2.283464566929 0
OS -0.196850393701 0
OE
SE

### symbols/sht_bot/features
#
#Feature symbol names
#
$0 r39.37
$1 s200
$2 s245

#
#Layer features
#
P 0 0 2 N 0 0
P 0 0 1 P 0 0
P 0 0 0 N 0 0

### symbols/sht_top/features
#
#Feature symbol names
#
$0 s200
$1 s245
$2 donut_r78.74x70.866

#
#Layer features
#
P 0 0 1 N 0 0
P 0 0 0 P 0 0
P 0 0 2 N 0 0

### symbols/sp-8c5_2p0_254+1/features
#
#Layer features
#
S P 0
OB -0.000350295276 -0.00035 I
OS 0.001379724409 -0.00208996063
OC 0.00208976378 -0.001380019685 0 0 Y
OS 0.000349704724 0.00035
OC -0.000350295276 -0.00035 -0.000000295276 0 N
OE
SE

### symbols/sp-8c5_2p0_254+2/features
#
#Layer features
#
S P 0
OB 0.157482283465 0.001180019685 I
OS 0.10235226378 0.001180019685
OC -0.072792027559 0.07195984252 0.000001377953 0 N
OC 0.00000226378 -0.10236003937 0.00000226378 -0.000000984252 N
OS 0.000392322835 -0.10236003937
OC 0.072100984252 -0.072657283465 -0.000000688976 0 N
OC 0.10235226378 -0.001180019685 0.00000226378 -0.000002755906 N
OS 0.157482283465 -0.001180019685
OC 0.157482283465 0.001180019685 0.00000226378 0 Y
OE
SE

### symbols/sp-8c5_2p0_254+3/features
#
#Layer features
#
S P 0
OB 0.00035 0.00035 I
OS -0.001380019685 0.00208996063
OC -0.00208996063 0.001380019685 0 0 Y
OS -0.00035 -0.00035
OC 0.00035 0.00035 0 0 N
OE
SE

### symbols/sp-8c5_2p0_254/features
#
#Layer features
#
S P 0
OB -0.157482185039 -0.001180019685 I
OS -0.102352165354 -0.001180019685
OC 0.072792125984 -0.07195984252 -0.000001279528 0 N
OC -0.000002165354 0.10236003937 -0.000002165354 0.000000984252 N
OS -0.000392125984 0.10236003937
OC -0.072100787402 0.07265738189 0.000000787402 0 N
OC -0.102352165354 0.001180019685 -0.000002165354 0.000002755906 N
OS -0.157482185039 0.001180019685
OC -0.157482185039 -0.001180019685 -0.000002165354 0 Y
OE
SE

### symbols/sp-9c5_7p0_254+1/features
#
#Layer features
#
S P 0
OB 0.00035 0.000349704724 I
OS -0.001380019685 0.00208976378
OC -0.00208996063 0.001379724409 0 0 Y
OS -0.00035 -0.000350295276
OC 0.00035 0.000349704724 0 -0.000000295276 N
OE
SE

### symbols/sp-9c5_7p0_254+2/features
#
#Layer features
#
S P 0
OB -0.177161909449 0.001180019685 I
OC -0.177161909449 -0.001180019685 -0.000001968504 0 Y
OS -0.112201968504 -0.001180019685
OC -0.112201968504 0.001180019685 -0.000001968504 0 N
OS -0.177161909449 0.001180019685
OE
SE

### symbols/sp-9c5_7p0_254+3/features
#
#Layer features
#
S P 0
OB -0.000350295276 -0.00035 I
OS 0.001379724409 -0.00208996063
OC 0.00208976378 -0.001380019685 0 0 Y
OS 0.000349704724 0.00035
OC -0.000350295276 -0.00035 -0.000000295276 0 N
OE
SE

### symbols/sp-9c5_7p0_254/features
#
#Layer features
#
S P 0
OB 0.177162007874 -0.001180019685 I
OC 0.177162007874 0.001180019685 0.000001968504 0 Y
OS 0.112201968504 0.001180019685
OC 0.112201968504 -0.001180019685 0.000001968504 0 N
OS 0.177162007874 -0.001180019685
OE
SE

### symbols/tmsri_1cu_y/features
#
#Feature symbol names
#
$0 r6
$1 r10
$2 r15.5
$3 r43
$4 r55
$5 r75
$6 r125
$7 r131
$8 r155
$9 s72.25
$10 s74.75
$11 s200

#
#Layer features
#
L 0 -1.3 0 -1.3 6 P 0 
L 0 -0.4 0 -0.4 3 P 0 
L 0 -0.5 0 -0.5 2 P 0 
L 0 -0.8 0 -0.8 3 P 0 
L 0 -0.9 0 -0.9 2 P 0 
L 0 0 0 -1.3 11 P 0 
L 0 -1.3 0 -1.3 8 N 0 
L 0 -0.9 0 -0.9 4 N 0 
L 0 -0.8 0 -0.8 4 N 0 
L 0 -0.5 0 -0.5 4 N 0 
L 0 -0.4 0 -0.4 4 N 0 
L 0 0 0 0 8 N 0 
L 0 -1.3 0 -1.3 8 N 0 
L 0 -0.9 0 -0.9 4 N 0 
L 0 -0.8 0 -0.8 4 N 0 
L 0 -0.5 0 -0.5 4 N 0 
L 0 -0.4 0 -0.4 4 N 0 
L 0 0 0 0 8 N 0 
L 0.05 -0.55 -0.05 -0.55 1 N 0 
L -0.05 -0.65 0.05 -0.65 1 N 0 
L 0.05 -0.75 -0.05 -0.75 1 N 0 
L 0 -0.8 0 -0.9 0 N 0 
L 0 -0.5 0 -0.4 0 N 0 
L 0.000125 0 0.000125 0 7 P 0 
L 0.000125 -1.3 0.000125 -1.3 7 P 0 
L 0.000125 0 0.000125 0 5 N 0 
L 0.000125 -1.3 0.000125 -1.3 5 N 0 
L -0.0015 -0.80425 -0.0015 -0.9055 10 P 0 
L 0.001125 -0.37875 0.001125 -0.499625 9 P 0 
L 0 -0.4 0 -0.4 5 N 0 
L 0 -0.8 0 -0.8 5 N 0 
L 0 -0.5 0 -0.5 5 N 0 
L 0 -0.9 0 -0.9 5 N 0 
L 0 -0.8 0 -0.9 0 N 0 
L 0 -0.4 0 -0.5 0 N 0 

### symbols/tmsri_y/features
#
#Feature symbol names
#
$0 r6
$1 r10
$2 r15.5
$3 r43
$4 r55
$5 r75
$6 r125
$7 r133.25
$8 r155
$9 s68.25
$10 s72.25
$11 s74.75
$12 s200

#
#Layer features
#
S P 0
OB -0.057083956693 -0.533113681102 I
OS -0.057083956693 -0.326523917323
OS 0.048929232283 -0.326523917323
OS 0.048929232283 -0.533113681102
OS -0.057083956693 -0.533113681102
OE
SE
L 0 -1.3 0 -1.3 6 P 0 
L 0 -0.4 0 -0.4 3 P 0 
L 0 -0.5 0 -0.5 2 P 0 
L 0 -0.6 0 -0.6 3 P 0 
L 0 -0.7 0 -0.7 2 P 0 
L 0 -0.8 0 -0.8 3 P 0 
L 0 -0.9 0 -0.9 2 P 0 
L 0 0 0 -1.3 12 P 0 
L 0 -1.3 0 -1.3 8 N 0 
L 0 -0.9 0 -0.9 4 N 0 
L 0 -0.8 0 -0.8 4 N 0 
L 0 -0.7 0 -0.7 4 N 0 
L 0 -0.6 0 -0.6 4 N 0 
L 0 -0.5 0 -0.5 4 N 0 
L 0 -0.4 0 -0.4 4 N 0 
L 0 0 0 0 8 N 0 
L 0 -1.3 0 -1.3 8 N 0 
L 0 -0.9 0 -0.9 4 N 0 
L 0 -0.8 0 -0.8 4 N 0 
L 0 -0.7 0 -0.7 4 N 0 
L 0 -0.6 0 -0.6 4 N 0 
L 0 -0.5 0 -0.5 4 N 0 
L 0 -0.4 0 -0.4 4 N 0 
L 0 0 0 0 8 N 0 
L 0.05 -0.55 -0.05 -0.55 1 N 0 
L -0.05 -0.65 0.05 -0.65 1 N 0 
L 0.05 -0.75 -0.05 -0.75 1 N 0 
L 0 -0.8 0 -0.9 0 N 0 
L 0 -0.5 0 -0.4 0 N 0 
L 0.000125 0 0.000125 0 7 P 0 
L 0.000125 -1.3 0.000125 -1.3 7 P 0 
L 0.000125 0 0.000125 0 5 N 0 
L 0.000125 -1.3 0.000125 -1.3 5 N 0 
L -0.0015 -0.80425 -0.0015 -0.9055 11 P 0 
L 0.001125 -0.698 -0.004125 -0.698 10 P 0 
L 0.003125 -0.5975 -0.006125 -0.5975 9 P 0 
L 0.001125 -0.37875 0.001125 -0.499625 10 P 0 
L 0 -0.4 0 -0.4 5 N 0 
L 0 -0.6 0 -0.6 5 N 0 
L 0 -0.8 0 -0.8 5 N 0 
L 0 -0.5 0 -0.5 5 N 0 
L 0 -0.7 0 -0.7 5 N 0 
L 0 -0.9 0 -0.9 5 N 0 
L 0 -0.8 0 -0.9 0 N 0 
L 0 -0.4 0 -0.5 0 N 0 
S P 0
OB -0.042869094488 -0.537033464567 I
OS -0.042869094488 -0.356996062992
OS 0.041970374016 -0.356996062992
OS 0.041970374016 -0.537033464567
OS -0.042869094488 -0.537033464567
OE
SE
S P 0
OB -0.042869094488 -0.542033464567 I
OS -0.042869094488 -0.361996062992
OS 0.041970374016 -0.361996062992
OS 0.041970374016 -0.542033464567
OS -0.042869094488 -0.542033464567
OE
SE

### symbols/tpb30v20d10at28bpm+1/features
#
#Layer features
#
S P 0
OB -0.00035 -0.00035 I
OS 0.001380019685 -0.00208996063
OC 0.00208996063 -0.001380019685 0 0 Y
OS 0.00035 0.00035
OC -0.00035 -0.00035 0 0 N
OE
SE

### symbols/tpb30v20d10at28bpm/features
#
#Layer features
#
S P 0
OB 0.00035 0.00035 I
OS -0.00137992126 0.00208996063
OC -0.00208996063 0.00137992126 0 0 Y
OS -0.00035 -0.00035
OC 0.00035 0.00035 0 0 N
OE
SE

### symbols/v17d8at30sm11+1/features
#
#Layer features
#
S P 0
OB 0.00035 -0.00035 I
OS 0.00208996063 0.001380019685
OC 0.001380019685 0.00208996063 0 0 Y
OS -0.00035 0.00035
OC 0.00035 -0.00035 0 0 N
OE
SE

### symbols/v17d8at30sm11+2/features
#
#Layer features
#
S P 0
OB 0.00035 0.00035 I
OC -0.00035 -0.00035 0 0 N
OS 0.001380019685 -0.00208996063
OC 0.00208996063 -0.001380019685 0 0 Y
OS 0.00035 0.00035
OE
SE

### symbols/v17d8at30sm11+3/features
#
#Layer features
#
S P 0
OB -0.000349704724 0.00035 I
OS -0.00208976378 -0.001380019685
OC -0.001379724409 -0.00208996063 0 0 Y
OS 0.000350295276 -0.00035
OC -0.000349704724 0.00035 0.000000295276 0 N
OE
SE

### symbols/v17d8at30sm11/features
#
#Layer features
#
S P 0
OB 0.000350295276 0.00035 I
OS -0.001379724409 0.00208996063
OC -0.00208976378 0.001380019685 0 0 Y
OS -0.000349704724 -0.00035
OC 0.000350295276 0.00035 0.000000295276 0 N
OE
SE

### symbols/v20d10at28pg/features
#
#Layer features
#
S P 0
OB 0.000349901575 0.00035 I
OS -0.001380019685 0.002090059055
OC -0.002090059055 0.001380019685 0 0 Y
OS -0.000350098425 -0.00035
OC 0.000349901575 0.00035 -0.000000098425 0 N
OE
SE

### symbols/v20d10at28sm14+1/features
#
#Layer features
#
S P 0
OB -0.00035 -0.000349704724 I
OS 0.001380019685 -0.00208976378
OC 0.00208996063 -0.001379724409 0 0 Y
OS 0.00035 0.000350295276
OC -0.00035 -0.000349704724 0 0.000000295276 N
OE
SE

### symbols/v20d10at28sm14+10/features
#
#Layer features
#
S P 0
OB -0.000481299213 -0.000111318898 I
OS 0.000058661417 -0.002501279528
OC -0.000562106299 0.002438385827 -0.000001279528 0 Y
OC 0.001038681102 -0.002281299213 -0.000001279528 -0.000002755906 Y
OS 0.000478641732 0.000108661417
OC -0.000481299213 -0.000111318898 -0.000001377953 -0.000001279528 N
OE
SE

### symbols/v20d10at28sm14+11/features
#
#Layer features
#
S P 0
OB -0.000390354331 -0.000309940945 I
OS 0.001119685039 -0.00223996063
OC 0.001909645669 -0.001619980315 0 0 Y
OS 0.000389665354 0.00031003937
OC -0.000390354331 -0.000309940945 -0.000000295276 0 N
OE
SE

### symbols/v20d10at28sm14+12/features
#
#Layer features
#
S P 0
OB -0.000128937008 0.000479035433 I
OS -0.002498917323 -0.000140944882
OC 0.002420177165 0.00063730315 0.000000098425 -0.000000984252 Y
OC -0.002238976378 -0.001111023622 0.000002066929 -0.000000984252 Y
OS 0.000131102362 -0.000481003937
OC -0.000128937008 0.000479035433 0.000001082677 -0.000000984252 N
OE
SE

### symbols/v20d10at28sm14+13/features
#
#Layer features
#
S P 0
OB -0.000321358268 0.000381594488 I
OS -0.002201377953 -0.001188385827
OC 0.00191761811 0.001608661417 -0.000000295276 0.000001574803 Y
OC -0.001561417323 -0.001958366142 -0.000001377953 0.00000019685 Y
OS 0.000318602362 -0.000378444882
OC -0.000321358268 0.000381594488 -0.000001377953 0.000001574803 N
OE
SE

### symbols/v20d10at28sm14+14/features
#
#Layer features
#
S P 0
OB 0.000290551181 0.000400492126 I
OS -0.001699507874 0.001840452756
OC 0.002037106299 -0.001459547244 0.000001082677 0.000000492126 Y
OC -0.002289468504 0.001020472441 -0.000000098425 0.000000492126 Y
OS -0.000289468504 -0.000399507874
OC 0.000290551181 0.000400492126 0.000000492126 0.000000492126 N
OE
SE

### symbols/v20d10at28sm14+15/features
#
#Layer features
#
S P 0
OB 0.000089173228 0.000489370079 I
OS -0.002320866142 0.000939370079
OC 0.002459350394 -0.000454527559 -0.000001574803 -0.000000590551 Y
OC -0.002500885827 -0.000050590551 -0.000000295276 -0.000000590551 Y
OS -0.000090846457 -0.000490649606
OC 0.000089173228 0.000489370079 -0.000000885827 -0.000000590551 N
OE
SE

### symbols/v20d10at28sm14+16/features
#
#Layer features
#
S P 0
OB 0.000431299213 -0.000251181102 I
OS 0.001671358268 0.001858858268
OC -0.001264665354 -0.002159448819 0.000001279528 -0.00000265748 Y
OC 0.000811318898 0.002368897638 0.000001279528 0.00000019685 Y
OS -0.000428641732 0.000248818898
OC 0.000431299213 -0.000251181102 0.000001377953 -0.000001181102 N
OE
SE

### symbols/v20d10at28sm14+17/features
#
#Layer features
#
S P 0
OB -0.00002519685 0.00048996063 I
OS -0.00247519685 0.0005
OC -0.00247519685 -0.0005 -0.00002519685 0 Y
OS -0.00002519685 -0.000490059055
OC -0.00002519685 0.00048996063 -0.00002519685 -0.000000098425 N
OE
SE

### symbols/v20d10at28sm14+18/features
#
#Layer features
#
S P 0
OB -0.00048996063 -0.00002519685 I
OS -0.0005 -0.00247519685
OC 0.0005 -0.00247519685 0 -0.00002519685 Y
OS 0.000490059055 -0.00002519685
OC -0.00048996063 -0.00002519685 0.000000098425 -0.00002519685 N
OE
SE

### symbols/v20d10at28sm14+19/features
#
#Layer features
#
S P 0
OB 0.000025295276 -0.00048996063 I
OS 0.002475295276 -0.0005
OC 0.002475295276 0.0005 0.000025295276 0 Y
OS 0.000025295276 0.00048996063
OC 0.000025295276 -0.00048996063 0.000025295276 0 N
OE
SE

### symbols/v20d10at28sm14+2/features
#
#Layer features
#
S P 0
OB -0.000349704724 0.00035 I
OS -0.00208976378 -0.001380019685
OC -0.001379724409 -0.00208996063 0 0 Y
OS 0.000350295276 -0.00035
OC -0.000349704724 0.00035 0.000000295276 0 N
OE
SE

### symbols/v20d10at28sm14+3/features
#
#Layer features
#
S P 0
OB 0.00035 -0.00035 I
OS 0.00208996063 0.001380019685
OC 0.001380019685 0.00208996063 0 0 Y
OS -0.00035 0.00035
OC 0.00035 -0.00035 0 0 N
OE
SE

### symbols/v20d10at28sm14+4/features
#
#Layer features
#
S P 0
OB 0.000490059055 0.000025295276 I
OS 0.0005 0.002475295276
OC -0.0005 0.002475295276 0 0.000025295276 Y
OS -0.00048996063 0.000025295276
OC 0.000490059055 0.000025295276 0.000000098425 0.000025295276 N
OE
SE

### symbols/v20d10at28sm14+5/features
#
#Layer features
#
S P 0
OB 0.000431102362 0.000250984252 I
OS -0.000828838583 0.002360925197
OC 0.001286515748 -0.002147440945 0.000001082677 -0.000000098425 Y
OC -0.001688877953 0.001850984252 0.000001082677 0.00000226378 Y
OS -0.000428838583 -0.000249015748
OC 0.000431102362 0.000250984252 0.000001181102 0.000000984252 N
OE
SE

### symbols/v20d10at28sm14+6/features
#
#Layer features
#
S P 0
OB 0.000280413386 -0.000410433071 I
OS 0.002310433071 0.000959547244
OC -0.002071456693 -0.001403543307 0 -0.000000393701 Y
OC 0.001750492126 0.001789566929 0.000001082677 -0.000000393701 Y
OS -0.000279527559 0.000409547244
OC 0.000280413386 -0.000410433071 0.000000492126 -0.000000393701 N
OE
SE

### symbols/v20d10at28sm14+7/features
#
#Layer features
#
S P 0
OB -0.000299507874 -0.000389370079 I
OS 0.001640551181 -0.001889370079
OC -0.00198523622 0.001521358268 0.000001279528 0.000000590551 Y
OC 0.002250492126 -0.001089370079 -0.000000098425 0.000000590551 Y
OS 0.000300492126 0.000390649606
OC -0.000299507874 -0.000389370079 0.000000492126 0.000000688976 N
OE
SE

### symbols/v20d10at28sm14+8/features
#
#Layer features
#
S P 0
OB -0.000389370079 0.000299507874 I
OS -0.001889370079 -0.001640551181
OC 0.001521358268 0.00198523622 0.000000590551 -0.000001279528 Y
OC -0.001089370079 -0.002250492126 0.000000590551 0.000000098425 Y
OS 0.000390551181 -0.000300492126
OC -0.000389370079 0.000299507874 0.000000590551 -0.000000492126 N
OE
SE

### symbols/v20d10at28sm14+9/features
#
#Layer features
#
S P 0
OB -0.000479232283 0.000109448819 I
OS -0.001009251969 -0.002290551181
OC 0.000531102362 0.002443996063 0.000000688976 -0.000001279528 Y
OC -0.000029232283 -0.002500590551 0.000000688976 0.000000098425 Y
OS 0.000480708661 -0.000110531496
OC -0.000479232283 0.000109448819 0.000000688976 -0.000000590551 N
OE
SE

### symbols/v20d10at28sm14/features
#
#Layer features
#
S P 0
OB 0.00035019685 0.00035 I
OS -0.001379724409 0.00208996063
OC -0.00208976378 0.001380019685 0 0 Y
OS -0.00034980315 -0.00035
OC 0.00035019685 0.00035 0.00000019685 0 N
OE
SE

### symbols/wai/features
#
#Feature symbol names
#
$0 s9.843

#
#Layer features
#
L -0.19685039 0.19685039 -0.19685039 -0.19685039 0 P 0 
L -0.19685039 -0.19685039 0.19685039 -0.19685039 0 P 0 
L 0.19685039 -0.19685039 0.19685039 0.19685039 0 P 0 
L 0.19685039 0.19685039 -0.19685039 0.19685039 0 P 0 

### symbols/zs-neg-line/features
#
#Feature symbol names
#
$0 s500
$1 b2
$2 wai

#
#Layer features
#
P 0 0 0 N 0 0
P 0 0 2 P 0 0
P 0 0 1 P 0 0

### symbols/zs-pos-line/features
#
#Feature symbol names
#
$0 s500
$1 b2
$2 wai

#
#Layer features
#
P 0 0 0 P 0 0
P 0 0 2 N 0 0
P 0 0 1 N 0 0

### misc/job_name
669gb-015a-org

### misc/last_save
20171103.173124

### misc/netlist_results_cad
0 short 0 broken 0 missing 0 extra

### misc/userattr
FORCE_LIB=YES

BOOLEAN {
    NAME=TEXT_DATECODE
    PROMPT=TEXT_DATECODE
    ENTITY=FEATURE
    DEF=NO
}

BOOLEAN {
    NAME=PLANT_SYMBOL
    PROMPT=PLANT_SYMBOL
    ENTITY=FEATURE
    DEF=NO
}

BOOLEAN {
    NAME=CDR300_ALIGN
    PROMPT=CDR300_ALIGN
    ENTITY=FEATURE
    DEF=NO
}

BOOLEAN {
    NAME=BGA
    PROMPT=BGA
    ENTITY=FEATURE
    DEF=NO
}

BOOLEAN {
    NAME=SMD_GASKET
    PROMPT=SMD_GASKET
    ENTITY=FEATURE
    DEF=NO
}

BOOLEAN {
    NAME=EMI_BORDER
    PROMPT=EMI_BORDER
    ENTITY=FEATURE
    DEF=NO
}

BOOLEAN {
    NAME=ORG_FLAG
    PROMPT=ORG_FLAG
    ENTITY=FEATURE
    DEF=NO
}

BOOLEAN {
    NAME=EMC_THIEF
    PROMPT=EMC_THIEF
    ENTITY=FEATURE
    DEF=NO
}

BOOLEAN {
    NAME=GCE_SLIVER
    PROMPT=GCE_SLIVER
    ENTITY=FEATURE
    DEF=NO
}

BOOLEAN {
    NAME=EIE_BARCODE
    PROMPT=EIE_BARCODE
    ENTITY=FEATURE
    DEF=NO
}

BOOLEAN {
    NAME=SMDEFPAD_SM
    PROMPT=SMDEFPAD_SM
    ENTITY=FEATURE
    DEF=NO
}

BOOLEAN {
    NAME=SMDEFPAD_SM_TOTALLY
    PROMPT=SMDEFPAD_SM_TOTALLY
    ENTITY=FEATURE
    DEF=NO
}

BOOLEAN {
    NAME=SMDEFPAD_SM_PARTLY
    PROMPT=SMDEFPAD_SM_PARTLY
    ENTITY=FEATURE
    DEF=NO
}

BOOLEAN {
    NAME=GASKET
    PROMPT=GASKET
    ENTITY=FEATURE
    DEF=NO
}

BOOLEAN {
    NAME=SPLIT_SM
    PROMPT=SPLIT_SM
    ENTITY=FEATURE
    DEF=NO
}

BOOLEAN {
    NAME=PTH_PAD
    PROMPT=PTH_PAD
    ENTITY=FEATURE
    DEF=NO
}

BOOLEAN {
    NAME=YKK
    PROMPT=YKK
    ENTITY=FEATURE
    DEF=NO
}


TEXT {
    NAME=DATECODE
    PROMPT=DATECODE
    MIN_LEN=0
    MAX_LEN=10
    ENTITY=JOB
    DEF=2000
}

TEXT {
    NAME=FILM_VERSION
    PROMPT=FILM VERSION
    MIN_LEN=0
    MAX_LEN=3
    ENTITY=LAYER
    DEF=000
}

TEXT {
    NAME=DTOOL_VERSION
    PROMPT=DRILL TOOL VERSION
    MIN_LEN=3
    MAX_LEN=3
    ENTITY=JOB
    DEF=000
}

TEXT {
    NAME=RTOOL_VERSION
    PROMPT=ROUT TOOL VERSION
    MIN_LEN=3
    MAX_LEN=3
    ENTITY=JOB
    DEF=000
}

TEXT {
    NAME=ITOOL_VERSION
    PROMPT=INNER TOOL VERSION
    MIN_LEN=3
    MAX_LEN=3
    ENTITY=JOB
    DEF=000
}

TEXT {
    NAME=OTOOL_VERSION
    PROMPT=OUTER TOOL VERSION
    MIN_LEN=3
    MAX_LEN=3
    ENTITY=JOB
    DEF=000
}

TEXT {
    NAME=MTOOL_VERSION
    PROMPT=MASK TOOL VERSION
    MIN_LEN=3
    MAX_LEN=3
    ENTITY=JOB
    DEF=000
}

TEXT {
    NAME=STOOL_VERSION
    PROMPT=SILK TOOL VERSION
    MIN_LEN=3
    MAX_LEN=3
    ENTITY=JOB
    DEF=000
}

TEXT {
    NAME=TOOL_VERSION
    PROMPT=TOOL VERSION
    MIN_LEN=3
    MAX_LEN=3
    ENTITY=JOB
    DEF=000
}

TEXT {
    NAME=STRETCHX
    PROMPT=STRETCH X FOR LAYER
    MIN_LEN=0
    MAX_LEN=25
    ENTITY=LAYER
    DEF=100.0000
}

TEXT {
    NAME=STRETCHY
    PROMPT=STRETCH Y FOR LAYER
    MIN_LEN=0
    MAX_LEN=25
    ENTITY=LAYER
    DEF=100.0000
}

TEXT {
    NAME=PROJECTX
    PROMPT=PROJECT X FOR LAYER
    MIN_LEN=0
    MAX_LEN=25
    ENTITY=LAYER
    DEF=
}

TEXT {
    NAME=PROJECTY
    PROMPT=PROJECT Y FOR LAYER
    MIN_LEN=0
    MAX_LEN=25
    ENTITY=LAYER
    DEF=
}

TEXT {
    NAME=NORMAL_DISTANCEX
    PROMPT=X DISTANCE(1:1)
    MIN_LEN=0
    MAX_LEN=25
    ENTITY=LAYER
    DEF=
}

TEXT {
    NAME=NORMAL_DISTANCEY
    PROMPT=Y DISTANCE(1:1)
    MIN_LEN=0
    MAX_LEN=25
    ENTITY=LAYER
    DEF=
}

TEXT {
    NAME=DISTANCEX
    PROMPT=STRETCH X DISTANCE
    MIN_LEN=0
    MAX_LEN=25
    ENTITY=LAYER
    DEF=
}

TEXT {
    NAME=DISTANCEY
    PROMPT=STRETCH Y DISTANCE
    MIN_LEN=0
    MAX_LEN=25
    ENTITY=LAYER
    DEF=
}

TEXT {
    NAME=OUT_STRCHX
    PROMPT=STRETCH X FOR OUTER LAYER
    MIN_LEN=0
    MAX_LEN=25
    ENTITY=LAYER
    DEF=
}

TEXT {
    NAME=OUT_STRCHY
    PROMPT=STRETCH Y FOR OUTER LAYER
    MIN_LEN=0
    MAX_LEN=25
    ENTITY=LAYER
    DEF=
}

TEXT {
    NAME=IN_STRCHX
    PROMPT=STRETCH X FOR INNER LAYER
    MIN_LEN=0
    MAX_LEN=25
    ENTITY=LAYER
    DEF=
}

TEXT {
    NAME=IN_STRCHY
    PROMPT=STRETCH Y FOR INNER LAYER
    MIN_LEN=0
    MAX_LEN=25
    ENTITY=LAYER
    DEF=
}

TEXT {
    NAME=SMC_STRCHX
    PROMPT=STRETCH X FOR SMC
    MIN_LEN=0
    MAX_LEN=25
    ENTITY=LAYER
    DEF=
}

TEXT {
    NAME=SMC_STRCHY
    PROMPT=STRETCH Y FOR SMC
    MIN_LEN=0
    MAX_LEN=25
    ENTITY=LAYER
    DEF=
}

TEXT {
    NAME=SMS_STRCHX
    PROMPT=STRETCH X FOR SMS
    MIN_LEN=0
    MAX_LEN=25
    ENTITY=LAYER
    DEF=
}

TEXT {
    NAME=SMS_STRCHY
    PROMPT=STRETCH Y FOR SMS
    MIN_LEN=0
    MAX_LEN=25
    ENTITY=LAYER
    DEF=
}

TEXT {
    NAME=LEGC_STRCHX
    PROMPT=STRETCH X FOR LEGC
    MIN_LEN=0
    MAX_LEN=25
    ENTITY=LAYER
    DEF=
}

TEXT {
    NAME=LEGC_STRCHY
    PROMPT=STRETCH Y FOR LEGC
    MIN_LEN=0
    MAX_LEN=25
    ENTITY=LAYER
    DEF=
}

TEXT {
    NAME=LEGS_STRCHX
    PROMPT=STRETCH X FOR LEGS
    MIN_LEN=0
    MAX_LEN=25
    ENTITY=LAYER
    DEF=
}

TEXT {
    NAME=LEGS_STRCHY
    PROMPT=STRETCH Y FOR LEGS
    MIN_LEN=0
    MAX_LEN=25
    ENTITY=LAYER
    DEF=
}

TEXT {
    NAME=DATECODE-YEAR
    PROMPT=DATECODE-YEAR
    MIN_LEN=0
    MAX_LEN=2
    ENTITY=JOB
    DEF=01
}

TEXT {
    NAME=DATECODE-WEEK
    PROMPT=DATECODE-WEEK
    MIN_LEN=0
    MAX_LEN=2
    ENTITY=JOB
    DEF=01
}

TEXT {
    NAME=DATECODE-DAY
    PROMPT=DATECODE-DAY
    MIN_LEN=0
    MAX_LEN=3
    ENTITY=JOB
    DEF=000
}

TEXT {
    NAME=DATECODE-SERIAL
    PROMPT=DATECODE-SERIAL
    MIN_LEN=0
    MAX_LEN=3
    ENTITY=JOB
    DEF=-00
}

TEXT {
    NAME=COPPER_AREA
    PROMPT=COPPER_AREA
    MIN_LEN=0
    MAX_LEN=20
    ENTITY=LAYER
    DEF=
}

TEXT {
    NAME=PLOT_USER
    PROMPT=PLOT_USER
    MIN_LEN=0
    MAX_LEN=6
    ENTITY=LAYER
    DEF=000000
}

TEXT {
    NAME=PLOT_VERSION
    PROMPT=PLOT_VERSION
    MIN_LEN=0
    MAX_LEN=8
    ENTITY=LAYER
    DEF=00000000
}

TEXT {
    NAME=GCE_VERSION
    PROMPT=GCD_VERSION
    MIN_LEN=0
    MAX_LEN=20
    ENTITY=LAYER
    DEF=
}

TEXT {
    NAME=SOURCE_WIDTH
    PROMPT=SOURCE_LINE_WIDTH
    MIN_LEN=0
    MAX_LEN=20
    ENTITY=FEATURE
    DEF=
}

TEXT {
    NAME=SAVE_CODE
    PROMPT=SAVE_CODE
    MIN_LEN=0
    MAX_LEN=999
    ENTITY=LAYER
    DEF=
}

TEXT {
    NAME=FILM_BAR_CODE
    PROMPT=FILM_BAR_CODE
    MIN_LEN=0
    MAX_LEN=999
    ENTITY=LAYER
    DEF=
}

TEXT {
    NAME=SERIAL_NUM
    PROMPT=SERIAL_NUMBER
    MIN_LEN=1
    MAX_LEN=2
    ENTITY=JOB
    DEF=00
}

TEXT {
    NAME=SHT_NORMAL_DISTANCEX
    PROMPT=SHT X DISTANCE(1:1)
    MIN_LEN=0
    MAX_LEN=25
    ENTITY=LAYER
    DEF=
}

TEXT {
    NAME=SHT_NORMAL_DISTANCEY
    PROMPT=SHT Y DISTANCE(1:1)
    MIN_LEN=0
    MAX_LEN=25
    ENTITY=LAYER
    DEF=
}

TEXT {
    NAME=SHT_STRETCHX
    PROMPT=STRETCH SHTCCD X FOR LAYER
    MIN_LEN=0
    MAX_LEN=25
    ENTITY=LAYER
    DEF=100.0000
}

TEXT {
    NAME=SHT_STRETCHY
    PROMPT=STRETCH SHTCCD Y FOR LAYER
    MIN_LEN=0
    MAX_LEN=25
    ENTITY=LAYER
    DEF=100.0000
}

TEXT {
    NAME=PCB_SERIAL
    PROMPT=PCB_SERIAL
    MIN_LEN=1
    MAX_LEN=2
    ENTITY=LAYER
    DEF=00
}

TEXT {
    NAME=GCE
    PROMPT=GCE
    MIN_LEN=0
    MAX_LEN=10
    ENTITY=JOB
    DEF=
}

TEXT {
    NAME=VER
    PROMPT=VER
    MIN_LEN=0
    MAX_LEN=2
    ENTITY=JOB
    DEF=00
}

TEXT {
    NAME=NVER
    PROMPT=NVER
    MIN_LEN=0
    MAX_LEN=3
    ENTITY=JOB
    DEF=
}

TEXT {
    NAME=NJOB
    PROMPT=NJOB
    MIN_LEN=0
    MAX_LEN=10
    ENTITY=JOB
    DEF=
}

TEXT {
    NAME=OLD
    PROMPT=OLD
    MIN_LEN=0
    MAX_LEN=12
    ENTITY=JOB
    DEF=
}

TEXT {
    NAME=VER_9_13
    PROMPT=VER_9_13
    MIN_LEN=0
    MAX_LEN=10
    ENTITY=JOB
    DEF=-00
}

TEXT {
    NAME=VER_166_11_13
    PROMPT=VER_166_11_13
    MIN_LEN=0
    MAX_LEN=15
    ENTITY=JOB
    DEF=-00
}

TEXT {
    NAME=VER_166_6_9
    PROMPT=VER_166_6_9
    MIN_LEN=0
    MAX_LEN=15
    ENTITY=JOB
    DEF=-00
}

TEXT {
    NAME=WORK_SERIAL
    PROMPT=WORK_SERIAL
    MIN_LEN=0
    MAX_LEN=2
    ENTITY=LAYER
    DEF=00
}

TEXT {
    NAME=EIE_SERIAL
    PROMPT=EIE_SERIAL
    MIN_LEN=0
    MAX_LEN=3
    ENTITY=JOB
    DEF=000
}

TEXT {
    NAME=UVW_ADD_6MIL
    PROMPT=UVW_ADD_6MIL
    MIN_LEN=0
    MAX_LEN=3
    ENTITY=JOB
    DEF=NO
}

TEXT {
    NAME=LOT_CODE
    PROMPT=LOT_CODE
    MIN_LEN=0
    MAX_LEN=3
    ENTITY=JOB
    DEF=000
}

TEXT {
    NAME=STACKX
    PROMPT=STACK X FOR LAYER
    MIN_LEN=0
    MAX_LEN=25
    ENTITY=LAYER
    DEF=0
}

TEXT {
    NAME=STACKY
    PROMPT=STACK Y FOR LAYER
    MIN_LEN=0
    MAX_LEN=25
    ENTITY=LAYER
    DEF=0
}

TEXT {
    NAME=BARCODE
    PROMPT=BARCODE
    MIN_LEN=0
    MAX_LEN=10
    ENTITY=JOB
    DEF=GCE
}

TEXT {
    NAME=675XD
    PROMPT=675_DATECODE_FORMAT
    MIN_LEN=1
    MAX_LEN=6
    ENTITY=JOB
    DEF=000000
}

TEXT {
    NAME=675XDF
    PROMPT=675_DATECODE_TYPE1
    MIN_LEN=1
    MAX_LEN=3
    ENTITY=JOB
    DEF=000
}

TEXT {
    NAME=675XDS
    PROMPT=675_DATECODE_TYPE2
    MIN_LEN=1
    MAX_LEN=4
    ENTITY=JOB
    DEF=0000
}

TEXT {
    NAME=675D
    PROMPT=675_DATECODE_TYPE3
    MIN_LEN=1
    MAX_LEN=5
    ENTITY=JOB
    DEF=00000
}

TEXT {
    NAME=675LL
    PROMPT=675_LOTCODE_FORMAT
    MIN_LEN=1
    MAX_LEN=7
    ENTITY=JOB
    DEF=0000-00
}

TEXT {
    NAME=675LLM
    PROMPT=675_LOTCODE_TYPE1
    MIN_LEN=1
    MAX_LEN=4
    ENTITY=JOB
    DEF=0000
}

TEXT {
    NAME=675LLS
    PROMPT=675_LOTCODE_TYPE2
    MIN_LEN=1
    MAX_LEN=3
    ENTITY=JOB
    DEF=-00
}

TEXT {
    NAME=WSR
    PROMPT=675_LOTCODE_TYPE2
    MIN_LEN=1
    MAX_LEN=10
    ENTITY=JOB
    DEF=YYWW-88-11
}

TEXT {
    NAME=GCE_STRING
    PROMPT=GCE_STRING
    MIN_LEN=0
    MAX_LEN=20
    ENTITY=FEATURE
    DEF=
}

TEXT {
    NAME=GDC
    PROMPT=GCE_DATECODE_TYPE
    MIN_LEN=1
    MAX_LEN=2
    ENTITY=JOB
    DEF=00
}

TEXT {
    NAME=GDCS
    PROMPT=GCE_DATECODE_TYPE2
    MIN_LEN=1
    MAX_LEN=2
    ENTITY=JOB
    DEF=08
}

TEXT {
    NAME=NDC
    PROMPT=VERSION AND SERIAL
    MIN_LEN=1
    MAX_LEN=4
    ENTITY=JOB
    DEF=0000
}

TEXT {
    NAME=DDSL
    PROMPT=DDSL
    MIN_LEN=1
    MAX_LEN=4
    ENTITY=JOB
    DEF=DDSL
}

TEXT {
    NAME=END
    PROMPT=CUSTOM SPEC
    MIN_LEN=0
    MAX_LEN=3
    ENTITY=JOB
    DEF=000
}

TEXT {
    NAME=LAST6
    PROMPT=LAST6
    MIN_LEN=0
    MAX_LEN=15
    ENTITY=JOB
    DEF=-00
}

TEXT {
    NAME=VW
    PROMPT=VW_STEP
    MIN_LEN=0
    MAX_LEN=3
    ENTITY=JOB
    DEF=STD
}

TEXT {
    NAME=DSCP
    PROMPT=DSCP
    MIN_LEN=1
    MAX_LEN=5
    ENTITY=JOB
    DEF=88-11
}

TEXT {
    NAME=OUT_PROJECTX
    PROMPT=PROJECT X FOR OUTER LAYER
    MIN_LEN=0
    MAX_LEN=25
    ENTITY=LAYER
    DEF=
}

TEXT {
    NAME=OUT_PROJECTY
    PROMPT=PROJECT Y FOR OUTER LAYER
    MIN_LEN=0
    MAX_LEN=25
    ENTITY=LAYER
    DEF=
}

TEXT {
    NAME=E8
    PROMPT=E82152
    MIN_LEN=0
    MAX_LEN=6
    ENTITY=JOB
    DEF=E82152
}

TEXT {
    NAME=TODAY
    PROMPT=TODAY
    MIN_LEN=0
    MAX_LEN=1
    ENTITY=JOB
    DEF=
}

TEXT {
    NAME=DN
    PROMPT=DN
    MIN_LEN=0
    MAX_LEN=2
    ENTITY=JOB
    DEF=DN
}

TEXT {
    NAME=WEEK-DAY
    PROMPT=WEEK-DAY
    MIN_LEN=0
    MAX_LEN=8
    ENTITY=JOB
    DEF=000
}

TEXT {
    NAME=TEXT_OHMS
    PROMPT=TEXT_OHMS
    MIN_LEN=0
    MAX_LEN=20
    ENTITY=FEATURE
    DEF=
}

TEXT {
    NAME=TEXT_ATTR
    PROMPT=TEXT_ATTR
    MIN_LEN=0
    MAX_LEN=20
    ENTITY=FEATURE
    DEF=
}

TEXT {
    NAME=SVER_9_13
    PROMPT=SVER_9_13
    MIN_LEN=0
    MAX_LEN=10
    ENTITY=JOB
    DEF=
}

TEXT {
    NAME=SVER_166_11_13
    PROMPT=SVER_166_11_13
    MIN_LEN=0
    MAX_LEN=15
    ENTITY=JOB
    DEF=
}

TEXT {
    NAME=WK
    PROMPT=WK
    MIN_LEN=0
    MAX_LEN=10
    ENTITY=JOB
    DEF=
}

TEXT {
    NAME=DS
    PROMPT=DS
    MIN_LEN=0
    MAX_LEN=2
    ENTITY=JOB
    DEF=88
}

TEXT {
    NAME=CP
    PROMPT=CP
    MIN_LEN=0
    MAX_LEN=2
    ENTITY=JOB
    DEF=22
}

TEXT {
    NAME=SJOB
    PROMPT=SJOB
    MIN_LEN=0
    MAX_LEN=13
    ENTITY=JOB
    DEF=
}

TEXT {
    NAME=CJOB
    PROMPT=CJOB
    MIN_LEN=0
    MAX_LEN=13
    ENTITY=JOB
    DEF=
}

TEXT {
    NAME=SS8388
    PROMPT=SS8388
    MIN_LEN=1
    MAX_LEN=4
    ENTITY=JOB
    DEF=8888
}

TEXT {
    NAME=CH
    PROMPT=CH
    MIN_LEN=0
    MAX_LEN=5
    ENTITY=JOB
    DEF=CHINA
}

TEXT {
    NAME=LOT
    PROMPT=LOT
    MIN_LEN=0
    MAX_LEN=3
    ENTITY=JOB
    DEF=000
}

TEXT {
    NAME=NUMBER
    PROMPT=FILM NUMBER
    MIN_LEN=0
    MAX_LEN=8
    ENTITY=LAYER
    DEF=0000000
}

TEXT {
    NAME=OUT_PROJECT3X
    PROMPT=PROJECT X3 FOR OUTER LAYER
    MIN_LEN=0
    MAX_LEN=25
    ENTITY=LAYER
    DEF=
}

TEXT {
    NAME=OUT_PROJECT3Y
    PROMPT=PROJECT Y3 FOR OUTER LAYER
    MIN_LEN=0
    MAX_LEN=25
    ENTITY=LAYER
    DEF=
}

TEXT {
    NAME=N4
    PROMPT=N4
    MIN_LEN=0
    MAX_LEN=4
    ENTITY=JOB
    DEF=
}

TEXT {
    NAME=SERIAL_SM
    PROMPT=SERIAL_NUMBER_FOR_SM
    MIN_LEN=1
    MAX_LEN=2
    ENTITY=JOB
    DEF=01
}

TEXT {
    NAME=SCPAD_STRETCHX
    PROMPT=STRETCH SCPAD X FOR LAYER
    MIN_LEN=0
    MAX_LEN=25
    ENTITY=LAYER
    DEF=100.0000
}

TEXT {
    NAME=SCPAD_STRETCHY
    PROMPT=STRETCH SCPAD Y FOR LAYER
    MIN_LEN=0
    MAX_LEN=25
    ENTITY=LAYER
    DEF=100.0000
}

TEXT {
    NAME=V0A
    PROMPT=V0A
    MIN_LEN=0
    MAX_LEN=8
    ENTITY=JOB
    DEF=GX D-V0A
}

TEXT {
    NAME=V0A2
    PROMPT=V0A2
    MIN_LEN=0
    MAX_LEN=10
    ENTITY=JOB
    DEF=GX D-V0A-2
}

TEXT {
    NAME=V0ADS
    PROMPT=V0ADS
    MIN_LEN=0
    MAX_LEN=9
    ENTITY=JOB
    DEF=GX DS-V0A
}

TEXT {
    NAME=H
    PROMPT=H
    MIN_LEN=0
    MAX_LEN=4
    ENTITY=JOB
    DEF=GX H
}

TEXT {
    NAME=94
    PROMPT=94
    MIN_LEN=0
    MAX_LEN=5
    ENTITY=JOB
    DEF=94V-0
}

TEXT {
    NAME=DAR
    PROMPT=DRILL PAD ANNULARRING
    MIN_LEN=0
    MAX_LEN=3
    ENTITY=JOB
    DEF=DAR
}

TEXT {
    NAME=PCS_X
    PROMPT=PCS X
    MIN_LEN=0
    MAX_LEN=20
    ENTITY=LAYER
    DEF=
}

TEXT {
    NAME=PCS_Y
    PROMPT=PCS Y
    MIN_LEN=0
    MAX_LEN=20
    ENTITY=LAYER
    DEF=
}

TEXT {
    NAME=ARRAY_X
    PROMPT=ARRAY X
    MIN_LEN=0
    MAX_LEN=20
    ENTITY=LAYER
    DEF=
}

TEXT {
    NAME=ARRAY_Y
    PROMPT=ARRAY Y
    MIN_LEN=0
    MAX_LEN=20
    ENTITY=LAYER
    DEF=
}


OPTION {
    NAME=UL_MARK
    PROMPT=UL_MARK
    OPTIONS=GX B-V0;GX B-V0A;GX 211-V0;GX 211-V0A
    DELETED=NO;NO;NO;NO
    ENTITY=JOB
    DEF=GX B-V0
}

OPTION {
    NAME=DATECODE_TYPE
    PROMPT=DATECODE_TYPE
    OPTIONS=YYWW;WWYY;SPECIAL
    DELETED=NO;NO;NO
    ENTITY=JOB
    DEF=YYWW
}

OPTION {
    NAME=LAYER_LOCK
    PROMPT=LAYER_LOCK
    OPTIONS=LOCK;UNLOCK
    DELETED=NO;NO
    ENTITY=LAYER
    DEF=LOCK
}

OPTION {
    NAME=DATECODE-DOT
    PROMPT=DATECODE-DOT
    OPTIONS=.;-88
    DELETED=NO;NO
    ENTITY=JOB
    DEF=.
}

OPTION {
    NAME=DATECODETYPE
    PROMPT=DATECODETYPE
    OPTIONS=YYWW;WWYY;YYWW.;WWYY.;YYWW-SS;WWYY-SS;WYY;YWW;WYY-SS;YWW-SS;DDDYY;YYWW-88;YYWW8888;WWYY8888
    DELETED=NO;NO;NO;NO;NO;NO;NO;NO;NO;NO;NO;NO;NO;NO
    ENTITY=JOB
    DEF=YYWW
}

OPTION {
    NAME=FILMTYPE
    PROMPT=FILMTYPE
    OPTIONS=S;E;U;H;N;C;R
    DELETED=NO;NO;NO;NO;NO;NO;NO
    ENTITY=JOB
    DEF=S
}

OPTION {
    NAME=WEEK_TYPE
    PROMPT=WEEK_TYPE
    OPTIONS=EVEN;ODD
    DELETED=NO;NO
    ENTITY=JOB
    DEF=EVEN
}


INTEGER {
    NAME=TEXT_FLAG
    PROMPT=TEXT_FLAG
    MIN_VAL=1
    MAX_VAL=65536
    ENTITY=FEATURE
    DEF=1
}

INTEGER {
    NAME=TAMA_FLAG
    PROMPT=TAMA_FLAG
    MIN_VAL=1
    MAX_VAL=100
    ENTITY=FEATURE
    DEF=1
}

INTEGER {
    NAME=INSPECTA_FLAG
    PROMPT=INSPECTA_FLAG
    MIN_VAL=1
    MAX_VAL=100
    ENTITY=FEATURE
    DEF=1
}

INTEGER {
    NAME=CHEAT_FLAG
    PROMPT=CHEAT_FLAG
    MIN_VAL=1
    MAX_VAL=100
    ENTITY=FEATURE
    DEF=1
}

INTEGER {
    NAME=SEAL_FLAG
    PROMPT=SEAL_FLAG
    MIN_VAL=1
    MAX_VAL=24
    ENTITY=FEATURE
    DEF=1
}

INTEGER {
    NAME=CPON_FLAG
    PROMPT=CPON_FLAG
    MIN_VAL=1
    MAX_VAL=100
    ENTITY=FEATURE
    DEF=1
}

INTEGER {
    NAME=FILM_NUM
    PROMPT=FILM_NUM
    MIN_VAL=1
    MAX_VAL=10
    ENTITY=FEATURE
    DEF=1
}

INTEGER {
    NAME=PKE_FLAG
    PROMPT=PKE_FLAG
    MIN_VAL=1
    MAX_VAL=100
    ENTITY=FEATURE
    DEF=1
}

INTEGER {
    NAME=TAMA_CCD
    PROMPT=TAMA_CCD
    MIN_VAL=1
    MAX_VAL=4
    ENTITY=FEATURE
    DEF=1
}

INTEGER {
    NAME=OLEC_CCD
    PROMPT=OLEC_CCD
    MIN_VAL=1
    MAX_VAL=4
    ENTITY=FEATURE
    DEF=1
}

INTEGER {
    NAME=REG_FLAG
    PROMPT=REG_FLAG
    MIN_VAL=1
    MAX_VAL=24
    ENTITY=FEATURE
    DEF=1
}

### symbols/8888-lcd/attrlist
.out_break = no
.out_scale = no
.break_away = no
.comment = 
.text = 
.nomenclature_type = 
.source_name = 
.attached_f_attr = 
.barcode_type = notdef
.text_version = 1
.barcode_bg = 1
.barcode_astr = 1
.barcode_astr_pos = 1
.entity_version = 29840
.fill_dx = 0.100000
.fill_dy = 0.100000
.image_dx = -1.000000
.image_dy = -1.000000
.text_x_size = 0.000000
.text_y_size = 0.000000
.text_line_width = 0.000000
.text_rotation = 0.000000

### symbols/8888/attrlist
.out_break = no
.out_scale = no
.break_away = no
.comment = 
.text = 
.nomenclature_type = 
.source_name = 
.attached_f_attr = 
.barcode_type = notdef
.text_version = 1
.barcode_bg = 1
.barcode_astr = 1
.barcode_astr_pos = 1
.entity_version = 29839
.fill_dx = 0.100000
.fill_dy = 0.100000
.image_dx = -1.000000
.image_dy = -1.000000
.text_x_size = 0.000000
.text_y_size = 0.000000
.text_line_width = 0.000000
.text_rotation = 0.000000

### symbols/b1_2-test/attrlist
.out_break = no
.out_scale = no
.break_away = no
.comment = 
.text = 
.nomenclature_type = 
.source_name = 
.attached_f_attr = 
.barcode_type = notdef
.text_version = 1
.barcode_bg = 1
.barcode_astr = 1
.barcode_astr_pos = 1
.entity_version = 29828
.fill_dx = 0.100000
.fill_dy = 0.100000
.image_dx = -1.000000
.image_dy = -1.000000
.text_x_size = 0.000000
.text_y_size = 0.000000
.text_line_width = 0.000000
.text_rotation = 0.000000

### symbols/b1_2/attrlist
.out_break = no
.out_scale = no
.break_away = no
.comment = 
.text = 
.nomenclature_type = 
.source_name = 
.attached_f_attr = 
.barcode_type = notdef
.text_version = 1
.barcode_bg = 1
.barcode_astr = 1
.barcode_astr_pos = 1
.entity_version = 29827
.fill_dx = 0.100000
.fill_dy = 0.100000
.image_dx = -1.000000
.image_dy = -1.000000
.text_x_size = 0.000000
.text_y_size = 0.000000
.text_line_width = 0.000000
.text_rotation = 0.000000

### symbols/b2-1-test/attrlist
.out_break = no
.out_scale = no
.break_away = no
.comment = 
.text = 
.nomenclature_type = 
.source_name = 
.attached_f_attr = 
.barcode_type = notdef
.text_version = 1
.barcode_bg = 1
.barcode_astr = 1
.barcode_astr_pos = 1
.entity_version = 29830
.fill_dx = 0.100000
.fill_dy = 0.100000
.image_dx = -1.000000
.image_dy = -1.000000
.text_x_size = 0.000000
.text_y_size = 0.000000
.text_line_width = 0.000000
.text_rotation = 0.000000

### symbols/b2-1/attrlist
.out_break = no
.out_scale = no
.break_away = no
.comment = 
.text = 
.nomenclature_type = 
.source_name = 
.attached_f_attr = 
.barcode_type = notdef
.text_version = 1
.barcode_bg = 1
.barcode_astr = 1
.barcode_astr_pos = 1
.entity_version = 29829
.fill_dx = 0.100000
.fill_dy = 0.100000
.image_dx = -1.000000
.image_dy = -1.000000
.text_x_size = 0.000000
.text_y_size = 0.000000
.text_line_width = 0.000000
.text_rotation = 0.000000

### symbols/b2/attrlist
.out_break = no
.out_scale = no
.break_away = no
.comment = 
.text = 
.nomenclature_type = 
.source_name = 
.attached_f_attr = 
.barcode_type = notdef
.text_version = 1
.barcode_bg = 1
.barcode_astr = 1
.barcode_astr_pos = 1
.entity_version = 29812
.fill_dx = 0.100000
.fill_dy = 0.100000
.image_dx = -1.000000
.image_dy = -1.000000
.text_x_size = 0.000000
.text_y_size = 0.000000
.text_line_width = 0.000000
.text_rotation = 0.000000

### symbols/hm8888/attrlist
.out_break = no
.out_scale = no
.break_away = no
.comment = 
.text = 
.nomenclature_type = 
.source_name = 
.attached_f_attr = 
.barcode_type = notdef
.text_version = 1
.barcode_bg = 1
.barcode_astr = 1
.barcode_astr_pos = 1
.entity_version = 29841
.fill_dx = 0.100000
.fill_dy = 0.100000
.image_dx = -1.000000
.image_dy = -1.000000
.text_x_size = 0.000000
.text_y_size = 0.000000
.text_line_width = 0.000000
.text_rotation = 0.000000

### symbols/msro-old/attrlist
.out_break = no
.out_scale = no
.break_away = no
.comment = 
.text = 
.nomenclature_type = 
.source_name = 
.attached_f_attr = 
.barcode_type = notdef
.text_version = 1
.barcode_bg = 1
.barcode_astr = 1
.barcode_astr_pos = 1
.entity_version = 0
.fill_dx = 1.510000
.fill_dy = 0.210250
.image_dx = 0.210000
.image_dy = 0.209750
.text_x_size = 0.000000
.text_y_size = 0.000000
.text_line_width = 0.000000
.text_rotation = 0.000000

### symbols/msro/attrlist
.out_break = no
.out_scale = no
.break_away = no
.comment = 
.text = 
.nomenclature_type = 
.source_name = 
.attached_f_attr = 
.barcode_type = notdef
.text_version = 1
.barcode_bg = 1
.barcode_astr = 1
.barcode_astr_pos = 1
.entity_version = 0
.fill_dx = 1.510000
.fill_dy = 0.210250
.image_dx = 0.210000
.image_dy = 0.209750
.text_x_size = 0.000000
.text_y_size = 0.000000
.text_line_width = 0.000000
.text_rotation = 0.000000

### symbols/msro_y-old/attrlist
.out_break = no
.out_scale = no
.break_away = no
.comment = 
.text = 
.nomenclature_type = 
.source_name = 
.attached_f_attr = 
.barcode_type = notdef
.text_version = 1
.barcode_bg = 1
.barcode_astr = 1
.barcode_astr_pos = 1
.entity_version = 64427
.fill_dx = 1.510000
.fill_dy = 0.210250
.image_dx = 0.210000
.image_dy = 0.209750
.text_x_size = 0.000000
.text_y_size = 0.000000
.text_line_width = 0.000000
.text_rotation = 0.000000

### symbols/msro_y/attrlist
.out_break = no
.out_scale = no
.break_away = no
.comment = 
.text = 
.nomenclature_type = 
.source_name = 
.attached_f_attr = 
.barcode_type = notdef
.text_version = 1
.barcode_bg = 1
.barcode_astr = 1
.barcode_astr_pos = 1
.entity_version = 64427
.fill_dx = 1.510000
.fill_dy = 0.210250
.image_dx = 0.210000
.image_dy = 0.209750
.text_x_size = 0.000000
.text_y_size = 0.000000
.text_line_width = 0.000000
.text_rotation = 0.000000

### symbols/p-nut-old/attrlist
.out_break = no
.out_scale = no
.break_away = no
.comment = 
.text = 
.nomenclature_type = 
.source_name = 
.entity_version = 2
.fill_dx = 0.100000
.fill_dy = 0.100000
.image_dx = 0.300000
.image_dy = 0.300000
.text_x_size = 0.000000
.text_y_size = 0.000000
.text_line_width = 0.000000
.text_rotation = 0.000000

### symbols/p-nut/attrlist
.out_break = no
.out_scale = no
.break_away = no
.comment = 
.text = 
.nomenclature_type = 
.source_name = 
.attached_f_attr = 
.barcode_type = notdef
.text_version = 1
.barcode_bg = 1
.barcode_astr = 1
.barcode_astr_pos = 1
.entity_version = 29825
.fill_dx = 0.100000
.fill_dy = 0.100000
.image_dx = 0.300000
.image_dy = 0.300000
.text_x_size = 0.000000
.text_y_size = 0.000000
.text_line_width = 0.000000
.text_rotation = 0.000000

### symbols/pke-bot-old/attrlist
.out_break = no
.out_scale = no
.break_away = no
.comment = 
.text = 
.nomenclature_type = 
.source_name = 
.entity_version = 2
.fill_dx = 0.100000
.fill_dy = 0.100000
.image_dx = -1.000000
.image_dy = -1.000000
.text_x_size = 0.000000
.text_y_size = 0.000000
.text_line_width = 0.000000
.text_rotation = 0.000000

### symbols/pke-bot/attrlist
.out_break = no
.out_scale = no
.break_away = no
.comment = 
.text = 
.nomenclature_type = 
.source_name = 
.entity_version = 2
.fill_dx = 0.100000
.fill_dy = 0.100000
.image_dx = -1.000000
.image_dy = -1.000000
.text_x_size = 0.000000
.text_y_size = 0.000000
.text_line_width = 0.000000
.text_rotation = 0.000000

### symbols/pke-top-old/attrlist
.out_break = no
.out_scale = no
.break_away = no
.comment = 
.text = 
.nomenclature_type = 
.source_name = 
.entity_version = 1
.fill_dx = 0.100000
.fill_dy = 0.100000
.image_dx = -1.000000
.image_dy = -1.000000
.text_x_size = 0.000000
.text_y_size = 0.000000
.text_line_width = 0.000000
.text_rotation = 0.000000

### symbols/pke-top/attrlist
.out_break = no
.out_scale = no
.break_away = no
.comment = 
.text = 
.nomenclature_type = 
.source_name = 
.entity_version = 1
.fill_dx = 0.100000
.fill_dy = 0.100000
.image_dx = -1.000000
.image_dy = -1.000000
.text_x_size = 0.000000
.text_y_size = 0.000000
.text_line_width = 0.000000
.text_rotation = 0.000000

### symbols/reg_lb/attrlist
.out_break = no
.out_scale = no
.break_away = no
.comment = 
.text = 
.nomenclature_type = 
.source_name = 
.attached_f_attr = 
.barcode_type = notdef
.text_version = 1
.barcode_bg = 1
.barcode_astr = 1
.barcode_astr_pos = 1
.entity_version = 29835
.fill_dx = 0.100000
.fill_dy = 0.100000
.image_dx = -1.000000
.image_dy = -1.000000
.text_x_size = 0.000000
.text_y_size = 0.000000
.text_line_width = 0.000000
.text_rotation = 0.000000

### symbols/reg_lt/attrlist
.out_break = no
.out_scale = no
.break_away = no
.comment = 
.text = 
.nomenclature_type = 
.source_name = 
.attached_f_attr = 
.barcode_type = notdef
.text_version = 1
.barcode_bg = 1
.barcode_astr = 1
.barcode_astr_pos = 1
.entity_version = 29836
.fill_dx = 0.100000
.fill_dy = 0.100000
.image_dx = -1.000000
.image_dy = -1.000000
.text_x_size = 0.000000
.text_y_size = 0.000000
.text_line_width = 0.000000
.text_rotation = 0.000000

### symbols/reg_rb/attrlist
.out_break = no
.out_scale = no
.break_away = no
.comment = 
.text = 
.nomenclature_type = 
.source_name = 
.attached_f_attr = 
.barcode_type = notdef
.text_version = 1
.barcode_bg = 1
.barcode_astr = 1
.barcode_astr_pos = 1
.entity_version = 29837
.fill_dx = 0.100000
.fill_dy = 0.100000
.image_dx = -1.000000
.image_dy = -1.000000
.text_x_size = 0.000000
.text_y_size = 0.000000
.text_line_width = 0.000000
.text_rotation = 0.000000

### symbols/reg_rt/attrlist
.out_break = no
.out_scale = no
.break_away = no
.comment = 
.text = 
.nomenclature_type = 
.source_name = 
.attached_f_attr = 
.barcode_type = notdef
.text_version = 1
.barcode_bg = 1
.barcode_astr = 1
.barcode_astr_pos = 1
.entity_version = 29838
.fill_dx = 0.100000
.fill_dy = 0.100000
.image_dx = -1.000000
.image_dy = -1.000000
.text_x_size = 0.000000
.text_y_size = 0.000000
.text_line_width = 0.000000
.text_rotation = 0.000000

### symbols/seal_new/attrlist
.out_break = no
.out_scale = no
.break_away = no
.comment = 
.text = 
.nomenclature_type = 
.source_name = 
.attached_f_attr = 
.barcode_type = notdef
.text_version = 1
.barcode_bg = 1
.barcode_astr = 1
.barcode_astr_pos = 1
.entity_version = 29826
.fill_dx = 0.100000
.fill_dy = 0.100000
.image_dx = -1.000000
.image_dy = -1.000000
.text_x_size = 0.000000
.text_y_size = 0.000000
.text_line_width = 0.000000
.text_rotation = 0.000000

### symbols/sht_bot/attrlist
.out_break = no
.out_scale = no
.break_away = no
.comment = 
.text = 
.nomenclature_type = 
.source_name = 
.attached_f_attr = 
.barcode_type = notdef
.text_version = 1
.barcode_bg = 1
.barcode_astr = 1
.barcode_astr_pos = 1
.entity_version = 29877
.fill_dx = 0.100000
.fill_dy = 0.100000
.image_dx = -1.000000
.image_dy = -1.000000
.text_x_size = 0.000000
.text_y_size = 0.000000
.text_line_width = 0.000000
.text_rotation = 0.000000

### symbols/sht_top/attrlist
.out_break = no
.out_scale = no
.break_away = no
.comment = 
.text = 
.nomenclature_type = 
.source_name = 
.attached_f_attr = 
.barcode_type = notdef
.text_version = 1
.barcode_bg = 1
.barcode_astr = 1
.barcode_astr_pos = 1
.entity_version = 29878
.fill_dx = 0.100000
.fill_dy = 0.100000
.image_dx = -1.000000
.image_dy = -1.000000
.text_x_size = 0.000000
.text_y_size = 0.000000
.text_line_width = 0.000000
.text_rotation = 0.000000

### symbols/sp-8c5_2p0_254+1/attrlist
.out_break = no
.out_scale = no
.break_away = no
.comment = 
.fill_dx = 0.1
.fill_dy = 0.1
.image_dx = -1
.image_dy = -1

### symbols/sp-8c5_2p0_254+2/attrlist
.out_break = no
.out_scale = no
.break_away = no
.comment = 
.fill_dx = 0.1
.fill_dy = 0.1
.image_dx = -1
.image_dy = -1

### symbols/sp-8c5_2p0_254+3/attrlist
.out_break = no
.out_scale = no
.break_away = no
.comment = 
.fill_dx = 0.1
.fill_dy = 0.1
.image_dx = -1
.image_dy = -1

### symbols/sp-8c5_2p0_254/attrlist
.out_break = no
.out_scale = no
.break_away = no
.comment = 
.fill_dx = 0.1
.fill_dy = 0.1
.image_dx = -1
.image_dy = -1

### symbols/sp-9c5_7p0_254+1/attrlist
.out_break = no
.out_scale = no
.break_away = no
.comment = 
.fill_dx = 0.1
.fill_dy = 0.1
.image_dx = -1
.image_dy = -1

### symbols/sp-9c5_7p0_254+2/attrlist
.out_break = no
.out_scale = no
.break_away = no
.comment = 
.fill_dx = 0.1
.fill_dy = 0.1
.image_dx = -1
.image_dy = -1

### symbols/sp-9c5_7p0_254+3/attrlist
.out_break = no
.out_scale = no
.break_away = no
.comment = 
.fill_dx = 0.1
.fill_dy = 0.1
.image_dx = -1
.image_dy = -1

### symbols/sp-9c5_7p0_254/attrlist
.out_break = no
.out_scale = no
.break_away = no
.comment = 
.fill_dx = 0.1
.fill_dy = 0.1
.image_dx = -1
.image_dy = -1

### symbols/tmsri_1cu_y/attrlist
.out_break = no
.out_scale = no
.break_away = no
.comment = 
.text = 
.nomenclature_type = 
.source_name = 
.attached_f_attr = 
.barcode_type = notdef
.text_version = 1
.barcode_bg = 1
.barcode_astr = 1
.barcode_astr_pos = 1
.entity_version = 29832
.fill_dx = 0.100000
.fill_dy = 0.100000
.image_dx = -1.000000
.image_dy = -1.000000
.text_x_size = 0.000000
.text_y_size = 0.000000
.text_line_width = 0.000000
.text_rotation = 0.000000

### symbols/tmsri_y/attrlist
.out_break = no
.out_scale = no
.break_away = no
.comment = 
.text = 
.nomenclature_type = 
.source_name = 
.attached_f_attr = 
.barcode_type = notdef
.text_version = 1
.barcode_bg = 1
.barcode_astr = 1
.barcode_astr_pos = 1
.entity_version = 29831
.fill_dx = 0.100000
.fill_dy = 0.100000
.image_dx = -1.000000
.image_dy = -1.000000
.text_x_size = 0.000000
.text_y_size = 0.000000
.text_line_width = 0.000000
.text_rotation = 0.000000

### symbols/tpb30v20d10at28bpm+1/attrlist
.out_break = no
.out_scale = no
.break_away = no
.comment = 
.fill_dx = 0.1
.fill_dy = 0.1
.image_dx = -1
.image_dy = -1

### symbols/tpb30v20d10at28bpm/attrlist
.out_break = no
.out_scale = no
.break_away = no
.comment = 
.fill_dx = 0.1
.fill_dy = 0.1
.image_dx = -1
.image_dy = -1

### symbols/v17d8at30sm11+1/attrlist
.out_break = no
.out_scale = no
.break_away = no
.comment = 
.fill_dx = 0.1
.fill_dy = 0.1
.image_dx = -1
.image_dy = -1

### symbols/v17d8at30sm11+2/attrlist
.out_break = no
.out_scale = no
.break_away = no
.comment = 
.fill_dx = 0.1
.fill_dy = 0.1
.image_dx = -1
.image_dy = -1

### symbols/v17d8at30sm11+3/attrlist
.out_break = no
.out_scale = no
.break_away = no
.comment = 
.fill_dx = 0.1
.fill_dy = 0.1
.image_dx = -1
.image_dy = -1

### symbols/v17d8at30sm11/attrlist
.out_break = no
.out_scale = no
.break_away = no
.comment = 
.fill_dx = 0.1
.fill_dy = 0.1
.image_dx = -1
.image_dy = -1

### symbols/v20d10at28pg/attrlist
.out_break = no
.out_scale = no
.break_away = no
.comment = 
.fill_dx = 0.1
.fill_dy = 0.1
.image_dx = -1
.image_dy = -1

### symbols/v20d10at28sm14+1/attrlist
.out_break = no
.out_scale = no
.break_away = no
.comment = 
.fill_dx = 0.1
.fill_dy = 0.1
.image_dx = -1
.image_dy = -1

### symbols/v20d10at28sm14+10/attrlist
.out_break = no
.out_scale = no
.break_away = no
.comment = 
.fill_dx = 0.1
.fill_dy = 0.1
.image_dx = -1
.image_dy = -1

### symbols/v20d10at28sm14+11/attrlist
.out_break = no
.out_scale = no
.break_away = no
.comment = 
.fill_dx = 0.1
.fill_dy = 0.1
.image_dx = -1
.image_dy = -1

### symbols/v20d10at28sm14+12/attrlist
.out_break = no
.out_scale = no
.break_away = no
.comment = 
.fill_dx = 0.1
.fill_dy = 0.1
.image_dx = -1
.image_dy = -1

### symbols/v20d10at28sm14+13/attrlist
.out_break = no
.out_scale = no
.break_away = no
.comment = 
.fill_dx = 0.1
.fill_dy = 0.1
.image_dx = -1
.image_dy = -1

### symbols/v20d10at28sm14+14/attrlist
.out_break = no
.out_scale = no
.break_away = no
.comment = 
.fill_dx = 0.1
.fill_dy = 0.1
.image_dx = -1
.image_dy = -1

### symbols/v20d10at28sm14+15/attrlist
.out_break = no
.out_scale = no
.break_away = no
.comment = 
.fill_dx = 0.1
.fill_dy = 0.1
.image_dx = -1
.image_dy = -1

### symbols/v20d10at28sm14+16/attrlist
.out_break = no
.out_scale = no
.break_away = no
.comment = 
.fill_dx = 0.1
.fill_dy = 0.1
.image_dx = -1
.image_dy = -1

### symbols/v20d10at28sm14+17/attrlist
.out_break = no
.out_scale = no
.break_away = no
.comment = 
.fill_dx = 0.1
.fill_dy = 0.1
.image_dx = -1
.image_dy = -1

### symbols/v20d10at28sm14+18/attrlist
.out_break = no
.out_scale = no
.break_away = no
.comment = 
.fill_dx = 0.1
.fill_dy = 0.1
.image_dx = -1
.image_dy = -1

### symbols/v20d10at28sm14+19/attrlist
.out_break = no
.out_scale = no
.break_away = no
.comment = 
.fill_dx = 0.1
.fill_dy = 0.1
.image_dx = -1
.image_dy = -1

### symbols/v20d10at28sm14+2/attrlist
.out_break = no
.out_scale = no
.break_away = no
.comment = 
.fill_dx = 0.1
.fill_dy = 0.1
.image_dx = -1
.image_dy = -1

### symbols/v20d10at28sm14+3/attrlist
.out_break = no
.out_scale = no
.break_away = no
.comment = 
.fill_dx = 0.1
.fill_dy = 0.1
.image_dx = -1
.image_dy = -1

### symbols/v20d10at28sm14+4/attrlist
.out_break = no
.out_scale = no
.break_away = no
.comment = 
.fill_dx = 0.1
.fill_dy = 0.1
.image_dx = -1
.image_dy = -1

### symbols/v20d10at28sm14+5/attrlist
.out_break = no
.out_scale = no
.break_away = no
.comment = 
.fill_dx = 0.1
.fill_dy = 0.1
.image_dx = -1
.image_dy = -1

### symbols/v20d10at28sm14+6/attrlist
.out_break = no
.out_scale = no
.break_away = no
.comment = 
.fill_dx = 0.1
.fill_dy = 0.1
.image_dx = -1
.image_dy = -1

### symbols/v20d10at28sm14+7/attrlist
.out_break = no
.out_scale = no
.break_away = no
.comment = 
.fill_dx = 0.1
.fill_dy = 0.1
.image_dx = -1
.image_dy = -1

### symbols/v20d10at28sm14+8/attrlist
.out_break = no
.out_scale = no
.break_away = no
.comment = 
.fill_dx = 0.1
.fill_dy = 0.1
.image_dx = -1
.image_dy = -1

### symbols/v20d10at28sm14+9/attrlist
.out_break = no
.out_scale = no
.break_away = no
.comment = 
.fill_dx = 0.1
.fill_dy = 0.1
.image_dx = -1
.image_dy = -1

### symbols/v20d10at28sm14/attrlist
.out_break = no
.out_scale = no
.break_away = no
.comment = 
.fill_dx = 0.1
.fill_dy = 0.1
.image_dx = -1
.image_dy = -1

### symbols/wai/attrlist
.out_break = no
.out_scale = no
.break_away = no
.comment = 
.text = 
.nomenclature_type = 
.source_name = 
.attached_f_attr = 
.barcode_type = notdef
.text_version = 1
.barcode_bg = 1
.barcode_astr = 1
.barcode_astr_pos = 1
.entity_version = 29813
.fill_dx = 0.100000
.fill_dy = 0.100000
.image_dx = -1.000000
.image_dy = -1.000000
.text_x_size = 0.000000
.text_y_size = 0.000000
.text_line_width = 0.000000
.text_rotation = 0.000000

### symbols/zs-neg-line/attrlist
.out_break = no
.out_scale = no
.break_away = no
.comment = 
.text = 
.nomenclature_type = 
.source_name = 
.attached_f_attr = 
.barcode_type = notdef
.text_version = 1
.barcode_bg = 1
.barcode_astr = 1
.barcode_astr_pos = 1
.entity_version = 29833
.fill_dx = 0.100000
.fill_dy = 0.100000
.image_dx = -1.000000
.image_dy = -1.000000
.text_x_size = 0.000000
.text_y_size = 0.000000
.text_line_width = 0.000000
.text_rotation = 0.000000

### symbols/zs-pos-line/attrlist
.out_break = no
.out_scale = no
.break_away = no
.comment = 
.text = 
.nomenclature_type = 
.source_name = 
.attached_f_attr = 
.barcode_type = notdef
.text_version = 1
.barcode_bg = 1
.barcode_astr = 1
.barcode_astr_pos = 1
.entity_version = 29834
.fill_dx = 0.100000
.fill_dy = 0.100000
.image_dx = -1.000000
.image_dy = -1.000000
.text_x_size = 0.000000
.text_y_size = 0.000000
.text_line_width = 0.000000
.text_rotation = 0.000000

